; run on Fri Oct 02 10:48:29 2015 CONSTRAINTS_VIEW_GENERATED
( ConstraintFile "@baseboard_fab2_lib.baseboard_fab2(sch_1)"
	( constraintHeader
		( objectKey
			( logical )
		)
		( version
			( 16.6 )
		)
		( revisionNumber
			( logicalViewRevNum 302 )
			( physicalViewRevNum 1 )
			( otherViewRevNum 0 )
		)
		( contents
			( drawing )
			( dictionaryExtensions )
			( worksheetCustomizations )
			( crossSection )
			( electricalConstraints )
			( physicalConstraints )
			( spacingConstraints )
			( sameNetSpacingConstraints )
			( netClasses )
			( properties )
		)
		( precision
			( units mil )
			( numberOfDecimalPlaces 2 )
		)
	)
	( drawing
		( attribute "DRAWING_EXTENTS" "770373.13,336785.80"
		)
		( attribute "DRAWING_LOWER_LEFT" "-30224.80,-14061.09"
		)
	)
	( DictionaryExtensions
		( Attribute
			( Name "BOM_COST" )
			( Description " " )
			( Value
				( DataType ( dString ) )
				( Status  sProperty  sPackage )
			)
			( Objects
				( ValidObjects  oGate  oGateDefn  oBlock  oPart  oDesign  oSystem  oPartDefn  oNet  oPinDefn  oPin  oXnet  oRegion  oECSet  oDRC  oNetClass  oDiffPair  oBus  oPinPair  oMatchGroup  oIODriver  oDie  oInterposer  oSpacer  oClassClass  oRatBundle  oShape  oFromTo  oNetInterface  oNetGroup  oVoltageDefinition  oWireProfile  oVia  oSymbolDefn  oSymbol  oLine  oFigure  oVoid  oCLine  oRegionClass  oRegionClassClass  oGroup )
				( NoInherit
					( oGate oPin )
				)
			)
			( Analysis
			)
		)
		( Attribute
			( Name "SEC_TYPE" )
			( Description " " )
			( Value
				( DataType ( dString ) )
				( Status  sProperty  sPackage )
			)
			( Objects
				( ValidObjects  oGate  oGateDefn  oBlock  oPart  oDesign  oSystem  oPartDefn  oIODriver  oSymbolDefn  oSymbol )
				( NoInherit
					( oGate oPin )
				)
			)
			( Analysis
			)
		)
		( Attribute
			( Name "TOLERANCE" )
			( Description " " )
			( Value
				( DataType ( dString ) )
				( Status  sProperty  sPackage )
			)
			( Objects
				( ValidObjects  oGate  oGateDefn  oBlock  oPart  oDesign  oSystem  oPartDefn  oPinDefn  oPin  oXnet  oNet  oRegion  oECSet  oDRC  oNetClass  oDiffPair  oBus  oPinPair  oMatchGroup  oIODriver  oDie  oInterposer  oSpacer  oClassClass  oRatBundle  oShape  oFromTo  oNetInterface  oNetGroup  oVoltageDefinition  oWireProfile  oVia  oSymbolDefn  oSymbol  oLine  oFigure  oVoid  oCLine  oRegionClass  oRegionClassClass  oGroup )
				( NoInherit
					( oGate oPin )
				)
			)
			( Analysis
			)
		)
		( Attribute
			( Name "WATTAGE" )
			( Description " " )
			( Value
				( DataType ( dString ) )
				( Status  sProperty  sPackage )
			)
			( Objects
				( ValidObjects  oGate  oGateDefn  oBlock  oPart  oDesign  oSystem  oPartDefn  oPinDefn  oPin  oXnet  oNet  oRegion  oECSet  oDRC  oNetClass  oDiffPair  oBus  oPinPair  oMatchGroup  oIODriver  oDie  oInterposer  oSpacer  oClassClass  oRatBundle  oShape  oFromTo  oNetInterface  oNetGroup  oVoltageDefinition  oWireProfile  oVia  oSymbolDefn  oSymbol  oLine  oFigure  oVoid  oCLine  oRegionClass  oRegionClassClass  oGroup )
				( NoInherit
					( oGate oPin )
				)
			)
			( Analysis
			)
		)
		( Attribute
			( Name "SKT_NUMBER" )
			( Description " " )
			( Value
				( DataType ( dString ) )
				( Status  sProperty  sPackage )
			)
			( Objects
				( ValidObjects  oGate  oGateDefn  oBlock  oPart  oDesign  oSystem  oPartDefn  oIODriver  oSymbolDefn  oSymbol )
				( NoInherit
					( oGate oPin )
				)
			)
			( Analysis
			)
		)
		( Attribute
			( Name "CD_SEC" )
			( Description " " )
			( Value
				( DataType ( dString ) )
				( Status  sProperty  sPackage )
			)
			( Objects
				( ValidObjects  oGate  oGateDefn  oBlock  oPart  oDesign  oSystem  oPartDefn  oPinDefn  oPin  oXnet  oNet  oRegion  oECSet  oDRC  oNetClass  oDiffPair  oBus  oPinPair  oMatchGroup  oIODriver  oDie  oInterposer  oSpacer  oClassClass  oRatBundle  oShape  oFromTo  oNetInterface  oNetGroup  oVoltageDefinition  oWireProfile  oVia  oSymbolDefn  oSymbol  oLine  oFigure  oVoid  oCLine  oRegionClass  oRegionClassClass  oGroup )
				( NoInherit
					( oGate oPin )
				)
			)
			( Analysis
			)
		)
		( Attribute
			( Name "CDS_LMAN_SYM_OUTLINE" )
			( Description " " )
			( Value
				( DataType ( dString ) )
				( Status  sProperty  sPackage )
			)
			( Objects
				( ValidObjects  oGate  oGateDefn  oBlock  oPart  oDesign  oSystem  oPartDefn  oIODriver  oSymbolDefn  oSymbol )
				( NoInherit
					( oGate oPin )
				)
			)
			( Analysis
			)
		)
		( Attribute
			( Name "SKU" )
			( Description " " )
			( Value
				( DataType ( dString ) )
				( Status  sProperty  sPackage )
			)
			( Objects
				( ValidObjects  oGate  oGateDefn  oBlock  oPart  oDesign  oSystem  oPartDefn  oIODriver  oSymbolDefn  oSymbol )
				( NoInherit
					( oGate oPin )
				)
			)
			( Analysis
			)
		)
		( Attribute
			( Name "COLOR" )
			( Description " " )
			( Value
				( DataType ( dString ) )
				( Status  sProperty  sPackage )
			)
			( Objects
				( ValidObjects  oGate  oGateDefn  oBlock  oPart  oDesign  oSystem  oPartDefn  oPinDefn  oPin  oXnet  oNet  oRegion  oECSet  oDRC  oNetClass  oDiffPair  oBus  oPinPair  oMatchGroup  oIODriver  oDie  oInterposer  oSpacer  oClassClass  oRatBundle  oShape  oFromTo  oNetInterface  oNetGroup  oVoltageDefinition  oWireProfile  oVia  oSymbolDefn  oSymbol  oLine  oFigure  oVoid  oCLine  oRegionClass  oRegionClassClass  oGroup )
				( NoInherit
					( oGate oPin )
				)
			)
			( Analysis
			)
		)
		( Attribute
			( Name "VOLATGE" )
			( Description " " )
			( Value
				( DataType ( dString ) )
				( Status  sProperty  sPackage )
			)
			( Objects
				( ValidObjects  oNet  oXnet  oPinPair  oBus  oDiffPair  oECSet  oFromTo )
			)
			( Analysis
			)
		)
		( Attribute
			( Name "SPOF" )
			( Description " " )
			( Value
				( DataType ( dString ) )
				( Status  sProperty  sPackage )
			)
			( Objects
				( ValidObjects  oGate  oGateDefn  oBlock  oPart  oDesign  oSystem  oPartDefn  oPinDefn  oPin  oXnet  oNet  oRegion  oECSet  oDRC  oNetClass  oDiffPair  oBus  oPinPair  oMatchGroup  oIODriver  oDie  oInterposer  oSpacer  oClassClass  oRatBundle  oShape  oFromTo  oNetInterface  oNetGroup  oVoltageDefinition  oWireProfile  oVia  oSymbolDefn  oSymbol  oLine  oFigure  oVoid  oCLine  oRegionClass  oRegionClassClass  oGroup )
				( NoInherit
					( oGate oPin )
				)
			)
			( Analysis
			)
		)
		( Attribute
			( Name "BOM" )
			( Description " " )
			( Value
				( DataType ( dString ) )
				( Status  sProperty  sPackage )
			)
			( Objects
				( ValidObjects  oGate  oGateDefn  oBlock  oPart  oDesign  oSystem  oPartDefn  oPinDefn  oPin  oXnet  oNet  oRegion  oECSet  oDRC  oNetClass  oDiffPair  oBus  oPinPair  oMatchGroup  oIODriver  oDie  oInterposer  oSpacer  oClassClass  oRatBundle  oShape  oFromTo  oNetInterface  oNetGroup  oVoltageDefinition  oWireProfile  oVia  oSymbolDefn  oSymbol  oLine  oFigure  oVoid  oCLine  oRegionClass  oRegionClassClass  oGroup )
				( NoInherit
					( oGate oPin )
				)
			)
			( Analysis
			)
		)
		( Attribute
			( Name "FIN" )
			( Description " " )
			( Value
				( DataType ( dString ) )
				( Status  sProperty  sPackage )
			)
			( Objects
				( ValidObjects  oGate  oGateDefn  oBlock  oPart  oDesign  oSystem  oPartDefn  oIODriver  oSymbolDefn  oSymbol )
				( NoInherit
					( oGate oPin )
				)
			)
			( Analysis
			)
		)
		( Attribute
			( Name "P1V5_STBY_IBMC" )
			( Description " " )
			( Value
				( DataType ( dString ) )
				( Status  sProperty  sPackage )
			)
			( Objects
				( ValidObjects  oGate  oGateDefn  oBlock  oPart  oDesign  oSystem  oPartDefn  oIODriver  oSymbolDefn  oSymbol )
				( NoInherit
					( oGate oPin )
				)
			)
			( Analysis
			)
		)
		( Attribute
			( Name "P1V5_STBY_IBMC_VR" )
			( Description " " )
			( Value
				( DataType ( dString ) )
				( Status  sProperty  sPackage )
			)
			( Objects
				( ValidObjects  oGate  oGateDefn  oBlock  oPart  oDesign  oSystem  oPartDefn  oIODriver  oSymbolDefn  oSymbol )
				( NoInherit
					( oGate oPin )
				)
			)
			( Analysis
			)
		)
		( Attribute
			( Name "$location" )
			( Description "" )
			( Value
				( DataType ( dString ) )
				( Status  sProperty )
			)
			( Objects
				( ValidObjects  oAll )
			)
			( Analysis
			)
		)
		( Attribute
			( Name "$sec" )
			( Description "" )
			( Value
				( DataType ( dString ) )
				( Status  sProperty )
			)
			( Objects
				( ValidObjects  oAll )
			)
			( Analysis
			)
		)
		( Attribute
			( Name "WACKO" )
			( Description " " )
			( Value
				( DataType ( dString ) )
				( Status  sProperty  sPackage )
			)
			( Objects
				( ValidObjects  oGate  oGateDefn  oBlock  oPart  oDesign  oSystem  oPartDefn  oIODriver  oSymbolDefn  oSymbol )
				( NoInherit
					( oGate oPin )
				)
			)
			( Analysis
			)
		)
		( Attribute
			( Name "BODY_TYPE" )
			( Description " " )
			( Value
				( DataType ( dString ) )
				( Status  sProperty  sPackage )
			)
			( Objects
				( ValidObjects  oGate  oGateDefn  oBlock  oPart  oDesign  oSystem  oPartDefn  oIODriver  oSymbolDefn  oSymbol )
			)
			( Analysis
			)
		)
		( Attribute
			( Name "ECSET_MAPPING_TAG_UD" )
			( Description " " )
			( Value
				( DataType ( dString ) )
				( Status  sProperty )
			)
			( Objects
				( ValidObjects  oPart  oPinDefn  oPin  oIODriver  oSymbolDefn  oSymbol )
			)
			( Analysis
			)
		)
		( Attribute
			( Name "TYPE" )
			( Description " " )
			( Value
				( DataType ( dString ) )
				( Status  sProperty )
			)
			( Objects
				( ValidObjects  oDesign  oPartDefn  oPart  oGateDefn  oGate  oIODriver  oSymbolDefn  oSymbol )
			)
			( Analysis
			)
		)
		( Attribute
			( Name "CURRENT" )
			( Description " " )
			( Value
				( DataType ( dString ) )
				( Status  sProperty )
			)
			( Objects
				( ValidObjects  oDesign  oPartDefn  oPart  oGateDefn  oGate  oIODriver  oSymbolDefn  oSymbol )
			)
			( Analysis
			)
		)
		( Attribute
			( Name "PART_CONFIG" )
			( Description " " )
			( Value
				( DataType ( dString ) )
				( Status  sProperty )
			)
			( Objects
				( ValidObjects  oDesign  oPartDefn  oPart  oGateDefn  oGate  oIODriver  oSymbolDefn  oSymbol )
			)
			( Analysis
			)
		)
		( Attribute
			( Name "NAME" )
			( Description " " )
			( Value
				( DataType ( dString ) )
				( Status  sProperty )
			)
			( Objects
				( ValidObjects  oDesign  oPartDefn  oPart  oGateDefn  oGate  oIODriver  oSymbolDefn  oSymbol )
			)
			( Analysis
			)
		)
		( Attribute
			( Name "PIN_SHORT" )
			( Description " " )
			( Value
				( DataType ( dString ) )
				( Status  sProperty )
			)
			( Objects
				( ValidObjects  oDesign  oPartDefn  oPart  oGateDefn  oGate  oIODriver  oSymbolDefn  oSymbol )
			)
			( Analysis
			)
		)
		( Attribute
			( Name "REV" )
			( Description " " )
			( Value
				( DataType ( dString ) )
				( Status  sProperty )
			)
			( Objects
				( ValidObjects  oDesign  oPartDefn  oPart  oGateDefn  oGate  oIODriver  oSymbolDefn  oSymbol )
			)
			( Analysis
			)
		)
		( Attribute
			( Name "PART_SYM_NUM" )
			( Description " " )
			( Value
				( DataType ( dString ) )
				( Status  sProperty )
			)
			( Objects
				( ValidObjects  oDesign  oPartDefn  oPart  oGateDefn  oGate  oIODriver  oSymbolDefn  oSymbol )
			)
			( Analysis
			)
		)
		( Attribute
			( Name "TH" )
			( Description " " )
			( Value
				( DataType ( dString ) )
				( Status  sProperty )
			)
			( Objects
				( ValidObjects  oDesign  oPartDefn  oPart  oGateDefn  oGate  oIODriver  oSymbolDefn  oSymbol )
			)
			( Analysis
			)
		)
		( Attribute
			( Name "L1" )
			( Description " " )
			( Value
				( DataType ( dString ) )
				( Status  sProperty )
			)
			( Objects
				( ValidObjects  oXnet  oNet  oECSet  oDiffPair  oBus  oPinPair  oFromTo )
			)
			( Analysis
			)
		)
		( Attribute
			( Name "ROM" )
			( Description " " )
			( Value
				( DataType ( dString ) )
				( Status  sProperty )
			)
			( Objects
				( ValidObjects  oDesign  oPartDefn  oPart  oGateDefn  oGate  oIODriver  oSymbolDefn  oSymbol )
			)
			( Analysis
			)
		)
		( Attribute
			( Name "ROMM" )
			( Description " " )
			( Value
				( DataType ( dString ) )
				( Status  sProperty )
			)
			( Objects
				( ValidObjects  oDesign  oPartDefn  oPart  oGateDefn  oGate  oIODriver  oSymbolDefn  oSymbol )
			)
			( Analysis
			)
		)
		( Attribute
			( Name "BAD_VOLTAGE" )
			( Description " " )
			( Value
				( DataType ( dString ) )
				( Status  sProperty )
			)
			( Objects
				( ValidObjects  oXnet  oNet  oECSet  oDiffPair  oBus  oPinPair  oFromTo )
			)
			( Analysis
			)
		)
		( Attribute
			( Name "R00M" )
			( Description " " )
			( Value
				( DataType ( dString ) )
				( Status  sProperty )
			)
			( Objects
				( ValidObjects  oDesign  oPartDefn  oPart  oGateDefn  oGate  oPinDefn  oPin  oXnet  oNet  oRegion  oECSet  oDRC  oNetClass  oDiffPair  oBus  oPinPair  oMatchGroup  oIODriver  oDie  oInterposer  oSpacer  oClassClass  oRatBundle  oShape  oFromTo  oNetInterface  oNetGroup  oVoltageDefinition  oWireProfile  oVia  oSymbolDefn  oSymbol  oLine  oFigure  oVoid  oCLine  oRegionClass  oRegionClassClass  oGroup )
			)
			( Analysis
			)
		)
		( Attribute
			( Name "COLOR2" )
			( Description " " )
			( Value
				( DataType ( dString ) )
				( Status  sProperty )
			)
			( Objects
				( ValidObjects  oDesign  oPartDefn  oPart  oGateDefn  oGate  oPinDefn  oPin  oXnet  oNet  oRegion  oECSet  oDRC  oNetClass  oDiffPair  oBus  oPinPair  oMatchGroup  oIODriver  oDie  oInterposer  oSpacer  oClassClass  oRatBundle  oShape  oFromTo  oNetInterface  oNetGroup  oVoltageDefinition  oWireProfile  oVia  oSymbolDefn  oSymbol  oLine  oFigure  oVoid  oCLine  oRegionClass  oRegionClassClass  oGroup )
			)
			( Analysis
			)
		)
		( Attribute
			( Name "COLOR1" )
			( Description " " )
			( Value
				( DataType ( dString ) )
				( Status  sProperty )
			)
			( Objects
				( ValidObjects  oDesign  oPartDefn  oPart  oGateDefn  oGate  oPinDefn  oPin  oXnet  oNet  oRegion  oECSet  oDRC  oNetClass  oDiffPair  oBus  oPinPair  oMatchGroup  oIODriver  oDie  oInterposer  oSpacer  oClassClass  oRatBundle  oShape  oFromTo  oNetInterface  oNetGroup  oVoltageDefinition  oWireProfile  oVia  oSymbolDefn  oSymbol  oLine  oFigure  oVoid  oCLine  oRegionClass  oRegionClassClass  oGroup )
			)
			( Analysis
			)
		)
		( Attribute
			( Name "EPG_RP_TP" )
			( Description " " )
			( Value
				( DataType ( dBoolean ) )
				( Status  sProperty )
			)
			( Objects
				( ValidObjects  oNet )
			)
			( Analysis
			)
		)
		( Attribute
			( Name "STD_CST" )
			( Description " " )
			( Value
				( DataType ( dString ) )
				( Status  sProperty )
			)
			( Objects
				( ValidObjects  oDesign  oPartDefn  oPart  oGateDefn  oGate  oPinDefn  oPin  oXnet  oNet  oRegion  oECSet  oDRC  oNetClass  oDiffPair  oBus  oPinPair  oMatchGroup  oIODriver  oDie  oInterposer  oSpacer  oClassClass  oRatBundle  oShape  oFromTo  oNetInterface  oNetGroup  oVoltageDefinition  oWireProfile  oVia  oSymbolDefn  oSymbol  oLine  oFigure  oVoid  oCLine  oRegionClass  oRegionClassClass  oGroup )
			)
			( Analysis
			)
		)
		( Attribute
			( Name "RPL_CODE" )
			( Description " " )
			( Value
				( DataType ( dString ) )
				( Status  sProperty )
			)
			( Objects
				( ValidObjects  oDesign  oPartDefn  oPart  oGateDefn  oGate  oPinDefn  oPin  oXnet  oNet  oRegion  oECSet  oDRC  oNetClass  oDiffPair  oBus  oPinPair  oMatchGroup  oIODriver  oDie  oInterposer  oSpacer  oClassClass  oRatBundle  oShape  oFromTo  oNetInterface  oNetGroup  oVoltageDefinition  oWireProfile  oVia  oSymbolDefn  oSymbol  oLine  oFigure  oVoid  oCLine  oRegionClass  oRegionClassClass  oGroup )
			)
			( Analysis
			)
		)
		( Attribute
			( Name "MFG_STATUS" )
			( Description " " )
			( Value
				( DataType ( dString ) )
				( Status  sProperty )
			)
			( Objects
				( ValidObjects  oDesign  oPartDefn  oPart  oGateDefn  oGate  oPinDefn  oPin  oXnet  oNet  oRegion  oECSet  oDRC  oNetClass  oDiffPair  oBus  oPinPair  oMatchGroup  oIODriver  oDie  oInterposer  oSpacer  oClassClass  oRatBundle  oShape  oFromTo  oNetInterface  oNetGroup  oVoltageDefinition  oWireProfile  oVia  oSymbolDefn  oSymbol  oLine  oFigure  oVoid  oCLine  oRegionClass  oRegionClassClass  oGroup )
			)
			( Analysis
			)
		)
		( Attribute
			( Name "MFG_PN" )
			( Description " " )
			( Value
				( DataType ( dString ) )
				( Status  sProperty )
			)
			( Objects
				( ValidObjects  oDesign  oPartDefn  oPart  oGateDefn  oGate  oPinDefn  oPin  oXnet  oNet  oRegion  oECSet  oDRC  oNetClass  oDiffPair  oBus  oPinPair  oMatchGroup  oIODriver  oDie  oInterposer  oSpacer  oClassClass  oRatBundle  oShape  oFromTo  oNetInterface  oNetGroup  oVoltageDefinition  oWireProfile  oVia  oSymbolDefn  oSymbol  oLine  oFigure  oVoid  oCLine  oRegionClass  oRegionClassClass  oGroup )
			)
			( Analysis
			)
		)
		( Attribute
			( Name "MFG" )
			( Description " " )
			( Value
				( DataType ( dString ) )
				( Status  sProperty )
			)
			( Objects
				( ValidObjects  oDesign  oPartDefn  oPart  oGateDefn  oGate  oPinDefn  oPin  oXnet  oNet  oRegion  oECSet  oDRC  oNetClass  oDiffPair  oBus  oPinPair  oMatchGroup  oIODriver  oDie  oInterposer  oSpacer  oClassClass  oRatBundle  oShape  oFromTo  oNetInterface  oNetGroup  oVoltageDefinition  oWireProfile  oVia  oSymbolDefn  oSymbol  oLine  oFigure  oVoid  oCLine  oRegionClass  oRegionClassClass  oGroup )
			)
			( Analysis
			)
		)
		( Attribute
			( Name "HFE" )
			( Description " " )
			( Value
				( DataType ( dString ) )
				( Status  sProperty )
			)
			( Objects
				( ValidObjects  oDesign  oPartDefn  oPart  oGateDefn  oGate  oPinDefn  oPin  oXnet  oNet  oRegion  oECSet  oDRC  oNetClass  oDiffPair  oBus  oPinPair  oMatchGroup  oIODriver  oDie  oInterposer  oSpacer  oClassClass  oRatBundle  oShape  oFromTo  oNetInterface  oNetGroup  oVoltageDefinition  oWireProfile  oVia  oSymbolDefn  oSymbol  oLine  oFigure  oVoid  oCLine  oRegionClass  oRegionClassClass  oGroup )
			)
			( Analysis
			)
		)
		( Attribute
			( Name "HF" )
			( Description " " )
			( Value
				( DataType ( dString ) )
				( Status  sProperty )
			)
			( Objects
				( ValidObjects  oDesign  oPartDefn  oPart  oGateDefn  oGate  oPinDefn  oPin  oXnet  oNet  oRegion  oECSet  oDRC  oNetClass  oDiffPair  oBus  oPinPair  oMatchGroup  oIODriver  oDie  oInterposer  oSpacer  oClassClass  oRatBundle  oShape  oFromTo  oNetInterface  oNetGroup  oVoltageDefinition  oWireProfile  oVia  oSymbolDefn  oSymbol  oLine  oFigure  oVoid  oCLine  oRegionClass  oRegionClassClass  oGroup )
			)
			( Analysis
			)
		)
		( Attribute
			( Name "EU_TELC_SVR" )
			( Description " " )
			( Value
				( DataType ( dString ) )
				( Status  sProperty )
			)
			( Objects
				( ValidObjects  oDesign  oPartDefn  oPart  oGateDefn  oGate  oPinDefn  oPin  oXnet  oNet  oRegion  oECSet  oDRC  oNetClass  oDiffPair  oBus  oPinPair  oMatchGroup  oIODriver  oDie  oInterposer  oSpacer  oClassClass  oRatBundle  oShape  oFromTo  oNetInterface  oNetGroup  oVoltageDefinition  oWireProfile  oVia  oSymbolDefn  oSymbol  oLine  oFigure  oVoid  oCLine  oRegionClass  oRegionClassClass  oGroup )
			)
			( Analysis
			)
		)
		( Attribute
			( Name "EU_ROHS" )
			( Description " " )
			( Value
				( DataType ( dString ) )
				( Status  sProperty )
			)
			( Objects
				( ValidObjects  oDesign  oPartDefn  oPart  oGateDefn  oGate  oPinDefn  oPin  oXnet  oNet  oRegion  oECSet  oDRC  oNetClass  oDiffPair  oBus  oPinPair  oMatchGroup  oIODriver  oDie  oInterposer  oSpacer  oClassClass  oRatBundle  oShape  oFromTo  oNetInterface  oNetGroup  oVoltageDefinition  oWireProfile  oVia  oSymbolDefn  oSymbol  oLine  oFigure  oVoid  oCLine  oRegionClass  oRegionClassClass  oGroup )
			)
			( Analysis
			)
		)
		( Attribute
			( Name "MAX_FILENAME_VALUE" )
			( Description " " )
			( Value
				( DataType ( dString ) )
				( Status  sProperty )
			)
			( Objects
				( ValidObjects  oDesign )
			)
			( Analysis
			)
		)
		( Attribute
			( Name "SPEED_URL" )
			( Description " " )
			( Value
				( DataType ( dString ) )
				( Status  sProperty )
			)
			( Objects
				( ValidObjects  oDesign  oPartDefn  oPart  oGateDefn  oGate  oPinDefn  oPin  oXnet  oNet  oRegion  oECSet  oDRC  oNetClass  oDiffPair  oBus  oPinPair  oMatchGroup  oIODriver  oDie  oInterposer  oSpacer  oClassClass  oRatBundle  oShape  oFromTo  oNetInterface  oNetGroup  oVoltageDefinition  oWireProfile  oVia  oSymbolDefn  oSymbol  oLine  oFigure  oVoid  oCLine  oRegionClass  oRegionClassClass  oGroup )
			)
			( Analysis
			)
		)
		( Attribute
			( Name "LAST_SAVE_TIME" )
			( Description " " )
			( Value
				( DataType ( dString ) )
				( Status  sProperty )
			)
			( Objects
				( ValidObjects  oDesign )
			)
			( Analysis
			)
		)
		( Attribute
			( Name "LMS_SEC" )
			( Description " " )
			( Value
				( DataType ( dString ) )
				( Status  sProperty )
			)
			( Objects
				( ValidObjects  oDesign  oPartDefn  oPart  oGateDefn  oGate  oPinDefn  oPin  oXnet  oNet  oRegion  oECSet  oDRC  oNetClass  oDiffPair  oBus  oPinPair  oMatchGroup  oIODriver  oDie  oInterposer  oSpacer  oClassClass  oRatBundle  oShape  oFromTo  oNetInterface  oNetGroup  oVoltageDefinition  oWireProfile  oVia  oSymbolDefn  oSymbol  oLine  oFigure  oVoid  oCLine  oRegionClass  oRegionClassClass  oGroup )
			)
			( Analysis
			)
		)
		( Attribute
			( Name "LMS_LIB" )
			( Description " " )
			( Value
				( DataType ( dString ) )
				( Status  sProperty )
			)
			( Objects
				( ValidObjects  oDesign  oPartDefn  oPart  oGateDefn  oGate  oPinDefn  oPin  oXnet  oNet  oRegion  oECSet  oDRC  oNetClass  oDiffPair  oBus  oPinPair  oMatchGroup  oIODriver  oDie  oInterposer  oSpacer  oClassClass  oRatBundle  oShape  oFromTo  oNetInterface  oNetGroup  oVoltageDefinition  oWireProfile  oVia  oSymbolDefn  oSymbol  oLine  oFigure  oVoid  oCLine  oRegionClass  oRegionClassClass  oGroup )
			)
			( Analysis
			)
		)
		( Attribute
			( Name "RTS_SEC" )
			( Description " " )
			( Value
				( DataType ( dString ) )
				( Status  sProperty )
			)
			( Objects
				( ValidObjects  oDesign  oPartDefn  oPart  oGateDefn  oGate  oPinDefn  oPin  oXnet  oNet  oRegion  oECSet  oDRC  oNetClass  oDiffPair  oBus  oPinPair  oMatchGroup  oIODriver  oDie  oInterposer  oSpacer  oClassClass  oRatBundle  oShape  oFromTo  oNetInterface  oNetGroup  oVoltageDefinition  oWireProfile  oVia  oSymbolDefn  oSymbol  oLine  oFigure  oVoid  oCLine  oRegionClass  oRegionClassClass  oGroup )
			)
			( Analysis
			)
		)
		( Attribute
			( Name "RTS_LIB" )
			( Description " " )
			( Value
				( DataType ( dString ) )
				( Status  sProperty )
			)
			( Objects
				( ValidObjects  oDesign  oPartDefn  oPart  oGateDefn  oGate  oPinDefn  oPin  oXnet  oNet  oRegion  oECSet  oDRC  oNetClass  oDiffPair  oBus  oPinPair  oMatchGroup  oIODriver  oDie  oInterposer  oSpacer  oClassClass  oRatBundle  oShape  oFromTo  oNetInterface  oNetGroup  oVoltageDefinition  oWireProfile  oVia  oSymbolDefn  oSymbol  oLine  oFigure  oVoid  oCLine  oRegionClass  oRegionClassClass  oGroup )
			)
			( Analysis
			)
		)
		( Attribute
			( Name "LABEL" )
			( Description " " )
			( Value
				( DataType ( dString ) )
				( Status  sProperty )
			)
			( Objects
				( ValidObjects  oDesign  oPartDefn  oPart  oGateDefn  oGate  oPinDefn  oPin  oXnet  oNet  oRegion  oECSet  oDRC  oNetClass  oDiffPair  oBus  oPinPair  oMatchGroup  oIODriver  oDie  oInterposer  oSpacer  oClassClass  oRatBundle  oShape  oFromTo  oNetInterface  oNetGroup  oVoltageDefinition  oWireProfile  oVia  oSymbolDefn  oSymbol  oLine  oFigure  oVoid  oCLine  oRegionClass  oRegionClassClass  oGroup )
			)
			( Analysis
			)
		)
		( Attribute
			( Name "SQ_LINE_WIDTH_VALUES" )
			( Description " " )
			( Value
				( DataType ( dString ) )
				( Status  sProperty )
			)
			( Objects
				( ValidObjects  oDesign )
			)
			( Analysis
			)
		)
		( Attribute
			( Name "NB_CLOCK" )
			( Description " " )
			( Value
				( DataType ( dString ) )
				( Status  sProperty )
			)
			( Objects
				( ValidObjects  oDesign  oPartDefn  oPart  oGateDefn  oGate  oPinDefn  oPin  oXnet  oNet  oRegion  oECSet  oDRC  oNetClass  oDiffPair  oBus  oPinPair  oMatchGroup  oIODriver  oDie  oInterposer  oSpacer  oClassClass  oRatBundle  oShape  oFromTo  oNetInterface  oNetGroup  oVoltageDefinition  oWireProfile  oVia  oSymbolDefn  oSymbol  oLine  oFigure  oVoid  oCLine  oRegionClass  oRegionClassClass  oGroup )
			)
			( Analysis
			)
		)
		( Attribute
			( Name "RATED_VOLTAGE" )
			( Description " " )
			( Value
				( DataType ( dString ) )
				( Status  sProperty )
			)
			( Objects
				( ValidObjects  oDesign  oPartDefn  oPart  oGateDefn  oGate  oPinDefn  oPin  oXnet  oNet  oRegion  oECSet  oDRC  oNetClass  oDiffPair  oBus  oPinPair  oMatchGroup  oIODriver  oDie  oInterposer  oSpacer  oClassClass  oRatBundle  oShape  oFromTo  oNetInterface  oNetGroup  oVoltageDefinition  oWireProfile  oVia  oSymbolDefn  oSymbol  oLine  oFigure  oVoid  oCLine  oRegionClass  oRegionClassClass  oGroup )
			)
			( Analysis
			)
		)
		( Attribute
			( Name "DFM_EXCLUSION" )
			( Description " " )
			( Value
				( DataType ( dString ) )
				( Status  sProperty )
			)
			( Objects
				( ValidObjects  oDesign  oPartDefn  oPart  oGateDefn  oGate  oPinDefn  oPin  oXnet  oNet  oRegion  oECSet  oDRC  oNetClass  oDiffPair  oBus  oPinPair  oMatchGroup  oIODriver  oDie  oInterposer  oSpacer  oClassClass  oRatBundle  oShape  oFromTo  oNetInterface  oNetGroup  oVoltageDefinition  oWireProfile  oVia  oSymbolDefn  oSymbol  oLine  oFigure  oVoid  oCLine  oRegionClass  oRegionClassClass  oGroup )
			)
			( Analysis
			)
		)
		( Attribute
			( Name "LIPID" )
			( Description " " )
			( Value
				( DataType ( dString ) )
				( Status  sProperty )
			)
			( Objects
				( ValidObjects  oDesign  oPartDefn  oPart  oGateDefn  oGate  oPinDefn  oPin  oXnet  oNet  oRegion  oECSet  oDRC  oNetClass  oDiffPair  oBus  oPinPair  oMatchGroup  oIODriver  oDie  oInterposer  oSpacer  oClassClass  oRatBundle  oShape  oFromTo  oNetInterface  oNetGroup  oVoltageDefinition  oWireProfile  oVia  oSymbolDefn  oSymbol  oLine  oFigure  oVoid  oCLine  oRegionClass  oRegionClassClass  oGroup )
			)
			( Analysis
			)
		)
		( Attribute
			( Name "CHECKED" )
			( Description " " )
			( Value
				( DataType ( dString ) )
				( Status  sProperty )
			)
			( Objects
				( ValidObjects  oDesign  oPartDefn  oPart  oGateDefn  oGate  oPinDefn  oPin  oXnet  oNet  oRegion  oECSet  oDRC  oNetClass  oDiffPair  oBus  oPinPair  oMatchGroup  oIODriver  oDie  oInterposer  oSpacer  oClassClass  oRatBundle  oShape  oFromTo  oNetInterface  oNetGroup  oVoltageDefinition  oWireProfile  oVia  oSymbolDefn  oSymbol  oLine  oFigure  oVoid  oCLine  oRegionClass  oRegionClassClass  oGroup )
			)
			( Analysis
			)
		)
		( Attribute
			( Name "LEAD_LENGTH" )
			( Description " " )
			( Value
				( DataType ( dString ) )
				( Status  sProperty )
			)
			( Objects
				( ValidObjects  oDesign  oPartDefn  oPart  oGateDefn  oGate  oPinDefn  oPin  oXnet  oNet  oRegion  oECSet  oDRC  oNetClass  oDiffPair  oBus  oPinPair  oMatchGroup  oIODriver  oDie  oInterposer  oSpacer  oClassClass  oRatBundle  oShape  oFromTo  oNetInterface  oNetGroup  oVoltageDefinition  oWireProfile  oVia  oSymbolDefn  oSymbol  oLine  oFigure  oVoid  oCLine  oRegionClass  oRegionClassClass  oGroup )
			)
			( Analysis
			)
		)
		( Attribute
			( Name "STATUS" )
			( Description " " )
			( Value
				( DataType ( dString ) )
				( Status  sProperty )
			)
			( Objects
				( ValidObjects  oDesign  oPartDefn  oPart  oGateDefn  oGate  oPinDefn  oPin  oXnet  oNet  oRegion  oECSet  oDRC  oNetClass  oDiffPair  oBus  oPinPair  oMatchGroup  oIODriver  oDie  oInterposer  oSpacer  oClassClass  oRatBundle  oShape  oFromTo  oNetInterface  oNetGroup  oVoltageDefinition  oWireProfile  oVia  oSymbolDefn  oSymbol  oLine  oFigure  oVoid  oCLine  oRegionClass  oRegionClassClass  oGroup )
			)
			( Analysis
			)
		)
		( Attribute
			( Name "RPL" )
			( Description " " )
			( Value
				( DataType ( dString ) )
				( Status  sProperty )
			)
			( Objects
				( ValidObjects  oDesign  oPartDefn  oPart  oGateDefn  oGate  oPinDefn  oPin  oXnet  oNet  oRegion  oECSet  oDRC  oNetClass  oDiffPair  oBus  oPinPair  oMatchGroup  oIODriver  oDie  oInterposer  oSpacer  oClassClass  oRatBundle  oShape  oFromTo  oNetInterface  oNetGroup  oVoltageDefinition  oWireProfile  oVia  oSymbolDefn  oSymbol  oLine  oFigure  oVoid  oCLine  oRegionClass  oRegionClassClass  oGroup )
			)
			( Analysis
			)
		)
		( Attribute
			( Name "LPID" )
			( Description " " )
			( Value
				( DataType ( dString ) )
				( Status  sProperty )
			)
			( Objects
				( ValidObjects  oDesign  oPartDefn  oPart  oGateDefn  oGate  oPinDefn  oPin  oXnet  oNet  oRegion  oECSet  oDRC  oNetClass  oDiffPair  oBus  oPinPair  oMatchGroup  oIODriver  oDie  oInterposer  oSpacer  oClassClass  oRatBundle  oShape  oFromTo  oNetInterface  oNetGroup  oVoltageDefinition  oWireProfile  oVia  oSymbolDefn  oSymbol  oLine  oFigure  oVoid  oCLine  oRegionClass  oRegionClassClass  oGroup )
			)
			( Analysis
			)
		)
		( Attribute
			( Name "ENVCOMP" )
			( Description " " )
			( Value
				( DataType ( dString ) )
				( Status  sProperty )
			)
			( Objects
				( ValidObjects  oDesign  oPartDefn  oPart  oGateDefn  oGate  oPinDefn  oPin  oXnet  oNet  oRegion  oECSet  oDRC  oNetClass  oDiffPair  oBus  oPinPair  oMatchGroup  oIODriver  oDie  oInterposer  oSpacer  oClassClass  oRatBundle  oShape  oFromTo  oNetInterface  oNetGroup  oVoltageDefinition  oWireProfile  oVia  oSymbolDefn  oSymbol  oLine  oFigure  oVoid  oCLine  oRegionClass  oRegionClassClass  oGroup )
			)
			( Analysis
			)
		)
		( Attribute
			( Name "DESCRIPTION" )
			( Description " " )
			( Value
				( DataType ( dString ) )
				( Status  sProperty )
			)
			( Objects
				( ValidObjects  oDesign  oPartDefn  oPart  oGateDefn  oGate  oPinDefn  oPin  oXnet  oNet  oRegion  oECSet  oDRC  oNetClass  oDiffPair  oBus  oPinPair  oMatchGroup  oIODriver  oDie  oInterposer  oSpacer  oClassClass  oRatBundle  oShape  oFromTo  oNetInterface  oNetGroup  oVoltageDefinition  oWireProfile  oVia  oSymbolDefn  oSymbol  oLine  oFigure  oVoid  oCLine  oRegionClass  oRegionClassClass  oGroup )
			)
			( Analysis
			)
		)
		( Attribute
			( Name "DAYS" )
			( Description " " )
			( Value
				( DataType ( dString ) )
				( Status  sProperty )
			)
			( Objects
				( ValidObjects  oDesign  oPartDefn  oPart  oGateDefn  oGate  oPinDefn  oPin  oXnet  oNet  oRegion  oECSet  oDRC  oNetClass  oDiffPair  oBus  oPinPair  oMatchGroup  oIODriver  oDie  oInterposer  oSpacer  oClassClass  oRatBundle  oShape  oFromTo  oNetInterface  oNetGroup  oVoltageDefinition  oWireProfile  oVia  oSymbolDefn  oSymbol  oLine  oFigure  oVoid  oCLine  oRegionClass  oRegionClassClass  oGroup )
			)
			( Analysis
			)
		)
		( Attribute
			( Name "COMPONENT_TYPE" )
			( Description " " )
			( Value
				( DataType ( dString ) )
				( Status  sProperty )
			)
			( Objects
				( ValidObjects  oDesign  oPartDefn  oPart  oGateDefn  oGate  oPinDefn  oPin  oXnet  oNet  oRegion  oECSet  oDRC  oNetClass  oDiffPair  oBus  oPinPair  oMatchGroup  oIODriver  oDie  oInterposer  oSpacer  oClassClass  oRatBundle  oShape  oFromTo  oNetInterface  oNetGroup  oVoltageDefinition  oWireProfile  oVia  oSymbolDefn  oSymbol  oLine  oFigure  oVoid  oCLine  oRegionClass  oRegionClassClass  oGroup )
			)
			( Analysis
			)
		)
		( Attribute
			( Name "AML" )
			( Description " " )
			( Value
				( DataType ( dString ) )
				( Status  sProperty )
			)
			( Objects
				( ValidObjects  oDesign  oPartDefn  oPart  oGateDefn  oGate  oPinDefn  oPin  oXnet  oNet  oRegion  oECSet  oDRC  oNetClass  oDiffPair  oBus  oPinPair  oMatchGroup  oIODriver  oDie  oInterposer  oSpacer  oClassClass  oRatBundle  oShape  oFromTo  oNetInterface  oNetGroup  oVoltageDefinition  oWireProfile  oVia  oSymbolDefn  oSymbol  oLine  oFigure  oVoid  oCLine  oRegionClass  oRegionClassClass  oGroup )
			)
			( Analysis
			)
		)
		( Attribute
			( Name "SIG_BUS_MEMBER_CLOCK" )
			( Description " " )
			( Value
				( DataType ( dString ) )
				( Status  sProperty )
			)
			( Objects
				( ValidObjects  oXnet  oNet )
			)
			( Analysis
			)
		)
		( Attribute
			( Name "EMC_SCOPE_OF_CHECK" )
			( Description " " )
			( Value
				( DataType ( dString ) )
				( Status  sProperty )
			)
			( Objects
				( ValidObjects  oDesign )
			)
			( Analysis
			)
		)
		( Attribute
			( Name "EMC_SCOPE_OF_CHECK_FLAG" )
			( Description " " )
			( Value
				( DataType ( dString ) )
				( Status  sProperty )
			)
			( Objects
				( ValidObjects  oDesign )
			)
			( Analysis
			)
		)
		( Attribute
			( Name "FINDROOMROOM" )
			( Description " " )
			( Value
				( DataType ( dString ) )
				( Status  sProperty )
			)
			( Objects
				( ValidObjects  oDesign  oPartDefn  oPart  oGateDefn  oGate  oPinDefn  oPin  oXnet  oNet  oRegion  oECSet  oDRC  oNetClass  oDiffPair  oBus  oPinPair  oMatchGroup  oIODriver  oDie  oInterposer  oSpacer  oClassClass  oRatBundle  oShape  oFromTo  oNetInterface  oNetGroup  oVoltageDefinition  oWireProfile  oVia  oSymbolDefn  oSymbol  oLine  oFigure  oVoid  oCLine  oRegionClass  oRegionClassClass  oGroup )
			)
			( Analysis
			)
		)
		( Attribute
			( Name "BODIES" )
			( Description " " )
			( Value
				( DataType ( dString ) )
				( Status  sProperty )
			)
			( Objects
				( ValidObjects  oDesign  oPartDefn  oPart  oGateDefn  oGate  oPinDefn  oPin  oXnet  oNet  oRegion  oECSet  oDRC  oNetClass  oDiffPair  oBus  oPinPair  oMatchGroup  oIODriver  oDie  oInterposer  oSpacer  oClassClass  oRatBundle  oShape  oFromTo  oNetInterface  oNetGroup  oVoltageDefinition  oWireProfile  oVia  oSymbolDefn  oSymbol  oLine  oFigure  oVoid  oCLine  oRegionClass  oRegionClassClass  oGroup )
			)
			( Analysis
			)
		)
		( Attribute
			( Name "ATT" )
			( Description " " )
			( Value
				( DataType ( dString ) )
				( Status  sProperty )
			)
			( Objects
				( ValidObjects  oDesign  oPartDefn  oPart  oGateDefn  oGate  oPinDefn  oPin  oXnet  oNet  oRegion  oECSet  oDRC  oNetClass  oDiffPair  oBus  oPinPair  oMatchGroup  oIODriver  oDie  oInterposer  oSpacer  oClassClass  oRatBundle  oShape  oFromTo  oNetInterface  oNetGroup  oVoltageDefinition  oWireProfile  oVia  oSymbolDefn  oSymbol  oLine  oFigure  oVoid  oCLine  oRegionClass  oRegionClassClass  oGroup )
			)
			( Analysis
			)
		)
		( Attribute
			( Name "SIG_R2_NAME" )
			( Description " " )
			( Value
				( DataType ( dString ) )
				( Status  sProperty )
			)
			( Objects
				( ValidObjects  oDesign  oPartDefn  oPart  oGateDefn  oGate  oPinDefn  oPin  oXnet  oNet  oRegion  oECSet  oDRC  oNetClass  oDiffPair  oBus  oPinPair  oMatchGroup  oIODriver  oDie  oInterposer  oSpacer  oClassClass  oRatBundle  oShape  oFromTo  oNetInterface  oNetGroup  oVoltageDefinition  oWireProfile  oVia  oSymbolDefn  oSymbol  oLine  oFigure  oVoid  oCLine  oRegionClass  oRegionClassClass  oGroup )
			)
			( Analysis
			)
		)
		( Attribute
			( Name "SIG_R1_NAME" )
			( Description " " )
			( Value
				( DataType ( dString ) )
				( Status  sProperty )
			)
			( Objects
				( ValidObjects  oDesign  oPartDefn  oPart  oGateDefn  oGate  oPinDefn  oPin  oXnet  oNet  oRegion  oECSet  oDRC  oNetClass  oDiffPair  oBus  oPinPair  oMatchGroup  oIODriver  oDie  oInterposer  oSpacer  oClassClass  oRatBundle  oShape  oFromTo  oNetInterface  oNetGroup  oVoltageDefinition  oWireProfile  oVia  oSymbolDefn  oSymbol  oLine  oFigure  oVoid  oCLine  oRegionClass  oRegionClassClass  oGroup )
			)
			( Analysis
			)
		)
	)
	( crossSection
		( layer "SURFACE_INDEX_0"
			( attribute "CDS_LAYER_TYPE" "SURFACE"
				( Origin gBackEnd )
			)
			( attribute "CDS_LAYER_MATERIAL" "AIR"
				( Origin gBackEnd )
			)
			( attribute "CDS_LAYER_THICKNESS" "0.0000"
				( Units "uLayerThickness" "mil" 1.000000)
				( Origin gBackEnd )
			)
			( attribute "CDS_LAYER_ELECTRICAL_CONDUCTIVITY" "0.0000"
				( Units "uElectricalConductivity" "mho/cm" 1.000000)
				( Origin gBackEnd )
			)
			( attribute "CDS_LAYER_THERMAL_CONDUCTIVITY" "0.0000"
				( Units "uThermalConductivity" "W/cm-degC" 1.000000)
				( Origin gBackEnd )
			)
			( attribute "CDS_LAYER_DIELECTRIC_CONSTANT" "1.000"
				( Origin gBackEnd )
			)
			( attribute "CDS_LAYER_LOSS_TANGENT" "0.0000"
				( Origin gBackEnd )
			)
			( attribute "CDS_LAYER_NEGATIVE_ARTWORK" "FALSE"
				( Origin gBackEnd )
			)
			( attribute "CDS_LAYER_IS_SHIELD" "FALSE"
				( Origin gBackEnd )
			)
		)
		( layer "DIELECTRIC_INDEX_1"
			( attribute "CDS_LAYER_TYPE" "DIELECTRIC"
				( Origin gBackEnd )
			)
			( attribute "CDS_LAYER_MATERIAL" "CONFORMAL_COAT"
				( Origin gBackEnd )
			)
			( attribute "CDS_LAYER_THICKNESS" "0.5"
				( Units "uLayerThickness" "mil" 1.000000)
				( Origin gBackEnd )
			)
			( attribute "CDS_LAYER_ELECTRICAL_CONDUCTIVITY" "0.0000"
				( Units "uElectricalConductivity" "mho/cm" 1.000000)
				( Origin gBackEnd )
			)
			( attribute "CDS_LAYER_THERMAL_CONDUCTIVITY" "0.01200"
				( Units "uThermalConductivity" "W/cm-degC" 1.000000)
				( Origin gBackEnd )
			)
			( attribute "CDS_LAYER_DIELECTRIC_CONSTANT" "3.800"
				( Origin gBackEnd )
			)
			( attribute "CDS_LAYER_LOSS_TANGENT" "0.03500"
				( Origin gBackEnd )
			)
			( attribute "CDS_LAYER_NEGATIVE_ARTWORK" "FALSE"
				( Origin gBackEnd )
			)
			( attribute "CDS_LAYER_IS_SHIELD" "FALSE"
				( Origin gBackEnd )
			)
		)
		( layer "TOP"
			( attribute "CDS_LAYER_TYPE" "CONDUCTOR"
				( Origin gBackEnd )
			)
			( attribute "CDS_LAYER_MATERIAL" "COPPER"
				( Origin gBackEnd )
			)
			( attribute "CDS_LAYER_THICKNESS" "2.1"
				( Units "uLayerThickness" "mil" 1.000000)
				( Origin gBackEnd )
			)
			( attribute "CDS_LAYER_ELECTRICAL_CONDUCTIVITY" "595900"
				( Units "uElectricalConductivity" "mho/cm" 1.000000)
				( Origin gBackEnd )
			)
			( attribute "CDS_LAYER_THERMAL_CONDUCTIVITY" "0.0000"
				( Units "uThermalConductivity" "W/cm-degC" 1.000000)
				( Origin gBackEnd )
			)
			( attribute "CDS_LAYER_DIELECTRIC_CONSTANT" "4.500"
				( Origin gBackEnd )
			)
			( attribute "CDS_LAYER_LOSS_TANGENT" "0.0000"
				( Origin gBackEnd )
			)
			( attribute "CDS_LAYER_NEGATIVE_ARTWORK" "FALSE"
				( Origin gBackEnd )
			)
			( attribute "CDS_LAYER_IS_SHIELD" "FALSE"
				( Origin gBackEnd )
			)
			( attribute "CDS_LAYER_IS_NAMED" "1"
				( Origin gBackEnd )
			)
			( attribute "CDS_LAYER_IS_TOP_SUBSTRATE" "1"
				( Origin gBackEnd )
			)
			( attribute "CDS_LAYER_ETCH_FACTOR" "70.00"
				( Origin gBackEnd )
			)
			( attribute "CDS_LAYER_EMBEDDED_STATUS" "NOT_EMBEDDED"
				( Origin gBackEnd )
			)
		)
		( layer "DIELECTRIC_BELOW_TOP"
			( attribute "CDS_LAYER_TYPE" "DIELECTRIC"
				( Origin gBackEnd )
			)
			( attribute "CDS_LAYER_MATERIAL" "FR-4"
				( Origin gBackEnd )
			)
			( attribute "CDS_LAYER_THICKNESS" "2.67"
				( Units "uLayerThickness" "mil" 1.000000)
				( Origin gBackEnd )
			)
			( attribute "CDS_LAYER_ELECTRICAL_CONDUCTIVITY" "0.0000"
				( Units "uElectricalConductivity" "mho/cm" 1.000000)
				( Origin gBackEnd )
			)
			( attribute "CDS_LAYER_THERMAL_CONDUCTIVITY" "0.01200"
				( Units "uThermalConductivity" "W/cm-degC" 1.000000)
				( Origin gBackEnd )
			)
			( attribute "CDS_LAYER_DIELECTRIC_CONSTANT" "4.000"
				( Origin gBackEnd )
			)
			( attribute "CDS_LAYER_LOSS_TANGENT" "0.03500"
				( Origin gBackEnd )
			)
			( attribute "CDS_LAYER_NEGATIVE_ARTWORK" "FALSE"
				( Origin gBackEnd )
			)
			( attribute "CDS_LAYER_IS_SHIELD" "FALSE"
				( Origin gBackEnd )
			)
		)
		( layer "L2_GND1"
			( attribute "CDS_LAYER_TYPE" "PLANE"
				( Origin gBackEnd )
			)
			( attribute "CDS_LAYER_MATERIAL" "COPPER"
				( Origin gBackEnd )
			)
			( attribute "CDS_LAYER_THICKNESS" "1.25"
				( Units "uLayerThickness" "mil" 1.000000)
				( Origin gBackEnd )
			)
			( attribute "CDS_LAYER_ELECTRICAL_CONDUCTIVITY" "595900"
				( Units "uElectricalConductivity" "mho/cm" 1.000000)
				( Origin gBackEnd )
			)
			( attribute "CDS_LAYER_THERMAL_CONDUCTIVITY" "0.01200"
				( Units "uThermalConductivity" "W/cm-degC" 1.000000)
				( Origin gBackEnd )
			)
			( attribute "CDS_LAYER_DIELECTRIC_CONSTANT" "4.500"
				( Origin gBackEnd )
			)
			( attribute "CDS_LAYER_LOSS_TANGENT" "0.03500"
				( Origin gBackEnd )
			)
			( attribute "CDS_LAYER_NEGATIVE_ARTWORK" "FALSE"
				( Origin gBackEnd )
			)
			( attribute "CDS_LAYER_IS_SHIELD" "TRUE"
				( Origin gBackEnd )
			)
			( attribute "CDS_LAYER_IS_NAMED" "1"
				( Origin gBackEnd )
			)
			( attribute "CDS_LAYER_ETCH_FACTOR" "90.00"
				( Origin gBackEnd )
			)
			( attribute "CDS_LAYER_EMBEDDED_STATUS" "NOT_EMBEDDED"
				( Origin gBackEnd )
			)
		)
		( layer "DIELECTRIC_BELOW_L2_GND1"
			( attribute "CDS_LAYER_TYPE" "DIELECTRIC"
				( Origin gBackEnd )
			)
			( attribute "CDS_LAYER_MATERIAL" "FR-4"
				( Origin gBackEnd )
			)
			( attribute "CDS_LAYER_THICKNESS" "9"
				( Units "uLayerThickness" "mil" 1.000000)
				( Origin gBackEnd )
			)
			( attribute "CDS_LAYER_ELECTRICAL_CONDUCTIVITY" "0.0000"
				( Units "uElectricalConductivity" "mho/cm" 1.000000)
				( Origin gBackEnd )
			)
			( attribute "CDS_LAYER_THERMAL_CONDUCTIVITY" "0.01200"
				( Units "uThermalConductivity" "W/cm-degC" 1.000000)
				( Origin gBackEnd )
			)
			( attribute "CDS_LAYER_DIELECTRIC_CONSTANT" "4.100"
				( Origin gBackEnd )
			)
			( attribute "CDS_LAYER_LOSS_TANGENT" "0.03500"
				( Origin gBackEnd )
			)
			( attribute "CDS_LAYER_NEGATIVE_ARTWORK" "FALSE"
				( Origin gBackEnd )
			)
			( attribute "CDS_LAYER_IS_SHIELD" "FALSE"
				( Origin gBackEnd )
			)
		)
		( layer "L3_SIG1"
			( attribute "CDS_LAYER_TYPE" "CONDUCTOR"
				( Origin gBackEnd )
			)
			( attribute "CDS_LAYER_MATERIAL" "COPPER"
				( Origin gBackEnd )
			)
			( attribute "CDS_LAYER_THICKNESS" "1.25"
				( Units "uLayerThickness" "mil" 1.000000)
				( Origin gBackEnd )
			)
			( attribute "CDS_LAYER_ELECTRICAL_CONDUCTIVITY" "595900"
				( Units "uElectricalConductivity" "mho/cm" 1.000000)
				( Origin gBackEnd )
			)
			( attribute "CDS_LAYER_THERMAL_CONDUCTIVITY" "0.01200"
				( Units "uThermalConductivity" "W/cm-degC" 1.000000)
				( Origin gBackEnd )
			)
			( attribute "CDS_LAYER_DIELECTRIC_CONSTANT" "4.500"
				( Origin gBackEnd )
			)
			( attribute "CDS_LAYER_LOSS_TANGENT" "0.03500"
				( Origin gBackEnd )
			)
			( attribute "CDS_LAYER_NEGATIVE_ARTWORK" "FALSE"
				( Origin gBackEnd )
			)
			( attribute "CDS_LAYER_IS_SHIELD" "FALSE"
				( Origin gBackEnd )
			)
			( attribute "CDS_LAYER_IS_NAMED" "1"
				( Origin gBackEnd )
			)
			( attribute "CDS_LAYER_ETCH_FACTOR" "90.00"
				( Origin gBackEnd )
			)
			( attribute "CDS_LAYER_EMBEDDED_STATUS" "NOT_EMBEDDED"
				( Origin gBackEnd )
			)
		)
		( layer "DIELECTRIC_BELOW_L3_SIG1"
			( attribute "CDS_LAYER_TYPE" "DIELECTRIC"
				( Origin gBackEnd )
			)
			( attribute "CDS_LAYER_MATERIAL" "FR-4"
				( Origin gBackEnd )
			)
			( attribute "CDS_LAYER_THICKNESS" "3"
				( Units "uLayerThickness" "mil" 1.000000)
				( Origin gBackEnd )
			)
			( attribute "CDS_LAYER_ELECTRICAL_CONDUCTIVITY" "0.0000"
				( Units "uElectricalConductivity" "mho/cm" 1.000000)
				( Origin gBackEnd )
			)
			( attribute "CDS_LAYER_THERMAL_CONDUCTIVITY" "0.0000"
				( Units "uThermalConductivity" "W/cm-degC" 1.000000)
				( Origin gBackEnd )
			)
			( attribute "CDS_LAYER_DIELECTRIC_CONSTANT" "4.500"
				( Origin gBackEnd )
			)
			( attribute "CDS_LAYER_LOSS_TANGENT" "0.03500"
				( Origin gBackEnd )
			)
			( attribute "CDS_LAYER_NEGATIVE_ARTWORK" "FALSE"
				( Origin gBackEnd )
			)
			( attribute "CDS_LAYER_IS_SHIELD" "FALSE"
				( Origin gBackEnd )
			)
		)
		( layer "L4_GND2"
			( attribute "CDS_LAYER_TYPE" "PLANE"
				( Origin gBackEnd )
			)
			( attribute "CDS_LAYER_MATERIAL" "COPPER"
				( Origin gBackEnd )
			)
			( attribute "CDS_LAYER_THICKNESS" "1.25"
				( Units "uLayerThickness" "mil" 1.000000)
				( Origin gBackEnd )
			)
			( attribute "CDS_LAYER_ELECTRICAL_CONDUCTIVITY" "595900"
				( Units "uElectricalConductivity" "mho/cm" 1.000000)
				( Origin gBackEnd )
			)
			( attribute "CDS_LAYER_THERMAL_CONDUCTIVITY" "0.0000"
				( Units "uThermalConductivity" "W/cm-degC" 1.000000)
				( Origin gBackEnd )
			)
			( attribute "CDS_LAYER_DIELECTRIC_CONSTANT" "4.500"
				( Origin gBackEnd )
			)
			( attribute "CDS_LAYER_LOSS_TANGENT" "0.03500"
				( Origin gBackEnd )
			)
			( attribute "CDS_LAYER_NEGATIVE_ARTWORK" "FALSE"
				( Origin gBackEnd )
			)
			( attribute "CDS_LAYER_IS_SHIELD" "TRUE"
				( Origin gBackEnd )
			)
			( attribute "CDS_LAYER_IS_NAMED" "1"
				( Origin gBackEnd )
			)
			( attribute "CDS_LAYER_ETCH_FACTOR" "90.00"
				( Origin gBackEnd )
			)
			( attribute "CDS_LAYER_EMBEDDED_STATUS" "NOT_EMBEDDED"
				( Origin gBackEnd )
			)
		)
		( layer "DIELECTRIC_BELOW_L4_GND2"
			( attribute "CDS_LAYER_TYPE" "DIELECTRIC"
				( Origin gBackEnd )
			)
			( attribute "CDS_LAYER_MATERIAL" "FR-4"
				( Origin gBackEnd )
			)
			( attribute "CDS_LAYER_THICKNESS" "9"
				( Units "uLayerThickness" "mil" 1.000000)
				( Origin gBackEnd )
			)
			( attribute "CDS_LAYER_ELECTRICAL_CONDUCTIVITY" "0.0000"
				( Units "uElectricalConductivity" "mho/cm" 1.000000)
				( Origin gBackEnd )
			)
			( attribute "CDS_LAYER_THERMAL_CONDUCTIVITY" "0.01200"
				( Units "uThermalConductivity" "W/cm-degC" 1.000000)
				( Origin gBackEnd )
			)
			( attribute "CDS_LAYER_DIELECTRIC_CONSTANT" "4.000"
				( Origin gBackEnd )
			)
			( attribute "CDS_LAYER_LOSS_TANGENT" "0.03500"
				( Origin gBackEnd )
			)
			( attribute "CDS_LAYER_NEGATIVE_ARTWORK" "FALSE"
				( Origin gBackEnd )
			)
			( attribute "CDS_LAYER_IS_SHIELD" "FALSE"
				( Origin gBackEnd )
			)
		)
		( layer "L5_SIG2"
			( attribute "CDS_LAYER_TYPE" "CONDUCTOR"
				( Origin gBackEnd )
			)
			( attribute "CDS_LAYER_MATERIAL" "COPPER"
				( Origin gBackEnd )
			)
			( attribute "CDS_LAYER_THICKNESS" "1.25"
				( Units "uLayerThickness" "mil" 1.000000)
				( Origin gBackEnd )
			)
			( attribute "CDS_LAYER_ELECTRICAL_CONDUCTIVITY" "595900"
				( Units "uElectricalConductivity" "mho/cm" 1.000000)
				( Origin gBackEnd )
			)
			( attribute "CDS_LAYER_THERMAL_CONDUCTIVITY" "0.01200"
				( Units "uThermalConductivity" "W/cm-degC" 1.000000)
				( Origin gBackEnd )
			)
			( attribute "CDS_LAYER_DIELECTRIC_CONSTANT" "4.500"
				( Origin gBackEnd )
			)
			( attribute "CDS_LAYER_LOSS_TANGENT" "0.03500"
				( Origin gBackEnd )
			)
			( attribute "CDS_LAYER_NEGATIVE_ARTWORK" "FALSE"
				( Origin gBackEnd )
			)
			( attribute "CDS_LAYER_IS_SHIELD" "FALSE"
				( Origin gBackEnd )
			)
			( attribute "CDS_LAYER_IS_NAMED" "1"
				( Origin gBackEnd )
			)
			( attribute "CDS_LAYER_ETCH_FACTOR" "90.00"
				( Origin gBackEnd )
			)
			( attribute "CDS_LAYER_EMBEDDED_STATUS" "NOT_EMBEDDED"
				( Origin gBackEnd )
			)
		)
		( layer "DIELECTRIC_BELOW_L5_SIG2"
			( attribute "CDS_LAYER_TYPE" "DIELECTRIC"
				( Origin gBackEnd )
			)
			( attribute "CDS_LAYER_MATERIAL" "FR-4"
				( Origin gBackEnd )
			)
			( attribute "CDS_LAYER_THICKNESS" "3"
				( Units "uLayerThickness" "mil" 1.000000)
				( Origin gBackEnd )
			)
			( attribute "CDS_LAYER_ELECTRICAL_CONDUCTIVITY" "0.0000"
				( Units "uElectricalConductivity" "mho/cm" 1.000000)
				( Origin gBackEnd )
			)
			( attribute "CDS_LAYER_THERMAL_CONDUCTIVITY" "0.0000"
				( Units "uThermalConductivity" "W/cm-degC" 1.000000)
				( Origin gBackEnd )
			)
			( attribute "CDS_LAYER_DIELECTRIC_CONSTANT" "4.500"
				( Origin gBackEnd )
			)
			( attribute "CDS_LAYER_LOSS_TANGENT" "0.03500"
				( Origin gBackEnd )
			)
			( attribute "CDS_LAYER_NEGATIVE_ARTWORK" "FALSE"
				( Origin gBackEnd )
			)
			( attribute "CDS_LAYER_IS_SHIELD" "FALSE"
				( Origin gBackEnd )
			)
		)
		( layer "L6_GND3"
			( attribute "CDS_LAYER_TYPE" "PLANE"
				( Origin gBackEnd )
			)
			( attribute "CDS_LAYER_MATERIAL" "COPPER"
				( Origin gBackEnd )
			)
			( attribute "CDS_LAYER_THICKNESS" "1.25"
				( Units "uLayerThickness" "mil" 1.000000)
				( Origin gBackEnd )
			)
			( attribute "CDS_LAYER_ELECTRICAL_CONDUCTIVITY" "595900"
				( Units "uElectricalConductivity" "mho/cm" 1.000000)
				( Origin gBackEnd )
			)
			( attribute "CDS_LAYER_THERMAL_CONDUCTIVITY" "0.0000"
				( Units "uThermalConductivity" "W/cm-degC" 1.000000)
				( Origin gBackEnd )
			)
			( attribute "CDS_LAYER_DIELECTRIC_CONSTANT" "4.500"
				( Origin gBackEnd )
			)
			( attribute "CDS_LAYER_LOSS_TANGENT" "0.03500"
				( Origin gBackEnd )
			)
			( attribute "CDS_LAYER_NEGATIVE_ARTWORK" "FALSE"
				( Origin gBackEnd )
			)
			( attribute "CDS_LAYER_IS_SHIELD" "TRUE"
				( Origin gBackEnd )
			)
			( attribute "CDS_LAYER_IS_NAMED" "1"
				( Origin gBackEnd )
			)
			( attribute "CDS_LAYER_ETCH_FACTOR" "90.00"
				( Origin gBackEnd )
			)
			( attribute "CDS_LAYER_EMBEDDED_STATUS" "NOT_EMBEDDED"
				( Origin gBackEnd )
			)
		)
		( layer "DIELECTRIC_BELOW_L6_GND3"
			( attribute "CDS_LAYER_TYPE" "DIELECTRIC"
				( Origin gBackEnd )
			)
			( attribute "CDS_LAYER_MATERIAL" "FR-4"
				( Origin gBackEnd )
			)
			( attribute "CDS_LAYER_THICKNESS" "4.5"
				( Units "uLayerThickness" "mil" 1.000000)
				( Origin gBackEnd )
			)
			( attribute "CDS_LAYER_ELECTRICAL_CONDUCTIVITY" "0.0000"
				( Units "uElectricalConductivity" "mho/cm" 1.000000)
				( Origin gBackEnd )
			)
			( attribute "CDS_LAYER_THERMAL_CONDUCTIVITY" "0.01200"
				( Units "uThermalConductivity" "W/cm-degC" 1.000000)
				( Origin gBackEnd )
			)
			( attribute "CDS_LAYER_DIELECTRIC_CONSTANT" "4.100"
				( Origin gBackEnd )
			)
			( attribute "CDS_LAYER_LOSS_TANGENT" "0.03500"
				( Origin gBackEnd )
			)
			( attribute "CDS_LAYER_NEGATIVE_ARTWORK" "FALSE"
				( Origin gBackEnd )
			)
			( attribute "CDS_LAYER_IS_SHIELD" "FALSE"
				( Origin gBackEnd )
			)
		)
		( layer "L7_PWR1-SIG"
			( attribute "CDS_LAYER_TYPE" "PLANE"
				( Origin gBackEnd )
			)
			( attribute "CDS_LAYER_MATERIAL" "COPPER"
				( Origin gBackEnd )
			)
			( attribute "CDS_LAYER_THICKNESS" "2.4"
				( Units "uLayerThickness" "mil" 1.000000)
				( Origin gBackEnd )
			)
			( attribute "CDS_LAYER_ELECTRICAL_CONDUCTIVITY" "595900"
				( Units "uElectricalConductivity" "mho/cm" 1.000000)
				( Origin gBackEnd )
			)
			( attribute "CDS_LAYER_THERMAL_CONDUCTIVITY" "0.01200"
				( Units "uThermalConductivity" "W/cm-degC" 1.000000)
				( Origin gBackEnd )
			)
			( attribute "CDS_LAYER_DIELECTRIC_CONSTANT" "4.500"
				( Origin gBackEnd )
			)
			( attribute "CDS_LAYER_LOSS_TANGENT" "0.03500"
				( Origin gBackEnd )
			)
			( attribute "CDS_LAYER_NEGATIVE_ARTWORK" "FALSE"
				( Origin gBackEnd )
			)
			( attribute "CDS_LAYER_IS_SHIELD" "TRUE"
				( Origin gBackEnd )
			)
			( attribute "CDS_LAYER_IS_NAMED" "1"
				( Origin gBackEnd )
			)
			( attribute "CDS_LAYER_ETCH_FACTOR" "90.00"
				( Origin gBackEnd )
			)
			( attribute "CDS_LAYER_EMBEDDED_STATUS" "NOT_EMBEDDED"
				( Origin gBackEnd )
			)
		)
		( layer "DIELECTRIC_BELOW_L7_PWR1-SIG"
			( attribute "CDS_LAYER_TYPE" "DIELECTRIC"
				( Origin gBackEnd )
			)
			( attribute "CDS_LAYER_MATERIAL" "FR-4"
				( Origin gBackEnd )
			)
			( attribute "CDS_LAYER_THICKNESS" "4.6"
				( Units "uLayerThickness" "mil" 1.000000)
				( Origin gBackEnd )
			)
			( attribute "CDS_LAYER_ELECTRICAL_CONDUCTIVITY" "0.0000"
				( Units "uElectricalConductivity" "mho/cm" 1.000000)
				( Origin gBackEnd )
			)
			( attribute "CDS_LAYER_THERMAL_CONDUCTIVITY" "0.01200"
				( Units "uThermalConductivity" "W/cm-degC" 1.000000)
				( Origin gBackEnd )
			)
			( attribute "CDS_LAYER_DIELECTRIC_CONSTANT" "4.000"
				( Origin gBackEnd )
			)
			( attribute "CDS_LAYER_LOSS_TANGENT" "0.03500"
				( Origin gBackEnd )
			)
			( attribute "CDS_LAYER_NEGATIVE_ARTWORK" "FALSE"
				( Origin gBackEnd )
			)
			( attribute "CDS_LAYER_IS_SHIELD" "FALSE"
				( Origin gBackEnd )
			)
		)
		( layer "L8_PWR2-SIG"
			( attribute "CDS_LAYER_TYPE" "PLANE"
				( Origin gBackEnd )
			)
			( attribute "CDS_LAYER_MATERIAL" "COPPER"
				( Origin gBackEnd )
			)
			( attribute "CDS_LAYER_THICKNESS" "2.4"
				( Units "uLayerThickness" "mil" 1.000000)
				( Origin gBackEnd )
			)
			( attribute "CDS_LAYER_ELECTRICAL_CONDUCTIVITY" "595900"
				( Units "uElectricalConductivity" "mho/cm" 1.000000)
				( Origin gBackEnd )
			)
			( attribute "CDS_LAYER_THERMAL_CONDUCTIVITY" "0.01200"
				( Units "uThermalConductivity" "W/cm-degC" 1.000000)
				( Origin gBackEnd )
			)
			( attribute "CDS_LAYER_DIELECTRIC_CONSTANT" "4.500"
				( Origin gBackEnd )
			)
			( attribute "CDS_LAYER_LOSS_TANGENT" "0.03500"
				( Origin gBackEnd )
			)
			( attribute "CDS_LAYER_NEGATIVE_ARTWORK" "FALSE"
				( Origin gBackEnd )
			)
			( attribute "CDS_LAYER_IS_SHIELD" "TRUE"
				( Origin gBackEnd )
			)
			( attribute "CDS_LAYER_IS_NAMED" "1"
				( Origin gBackEnd )
			)
			( attribute "CDS_LAYER_ETCH_FACTOR" "90.00"
				( Origin gBackEnd )
			)
			( attribute "CDS_LAYER_EMBEDDED_STATUS" "NOT_EMBEDDED"
				( Origin gBackEnd )
			)
		)
		( layer "DIELECTRIC_BELOW_L8_PWR2-SIG"
			( attribute "CDS_LAYER_TYPE" "DIELECTRIC"
				( Origin gBackEnd )
			)
			( attribute "CDS_LAYER_MATERIAL" "FR-4"
				( Origin gBackEnd )
			)
			( attribute "CDS_LAYER_THICKNESS" "4.5"
				( Units "uLayerThickness" "mil" 1.000000)
				( Origin gBackEnd )
			)
			( attribute "CDS_LAYER_ELECTRICAL_CONDUCTIVITY" "0.0000"
				( Units "uElectricalConductivity" "mho/cm" 1.000000)
				( Origin gBackEnd )
			)
			( attribute "CDS_LAYER_THERMAL_CONDUCTIVITY" "0.0000"
				( Units "uThermalConductivity" "W/cm-degC" 1.000000)
				( Origin gBackEnd )
			)
			( attribute "CDS_LAYER_DIELECTRIC_CONSTANT" "4.500"
				( Origin gBackEnd )
			)
			( attribute "CDS_LAYER_LOSS_TANGENT" "0.03500"
				( Origin gBackEnd )
			)
			( attribute "CDS_LAYER_NEGATIVE_ARTWORK" "FALSE"
				( Origin gBackEnd )
			)
			( attribute "CDS_LAYER_IS_SHIELD" "FALSE"
				( Origin gBackEnd )
			)
		)
		( layer "L9_GND4"
			( attribute "CDS_LAYER_TYPE" "PLANE"
				( Origin gBackEnd )
			)
			( attribute "CDS_LAYER_MATERIAL" "COPPER"
				( Origin gBackEnd )
			)
			( attribute "CDS_LAYER_THICKNESS" "1.25"
				( Units "uLayerThickness" "mil" 1.000000)
				( Origin gBackEnd )
			)
			( attribute "CDS_LAYER_ELECTRICAL_CONDUCTIVITY" "595900"
				( Units "uElectricalConductivity" "mho/cm" 1.000000)
				( Origin gBackEnd )
			)
			( attribute "CDS_LAYER_THERMAL_CONDUCTIVITY" "0.0000"
				( Units "uThermalConductivity" "W/cm-degC" 1.000000)
				( Origin gBackEnd )
			)
			( attribute "CDS_LAYER_DIELECTRIC_CONSTANT" "4.500"
				( Origin gBackEnd )
			)
			( attribute "CDS_LAYER_LOSS_TANGENT" "0.03500"
				( Origin gBackEnd )
			)
			( attribute "CDS_LAYER_NEGATIVE_ARTWORK" "FALSE"
				( Origin gBackEnd )
			)
			( attribute "CDS_LAYER_IS_SHIELD" "TRUE"
				( Origin gBackEnd )
			)
			( attribute "CDS_LAYER_IS_NAMED" "1"
				( Origin gBackEnd )
			)
			( attribute "CDS_LAYER_ETCH_FACTOR" "90.00"
				( Origin gBackEnd )
			)
			( attribute "CDS_LAYER_EMBEDDED_STATUS" "NOT_EMBEDDED"
				( Origin gBackEnd )
			)
		)
		( layer "DIELECTRIC_BELOW_L9_GND4"
			( attribute "CDS_LAYER_TYPE" "DIELECTRIC"
				( Origin gBackEnd )
			)
			( attribute "CDS_LAYER_MATERIAL" "FR-4"
				( Origin gBackEnd )
			)
			( attribute "CDS_LAYER_THICKNESS" "3"
				( Units "uLayerThickness" "mil" 1.000000)
				( Origin gBackEnd )
			)
			( attribute "CDS_LAYER_ELECTRICAL_CONDUCTIVITY" "0.0000"
				( Units "uElectricalConductivity" "mho/cm" 1.000000)
				( Origin gBackEnd )
			)
			( attribute "CDS_LAYER_THERMAL_CONDUCTIVITY" "0.01200"
				( Units "uThermalConductivity" "W/cm-degC" 1.000000)
				( Origin gBackEnd )
			)
			( attribute "CDS_LAYER_DIELECTRIC_CONSTANT" "4.100"
				( Origin gBackEnd )
			)
			( attribute "CDS_LAYER_LOSS_TANGENT" "0.03500"
				( Origin gBackEnd )
			)
			( attribute "CDS_LAYER_NEGATIVE_ARTWORK" "FALSE"
				( Origin gBackEnd )
			)
			( attribute "CDS_LAYER_IS_SHIELD" "FALSE"
				( Origin gBackEnd )
			)
		)
		( layer "L10_SIG3"
			( attribute "CDS_LAYER_TYPE" "CONDUCTOR"
				( Origin gBackEnd )
			)
			( attribute "CDS_LAYER_MATERIAL" "COPPER"
				( Origin gBackEnd )
			)
			( attribute "CDS_LAYER_THICKNESS" "1.25"
				( Units "uLayerThickness" "mil" 1.000000)
				( Origin gBackEnd )
			)
			( attribute "CDS_LAYER_ELECTRICAL_CONDUCTIVITY" "595900"
				( Units "uElectricalConductivity" "mho/cm" 1.000000)
				( Origin gBackEnd )
			)
			( attribute "CDS_LAYER_THERMAL_CONDUCTIVITY" "0.01200"
				( Units "uThermalConductivity" "W/cm-degC" 1.000000)
				( Origin gBackEnd )
			)
			( attribute "CDS_LAYER_DIELECTRIC_CONSTANT" "4.500"
				( Origin gBackEnd )
			)
			( attribute "CDS_LAYER_LOSS_TANGENT" "0.03500"
				( Origin gBackEnd )
			)
			( attribute "CDS_LAYER_NEGATIVE_ARTWORK" "FALSE"
				( Origin gBackEnd )
			)
			( attribute "CDS_LAYER_IS_SHIELD" "FALSE"
				( Origin gBackEnd )
			)
			( attribute "CDS_LAYER_IS_NAMED" "1"
				( Origin gBackEnd )
			)
			( attribute "CDS_LAYER_ETCH_FACTOR" "90.00"
				( Origin gBackEnd )
			)
			( attribute "CDS_LAYER_EMBEDDED_STATUS" "NOT_EMBEDDED"
				( Origin gBackEnd )
			)
		)
		( layer "DIELECTRIC_BELOW_L10_SIG3"
			( attribute "CDS_LAYER_TYPE" "DIELECTRIC"
				( Origin gBackEnd )
			)
			( attribute "CDS_LAYER_MATERIAL" "FR-4"
				( Origin gBackEnd )
			)
			( attribute "CDS_LAYER_THICKNESS" "9"
				( Units "uLayerThickness" "mil" 1.000000)
				( Origin gBackEnd )
			)
			( attribute "CDS_LAYER_ELECTRICAL_CONDUCTIVITY" "0.0000"
				( Units "uElectricalConductivity" "mho/cm" 1.000000)
				( Origin gBackEnd )
			)
			( attribute "CDS_LAYER_THERMAL_CONDUCTIVITY" "0.0000"
				( Units "uThermalConductivity" "W/cm-degC" 1.000000)
				( Origin gBackEnd )
			)
			( attribute "CDS_LAYER_DIELECTRIC_CONSTANT" "4.500"
				( Origin gBackEnd )
			)
			( attribute "CDS_LAYER_LOSS_TANGENT" "0.03500"
				( Origin gBackEnd )
			)
			( attribute "CDS_LAYER_NEGATIVE_ARTWORK" "FALSE"
				( Origin gBackEnd )
			)
			( attribute "CDS_LAYER_IS_SHIELD" "FALSE"
				( Origin gBackEnd )
			)
		)
		( layer "L11_GND5"
			( attribute "CDS_LAYER_TYPE" "PLANE"
				( Origin gBackEnd )
			)
			( attribute "CDS_LAYER_MATERIAL" "COPPER"
				( Origin gBackEnd )
			)
			( attribute "CDS_LAYER_THICKNESS" "1.25"
				( Units "uLayerThickness" "mil" 1.000000)
				( Origin gBackEnd )
			)
			( attribute "CDS_LAYER_ELECTRICAL_CONDUCTIVITY" "595900"
				( Units "uElectricalConductivity" "mho/cm" 1.000000)
				( Origin gBackEnd )
			)
			( attribute "CDS_LAYER_THERMAL_CONDUCTIVITY" "0.0000"
				( Units "uThermalConductivity" "W/cm-degC" 1.000000)
				( Origin gBackEnd )
			)
			( attribute "CDS_LAYER_DIELECTRIC_CONSTANT" "4.500"
				( Origin gBackEnd )
			)
			( attribute "CDS_LAYER_LOSS_TANGENT" "0.03500"
				( Origin gBackEnd )
			)
			( attribute "CDS_LAYER_NEGATIVE_ARTWORK" "FALSE"
				( Origin gBackEnd )
			)
			( attribute "CDS_LAYER_IS_SHIELD" "TRUE"
				( Origin gBackEnd )
			)
			( attribute "CDS_LAYER_IS_NAMED" "1"
				( Origin gBackEnd )
			)
			( attribute "CDS_LAYER_ETCH_FACTOR" "90.00"
				( Origin gBackEnd )
			)
			( attribute "CDS_LAYER_EMBEDDED_STATUS" "NOT_EMBEDDED"
				( Origin gBackEnd )
			)
		)
		( layer "DIELECTRIC_BELOW_L11_GND5"
			( attribute "CDS_LAYER_TYPE" "DIELECTRIC"
				( Origin gBackEnd )
			)
			( attribute "CDS_LAYER_MATERIAL" "FR-4"
				( Origin gBackEnd )
			)
			( attribute "CDS_LAYER_THICKNESS" "3"
				( Units "uLayerThickness" "mil" 1.000000)
				( Origin gBackEnd )
			)
			( attribute "CDS_LAYER_ELECTRICAL_CONDUCTIVITY" "0.0000"
				( Units "uElectricalConductivity" "mho/cm" 1.000000)
				( Origin gBackEnd )
			)
			( attribute "CDS_LAYER_THERMAL_CONDUCTIVITY" "0.01200"
				( Units "uThermalConductivity" "W/cm-degC" 1.000000)
				( Origin gBackEnd )
			)
			( attribute "CDS_LAYER_DIELECTRIC_CONSTANT" "4.500"
				( Origin gBackEnd )
			)
			( attribute "CDS_LAYER_LOSS_TANGENT" "0.03500"
				( Origin gBackEnd )
			)
			( attribute "CDS_LAYER_NEGATIVE_ARTWORK" "FALSE"
				( Origin gBackEnd )
			)
			( attribute "CDS_LAYER_IS_SHIELD" "FALSE"
				( Origin gBackEnd )
			)
		)
		( layer "L12_SIG4"
			( attribute "CDS_LAYER_TYPE" "CONDUCTOR"
				( Origin gBackEnd )
			)
			( attribute "CDS_LAYER_MATERIAL" "COPPER"
				( Origin gBackEnd )
			)
			( attribute "CDS_LAYER_THICKNESS" "1.25"
				( Units "uLayerThickness" "mil" 1.000000)
				( Origin gBackEnd )
			)
			( attribute "CDS_LAYER_ELECTRICAL_CONDUCTIVITY" "595900"
				( Units "uElectricalConductivity" "mho/cm" 1.000000)
				( Origin gBackEnd )
			)
			( attribute "CDS_LAYER_THERMAL_CONDUCTIVITY" "0.01200"
				( Units "uThermalConductivity" "W/cm-degC" 1.000000)
				( Origin gBackEnd )
			)
			( attribute "CDS_LAYER_DIELECTRIC_CONSTANT" "4.500"
				( Origin gBackEnd )
			)
			( attribute "CDS_LAYER_LOSS_TANGENT" "0.03500"
				( Origin gBackEnd )
			)
			( attribute "CDS_LAYER_NEGATIVE_ARTWORK" "FALSE"
				( Origin gBackEnd )
			)
			( attribute "CDS_LAYER_IS_SHIELD" "FALSE"
				( Origin gBackEnd )
			)
			( attribute "CDS_LAYER_IS_NAMED" "1"
				( Origin gBackEnd )
			)
			( attribute "CDS_LAYER_ETCH_FACTOR" "90.00"
				( Origin gBackEnd )
			)
			( attribute "CDS_LAYER_EMBEDDED_STATUS" "NOT_EMBEDDED"
				( Origin gBackEnd )
			)
		)
		( layer "DIELECTRIC_BELOW_L12_SIG4"
			( attribute "CDS_LAYER_TYPE" "DIELECTRIC"
				( Origin gBackEnd )
			)
			( attribute "CDS_LAYER_MATERIAL" "FR-4"
				( Origin gBackEnd )
			)
			( attribute "CDS_LAYER_THICKNESS" "9"
				( Units "uLayerThickness" "mil" 1.000000)
				( Origin gBackEnd )
			)
			( attribute "CDS_LAYER_ELECTRICAL_CONDUCTIVITY" "0.0000"
				( Units "uElectricalConductivity" "mho/cm" 1.000000)
				( Origin gBackEnd )
			)
			( attribute "CDS_LAYER_THERMAL_CONDUCTIVITY" "0.0000"
				( Units "uThermalConductivity" "W/cm-degC" 1.000000)
				( Origin gBackEnd )
			)
			( attribute "CDS_LAYER_DIELECTRIC_CONSTANT" "4.500"
				( Origin gBackEnd )
			)
			( attribute "CDS_LAYER_LOSS_TANGENT" "0.03500"
				( Origin gBackEnd )
			)
			( attribute "CDS_LAYER_NEGATIVE_ARTWORK" "FALSE"
				( Origin gBackEnd )
			)
			( attribute "CDS_LAYER_IS_SHIELD" "FALSE"
				( Origin gBackEnd )
			)
		)
		( layer "L13_GND6"
			( attribute "CDS_LAYER_TYPE" "PLANE"
				( Origin gBackEnd )
			)
			( attribute "CDS_LAYER_MATERIAL" "COPPER"
				( Origin gBackEnd )
			)
			( attribute "CDS_LAYER_THICKNESS" "1.25"
				( Units "uLayerThickness" "mil" 1.000000)
				( Origin gBackEnd )
			)
			( attribute "CDS_LAYER_ELECTRICAL_CONDUCTIVITY" "595900"
				( Units "uElectricalConductivity" "mho/cm" 1.000000)
				( Origin gBackEnd )
			)
			( attribute "CDS_LAYER_THERMAL_CONDUCTIVITY" "0.01200"
				( Units "uThermalConductivity" "W/cm-degC" 1.000000)
				( Origin gBackEnd )
			)
			( attribute "CDS_LAYER_DIELECTRIC_CONSTANT" "4.500"
				( Origin gBackEnd )
			)
			( attribute "CDS_LAYER_LOSS_TANGENT" "0.03500"
				( Origin gBackEnd )
			)
			( attribute "CDS_LAYER_NEGATIVE_ARTWORK" "FALSE"
				( Origin gBackEnd )
			)
			( attribute "CDS_LAYER_IS_SHIELD" "TRUE"
				( Origin gBackEnd )
			)
			( attribute "CDS_LAYER_IS_NAMED" "1"
				( Origin gBackEnd )
			)
			( attribute "CDS_LAYER_ETCH_FACTOR" "90.00"
				( Origin gBackEnd )
			)
			( attribute "CDS_LAYER_EMBEDDED_STATUS" "NOT_EMBEDDED"
				( Origin gBackEnd )
			)
		)
		( layer "DIELECTRIC_BELOW_L13_GND6"
			( attribute "CDS_LAYER_TYPE" "DIELECTRIC"
				( Origin gBackEnd )
			)
			( attribute "CDS_LAYER_MATERIAL" "FR-4"
				( Origin gBackEnd )
			)
			( attribute "CDS_LAYER_THICKNESS" "2.67"
				( Units "uLayerThickness" "mil" 1.000000)
				( Origin gBackEnd )
			)
			( attribute "CDS_LAYER_ELECTRICAL_CONDUCTIVITY" "0.0000"
				( Units "uElectricalConductivity" "mho/cm" 1.000000)
				( Origin gBackEnd )
			)
			( attribute "CDS_LAYER_THERMAL_CONDUCTIVITY" "0.01200"
				( Units "uThermalConductivity" "W/cm-degC" 1.000000)
				( Origin gBackEnd )
			)
			( attribute "CDS_LAYER_DIELECTRIC_CONSTANT" "4.500"
				( Origin gBackEnd )
			)
			( attribute "CDS_LAYER_LOSS_TANGENT" "0.03500"
				( Origin gBackEnd )
			)
			( attribute "CDS_LAYER_NEGATIVE_ARTWORK" "FALSE"
				( Origin gBackEnd )
			)
			( attribute "CDS_LAYER_IS_SHIELD" "FALSE"
				( Origin gBackEnd )
			)
		)
		( layer "BOTTOM"
			( attribute "CDS_LAYER_TYPE" "CONDUCTOR"
				( Origin gBackEnd )
			)
			( attribute "CDS_LAYER_MATERIAL" "COPPER"
				( Origin gBackEnd )
			)
			( attribute "CDS_LAYER_THICKNESS" "2.1"
				( Units "uLayerThickness" "mil" 1.000000)
				( Origin gBackEnd )
			)
			( attribute "CDS_LAYER_ELECTRICAL_CONDUCTIVITY" "595900"
				( Units "uElectricalConductivity" "mho/cm" 1.000000)
				( Origin gBackEnd )
			)
			( attribute "CDS_LAYER_THERMAL_CONDUCTIVITY" "0.0000"
				( Units "uThermalConductivity" "W/cm-degC" 1.000000)
				( Origin gBackEnd )
			)
			( attribute "CDS_LAYER_DIELECTRIC_CONSTANT" "4.500"
				( Origin gBackEnd )
			)
			( attribute "CDS_LAYER_LOSS_TANGENT" "0.0000"
				( Origin gBackEnd )
			)
			( attribute "CDS_LAYER_NEGATIVE_ARTWORK" "FALSE"
				( Origin gBackEnd )
			)
			( attribute "CDS_LAYER_IS_SHIELD" "FALSE"
				( Origin gBackEnd )
			)
			( attribute "CDS_LAYER_IS_NAMED" "1"
				( Origin gBackEnd )
			)
			( attribute "CDS_LAYER_IS_BOTTOM_SUBSTRATE" "1"
				( Origin gBackEnd )
			)
			( attribute "CDS_LAYER_ETCH_FACTOR" "70.00"
				( Origin gBackEnd )
			)
			( attribute "CDS_LAYER_EMBEDDED_STATUS" "NOT_EMBEDDED"
				( Origin gBackEnd )
			)
		)
		( layer "DIELECTRIC_BELOW_BOTTOM"
			( attribute "CDS_LAYER_TYPE" "DIELECTRIC"
				( Origin gBackEnd )
			)
			( attribute "CDS_LAYER_MATERIAL" "CONFORMAL_COAT"
				( Origin gBackEnd )
			)
			( attribute "CDS_LAYER_THICKNESS" "0.5"
				( Units "uLayerThickness" "mil" 1.000000)
				( Origin gBackEnd )
			)
			( attribute "CDS_LAYER_ELECTRICAL_CONDUCTIVITY" "0.0000"
				( Units "uElectricalConductivity" "mho/cm" 1.000000)
				( Origin gBackEnd )
			)
			( attribute "CDS_LAYER_THERMAL_CONDUCTIVITY" "0.01200"
				( Units "uThermalConductivity" "W/cm-degC" 1.000000)
				( Origin gBackEnd )
			)
			( attribute "CDS_LAYER_DIELECTRIC_CONSTANT" "3.800"
				( Origin gBackEnd )
			)
			( attribute "CDS_LAYER_LOSS_TANGENT" "0.03500"
				( Origin gBackEnd )
			)
			( attribute "CDS_LAYER_NEGATIVE_ARTWORK" "FALSE"
				( Origin gBackEnd )
			)
			( attribute "CDS_LAYER_IS_SHIELD" "FALSE"
				( Origin gBackEnd )
			)
		)
		( layer "SURFACE_2_BELOW_BOTTOM"
			( attribute "CDS_LAYER_TYPE" "SURFACE"
				( Origin gBackEnd )
			)
			( attribute "CDS_LAYER_MATERIAL" "AIR"
				( Origin gBackEnd )
			)
			( attribute "CDS_LAYER_THICKNESS" "0.0000"
				( Units "uLayerThickness" "mil" 1.000000)
				( Origin gBackEnd )
			)
			( attribute "CDS_LAYER_ELECTRICAL_CONDUCTIVITY" "0.0000"
				( Units "uElectricalConductivity" "mho/cm" 1.000000)
				( Origin gBackEnd )
			)
			( attribute "CDS_LAYER_THERMAL_CONDUCTIVITY" "0.0000"
				( Units "uThermalConductivity" "W/cm-degC" 1.000000)
				( Origin gBackEnd )
			)
			( attribute "CDS_LAYER_DIELECTRIC_CONSTANT" "1.000"
				( Origin gBackEnd )
			)
			( attribute "CDS_LAYER_LOSS_TANGENT" "0.0000"
				( Origin gBackEnd )
			)
			( attribute "CDS_LAYER_NEGATIVE_ARTWORK" "FALSE"
				( Origin gBackEnd )
			)
			( attribute "CDS_LAYER_IS_SHIELD" "FALSE"
				( Origin gBackEnd )
			)
		)
	)
	( designConstraints
		( ruleChanges
			( allRules )
			( design "@baseboard_fab2_lib.baseboard_fab2(sch_1)"
				( physicalCSetRef "@crescent_city_bb_fab1_lib.crescent_city_bb_fab1(sch_1):\DEFAULT\" )
				( spacingCSetRef "@crescent_city_bb_fab1_lib.crescent_city_bb_fab1(sch_1):\DEFAULT\" )
				( sameNetSpacingCSetRef "@crescent_city_bb_fab1_lib.crescent_city_bb_fab1(sch_1):\DEFAULT\" )
				( attribute "MAX_FILENAME_VALUE" "228"
					( Origin gBackEnd )
				)
				( attribute "SQ_LINE_WIDTH_VALUES" "SINGLE_IMPEDANCE OFF|DIFF_IMPEDANCE OFF|TOP|4.00 MIL|NONE|5.00 MIL|L3_SIG1|4.00 MIL|NONE|4.00 MIL|L5_SIG2|4.00 MIL|NONE|4.00 MIL|L9_SIG_TEMP|3.52 MIL|NONE|4.00 MIL|L10_SIG_TEMP|3.52 MIL|NONE|4.00 MIL|L14_SIG3|4.00 MIL|NONE|4.00 MIL|L16_SIG4|4.00 MIL|NONE|4.00 MIL|BOTTOM|4.00 MIL|NONE|5.00 MIL"
					( Origin gBackEnd )
				)
				( objectStatus "crescent_city_fab2_2v290_20151002_C_gridout2" )
			)
			( electricalCSetMatchGroup "SPI_SWITCH_IO2:SPI_MUX-U3T1"
				( member ( pinPairRef "SPI_SWITCH_IO2:U2T1.4:U3T1.9") )
			)
			( electricalCSetMatchGroup "SPI_SWITCH_IO2:SPI_MUX-U7F1"
				( member ( pinPairRef "SPI_SWITCH_IO2:U2T1.4:U7F1.9") )
			)
			( electricalCSetMatchGroup "SVID_DIO0_CPU0:#SVID_CPU0_0_U36-EU109"
				( member ( pinPairRef "SVID_DIO0_CPU0:EU3P1.16:U5D1.DB45") )
			)
			( electricalCSetMatchGroup "SVID_DIO0_CPU0:#SVID_CPU0_0_U36-EU43"
				( member ( pinPairRef "SVID_DIO0_CPU0:EU4D4.18:U5D1.DB45") )
			)
			( electricalCSetMatchGroup "SVID_ALERT0_CPU0_N:#SVID_CPU0_0_U36-EU109"
				( member ( pinPairRef "SVID_ALERT0_CPU0_N:EU3P1.17:U5D1.DE44") )
			)
			( electricalCSetMatchGroup "SVID_ALERT0_CPU0_N:#SVID_CPU0_0_U36-EU43"
				( member ( pinPairRef "SVID_ALERT0_CPU0_N:EU4D4.19:U5D1.DE44") )
			)
			( electricalCSetMatchGroup "SPI_NIC_SCLK:SPI_NIC"
				( member ( pinPairRef "SPI_NIC_SCLK:U9E1.6:EU9E1.13") )
			)
			( electricalCSetMatchGroup "SPI_CS0_PRIMARY_R_N:SPI_MUX-U7F1"
				( member ( pinPairRef "SPI_CS0_PRIMARY_R_N:U8F1.9:U7F1.7") )
			)
			( electricalCSetMatchGroup "SPI_CS0_PRIMARY_R_N:SPI_MUX-U3T1"
				( member ( pinPairRef "SPI_CS0_PRIMARY_R_N:U8F1.9:U3T1.7") )
			)
			( electricalCSetMatchGroup "SPI_PCH_IO2:SPI_PCH-MUX"
				( member ( pinPairRef "SPI_PCH_IO2:U7C1.F5:U2T1.2") )
			)
			( electricalCSetMatchGroup "SPI_PCH_MOSI_R:SPI_PCH-MUX"
				( member ( pinPairRef "SPI_PCH_MOSI_R:U7C1.H4:U8F1.5") )
			)
			( electricalCSetMatchGroup "SPI_PCH_MOSI_R:SPI_PCH-TPM"
				( member ( pinPairRef "SPI_PCH_MOSI_R:U7C1.H4:J8E1.3") )
			)
			( electricalCSetMatchGroup "SPI_PCH_MISO_R:SPI_PCH-TPM"
				( member ( pinPairRef "SPI_PCH_MISO_R:U7C1.L3:J8E1.4") )
			)
			( electricalCSetMatchGroup "SPI_PCH_MISO_R:SPI_PCH-MUX"
				( member ( pinPairRef "SPI_PCH_MISO_R:U7C1.L3:U8F1.14") )
			)
			( electricalCSetMatchGroup "SPI_PCH_IO3:SPI_PCH-MUX"
				( member ( pinPairRef "SPI_PCH_IO3:U7C1.L1:U2T1.5") )
			)
			( electricalCSetMatchGroup "SPI_PCH_TPM_CS_N:SPI_PCH-TPM"
				( member ( pinPairRef "SPI_PCH_TPM_CS_N:U7C1.K4:J8E1.5") )
			)
			( electricalCSetMatchGroup "SPI_PCH_CS0_R1_N:SPI_PCH-MUX"
				( member ( pinPairRef "SPI_PCH_CS0_R1_N:U7C1.J3:U8F1.11") )
			)
			( electricalCSetMatchGroup "SPI_PCH_CLK:SPI_PCH-TPM"
				( member ( pinPairRef "SPI_PCH_CLK:U7C1.K2:J8E1.1") )
			)
			( electricalCSetMatchGroup "SPI_PCH_CLK:SPI_PCH-MUX"
				( member ( pinPairRef "SPI_PCH_CLK:U8F1.2:U7C1.K2") )
			)
			( electricalCSetMatchGroup "SPI_SWITCH_MOSI:SPI_MUX-U7F1"
				( member ( pinPairRef "SPI_SWITCH_MOSI:U8F1.7:U7F1.15") )
			)
			( electricalCSetMatchGroup "SPI_SWITCH_MOSI:SPI_MUX-U3T1"
				( member ( pinPairRef "SPI_SWITCH_MOSI:U8F1.7:U3T1.15") )
			)
			( electricalCSetMatchGroup "SPI_SWITCH_MISO:SPI_MUX-U7F1"
				( member ( pinPairRef "SPI_SWITCH_MISO:U7F1.8:U8F1.12") )
			)
			( electricalCSetMatchGroup "SPI_SWITCH_MISO:SPI_MUX-U3T1"
				( member ( pinPairRef "SPI_SWITCH_MISO:U8F1.12:U3T1.8") )
			)
			( electricalCSetMatchGroup "SPI_SWITCH_CLK:SPI_MUX-U7F1"
				( member ( pinPairRef "SPI_SWITCH_CLK:U8F1.4:U7F1.16") )
			)
			( electricalCSetMatchGroup "SPI_SWITCH_CLK:SPI_MUX-U3T1"
				( member ( pinPairRef "SPI_SWITCH_CLK:U8F1.4:U3T1.16") )
			)
			( electricalCSetMatchGroup "SPI_SWITCH_IO3:SPI_MUX-U3T1"
				( member ( pinPairRef "SPI_SWITCH_IO3:U2T1.7:U3T1.1") )
			)
			( electricalCSetMatchGroup "SPI_SWITCH_IO3:SPI_MUX-U7F1"
				( member ( pinPairRef "SPI_SWITCH_IO3:U2T1.7:U7F1.1") )
			)
			( electricalCSetMatchGroup "SGPIO_BMC:MG_SGPIO_BMC"
				( attribute "RELATIVE_PROPAGATION_DELAY_SCOPE" "G"
					( Parent
						( ecsetMatchGroupRef "SGPIO_BMC:MG_SGPIO_BMC" )
					)
					( Origin gBackEnd )
				)
				( attribute "RELATIVE_PROPAGATION_DELAY_PATH_TYPE" "AD:AR"
					( Parent
						( ecsetMatchGroupRef "SGPIO_BMC:MG_SGPIO_BMC" )
					)
					( Origin gBackEnd )
				)
				( attribute "RELATIVE_PROPAGATION_DELAY" ",1000.00 MIL"
					( Parent
						( ecsetMatchGroupRef "SGPIO_BMC:MG_SGPIO_BMC" )
					)
					( Units "uMatchProp" "ns" 1.000000)
					( Origin gBackEnd )
				)
			)
			( electricalCSetMatchGroup "SGPIO_BMC_DI:MG_SGPIO_BMC"
				( attribute "RELATIVE_PROPAGATION_DELAY_SCOPE" "G"
					( Parent
						( ecsetMatchGroupRef "SGPIO_BMC_DI:MG_SGPIO_BMC" )
					)
					( Origin gBackEnd )
				)
				( attribute "RELATIVE_PROPAGATION_DELAY_PATH_TYPE" "AD:AR"
					( Parent
						( ecsetMatchGroupRef "SGPIO_BMC_DI:MG_SGPIO_BMC" )
					)
					( Origin gBackEnd )
				)
				( attribute "RELATIVE_PROPAGATION_DELAY" ",1000.00 MIL"
					( Parent
						( ecsetMatchGroupRef "SGPIO_BMC_DI:MG_SGPIO_BMC" )
					)
					( Units "uMatchProp" "ns" 1.000000)
					( Origin gBackEnd )
				)
			)
			( electricalCSetMatchGroup "JTAG_PCH:MG_JTAG_PLD"
				( member ( pinPairRef "JTAG_PCH:U9F4.F2:U8D7.A7") )
			)
			( electricalCSetMatchGroup "JTAG_PCH:MG_JTAG_PCH_PLD"
				( member ( pinPairRef "JTAG_PCH:U9F4.F2:U7C1.AL18") )
			)
			( electricalCSetMatchGroup "JTAG_PCH:MG_JTAG_PCH_GBE"
				( member ( pinPairRef "JTAG_PCH:U9F4.F2:U7C1.BV21") )
			)
			( electricalCSetMatchGroup "JTAG_PCH:MG_JTAG"
				( member ( pinPairRef "JTAG_PCH:J7G2.8:U9F4.F2") )
			)
			( electricalCSetMatchGroup "CLK_100M_BMC_PE_R_DN:MG_CLK_G1-BCLK"
				( member ( pinPairRef "CLK_100M_BMC_PE_R_DN:U9F4.G21:U7C1.B29") )
			)
			( electricalCSetMatchGroup "PCIE_CO_SATA:MG_PCIE_L0"
				( member ( pinPairRef "PCIE_CO_SATA:J8F1.41:C8F15.2") )
			)
			( electricalCSetMatchGroup "PCIE_CO_SATA:MG_PCIE_L1"
				( member ( pinPairRef "PCIE_CO_SATA:U7C1.BA71:C8F15.1") )
			)
			( electricalCSetMatchGroup "PCIE_CO_SATA:MG_PCIE_ALL0"
				( member ( pinPairRef "PCIE_CO_SATA:J8F1.41:U7C1.BA71") )
			)
			( electricalCSetMatchGroup "CLK_100M_MEZZ_&_SLOT:MG_CLK_G2-BCLK"
				( member ( pinPairRef "CLK_100M_MEZZ_&_SLOT:U7C1.J33:J8G1.35") )
			)
			( electricalCSetMatchGroup "CLK_100M_CPU1_MCP_DN:MG_CLK_G1-BCLK"
				( member ( pinPairRef "CLK_100M_CPU1_MCP_DN:EU4D2.64:U2D1.BB25") )
			)
			( electricalCSetMatchGroup "PCIE_C_D:MG_PCIE_L0"
				( member ( pinPairRef "PCIE_C_D:J8G1.102:R2U29.1") )
			)
			( electricalCSetMatchGroup "PCIE_C_D:MG_PCIE_L1"
				( member ( pinPairRef "PCIE_C_D:U7C1.P59:R3641.1") )
			)
			( electricalCSetMatchGroup "PCIE_C_D:MG_PCIE_L2"
				( member ( pinPairRef "PCIE_C_D:U5D1.DM9:R2U29.1") )
			)
			( electricalCSetMatchGroup "PCIE_C_D:MG_PCIE_ALL0"
				( member ( pinPairRef "PCIE_C_D:U5D1.DM9:J8G1.102") )
			)
			( electricalCSetMatchGroup "PCIE_C_D:MG_PCIE_ALL1"
				( member ( pinPairRef "PCIE_C_D:U5D1.DM9:U7C1.P59") )
			)
			( electricalCSetMatchGroup "DMI:MG_DMI_L0"
				( member ( pinPairRef "DMI:U7C1.H46:C3M44.1") )
			)
			( electricalCSetMatchGroup "DMI:MG_DMI_L1"
				( member ( pinPairRef "DMI:C3M44.2:U5D1.CK9") )
			)
			( electricalCSetMatchGroup "PCIE_DEVICE:MG"
				( member ( pinPairRef "PCIE_DEVICE:U5D1.DW4:U7C1.A59") )
			)
			( electricalCSetMatchGroup "PCIE_DEVICE:MG_PCIE_L1"
				( member ( pinPairRef "PCIE_DEVICE:U5D1.DW4:C6B15.1") )
			)
			( electricalCSetMatchGroup "PCIE_DEVICE:MG_PCIE_L0"
				( member ( pinPairRef "PCIE_DEVICE:C6B15.2:U7C1.A59") )
			)
			( electricalCSetMatchGroup "CLK_100M_CPU_BCLKS:MG"
				( member ( pinPairRef "CLK_100M_CPU_BCLKS:U5D1.AU24:EU4D2.18") )
			)
			( electricalCSetMatchGroup "UPI_CPU1_CPU0_P1P1:MG_KTI_BUNDLE"
				( member ( pinPairRef "UPI_CPU1_CPU0_P1P1:U5D1.BH3:U2D1.AC10") )
			)
			( electricalCSetMatchGroup "UPI_CPU1_CPU0_P1P1:MG_KTI_CPU1_CPU0_P1P1"
				( member ( pinPairRef "UPI_CPU1_CPU0_P1P1:U5D1.BH3:U2D1.AC10") )
			)
			( electricalCSetMatchGroup "UPI_CPU1_CPU0_P0P0:MG_KTI_BUNDLE"
				( member ( pinPairRef "UPI_CPU1_CPU0_P0P0:U5D1.BH3:U2D1.AC10") )
			)
			( electricalCSetMatchGroup "UPI_CPU1_CPU0_P0P0:MG_KTI_CPU1_CPU0_P0P0"
				( member ( pinPairRef "UPI_CPU1_CPU0_P0P0:U5D1.BH3:U2D1.AC10") )
			)
			( electricalCSetMatchGroup "UPI_CPU0_CPU1_P1P1:MG_KTI_BUNDLE"
				( member ( pinPairRef "UPI_CPU0_CPU1_P1P1:U5D1.BH3:U2D1.AC10") )
			)
			( electricalCSetMatchGroup "UPI_CPU0_CPU1_P1P1:MG_KTI_CPU0_CPU1_P1P1"
				( member ( pinPairRef "UPI_CPU0_CPU1_P1P1:U5D1.BH3:U2D1.AC10") )
			)
			( electricalCSetMatchGroup "UPI_CPU0_CPU1_P0P0:MG_KTI_BUNDLE"
				( member ( pinPairRef "UPI_CPU0_CPU1_P0P0:U5D1.BH3:U2D1.AC10") )
			)
			( electricalCSetMatchGroup "UPI_CPU0_CPU1_P0P0:MG_KTI_CPU0_CPU1_P0P0"
				( member ( pinPairRef "UPI_CPU0_CPU1_P0P0:U5D1.BH3:U2D1.AC10") )
			)
			( electricalCSetMatchGroup "DDR_CLK1:MG_DDR_NEAR_DIMM-CLK1"
				( attribute "RELATIVE_PROPAGATION_DELAY_SCOPE" "C"
					( Parent
						( ecsetMatchGroupRef "DDR_CLK1:MG_DDR_NEAR_DIMM-CLK1" )
					)
					( Origin gBackEnd )
				)
				( attribute "RELATIVE_PROPAGATION_DELAY_PATH_TYPE" "L:S"
					( Parent
						( ecsetMatchGroupRef "DDR_CLK1:MG_DDR_NEAR_DIMM-CLK1" )
					)
					( Origin gBackEnd )
				)
				( attribute "RELATIVE_PROPAGATION_DELAY" "0.00 MIL,5.00 MIL"
					( Parent
						( ecsetMatchGroupRef "DDR_CLK1:MG_DDR_NEAR_DIMM-CLK1" )
					)
					( Units "uMatchProp" "ns" 1.000000)
					( Origin gBackEnd )
				)
			)
			( electricalCSetMatchGroup "DDR_CLK0:MG_DDR_FAR_DIMM-CLK0"
				( attribute "RELATIVE_PROPAGATION_DELAY_SCOPE" "C"
					( Parent
						( ecsetMatchGroupRef "DDR_CLK0:MG_DDR_FAR_DIMM-CLK0" )
					)
					( Origin gBackEnd )
				)
				( attribute "RELATIVE_PROPAGATION_DELAY_PATH_TYPE" "L:S"
					( Parent
						( ecsetMatchGroupRef "DDR_CLK0:MG_DDR_FAR_DIMM-CLK0" )
					)
					( Origin gBackEnd )
				)
				( attribute "RELATIVE_PROPAGATION_DELAY" "0.00 MIL,5.00 MIL"
					( Parent
						( ecsetMatchGroupRef "DDR_CLK0:MG_DDR_FAR_DIMM-CLK0" )
					)
					( Units "uMatchProp" "ns" 1.000000)
					( Origin gBackEnd )
				)
			)
			( electricalCSetMatchGroup "DDR_CTRL_DLL14-19:MG_DDR_CTRL"
				( member ( pinPairRef "DDR_CTRL_DLL14-19:U5D1.G52:J4G1.84") )
			)
			( electricalCSetMatchGroup "DDR_CTRL_DLL14-19:MG_DDR_FAR_DIMM-CLK0"
				( member ( pinPairRef "DDR_CTRL_DLL14-19:U5D1.G52:J4G1.84") )
			)
			( electricalCSetMatchGroup "DDR_F_CMD_DLL1-13:MG_DDR_NEAR_DIMM-CLK1"
				( member ( pinPairRef "DDR_F_CMD_DLL1-13:U5D1.F51:J6L1.228") )
			)
			( electricalCSetMatchGroup "DDR_F_CMD_DLL1-13:MG_DDR_FAR_DIMM_CMD"
				( member ( pinPairRef "DDR_F_CMD_DLL1-13:U5D1.F51:J4A1.228") )
			)
			( electricalCSetMatchGroup "DDR_F_CMD_DLL1-13:MG_DDR_FAR_DIMM-CLK0"
				( member ( pinPairRef "DDR_F_CMD_DLL1-13:U5D1.F51:J4A1.228") )
			)
			( electricalCSetMatchGroup "DDR_F_CMD_DLL1-13:MG_DDR_CMD_NEAR_DIMM"
				( member ( pinPairRef "DDR_F_CMD_DLL1-13:U5D1.F51:J6L1.228") )
			)
			( electricalCSetMatchGroup "DDR_E_CMD_DLL1-13:MG_DDR_NEAR_DIMM-CLK1"
				( member ( pinPairRef "DDR_E_CMD_DLL1-13:U5D1.F51:J6L2.228") )
			)
			( electricalCSetMatchGroup "DDR_E_CMD_DLL1-13:MG_DDR_FAR_DIMM_CMD"
				( member ( pinPairRef "DDR_E_CMD_DLL1-13:U5D1.F51:J4A2.228") )
			)
			( electricalCSetMatchGroup "DDR_E_CMD_DLL1-13:MG_DDR_FAR_DIMM-CLK0"
				( member ( pinPairRef "DDR_E_CMD_DLL1-13:U5D1.F51:J4A2.228") )
			)
			( electricalCSetMatchGroup "DDR_E_CMD_DLL1-13:MG_DDR_CMD_NEAR_DIMM"
				( member ( pinPairRef "DDR_E_CMD_DLL1-13:U5D1.F51:J6L2.228") )
			)
			( electricalCSetMatchGroup "DDR_D_CMD_DLL1-13:MG_DDR_NEAR_DIMM-CLK1"
				( member ( pinPairRef "DDR_D_CMD_DLL1-13:U5D1.F51:J6M1.228") )
			)
			( electricalCSetMatchGroup "DDR_D_CMD_DLL1-13:MG_DDR_FAR_DIMM_CMD"
				( member ( pinPairRef "DDR_D_CMD_DLL1-13:U5D1.F51:J4B1.228") )
			)
			( electricalCSetMatchGroup "DDR_D_CMD_DLL1-13:MG_DDR_FAR_DIMM-CLK0"
				( member ( pinPairRef "DDR_D_CMD_DLL1-13:U5D1.F51:J4B1.228") )
			)
			( electricalCSetMatchGroup "DDR_D_CMD_DLL1-13:MG_DDR_CMD_NEAR_DIMM"
				( member ( pinPairRef "DDR_D_CMD_DLL1-13:U5D1.F51:J6M1.228") )
			)
			( electricalCSetMatchGroup "DDR_DQS:MG_DQ-DQS_FAR_DIMM"
				( member ( pinPairRef "DDR_DQS:U5D1.AJ84:J4G1.152") )
			)
			( electricalCSetMatchGroup "DDR_DQS:MG_DQ-DQS_NEAR_DIMM"
				( member ( pinPairRef "DDR_DQS:U5D1.AJ84:J6T1.152") )
			)
			( electricalCSetMatchGroup "DDR_A_CMD_DLL1-13:MG_DDR_CMD_NEAR_DIMM"
				( member ( pinPairRef "DDR_A_CMD_DLL1-13:U5D1.F51:J6T1.228") )
			)
			( electricalCSetMatchGroup "DDR_A_CMD_DLL1-13:MG_DDR_FAR_DIMM-CLK0"
				( member ( pinPairRef "DDR_A_CMD_DLL1-13:U5D1.F51:J4G1.228") )
			)
			( electricalCSetMatchGroup "DDR_A_CMD_DLL1-13:MG_DDR_FAR_DIMM_CMD"
				( member ( pinPairRef "DDR_A_CMD_DLL1-13:U5D1.F51:J4G1.228") )
			)
			( electricalCSetMatchGroup "DDR_A_CMD_DLL1-13:MG_DDR_NEAR_DIMM-CLK1"
				( member ( pinPairRef "DDR_A_CMD_DLL1-13:U5D1.F51:J6T1.228") )
			)
			( electricalCSetMatchGroup "DDR_DQ_NEW:MG_DQ_NEAR_DIMM"
				( member ( pinPairRef "DDR_DQ_NEW:U5D1.AN86:J6T1.5") )
			)
			( electricalCSetMatchGroup "DDR_DQ_NEW:MG_DQ_FAR_DIMM"
				( member ( pinPairRef "DDR_DQ_NEW:U5D1.AN86:J4G1.5") )
			)
			( electricalCSetMatchGroup "DDR_DQ_NEW:MG_DQ-DQS_NEAR_DIMM"
				( member ( pinPairRef "DDR_DQ_NEW:U5D1.AN86:J6T1.5") )
			)
			( electricalCSetMatchGroup "DDR_DQ_NEW:MG_DQ-DQS_FAR_DIMM"
				( member ( pinPairRef "DDR_DQ_NEW:U5D1.AN86:J4G1.5") )
			)
			( electricalCSetMatchGroup "DDR_CTRL_DLL20-24:MG_DDR_CTRL"
				( member ( pinPairRef "DDR_CTRL_DLL20-24:U5D1.B51:J6T1.84") )
			)
			( electricalCSetMatchGroup "DDR_CTRL_DLL20-24:MG_DDR_NEAR_DIMM-CLK1"
				( member ( pinPairRef "DDR_CTRL_DLL20-24:U5D1.B51:J6T1.84") )
			)
			( electricalCSetMatchGroup "DDR_B_CMD_DLL1-13:MG_DDR_NEAR_DIMM-CLK1"
				( member ( pinPairRef "DDR_B_CMD_DLL1-13:U5D1.F51:J6U1.228") )
			)
			( electricalCSetMatchGroup "DDR_B_CMD_DLL1-13:MG_DDR_FAR_DIMM_CMD"
				( member ( pinPairRef "DDR_B_CMD_DLL1-13:U5D1.F51:J4G2.228") )
			)
			( electricalCSetMatchGroup "DDR_B_CMD_DLL1-13:MG_DDR_FAR_DIMM-CLK0"
				( member ( pinPairRef "DDR_B_CMD_DLL1-13:U5D1.F51:J4G2.228") )
			)
			( electricalCSetMatchGroup "DDR_B_CMD_DLL1-13:MG_DDR_CMD_NEAR_DIMM"
				( member ( pinPairRef "DDR_B_CMD_DLL1-13:U5D1.F51:J6U1.228") )
			)
			( electricalCSetMatchGroup "DDR_C_CMD_DLL1-13:MG_DDR_NEAR_DIMM-CLK1"
				( member ( pinPairRef "DDR_C_CMD_DLL1-13:U5D1.F51:J6U2.228") )
			)
			( electricalCSetMatchGroup "DDR_C_CMD_DLL1-13:MG_DDR_FAR_DIMM_CMD"
				( member ( pinPairRef "DDR_C_CMD_DLL1-13:U5D1.F51:J4G3.228") )
			)
			( electricalCSetMatchGroup "DDR_C_CMD_DLL1-13:MG_DDR_FAR_DIMM-CLK0"
				( member ( pinPairRef "DDR_C_CMD_DLL1-13:U5D1.F51:J4G3.228") )
			)
			( electricalCSetMatchGroup "DDR_C_CMD_DLL1-13:MG_DDR_CMD_NEAR_DIMM"
				( member ( pinPairRef "DDR_C_CMD_DLL1-13:U5D1.F51:J6U2.228") )
			)
			( electricalCSetMatchGroup "PCIE_SLOT_C:MG_PCIE_L0"
				( member ( pinPairRef "PCIE_SLOT_C:J8G1.195:C7G5.2") )
			)
			( electricalCSetMatchGroup "PCIE_SLOT_C:MG_PCIE_L1"
				( member ( pinPairRef "PCIE_SLOT_C:U5D1.BK5:C7G5.1") )
			)
			( electricalCSetMatchGroup "PCIE_SLOT_C:MG"
				( member ( pinPairRef "PCIE_SLOT_C:U5D1.BK5:J8G1.195") )
			)
			( electricalCSetMatchGroup "PCIE_SLOT_C_A:MG_PCIE_L0"
				( member ( pinPairRef "PCIE_SLOT_C_A:J8G1.195:C7G5.2") )
			)
			( electricalCSetMatchGroup "PCIE_SLOT_C_A:MG_PCIE_L1"
				( member ( pinPairRef "PCIE_SLOT_C_A:U5D1.BK5:C7G5.1") )
			)
			( electricalCSetMatchGroup "PCIE_SLOT:MG"
				( member ( pinPairRef "PCIE_SLOT:U5D1.CT9:J8G1.106") )
			)
			( electricalCSetMatchGroup "SVID_ALERT1_CPU0_N:#SVID_CPU1_0_U36-EU75"
				( member ( pinPairRef "SVID_ALERT1_CPU0_N:EU7A5.17:U5D1.DL44") )
			)
			( electricalCSetMatchGroup "SVID_ALERT1_CPU0_N:#SVID_CPU1_0_U36-EU21"
				( member ( pinPairRef "SVID_ALERT1_CPU0_N:EU7G1.17:U5D1.DL44") )
			)
			( electricalCSetMatchGroup "SVID_CLK1_CPU0:#SVID_CPU1_0_U36-EU75"
				( member ( pinPairRef "SVID_CLK1_CPU0:U5D1.DG44:EU7A5.15") )
			)
			( electricalCSetMatchGroup "SVID_CLK1_CPU0:#SVID_CPU1_0_U36-EU21"
				( member ( pinPairRef "SVID_CLK1_CPU0:U5D1.DG44:EU7G1.15") )
			)
			( electricalCSetMatchGroup "CLK_100M_CPU_MCP_&_REFCLK:MG_CLK_G1-BCLK"
				( member ( pinPairRef "CLK_100M_CPU_MCP_&_REFCLK:EU4D2.39:U5D1.BB25") )
			)
			( electricalCSetMatchGroup "SVID_DIO1_CPU0:#SVID_CPU1_0_U36-EU75"
				( member ( pinPairRef "SVID_DIO1_CPU0:EU7A5.16:U5D1.DJ44") )
			)
			( electricalCSetMatchGroup "SVID_DIO1_CPU0:#SVID_CPU1_0_U36-EU21"
				( member ( pinPairRef "SVID_DIO1_CPU0:EU7G1.16:U5D1.DJ44") )
			)
			( electricalCSetMatchGroup "SVID_CLK1_CPU1:#SVID_CPU1_1_U100-EU76"
				( member ( pinPairRef "SVID_CLK1_CPU1:U2D1.DG44:EU1G2.15") )
			)
			( electricalCSetMatchGroup "SVID_CLK1_CPU1:#SVID_CPU1_1_U100-EU77"
				( member ( pinPairRef "SVID_CLK1_CPU1:U2D1.DG44:EU1B1.15") )
			)
			( electricalCSetMatchGroup "SVID_DIO1_CPU1:#SVID_CPU1_1_U100-EU76"
				( member ( pinPairRef "SVID_DIO1_CPU1:EU1G2.16:U2D1.DJ44") )
			)
			( electricalCSetMatchGroup "SVID_DIO1_CPU1:#SVID_CPU1_1_U100-EU77"
				( member ( pinPairRef "SVID_DIO1_CPU1:EU1B1.16:U2D1.DJ44") )
			)
			( electricalCSetMatchGroup "CLS_SVID:#SVID_CPU1_1_U100-EU76"
				( member ( pinPairRef "CLS_SVID:EU1G2.16:U2D1.DJ44") )
			)
			( electricalCSetMatchGroup "CLS_SVID:#SVID_CPU1_1_U100-EU77"
				( member ( pinPairRef "CLS_SVID:EU1B1.16:U2D1.DJ44") )
			)
			( electricalCSetMatchGroup "SVID_CLK0_CPU1:#SVID_CPU0_1_U100-EU111"
				( member ( pinPairRef "SVID_CLK0_CPU1:U2D1.DC44:EU4D5.15") )
			)
			( electricalCSetMatchGroup "SVID_CLK0_CPU1:#SVID_CPU0_1_U100-EU47"
				( member ( pinPairRef "SVID_CLK0_CPU1:U2D1.DC44:EU1C2.17") )
			)
			( electricalCSetMatchGroup "SVID_DIO0_CPU1:#SVID_CPU0_1_U100-EU111"
				( member ( pinPairRef "SVID_DIO0_CPU1:EU4D5.16:U2D1.DB45") )
			)
			( electricalCSetMatchGroup "SVID_DIO0_CPU1:#SVID_CPU0_1_U100-EU47"
				( member ( pinPairRef "SVID_DIO0_CPU1:EU1C2.18:U2D1.DB45") )
			)
			( electricalCSetMatchGroup "SVID_ALERT1_CPU1_N:#SVID_CPU1_1_U100-EU76"
				( member ( pinPairRef "SVID_ALERT1_CPU1_N:EU1G2.17:U2D1.DL44") )
			)
			( electricalCSetMatchGroup "SVID_ALERT1_CPU1_N:#SVID_CPU1_1_U100-EU77"
				( member ( pinPairRef "SVID_ALERT1_CPU1_N:EU1B1.17:U2D1.DL44") )
			)
			( electricalCSetMatchGroup "SVID_ALERT0_CPU1_N:#SVID_CPU0_1_U100-EU111"
				( member ( pinPairRef "SVID_ALERT0_CPU1_N:EU4D5.17:U2D1.DE44") )
			)
			( electricalCSetMatchGroup "SVID_ALERT0_CPU1_N:#SVID_CPU0_1_U100-EU47"
				( member ( pinPairRef "SVID_ALERT0_CPU1_N:EU1C2.19:U2D1.DE44") )
			)
			( electricalCSetMatchGroup "DDR_J_CMD_DLL1-13:MG_DDR_CMD_NEAR_DIMM"
				( member ( pinPairRef "DDR_J_CMD_DLL1-13:U2D1.F51:J9U2.228") )
			)
			( electricalCSetMatchGroup "DDR_J_CMD_DLL1-13:MG_DDR_FAR_DIMM-CLK0"
				( member ( pinPairRef "DDR_J_CMD_DLL1-13:U2D1.F51:J1G3.228") )
			)
			( electricalCSetMatchGroup "DDR_J_CMD_DLL1-13:MG_DDR_FAR_DIMM_CMD"
				( member ( pinPairRef "DDR_J_CMD_DLL1-13:U2D1.F51:J1G3.228") )
			)
			( electricalCSetMatchGroup "DDR_J_CMD_DLL1-13:MG_DDR_NEAR_DIMM-CLK1"
				( member ( pinPairRef "DDR_J_CMD_DLL1-13:U2D1.F51:J9U2.228") )
			)
			( electricalCSetMatchGroup "DDR_H_CMD_DLL1-13:MG_DDR_CMD_NEAR_DIMM"
				( member ( pinPairRef "DDR_H_CMD_DLL1-13:U2D1.F51:J9U1.228") )
			)
			( electricalCSetMatchGroup "DDR_H_CMD_DLL1-13:MG_DDR_FAR_DIMM-CLK0"
				( member ( pinPairRef "DDR_H_CMD_DLL1-13:U2D1.F51:J1G2.228") )
			)
			( electricalCSetMatchGroup "DDR_H_CMD_DLL1-13:MG_DDR_FAR_DIMM_CMD"
				( member ( pinPairRef "DDR_H_CMD_DLL1-13:U2D1.F51:J1G2.228") )
			)
			( electricalCSetMatchGroup "DDR_H_CMD_DLL1-13:MG_DDR_NEAR_DIMM-CLK1"
				( member ( pinPairRef "DDR_H_CMD_DLL1-13:U2D1.F51:J9U1.228") )
			)
			( electricalCSetMatchGroup "DDR_G_CMD_DLL1-13:MG_DDR_NEAR_DIMM-CLK1"
				( member ( pinPairRef "DDR_G_CMD_DLL1-13:U2D1.F51:J9T1.228") )
			)
			( electricalCSetMatchGroup "DDR_G_CMD_DLL1-13:MG_DDR_FAR_DIMM_CMD"
				( member ( pinPairRef "DDR_G_CMD_DLL1-13:U2D1.F51:J1G1.228") )
			)
			( electricalCSetMatchGroup "DDR_G_CMD_DLL1-13:MG_DDR_FAR_DIMM-CLK0"
				( member ( pinPairRef "DDR_G_CMD_DLL1-13:U2D1.F51:J1G1.228") )
			)
			( electricalCSetMatchGroup "DDR_G_CMD_DLL1-13:MG_DDR_CMD_NEAR_DIMM"
				( member ( pinPairRef "DDR_G_CMD_DLL1-13:U2D1.F51:J9T1.228") )
			)
			( electricalCSetMatchGroup "DDR_K_CMD_DLL1-13:MG_DDR_CMD_NEAR_DIMM"
				( member ( pinPairRef "DDR_K_CMD_DLL1-13:U2D1.F51:J9M1.228") )
			)
			( electricalCSetMatchGroup "DDR_K_CMD_DLL1-13:MG_DDR_FAR_DIMM-CLK0"
				( member ( pinPairRef "DDR_K_CMD_DLL1-13:U2D1.F51:J1B1.228") )
			)
			( electricalCSetMatchGroup "DDR_K_CMD_DLL1-13:MG_DDR_FAR_DIMM_CMD"
				( member ( pinPairRef "DDR_K_CMD_DLL1-13:U2D1.F51:J1B1.228") )
			)
			( electricalCSetMatchGroup "DDR_K_CMD_DLL1-13:MG_DDR_NEAR_DIMM-CLK1"
				( member ( pinPairRef "DDR_K_CMD_DLL1-13:U2D1.F51:J9M1.228") )
			)
			( electricalCSetMatchGroup "DDR_L_CMD_DLL1-13:MG_DDR_CMD_NEAR_DIMM"
				( member ( pinPairRef "DDR_L_CMD_DLL1-13:U2D1.F51:J9L2.228") )
			)
			( electricalCSetMatchGroup "DDR_L_CMD_DLL1-13:MG_DDR_FAR_DIMM-CLK0"
				( member ( pinPairRef "DDR_L_CMD_DLL1-13:U2D1.F51:J1A2.228") )
			)
			( electricalCSetMatchGroup "DDR_L_CMD_DLL1-13:MG_DDR_FAR_DIMM_CMD"
				( member ( pinPairRef "DDR_L_CMD_DLL1-13:U2D1.F51:J1A2.228") )
			)
			( electricalCSetMatchGroup "DDR_L_CMD_DLL1-13:MG_DDR_NEAR_DIMM-CLK1"
				( member ( pinPairRef "DDR_L_CMD_DLL1-13:U2D1.F51:J9L2.228") )
			)
			( electricalCSetMatchGroup "DDR_M_CMD_DLL1-13:MG_DDR_CMD_NEAR_DIMM"
				( member ( pinPairRef "DDR_M_CMD_DLL1-13:U2D1.F51:J9L1.228") )
			)
			( electricalCSetMatchGroup "DDR_M_CMD_DLL1-13:MG_DDR_FAR_DIMM-CLK0"
				( member ( pinPairRef "DDR_M_CMD_DLL1-13:U2D1.F51:J1A1.228") )
			)
			( electricalCSetMatchGroup "DDR_M_CMD_DLL1-13:MG_DDR_FAR_DIMM_CMD"
				( member ( pinPairRef "DDR_M_CMD_DLL1-13:U2D1.F51:J1A1.228") )
			)
			( electricalCSetMatchGroup "DDR_M_CMD_DLL1-13:MG_DDR_NEAR_DIMM-CLK1"
				( member ( pinPairRef "DDR_M_CMD_DLL1-13:U2D1.F51:J9L1.228") )
			)
			( electricalCSetPinPair "SPI_SWITCH_IO2:U2T1.4:U3T1.9"
				( attribute "RELATIVE_PROPAGATION_DELAY_SCOPE" "G"
					( Parent
						( ecsetMatchGroupRef "SPI_SWITCH_IO2:SPI_MUX-U3T1" )
					)
					( Origin gBackEnd )
				)
				( attribute "RELATIVE_PROPAGATION_DELAY" "0.00 MIL,125.00 MIL"
					( Parent
						( ecsetMatchGroupRef "SPI_SWITCH_IO2:SPI_MUX-U3T1" )
					)
					( Units "uMatchProp" "ns" 1.000000)
					( Origin gBackEnd )
				)
			)
			( electricalCSetPinPair "SPI_SWITCH_IO2:U2T1.4:U7F1.9"
				( attribute "RELATIVE_PROPAGATION_DELAY_SCOPE" "G"
					( Parent
						( ecsetMatchGroupRef "SPI_SWITCH_IO2:SPI_MUX-U7F1" )
					)
					( Origin gBackEnd )
				)
				( attribute "RELATIVE_PROPAGATION_DELAY" "0.00 MIL,125.00 MIL"
					( Parent
						( ecsetMatchGroupRef "SPI_SWITCH_IO2:SPI_MUX-U7F1" )
					)
					( Units "uMatchProp" "ns" 1.000000)
					( Origin gBackEnd )
				)
			)
			( electricalCSetPinPair "SGPIO_PCH:R2L11.2:R2N31.2"
				( attribute "PROPAGATION_DELAY_MIN" "1000.00 MIL"
					( Units "uMaxMinProp" "ns" 1.000000)
					( Origin gBackEnd )
				)
				( attribute "PROPAGATION_DELAY_MAX" "15000.00 MIL"
					( Units "uMaxMinProp" "ns" 1.000000)
					( Origin gBackEnd )
				)
			)
			( electricalCSetPinPair "SGPIO_PCH:R2N31.1:U7C1.AL7"
				( attribute "PROPAGATION_DELAY_MIN" "100.00 MIL"
					( Units "uMaxMinProp" "ns" 1.000000)
					( Origin gBackEnd )
				)
				( attribute "PROPAGATION_DELAY_MAX" "2000.00 MIL"
					( Units "uMaxMinProp" "ns" 1.000000)
					( Origin gBackEnd )
				)
			)
			( electricalCSetPinPair "SGPIO_PCH:J8A1.1A2:R2L11.2"
				( attribute "PROPAGATION_DELAY_MIN" "100.00 MIL"
					( Units "uMaxMinProp" "ns" 1.000000)
					( Origin gBackEnd )
				)
				( attribute "PROPAGATION_DELAY_MAX" "1000.00 MIL"
					( Units "uMaxMinProp" "ns" 1.000000)
					( Origin gBackEnd )
				)
			)
			( electricalCSetPinPair "KR_OCP_RX:U7C1.BF31:C30.2"
				( attribute "PROPAGATION_DELAY_MAX" "1000.00 MIL"
					( Units "uMaxMinProp" "ns" 1.000000)
					( Origin gBackEnd )
				)
			)
			( electricalCSetPinPair "SVID_DIO0_CPU0:U5D1.DB45:R6N11.1"
				( attribute "PROPAGATION_DELAY_MAX" "4500.00 MIL"
					( Units "uMaxMinProp" "ns" 1.000000)
					( Origin gBackEnd )
				)
			)
			( electricalCSetPinPair "SVID_DIO0_CPU0:R3P11.1:R6N11.2"
				( attribute "PROPAGATION_DELAY_MAX" "27000.00 MIL"
					( Units "uMaxMinProp" "ns" 1.000000)
					( Origin gBackEnd )
				)
			)
			( electricalCSetPinPair "SVID_DIO0_CPU0:R6N2.1:R6N11.2"
				( attribute "PROPAGATION_DELAY_MAX" "400.00 MIL"
					( Units "uMaxMinProp" "ns" 1.000000)
					( Origin gBackEnd )
				)
			)
			( electricalCSetPinPair "SVID_DIO0_CPU0:EU3P1.16:R3P11.2"
				( attribute "PROPAGATION_DELAY_MAX" "1000.00 MIL"
					( Units "uMaxMinProp" "ns" 1.000000)
					( Origin gBackEnd )
				)
			)
			( electricalCSetPinPair "SVID_DIO0_CPU0:EU4D4.18:R4D66.1"
				( attribute "PROPAGATION_DELAY_MAX" "1000.00 MIL"
					( Units "uMaxMinProp" "ns" 1.000000)
					( Origin gBackEnd )
				)
			)
			( electricalCSetPinPair "SVID_DIO0_CPU0:R3P11.1:R3P13.2"
				( attribute "PROPAGATION_DELAY_MAX" "200.00 MIL"
					( Units "uMaxMinProp" "ns" 1.000000)
					( Origin gBackEnd )
				)
			)
			( electricalCSetPinPair "SVID_DIO0_CPU0:EU3P1.16:U5D1.DB45"
				( attribute "RELATIVE_PROPAGATION_DELAY_SCOPE" "G"
					( Parent
						( ecsetMatchGroupRef "SVID_DIO0_CPU0:#SVID_CPU0_0_U36-EU109" )
					)
					( Origin gBackEnd )
				)
				( attribute "RELATIVE_PROPAGATION_DELAY" ",250.00 MIL"
					( Parent
						( ecsetMatchGroupRef "SVID_DIO0_CPU0:#SVID_CPU0_0_U36-EU109" )
					)
					( Units "uMatchProp" "ns" 1.000000)
					( Origin gBackEnd )
				)
			)
			( electricalCSetPinPair "SVID_DIO0_CPU0:EU4D4.18:U5D1.DB45"
				( attribute "RELATIVE_PROPAGATION_DELAY_SCOPE" "G"
					( Parent
						( ecsetMatchGroupRef "SVID_DIO0_CPU0:#SVID_CPU0_0_U36-EU43" )
					)
					( Origin gBackEnd )
				)
				( attribute "RELATIVE_PROPAGATION_DELAY" ",250.00 MIL"
					( Parent
						( ecsetMatchGroupRef "SVID_DIO0_CPU0:#SVID_CPU0_0_U36-EU43" )
					)
					( Units "uMatchProp" "ns" 1.000000)
					( Origin gBackEnd )
				)
			)
			( electricalCSetPinPair "SVID_ALERT0_CPU0_N:U5D1.DE44:R6N10.1"
				( attribute "PROPAGATION_DELAY_MAX" "4500.00 MIL"
					( Units "uMaxMinProp" "ns" 1.000000)
					( Origin gBackEnd )
				)
			)
			( electricalCSetPinPair "SVID_ALERT0_CPU0_N:R6N10.2:R3P1.2"
				( attribute "PROPAGATION_DELAY_MAX" "27000.00 MIL"
					( Units "uMaxMinProp" "ns" 1.000000)
					( Origin gBackEnd )
				)
			)
			( electricalCSetPinPair "SVID_ALERT0_CPU0_N:R6N1.1:R6N10.2"
				( attribute "PROPAGATION_DELAY_MAX" "400.00 MIL"
					( Units "uMaxMinProp" "ns" 1.000000)
					( Origin gBackEnd )
				)
			)
			( electricalCSetPinPair "SVID_ALERT0_CPU0_N:EU3P1.17:R3P1.1"
				( attribute "PROPAGATION_DELAY_MAX" "1000.00 MIL"
					( Units "uMaxMinProp" "ns" 1.000000)
					( Origin gBackEnd )
				)
			)
			( electricalCSetPinPair "SVID_ALERT0_CPU0_N:EU4D4.19:R4D67.1"
				( attribute "PROPAGATION_DELAY_MAX" "1000.00 MIL"
					( Units "uMaxMinProp" "ns" 1.000000)
					( Origin gBackEnd )
				)
			)
			( electricalCSetPinPair "SVID_ALERT0_CPU0_N:EU3P1.17:U5D1.DE44"
				( attribute "RELATIVE_PROPAGATION_DELAY_SCOPE" "G"
					( Parent
						( ecsetMatchGroupRef "SVID_ALERT0_CPU0_N:#SVID_CPU0_0_U36-EU109" )
					)
					( Origin gBackEnd )
				)
				( attribute "RELATIVE_PROPAGATION_DELAY" ",250.00 MIL"
					( Parent
						( ecsetMatchGroupRef "SVID_ALERT0_CPU0_N:#SVID_CPU0_0_U36-EU109" )
					)
					( Units "uMatchProp" "ns" 1.000000)
					( Origin gBackEnd )
				)
			)
			( electricalCSetPinPair "SVID_ALERT0_CPU0_N:EU4D4.19:U5D1.DE44"
				( attribute "RELATIVE_PROPAGATION_DELAY_SCOPE" "G"
					( Parent
						( ecsetMatchGroupRef "SVID_ALERT0_CPU0_N:#SVID_CPU0_0_U36-EU43" )
					)
					( Origin gBackEnd )
				)
				( attribute "RELATIVE_PROPAGATION_DELAY" ",250.00 MIL"
					( Parent
						( ecsetMatchGroupRef "SVID_ALERT0_CPU0_N:#SVID_CPU0_0_U36-EU43" )
					)
					( Units "uMatchProp" "ns" 1.000000)
					( Origin gBackEnd )
				)
			)
			( electricalCSetPinPair "SPI_NIC_SCLK:U9E1.6:EU9E1.13"
				( attribute "RELATIVE_PROPAGATION_DELAY_SCOPE" "G"
					( Parent
						( ecsetMatchGroupRef "SPI_NIC_SCLK:SPI_NIC" )
					)
					( Origin gBackEnd )
				)
				( attribute "RELATIVE_PROPAGATION_DELAY" "0.00 MIL,250.00 MIL"
					( Parent
						( ecsetMatchGroupRef "SPI_NIC_SCLK:SPI_NIC" )
					)
					( Units "uMatchProp" "ns" 1.000000)
					( Origin gBackEnd )
				)
			)
			( electricalCSetPinPair "SPI_CS0_PRIMARY_R_N:U8F1.9:U7F1.7"
				( attribute "RELATIVE_PROPAGATION_DELAY_SCOPE" "G"
					( Parent
						( ecsetMatchGroupRef "SPI_CS0_PRIMARY_R_N:SPI_MUX-U7F1" )
					)
					( Origin gBackEnd )
				)
				( attribute "RELATIVE_PROPAGATION_DELAY" "0.00 MIL,250.00 MIL"
					( Parent
						( ecsetMatchGroupRef "SPI_CS0_PRIMARY_R_N:SPI_MUX-U7F1" )
					)
					( Units "uMatchProp" "ns" 1.000000)
					( Origin gBackEnd )
				)
			)
			( electricalCSetPinPair "SPI_CS0_PRIMARY_R_N:U8F1.9:U3T1.7"
				( attribute "RELATIVE_PROPAGATION_DELAY_SCOPE" "G"
					( Parent
						( ecsetMatchGroupRef "SPI_CS0_PRIMARY_R_N:SPI_MUX-U3T1" )
					)
					( Origin gBackEnd )
				)
				( attribute "RELATIVE_PROPAGATION_DELAY" "0.00 MIL,250.00 MIL"
					( Parent
						( ecsetMatchGroupRef "SPI_CS0_PRIMARY_R_N:SPI_MUX-U3T1" )
					)
					( Units "uMatchProp" "ns" 1.000000)
					( Origin gBackEnd )
				)
			)
			( electricalCSetPinPair "SPI_PCH_IO2:U7C1.F5:U2T1.2"
				( attribute "RELATIVE_PROPAGATION_DELAY_SCOPE" "G"
					( Parent
						( ecsetMatchGroupRef "SPI_PCH_IO2:SPI_PCH-MUX" )
					)
					( Origin gBackEnd )
				)
				( attribute "RELATIVE_PROPAGATION_DELAY" "0.00 MIL,125.00 MIL"
					( Parent
						( ecsetMatchGroupRef "SPI_PCH_IO2:SPI_PCH-MUX" )
					)
					( Units "uMatchProp" "ns" 1.000000)
					( Origin gBackEnd )
				)
			)
			( electricalCSetPinPair "SPI_PCH_MOSI_R:U7C1.H4:U8F1.5"
				( attribute "RELATIVE_PROPAGATION_DELAY_SCOPE" "G"
					( Parent
						( ecsetMatchGroupRef "SPI_PCH_MOSI_R:SPI_PCH-MUX" )
					)
					( Origin gBackEnd )
				)
				( attribute "RELATIVE_PROPAGATION_DELAY" "0.00 MIL,125.00 MIL"
					( Parent
						( ecsetMatchGroupRef "SPI_PCH_MOSI_R:SPI_PCH-MUX" )
					)
					( Units "uMatchProp" "ns" 1.000000)
					( Origin gBackEnd )
				)
			)
			( electricalCSetPinPair "SPI_PCH_MOSI_R:U7C1.H4:J8E1.3"
				( attribute "RELATIVE_PROPAGATION_DELAY_SCOPE" "G"
					( Parent
						( ecsetMatchGroupRef "SPI_PCH_MOSI_R:SPI_PCH-TPM" )
					)
					( Origin gBackEnd )
				)
				( attribute "RELATIVE_PROPAGATION_DELAY" "0.00 MIL,250.00 MIL"
					( Parent
						( ecsetMatchGroupRef "SPI_PCH_MOSI_R:SPI_PCH-TPM" )
					)
					( Units "uMatchProp" "ns" 1.000000)
					( Origin gBackEnd )
				)
			)
			( electricalCSetPinPair "SPI_PCH_MISO_R:U7C1.L3:J8E1.4"
				( attribute "RELATIVE_PROPAGATION_DELAY_SCOPE" "G"
					( Parent
						( ecsetMatchGroupRef "SPI_PCH_MISO_R:SPI_PCH-TPM" )
					)
					( Origin gBackEnd )
				)
				( attribute "RELATIVE_PROPAGATION_DELAY" "0.00 MIL,250.00 MIL"
					( Parent
						( ecsetMatchGroupRef "SPI_PCH_MISO_R:SPI_PCH-TPM" )
					)
					( Units "uMatchProp" "ns" 1.000000)
					( Origin gBackEnd )
				)
			)
			( electricalCSetPinPair "SPI_PCH_MISO_R:U7C1.L3:U8F1.14"
				( attribute "RELATIVE_PROPAGATION_DELAY_SCOPE" "G"
					( Parent
						( ecsetMatchGroupRef "SPI_PCH_MISO_R:SPI_PCH-MUX" )
					)
					( Origin gBackEnd )
				)
				( attribute "RELATIVE_PROPAGATION_DELAY" "0.00 MIL,125.00 MIL"
					( Parent
						( ecsetMatchGroupRef "SPI_PCH_MISO_R:SPI_PCH-MUX" )
					)
					( Units "uMatchProp" "ns" 1.000000)
					( Origin gBackEnd )
				)
			)
			( electricalCSetPinPair "SPI_PCH_IO3:U7C1.L1:U2T1.5"
				( attribute "RELATIVE_PROPAGATION_DELAY_SCOPE" "G"
					( Parent
						( ecsetMatchGroupRef "SPI_PCH_IO3:SPI_PCH-MUX" )
					)
					( Origin gBackEnd )
				)
				( attribute "RELATIVE_PROPAGATION_DELAY" "0.00 MIL,125.00 MIL"
					( Parent
						( ecsetMatchGroupRef "SPI_PCH_IO3:SPI_PCH-MUX" )
					)
					( Units "uMatchProp" "ns" 1.000000)
					( Origin gBackEnd )
				)
			)
			( electricalCSetPinPair "SPI_PCH_TPM_CS_N:U7C1.K4:J8E1.5"
				( attribute "RELATIVE_PROPAGATION_DELAY_SCOPE" "L"
					( Parent
						( ecsetMatchGroupRef "SPI_PCH_TPM_CS_N:SPI_PCH-TPM" )
					)
					( Origin gBackEnd )
				)
				( attribute "RELATIVE_PROPAGATION_DELAY" "0.00 MIL,250.00 MIL"
					( Parent
						( ecsetMatchGroupRef "SPI_PCH_TPM_CS_N:SPI_PCH-TPM" )
					)
					( Units "uMatchProp" "ns" 1.000000)
					( Origin gBackEnd )
				)
			)
			( electricalCSetPinPair "SPI_PCH_CS0_R1_N:U7C1.J3:U8F1.11"
				( attribute "RELATIVE_PROPAGATION_DELAY_SCOPE" "G"
					( Parent
						( ecsetMatchGroupRef "SPI_PCH_CS0_R1_N:SPI_PCH-MUX" )
					)
					( Origin gBackEnd )
				)
				( attribute "RELATIVE_PROPAGATION_DELAY" "0.00 MIL,125.00 MIL"
					( Parent
						( ecsetMatchGroupRef "SPI_PCH_CS0_R1_N:SPI_PCH-MUX" )
					)
					( Units "uMatchProp" "ns" 1.000000)
					( Origin gBackEnd )
				)
			)
			( electricalCSetPinPair "SPI_PCH_CLK:U7C1.K2:J8E1.1"
				( attribute "RELATIVE_PROPAGATION_DELAY_SCOPE" "G"
					( Parent
						( ecsetMatchGroupRef "SPI_PCH_CLK:SPI_PCH-TPM" )
					)
					( Origin gBackEnd )
				)
				( attribute "RELATIVE_PROPAGATION_DELAY" "0.00 MIL,250.00 MIL"
					( Parent
						( ecsetMatchGroupRef "SPI_PCH_CLK:SPI_PCH-TPM" )
					)
					( Units "uMatchProp" "ns" 1.000000)
					( Origin gBackEnd )
				)
			)
			( electricalCSetPinPair "SPI_PCH_CLK:U8F1.2:U7C1.K2"
				( attribute "RELATIVE_PROPAGATION_DELAY_SCOPE" "G"
					( Parent
						( ecsetMatchGroupRef "SPI_PCH_CLK:SPI_PCH-MUX" )
					)
					( Origin gBackEnd )
				)
				( attribute "RELATIVE_PROPAGATION_DELAY" "0.00 MIL,125.00 MIL"
					( Parent
						( ecsetMatchGroupRef "SPI_PCH_CLK:SPI_PCH-MUX" )
					)
					( Units "uMatchProp" "ns" 1.000000)
					( Origin gBackEnd )
				)
			)
			( electricalCSetPinPair "SPI_PCH_CLK:R8E9.1:NET.T.1"
				( attribute "PROPAGATION_DELAY_MAX" "200.00 MIL"
					( Units "uMaxMinProp" "ns" 1.000000)
					( Origin gBackEnd )
				)
			)
			( electricalCSetPinPair "SPI_PCH_CLK:R8E9.2:J8E1.1"
				( attribute "PROPAGATION_DELAY_MAX" "4000.00 MIL"
					( Units "uMaxMinProp" "ns" 1.000000)
					( Origin gBackEnd )
				)
			)
			( electricalCSetPinPair "SPI_SWITCH_MOSI:U8F1.7:U7F1.15"
				( attribute "RELATIVE_PROPAGATION_DELAY_SCOPE" "G"
					( Parent
						( ecsetMatchGroupRef "SPI_SWITCH_MOSI:SPI_MUX-U7F1" )
					)
					( Origin gBackEnd )
				)
				( attribute "RELATIVE_PROPAGATION_DELAY" "0.00 MIL,125.00 MIL"
					( Parent
						( ecsetMatchGroupRef "SPI_SWITCH_MOSI:SPI_MUX-U7F1" )
					)
					( Units "uMatchProp" "ns" 1.000000)
					( Origin gBackEnd )
				)
			)
			( electricalCSetPinPair "SPI_SWITCH_MOSI:U8F1.7:U3T1.15"
				( attribute "RELATIVE_PROPAGATION_DELAY_SCOPE" "G"
					( Parent
						( ecsetMatchGroupRef "SPI_SWITCH_MOSI:SPI_MUX-U3T1" )
					)
					( Origin gBackEnd )
				)
				( attribute "RELATIVE_PROPAGATION_DELAY" "0.00 MIL,125.00 MIL"
					( Parent
						( ecsetMatchGroupRef "SPI_SWITCH_MOSI:SPI_MUX-U3T1" )
					)
					( Units "uMatchProp" "ns" 1.000000)
					( Origin gBackEnd )
				)
			)
			( electricalCSetPinPair "SPI_SWITCH_MISO:U7F1.8:U8F1.12"
				( attribute "RELATIVE_PROPAGATION_DELAY_SCOPE" "G"
					( Parent
						( ecsetMatchGroupRef "SPI_SWITCH_MISO:SPI_MUX-U7F1" )
					)
					( Origin gBackEnd )
				)
				( attribute "RELATIVE_PROPAGATION_DELAY" "0.00 MIL,125.00 MIL"
					( Parent
						( ecsetMatchGroupRef "SPI_SWITCH_MISO:SPI_MUX-U7F1" )
					)
					( Units "uMatchProp" "ns" 1.000000)
					( Origin gBackEnd )
				)
			)
			( electricalCSetPinPair "SPI_SWITCH_MISO:U8F1.12:U3T1.8"
				( attribute "RELATIVE_PROPAGATION_DELAY_SCOPE" "G"
					( Parent
						( ecsetMatchGroupRef "SPI_SWITCH_MISO:SPI_MUX-U3T1" )
					)
					( Origin gBackEnd )
				)
				( attribute "RELATIVE_PROPAGATION_DELAY" "0.00 MIL,125.00 MIL"
					( Parent
						( ecsetMatchGroupRef "SPI_SWITCH_MISO:SPI_MUX-U3T1" )
					)
					( Units "uMatchProp" "ns" 1.000000)
					( Origin gBackEnd )
				)
			)
			( electricalCSetPinPair "SPI_SWITCH_MISO:U3T1.8:R3T2.2"
				( attribute "PROPAGATION_DELAY_MAX" "4000.00 MIL"
					( Units "uMaxMinProp" "ns" 1.000000)
					( Origin gBackEnd )
				)
			)
			( electricalCSetPinPair "SPI_SWITCH_MISO:U7F1.8:R7F4.2"
				( attribute "PROPAGATION_DELAY_MAX" "4000.00 MIL"
					( Units "uMaxMinProp" "ns" 1.000000)
					( Origin gBackEnd )
				)
			)
			( electricalCSetPinPair "SPI_SWITCH_MISO:R3T2.1:NET.T.1"
				( attribute "PROPAGATION_DELAY_MAX" "200.00 MIL"
					( Units "uMaxMinProp" "ns" 1.000000)
					( Origin gBackEnd )
				)
			)
			( electricalCSetPinPair "SPI_SWITCH_MISO:R7F4.1:NET.T.1"
				( attribute "PROPAGATION_DELAY_MAX" "200.00 MIL"
					( Units "uMaxMinProp" "ns" 1.000000)
					( Origin gBackEnd )
				)
			)
			( electricalCSetPinPair "SPI_SWITCH_CLK:U8F1.4:U7F1.16"
				( attribute "RELATIVE_PROPAGATION_DELAY_SCOPE" "G"
					( Parent
						( ecsetMatchGroupRef "SPI_SWITCH_CLK:SPI_MUX-U7F1" )
					)
					( Origin gBackEnd )
				)
				( attribute "RELATIVE_PROPAGATION_DELAY" "0.00 MIL,125.00 MIL"
					( Parent
						( ecsetMatchGroupRef "SPI_SWITCH_CLK:SPI_MUX-U7F1" )
					)
					( Units "uMatchProp" "ns" 1.000000)
					( Origin gBackEnd )
				)
			)
			( electricalCSetPinPair "SPI_SWITCH_CLK:U8F1.4:U3T1.16"
				( attribute "RELATIVE_PROPAGATION_DELAY_SCOPE" "G"
					( Parent
						( ecsetMatchGroupRef "SPI_SWITCH_CLK:SPI_MUX-U3T1" )
					)
					( Origin gBackEnd )
				)
				( attribute "RELATIVE_PROPAGATION_DELAY" "0.00 MIL,125.00 MIL"
					( Parent
						( ecsetMatchGroupRef "SPI_SWITCH_CLK:SPI_MUX-U3T1" )
					)
					( Units "uMatchProp" "ns" 1.000000)
					( Origin gBackEnd )
				)
			)
			( electricalCSetPinPair "SPI_SWITCH_CLK:R8F7.2:U3T1.16"
				( attribute "PROPAGATION_DELAY_MAX" "4000.00 MIL"
					( Units "uMaxMinProp" "ns" 1.000000)
					( Origin gBackEnd )
				)
			)
			( electricalCSetPinPair "SPI_SWITCH_CLK:R8F7.1:NET.T.1"
				( attribute "PROPAGATION_DELAY_MAX" "200.00 MIL"
					( Units "uMaxMinProp" "ns" 1.000000)
					( Origin gBackEnd )
				)
			)
			( electricalCSetPinPair "SPI_SWITCH_CLK:R8F8.1:NET.T.1"
				( attribute "PROPAGATION_DELAY_MAX" "200.00 MIL"
					( Units "uMaxMinProp" "ns" 1.000000)
					( Origin gBackEnd )
				)
			)
			( electricalCSetPinPair "SPI_SWITCH_CLK:U7F1.16:R8F8.2"
				( attribute "PROPAGATION_DELAY_MAX" "4000.00 MIL"
					( Units "uMaxMinProp" "ns" 1.000000)
					( Origin gBackEnd )
				)
			)
			( electricalCSetPinPair "SPI_SWITCH_IO3:U2T1.7:U3T1.1"
				( attribute "RELATIVE_PROPAGATION_DELAY_SCOPE" "G"
					( Parent
						( ecsetMatchGroupRef "SPI_SWITCH_IO3:SPI_MUX-U3T1" )
					)
					( Origin gBackEnd )
				)
				( attribute "RELATIVE_PROPAGATION_DELAY" "0.00 MIL,125.00 MIL"
					( Parent
						( ecsetMatchGroupRef "SPI_SWITCH_IO3:SPI_MUX-U3T1" )
					)
					( Units "uMatchProp" "ns" 1.000000)
					( Origin gBackEnd )
				)
			)
			( electricalCSetPinPair "SPI_SWITCH_IO3:U2T1.7:U7F1.1"
				( attribute "RELATIVE_PROPAGATION_DELAY_SCOPE" "G"
					( Parent
						( ecsetMatchGroupRef "SPI_SWITCH_IO3:SPI_MUX-U7F1" )
					)
					( Origin gBackEnd )
				)
				( attribute "RELATIVE_PROPAGATION_DELAY" "0.00 MIL,125.00 MIL"
					( Parent
						( ecsetMatchGroupRef "SPI_SWITCH_IO3:SPI_MUX-U7F1" )
					)
					( Units "uMatchProp" "ns" 1.000000)
					( Origin gBackEnd )
				)
			)
			( electricalCSetPinPair "MEMHOT:U5D1.AH13:U9G1.6"
				( attribute "PROPAGATION_DELAY_MAX" "20500.00 MIL"
					( Units "uMaxMinProp" "ns" 1.000000)
					( Origin gBackEnd )
				)
			)
			( electricalCSetPinPair "MEMHOT:U5D1.AH13:R2U40.2"
				( attribute "PROPAGATION_DELAY_MAX" "2500.00 MIL"
					( Units "uMaxMinProp" "ns" 1.000000)
					( Origin gBackEnd )
				)
			)
			( electricalCSetPinPair "SGPIO_BMC:R1U14.2:U8D7.J1"
				( attribute "PROPAGATION_DELAY_MIN" "1000.00 MIL"
					( Units "uMaxMinProp" "ns" 1.000000)
					( Origin gBackEnd )
				)
				( attribute "PROPAGATION_DELAY_MAX" "15000.00 MIL"
					( Units "uMaxMinProp" "ns" 1.000000)
					( Origin gBackEnd )
				)
			)
			( electricalCSetPinPair "SGPIO_BMC:U9F4.J5:R1U14.1"
				( attribute "PROPAGATION_DELAY_MIN" "100.00 MIL"
					( Units "uMaxMinProp" "ns" 1.000000)
					( Origin gBackEnd )
				)
				( attribute "PROPAGATION_DELAY_MAX" "2000.00 MIL"
					( Units "uMaxMinProp" "ns" 1.000000)
					( Origin gBackEnd )
				)
			)
			( electricalCSetPinPair "SGPIO_BMC_DI:R2R6.2:U9F4.J3"
				( attribute "PROPAGATION_DELAY_MIN" "1000.00 MIL"
					( Units "uMaxMinProp" "ns" 1.000000)
					( Origin gBackEnd )
				)
				( attribute "PROPAGATION_DELAY_MAX" "15000.00 MIL"
					( Units "uMaxMinProp" "ns" 1.000000)
					( Origin gBackEnd )
				)
			)
			( electricalCSetPinPair "SGPIO_BMC_DI:U8D7.F8:R2R6.1"
				( attribute "PROPAGATION_DELAY_MIN" "100.00 MIL"
					( Units "uMaxMinProp" "ns" 1.000000)
					( Origin gBackEnd )
				)
				( attribute "PROPAGATION_DELAY_MAX" "2000.00 MIL"
					( Units "uMaxMinProp" "ns" 1.000000)
					( Origin gBackEnd )
				)
			)
			( electricalCSetPinPair "RMII_RX_NEW:U9F4.D8:U7C1.AN3"
				( attribute "PROPAGATION_DELAY_MIN" "1000.00 MIL"
					( Units "uMaxMinProp" "ns" 1.000000)
					( Origin gBackEnd )
				)
				( attribute "PROPAGATION_DELAY_MAX" "8000.00 MIL"
					( Units "uMaxMinProp" "ns" 1.000000)
					( Origin gBackEnd )
				)
			)
			( electricalCSetPinPair "JTAG_PCH:U9F4.F2:U8D7.A7"
				( attribute "RELATIVE_PROPAGATION_DELAY_SCOPE" "G"
					( Parent
						( ecsetMatchGroupRef "JTAG_PCH:MG_JTAG_PLD" )
					)
					( Origin gBackEnd )
				)
				( attribute "RELATIVE_PROPAGATION_DELAY" ",1000.00 MIL"
					( Parent
						( ecsetMatchGroupRef "JTAG_PCH:MG_JTAG_PLD" )
					)
					( Units "uMatchProp" "ns" 1.000000)
					( Origin gBackEnd )
				)
			)
			( electricalCSetPinPair "JTAG_PCH:U9F4.F2:U7C1.AL18"
				( attribute "RELATIVE_PROPAGATION_DELAY_SCOPE" "G"
					( Parent
						( ecsetMatchGroupRef "JTAG_PCH:MG_JTAG_PCH_PLD" )
					)
					( Origin gBackEnd )
				)
				( attribute "RELATIVE_PROPAGATION_DELAY" ",1000.00 MIL"
					( Parent
						( ecsetMatchGroupRef "JTAG_PCH:MG_JTAG_PCH_PLD" )
					)
					( Units "uMatchProp" "ns" 1.000000)
					( Origin gBackEnd )
				)
			)
			( electricalCSetPinPair "JTAG_PCH:U9F4.F2:U7C1.BV21"
				( attribute "RELATIVE_PROPAGATION_DELAY_SCOPE" "G"
					( Parent
						( ecsetMatchGroupRef "JTAG_PCH:MG_JTAG_PCH_GBE" )
					)
					( Origin gBackEnd )
				)
				( attribute "RELATIVE_PROPAGATION_DELAY" ",1000.00 MIL"
					( Parent
						( ecsetMatchGroupRef "JTAG_PCH:MG_JTAG_PCH_GBE" )
					)
					( Units "uMatchProp" "ns" 1.000000)
					( Origin gBackEnd )
				)
			)
			( electricalCSetPinPair "JTAG_PCH:J7G2.8:U9F4.F2"
				( attribute "PROPAGATION_DELAY_MAX" "24000.00 MIL"
					( Units "uMaxMinProp" "ns" 1.000000)
					( Origin gBackEnd )
				)
				( attribute "RELATIVE_PROPAGATION_DELAY_SCOPE" "G"
					( Parent
						( ecsetMatchGroupRef "JTAG_PCH:MG_JTAG" )
					)
					( Origin gBackEnd )
				)
				( attribute "RELATIVE_PROPAGATION_DELAY" ",1000.00 MIL"
					( Parent
						( ecsetMatchGroupRef "JTAG_PCH:MG_JTAG" )
					)
					( Units "uMatchProp" "ns" 1.000000)
					( Origin gBackEnd )
				)
			)
			( electricalCSetPinPair "JTAG_PCH:J7G2.8:U7C1.BV21"
				( attribute "PROPAGATION_DELAY_MAX" "24000.00 MIL"
					( Units "uMaxMinProp" "ns" 1.000000)
					( Origin gBackEnd )
				)
			)
			( electricalCSetPinPair "JTAG_PCH:J7G2.8:U7C1.AL18"
				( attribute "PROPAGATION_DELAY_MAX" "24000.00 MIL"
					( Units "uMaxMinProp" "ns" 1.000000)
					( Origin gBackEnd )
				)
			)
			( electricalCSetPinPair "JTAG_PCH:J7G2.8:U8D7.A7"
				( attribute "PROPAGATION_DELAY_MAX" "24000.00 MIL"
					( Units "uMaxMinProp" "ns" 1.000000)
					( Origin gBackEnd )
				)
			)
			( electricalCSetPinPair "JTAG_PCH:J7G2.8:R8G18.2"
				( attribute "PROPAGATION_DELAY_MAX" "1100.00 MIL"
					( Units "uMaxMinProp" "ns" 1.000000)
					( Origin gBackEnd )
				)
			)
			( electricalCSetPinPair "JTAG_PCH:J7G2.8:R8G17.2"
				( attribute "PROPAGATION_DELAY_MAX" "1100.00 MIL"
					( Units "uMaxMinProp" "ns" 1.000000)
					( Origin gBackEnd )
				)
			)
			( electricalCSetPinPair "JTAG_PCH:J7G2.8:R8G15.2"
				( attribute "PROPAGATION_DELAY_MAX" "1100.00 MIL"
					( Units "uMaxMinProp" "ns" 1.000000)
					( Origin gBackEnd )
				)
			)
			( electricalCSetPinPair "JTAG_PCH:J7G2.8:R8G16.2"
				( attribute "PROPAGATION_DELAY_MAX" "1100.00 MIL"
					( Units "uMaxMinProp" "ns" 1.000000)
					( Origin gBackEnd )
				)
			)
			( electricalCSetPinPair "JTAG_BMC:J7G2.8:R8G16.2"
				( attribute "PROPAGATION_DELAY_MAX" "1100.00 MIL"
					( Units "uMaxMinProp" "ns" 1.000000)
					( Origin gBackEnd )
				)
			)
			( electricalCSetPinPair "JTAG_BMC:J7G2.8:R8G15.2"
				( attribute "PROPAGATION_DELAY_MAX" "1100.00 MIL"
					( Units "uMaxMinProp" "ns" 1.000000)
					( Origin gBackEnd )
				)
			)
			( electricalCSetPinPair "JTAG_BMC:J7G2.8:R8G17.2"
				( attribute "PROPAGATION_DELAY_MAX" "1100.00 MIL"
					( Units "uMaxMinProp" "ns" 1.000000)
					( Origin gBackEnd )
				)
			)
			( electricalCSetPinPair "JTAG_BMC:J7G2.8:R8G18.2"
				( attribute "PROPAGATION_DELAY_MAX" "1100.00 MIL"
					( Units "uMaxMinProp" "ns" 1.000000)
					( Origin gBackEnd )
				)
			)
			( electricalCSetPinPair "JTAG_BMC:J7G2.8:U8D7.A7"
				( attribute "PROPAGATION_DELAY_MAX" "24000.00 MIL"
					( Units "uMaxMinProp" "ns" 1.000000)
					( Origin gBackEnd )
				)
			)
			( electricalCSetPinPair "JTAG_BMC:J7G2.8:U7C1.AL18"
				( attribute "PROPAGATION_DELAY_MAX" "24000.00 MIL"
					( Units "uMaxMinProp" "ns" 1.000000)
					( Origin gBackEnd )
				)
			)
			( electricalCSetPinPair "JTAG_BMC:J7G2.8:U7C1.BV21"
				( attribute "PROPAGATION_DELAY_MAX" "24000.00 MIL"
					( Units "uMaxMinProp" "ns" 1.000000)
					( Origin gBackEnd )
				)
			)
			( electricalCSetPinPair "JTAG_BMC:J7G2.8:U9F4.F2"
				( attribute "PROPAGATION_DELAY_MAX" "24000.00 MIL"
					( Units "uMaxMinProp" "ns" 1.000000)
					( Origin gBackEnd )
				)
			)
			( electricalCSetPinPair "JTAG_PCH_GBE_TRST_N:J7G2.4:R8G10.2"
				( attribute "PROPAGATION_DELAY_MAX" "1000.00 MIL"
					( Units "uMaxMinProp" "ns" 1.000000)
					( Origin gBackEnd )
				)
			)
			( electricalCSetPinPair "JTAG_PCH_GBE_TRST_N:J7G2.4:R8G9.2"
				( attribute "PROPAGATION_DELAY_MAX" "1000.00 MIL"
					( Units "uMaxMinProp" "ns" 1.000000)
					( Origin gBackEnd )
				)
			)
			( electricalCSetPinPair "JTAG_PCH_GBE_TRST_N:J7G2.4:U7C1.CA24"
				( attribute "PROPAGATION_DELAY_MAX" "24000.00 MIL"
					( Units "uMaxMinProp" "ns" 1.000000)
					( Origin gBackEnd )
				)
			)
			( electricalCSetPinPair "JTAG_PCH_GBE_TRST_N:J7G2.4:U9F4.E1"
				( attribute "PROPAGATION_DELAY_MAX" "24000.00 MIL"
					( Units "uMaxMinProp" "ns" 1.000000)
					( Origin gBackEnd )
				)
			)
			( electricalCSetPinPair "RMII_TX_1:U9F4.D9:R8F33.1"
				( attribute "PROPAGATION_DELAY_MAX" "500.00 MIL"
					( Units "uMaxMinProp" "ns" 1.000000)
					( Origin gBackEnd )
				)
			)
			( electricalCSetPinPair "RMII_TX_1:U9F4.D9:U7C1.AL3"
				( attribute "PROPAGATION_DELAY_MIN" "1000.00 MIL"
					( Units "uMaxMinProp" "ns" 1.000000)
					( Origin gBackEnd )
				)
				( attribute "PROPAGATION_DELAY_MAX" "8000.00 MIL"
					( Units "uMaxMinProp" "ns" 1.000000)
					( Origin gBackEnd )
				)
			)
			( electricalCSetPinPair "CLK_100M_BMC_PE_R_DN:U9F4.G21:U7C1.B29"
				( attribute "RELATIVE_PROPAGATION_DELAY_SCOPE" "G"
					( Parent
						( ecsetMatchGroupRef "CLK_100M_BMC_PE_R_DN:MG_CLK_G1-BCLK" )
					)
					( Origin gBackEnd )
				)
				( attribute "RELATIVE_PROPAGATION_DELAY" "0.00 MIL,5000.00 MIL"
					( Parent
						( ecsetMatchGroupRef "CLK_100M_BMC_PE_R_DN:MG_CLK_G1-BCLK" )
					)
					( Units "uMatchProp" "ns" 1.000000)
					( Origin gBackEnd )
				)
			)
			( electricalCSetPinPair "RMII_TX_NEW:U9F4.A10:U7C1.AM2"
				( attribute "PROPAGATION_DELAY_MIN" "1000.00 MIL"
					( Units "uMaxMinProp" "ns" 1.000000)
					( Origin gBackEnd )
				)
				( attribute "PROPAGATION_DELAY_MAX" "8000.00 MIL"
					( Units "uMaxMinProp" "ns" 1.000000)
					( Origin gBackEnd )
				)
			)
			( electricalCSetPinPair "RMII_TX:U9F4.A10:U7C1.AL1"
				( attribute "PROPAGATION_DELAY_MIN" "1000.00 MIL"
					( Units "uMaxMinProp" "ns" 1.000000)
					( Origin gBackEnd )
				)
				( attribute "PROPAGATION_DELAY_MAX" "8000.00 MIL"
					( Units "uMaxMinProp" "ns" 1.000000)
					( Origin gBackEnd )
				)
			)
			( electricalCSetPinPair "RMII_TX:U9F4.A10:R1T28.1"
				( attribute "PROPAGATION_DELAY_MAX" "500.00 MIL"
					( Units "uMaxMinProp" "ns" 1.000000)
					( Origin gBackEnd )
				)
			)
			( electricalCSetPinPair "RMII_RX:U9F4.A9:U7C1.AM2"
				( attribute "PROPAGATION_DELAY_MIN" "1000.00 MIL"
					( Units "uMaxMinProp" "ns" 1.000000)
					( Origin gBackEnd )
				)
				( attribute "PROPAGATION_DELAY_MAX" "8000.00 MIL"
					( Units "uMaxMinProp" "ns" 1.000000)
					( Origin gBackEnd )
				)
			)
			( electricalCSetPinPair "RMII_SPRNGVLLE_BMC_PCH_RXD0:EU9E1.6:R9E17.1"
				( attribute "PROPAGATION_DELAY_MIN" "0.00 MIL"
					( Units "uMaxMinProp" "ns" 1.000000)
					( Origin gBackEnd )
				)
				( attribute "PROPAGATION_DELAY_MAX" "500.00 MIL"
					( Units "uMaxMinProp" "ns" 1.000000)
					( Origin gBackEnd )
				)
			)
			( electricalCSetPinPair "RMII_SPRNGVLLE_BMC_PCH_RXD0:R3P3.2:U7C1.AL1"
				( attribute "PROPAGATION_DELAY_MIN" "0.00 MIL"
					( Units "uMaxMinProp" "ns" 1.000000)
					( Origin gBackEnd )
				)
				( attribute "PROPAGATION_DELAY_MAX" "500.00 MIL"
					( Units "uMaxMinProp" "ns" 1.000000)
					( Origin gBackEnd )
				)
			)
			( electricalCSetPinPair "RMII_SPRNGVLLE_BMC_PCH_RXD0:U9F4.A9:EU9E1.6"
				( attribute "PROPAGATION_DELAY_MIN" "1000.00 MIL"
					( Units "uMaxMinProp" "ns" 1.000000)
					( Origin gBackEnd )
				)
				( attribute "PROPAGATION_DELAY_MAX" "8000.00 MIL"
					( Units "uMaxMinProp" "ns" 1.000000)
					( Origin gBackEnd )
				)
			)
			( electricalCSetPinPair "RMII_SPRNGVLLE_BMC_PCH_RXD0:U9F4.A9:U7C1.AL1"
				( attribute "PROPAGATION_DELAY_MIN" "1000.00 MIL"
					( Units "uMaxMinProp" "ns" 1.000000)
					( Origin gBackEnd )
				)
				( attribute "PROPAGATION_DELAY_MAX" "8000.00 MIL"
					( Units "uMaxMinProp" "ns" 1.000000)
					( Origin gBackEnd )
				)
			)
			( electricalCSetPinPair "RMII_RX_1:U9F4.C8:U7C1.AH2"
				( attribute "PROPAGATION_DELAY_MIN" "8000.00 MIL"
					( Units "uMaxMinProp" "ns" 1.000000)
					( Origin gBackEnd )
				)
				( attribute "PROPAGATION_DELAY_MAX" "14000.00 MIL"
					( Units "uMaxMinProp" "ns" 1.000000)
					( Origin gBackEnd )
				)
			)
			( electricalCSetPinPair "FIVR:U5D1.AU14:U7D2.3"
				( attribute "PROPAGATION_DELAY_MAX" "13000.00 MIL"
					( Units "uMaxMinProp" "ns" 1.000000)
					( Origin gBackEnd )
				)
			)
			( electricalCSetPinPair "PCIE_CO_SATA:J8F1.41:C8F15.2"
				( attribute "RELATIVE_PROPAGATION_DELAY_SCOPE" "L"
					( Parent
						( ecsetMatchGroupRef "PCIE_CO_SATA:MG_PCIE_L0" )
					)
					( Origin gBackEnd )
				)
				( attribute "RELATIVE_PROPAGATION_DELAY" ",5.00 MIL"
					( Parent
						( ecsetMatchGroupRef "PCIE_CO_SATA:MG_PCIE_L0" )
					)
					( Units "uMatchProp" "ns" 1.000000)
					( Origin gBackEnd )
				)
			)
			( electricalCSetPinPair "PCIE_CO_SATA:U7C1.BA71:C8F15.1"
				( attribute "RELATIVE_PROPAGATION_DELAY_SCOPE" "L"
					( Parent
						( ecsetMatchGroupRef "PCIE_CO_SATA:MG_PCIE_L1" )
					)
					( Origin gBackEnd )
				)
				( attribute "RELATIVE_PROPAGATION_DELAY" ",5.00 MIL"
					( Parent
						( ecsetMatchGroupRef "PCIE_CO_SATA:MG_PCIE_L1" )
					)
					( Units "uMatchProp" "ns" 1.000000)
					( Origin gBackEnd )
				)
			)
			( electricalCSetPinPair "PCIE_CO_SATA:J8F1.41:U7C1.BA71"
				( attribute "PROPAGATION_DELAY_MAX" "16000.00 MIL"
					( Units "uMaxMinProp" "ns" 1.000000)
					( Origin gBackEnd )
				)
				( attribute "RELATIVE_PROPAGATION_DELAY_SCOPE" "L"
					( Parent
						( ecsetMatchGroupRef "PCIE_CO_SATA:MG_PCIE_ALL0" )
					)
					( Origin gBackEnd )
				)
				( attribute "RELATIVE_PROPAGATION_DELAY" ",5.00 MIL"
					( Parent
						( ecsetMatchGroupRef "PCIE_CO_SATA:MG_PCIE_ALL0" )
					)
					( Units "uMatchProp" "ns" 1.000000)
					( Origin gBackEnd )
				)
			)
			( electricalCSetPinPair "CLK_100M_MEZZ_&_SLOT:U7C1.J33:J8G1.35"
				( attribute "RELATIVE_PROPAGATION_DELAY_SCOPE" "G"
					( Parent
						( ecsetMatchGroupRef "CLK_100M_MEZZ_&_SLOT:MG_CLK_G2-BCLK" )
					)
					( Origin gBackEnd )
				)
				( attribute "RELATIVE_PROPAGATION_DELAY" "4975.98 MIL,5000.00 MIL"
					( Parent
						( ecsetMatchGroupRef "CLK_100M_MEZZ_&_SLOT:MG_CLK_G2-BCLK" )
					)
					( Units "uMatchProp" "ns" 1.000000)
					( Origin gBackEnd )
				)
			)
			( electricalCSetPinPair "SFI:J9C1.13:U7C1.BH31"
				( attribute "PROPAGATION_DELAY_MIN" "3000 ns"
					( Units "uMaxMinProp" "ns" 1.000000)
					( Origin gBackEnd )
				)
				( attribute "PROPAGATION_DELAY_MAX" "5000.00 MIL"
					( Units "uMaxMinProp" "ns" 1.000000)
					( Origin gBackEnd )
				)
			)
			( electricalCSetPinPair "CLK_100M_CPU1_MCP_DN:EU4D2.64:U2D1.BB25"
				( attribute "RELATIVE_PROPAGATION_DELAY_SCOPE" "G"
					( Parent
						( ecsetMatchGroupRef "CLK_100M_CPU1_MCP_DN:MG_CLK_G1-BCLK" )
					)
					( Origin gBackEnd )
				)
				( attribute "RELATIVE_PROPAGATION_DELAY" "0.00 MIL,5000.00 MIL"
					( Parent
						( ecsetMatchGroupRef "CLK_100M_CPU1_MCP_DN:MG_CLK_G1-BCLK" )
					)
					( Units "uMatchProp" "ns" 1.000000)
					( Origin gBackEnd )
				)
			)
			( electricalCSetPinPair "XDP_CPU_TCK0:U2D1.AA14:R7P29.1"
				( attribute "PROPAGATION_DELAY_MAX" "1100.00 MIL"
					( Units "uMaxMinProp" "ns" 1.000000)
					( Origin gBackEnd )
				)
			)
			( electricalCSetPinPair "XDP_CPU_TCK0:U7C1.AF54:R3M10.1"
				( attribute "PROPAGATION_DELAY_MAX" "1100.00 MIL"
					( Units "uMaxMinProp" "ns" 1.000000)
					( Origin gBackEnd )
				)
			)
			( electricalCSetPinPair "XDP_CPU_TCK0:J9A3.57:U2D1.AA14"
				( attribute "PROPAGATION_DELAY_MAX" "24000.00 MIL"
					( Units "uMaxMinProp" "ns" 1.000000)
					( Origin gBackEnd )
				)
			)
			( electricalCSetPinPair "PMSYNC:U7C1.U13:R3N9.1"
				( attribute "PROPAGATION_DELAY_MAX" "2100.00 MIL"
					( Units "uMaxMinProp" "ns" 1.000000)
					( Origin gBackEnd )
				)
			)
			( electricalCSetPinPair "PMSYNC:U5D1.AR14:R4P18.1"
				( attribute "PROPAGATION_DELAY_MAX" "2500.00 MIL"
					( Units "uMaxMinProp" "ns" 1.000000)
					( Origin gBackEnd )
				)
			)
			( electricalCSetPinPair "PMSYNC:U2D1.AR14:R7P25.1"
				( attribute "PROPAGATION_DELAY_MAX" "2500.00 MIL"
					( Units "uMaxMinProp" "ns" 1.000000)
					( Origin gBackEnd )
				)
			)
			( electricalCSetPinPair "PCIE_C_D:J8G1.102:R2U29.1"
				( attribute "RELATIVE_PROPAGATION_DELAY_SCOPE" "L"
					( Parent
						( ecsetMatchGroupRef "PCIE_C_D:MG_PCIE_L0" )
					)
					( Origin gBackEnd )
				)
				( attribute "RELATIVE_PROPAGATION_DELAY" ",5.00 MIL"
					( Parent
						( ecsetMatchGroupRef "PCIE_C_D:MG_PCIE_L0" )
					)
					( Units "uMatchProp" "ns" 1.000000)
					( Origin gBackEnd )
				)
			)
			( electricalCSetPinPair "PCIE_C_D:U7C1.P59:R3641.1"
				( attribute "RELATIVE_PROPAGATION_DELAY_SCOPE" "L"
					( Parent
						( ecsetMatchGroupRef "PCIE_C_D:MG_PCIE_L1" )
					)
					( Origin gBackEnd )
				)
				( attribute "RELATIVE_PROPAGATION_DELAY" ",5.00 MIL"
					( Parent
						( ecsetMatchGroupRef "PCIE_C_D:MG_PCIE_L1" )
					)
					( Units "uMatchProp" "ns" 1.000000)
					( Origin gBackEnd )
				)
			)
			( electricalCSetPinPair "PCIE_C_D:U5D1.DM9:R2U29.1"
				( attribute "RELATIVE_PROPAGATION_DELAY_SCOPE" "L"
					( Parent
						( ecsetMatchGroupRef "PCIE_C_D:MG_PCIE_L2" )
					)
					( Origin gBackEnd )
				)
				( attribute "RELATIVE_PROPAGATION_DELAY" ",5.00 MIL"
					( Parent
						( ecsetMatchGroupRef "PCIE_C_D:MG_PCIE_L2" )
					)
					( Units "uMatchProp" "ns" 1.000000)
					( Origin gBackEnd )
				)
			)
			( electricalCSetPinPair "PCIE_C_D:U5D1.DM9:J8G1.102"
				( attribute "PROPAGATION_DELAY_MIN" "3000.00 MIL"
					( Units "uMaxMinProp" "ns" 1.000000)
					( Origin gBackEnd )
				)
				( attribute "PROPAGATION_DELAY_MAX" "16000.00 MIL"
					( Units "uMaxMinProp" "ns" 1.000000)
					( Origin gBackEnd )
				)
				( attribute "RELATIVE_PROPAGATION_DELAY_SCOPE" "L"
					( Parent
						( ecsetMatchGroupRef "PCIE_C_D:MG_PCIE_ALL0" )
					)
					( Origin gBackEnd )
				)
				( attribute "RELATIVE_PROPAGATION_DELAY" ",5.00 MIL"
					( Parent
						( ecsetMatchGroupRef "PCIE_C_D:MG_PCIE_ALL0" )
					)
					( Units "uMatchProp" "ns" 1.000000)
					( Origin gBackEnd )
				)
			)
			( electricalCSetPinPair "PCIE_C_D:U5D1.DM9:U7C1.P59"
				( attribute "PROPAGATION_DELAY_MIN" "3000.00 MIL"
					( Units "uMaxMinProp" "ns" 1.000000)
					( Origin gBackEnd )
				)
				( attribute "PROPAGATION_DELAY_MAX" "17000.00 MIL"
					( Units "uMaxMinProp" "ns" 1.000000)
					( Origin gBackEnd )
				)
				( attribute "RELATIVE_PROPAGATION_DELAY_SCOPE" "L"
					( Parent
						( ecsetMatchGroupRef "PCIE_C_D:MG_PCIE_ALL1" )
					)
					( Origin gBackEnd )
				)
				( attribute "RELATIVE_PROPAGATION_DELAY" ",5.00 MIL"
					( Parent
						( ecsetMatchGroupRef "PCIE_C_D:MG_PCIE_ALL1" )
					)
					( Units "uMatchProp" "ns" 1.000000)
					( Origin gBackEnd )
				)
			)
			( electricalCSetPinPair "DMI:U7C1.H46:C3M44.1"
				( attribute "RELATIVE_PROPAGATION_DELAY_SCOPE" "L"
					( Parent
						( ecsetMatchGroupRef "DMI:MG_DMI_L0" )
					)
					( Origin gBackEnd )
				)
				( attribute "RELATIVE_PROPAGATION_DELAY" ",5.00 MIL"
					( Parent
						( ecsetMatchGroupRef "DMI:MG_DMI_L0" )
					)
					( Units "uMatchProp" "ns" 1.000000)
					( Origin gBackEnd )
				)
			)
			( electricalCSetPinPair "DMI:C3M44.2:U5D1.CK9"
				( attribute "RELATIVE_PROPAGATION_DELAY_SCOPE" "L"
					( Parent
						( ecsetMatchGroupRef "DMI:MG_DMI_L1" )
					)
					( Origin gBackEnd )
				)
				( attribute "RELATIVE_PROPAGATION_DELAY" ",5.00 MIL"
					( Parent
						( ecsetMatchGroupRef "DMI:MG_DMI_L1" )
					)
					( Units "uMatchProp" "ns" 1.000000)
					( Origin gBackEnd )
				)
			)
			( electricalCSetPinPair "DMI:U7C1.H46:U5D1.CK9"
				( attribute "PROPAGATION_DELAY_MAX" "15000.00 MIL"
					( Units "uMaxMinProp" "ns" 1.000000)
					( Origin gBackEnd )
				)
			)
			( electricalCSetPinPair "PCIE_DEVICE:U5D1.DW4:U7C1.A59"
				( attribute "PROPAGATION_DELAY_MIN" "3000.00 MIL"
					( Units "uMaxMinProp" "ns" 1.000000)
					( Origin gBackEnd )
				)
				( attribute "PROPAGATION_DELAY_MAX" "17000.00 MIL"
					( Units "uMaxMinProp" "ns" 1.000000)
					( Origin gBackEnd )
				)
				( attribute "RELATIVE_PROPAGATION_DELAY_SCOPE" "N"
					( Parent
						( ecsetMatchGroupRef "PCIE_DEVICE:MG" )
					)
					( Origin gBackEnd )
				)
				( attribute "RELATIVE_PROPAGATION_DELAY" ",500.00 MIL"
					( Parent
						( ecsetMatchGroupRef "PCIE_DEVICE:MG" )
					)
					( Units "uMatchProp" "ns" 1.000000)
					( Origin gBackEnd )
				)
			)
			( electricalCSetPinPair "PCIE_DEVICE:U5D1.DW4:C6B15.1"
				( attribute "RELATIVE_PROPAGATION_DELAY_SCOPE" "L"
					( Parent
						( ecsetMatchGroupRef "PCIE_DEVICE:MG_PCIE_L1" )
					)
					( Origin gBackEnd )
				)
				( attribute "RELATIVE_PROPAGATION_DELAY" ",5.00 MIL"
					( Parent
						( ecsetMatchGroupRef "PCIE_DEVICE:MG_PCIE_L1" )
					)
					( Units "uMatchProp" "ns" 1.000000)
					( Origin gBackEnd )
				)
			)
			( electricalCSetPinPair "PCIE_DEVICE:C6B15.2:U7C1.A59"
				( attribute "RELATIVE_PROPAGATION_DELAY_SCOPE" "L"
					( Parent
						( ecsetMatchGroupRef "PCIE_DEVICE:MG_PCIE_L0" )
					)
					( Origin gBackEnd )
				)
				( attribute "RELATIVE_PROPAGATION_DELAY" ",5.00 MIL"
					( Parent
						( ecsetMatchGroupRef "PCIE_DEVICE:MG_PCIE_L0" )
					)
					( Units "uMatchProp" "ns" 1.000000)
					( Origin gBackEnd )
				)
			)
			( electricalCSetPinPair "CLK_100M_CPU_BCLKS:U5D1.AU24:EU4D2.18"
				( attribute "PROPAGATION_DELAY_MIN" "4000.00 MIL"
					( Units "uMaxMinProp" "ns" 1.000000)
					( Origin gBackEnd )
				)
				( attribute "PROPAGATION_DELAY_MAX" "16000.00 MIL"
					( Units "uMaxMinProp" "ns" 1.000000)
					( Origin gBackEnd )
				)
				( attribute "RELATIVE_PROPAGATION_DELAY_SCOPE" "C"
					( Parent
						( ecsetMatchGroupRef "CLK_100M_CPU_BCLKS:MG" )
					)
					( Origin gBackEnd )
				)
				( attribute "RELATIVE_PROPAGATION_DELAY" ",500.00 MIL"
					( Parent
						( ecsetMatchGroupRef "CLK_100M_CPU_BCLKS:MG" )
					)
					( Units "uMatchProp" "ns" 1.000000)
					( Origin gBackEnd )
				)
			)
			( electricalCSetPinPair "UPI_CPU1_CPU0_P1P1:U5D1.BH3:U2D1.AC10"
				( attribute "RELATIVE_PROPAGATION_DELAY_SCOPE" "N"
					( Parent
						( ecsetMatchGroupRef "UPI_CPU1_CPU0_P1P1:MG_KTI_BUNDLE" )
					)
					( Origin gBackEnd )
				)
				( attribute "RELATIVE_PROPAGATION_DELAY" ",500.00 MIL"
					( Parent
						( ecsetMatchGroupRef "UPI_CPU1_CPU0_P1P1:MG_KTI_BUNDLE" )
					)
					( Units "uMatchProp" "ns" 1.000000)
					( Origin gBackEnd )
				)
				( attribute "RELATIVE_PROPAGATION_DELAY_SCOPE" "G"
					( Parent
						( ecsetMatchGroupRef "UPI_CPU1_CPU0_P1P1:MG_KTI_CPU1_CPU0_P1P1" )
					)
					( Origin gBackEnd )
				)
				( attribute "RELATIVE_PROPAGATION_DELAY" "-1055.00 MIL,1055.00 MIL"
					( Parent
						( ecsetMatchGroupRef "UPI_CPU1_CPU0_P1P1:MG_KTI_CPU1_CPU0_P1P1" )
					)
					( Units "uMatchProp" "ns" 1.000000)
					( Origin gBackEnd )
				)
			)
			( electricalCSetPinPair "UPI_CPU1_CPU0_P0P0:U5D1.BH3:U2D1.AC10"
				( attribute "RELATIVE_PROPAGATION_DELAY_SCOPE" "N"
					( Parent
						( ecsetMatchGroupRef "UPI_CPU1_CPU0_P0P0:MG_KTI_BUNDLE" )
					)
					( Origin gBackEnd )
				)
				( attribute "RELATIVE_PROPAGATION_DELAY" ",500.00 MIL"
					( Parent
						( ecsetMatchGroupRef "UPI_CPU1_CPU0_P0P0:MG_KTI_BUNDLE" )
					)
					( Units "uMatchProp" "ns" 1.000000)
					( Origin gBackEnd )
				)
				( attribute "RELATIVE_PROPAGATION_DELAY_SCOPE" "G"
					( Parent
						( ecsetMatchGroupRef "UPI_CPU1_CPU0_P0P0:MG_KTI_CPU1_CPU0_P0P0" )
					)
					( Origin gBackEnd )
				)
				( attribute "RELATIVE_PROPAGATION_DELAY" "-1315.00 MIL,1315.00 MIL"
					( Parent
						( ecsetMatchGroupRef "UPI_CPU1_CPU0_P0P0:MG_KTI_CPU1_CPU0_P0P0" )
					)
					( Units "uMatchProp" "ns" 1.000000)
					( Origin gBackEnd )
				)
			)
			( electricalCSetPinPair "UPI_CPU0_CPU1_P1P1:U5D1.BH3:U2D1.AC10"
				( attribute "RELATIVE_PROPAGATION_DELAY_SCOPE" "N"
					( Parent
						( ecsetMatchGroupRef "UPI_CPU0_CPU1_P1P1:MG_KTI_BUNDLE" )
					)
					( Origin gBackEnd )
				)
				( attribute "RELATIVE_PROPAGATION_DELAY" ",500.00 MIL"
					( Parent
						( ecsetMatchGroupRef "UPI_CPU0_CPU1_P1P1:MG_KTI_BUNDLE" )
					)
					( Units "uMatchProp" "ns" 1.000000)
					( Origin gBackEnd )
				)
				( attribute "RELATIVE_PROPAGATION_DELAY_SCOPE" "G"
					( Parent
						( ecsetMatchGroupRef "UPI_CPU0_CPU1_P1P1:MG_KTI_CPU0_CPU1_P1P1" )
					)
					( Origin gBackEnd )
				)
				( attribute "RELATIVE_PROPAGATION_DELAY" "-1315.00 MIL,1315.00 MIL"
					( Parent
						( ecsetMatchGroupRef "UPI_CPU0_CPU1_P1P1:MG_KTI_CPU0_CPU1_P1P1" )
					)
					( Units "uMatchProp" "ns" 1.000000)
					( Origin gBackEnd )
				)
			)
			( electricalCSetPinPair "UPI_CPU0_CPU1_P0P0:U5D1.BH3:U2D1.AC10"
				( attribute "RELATIVE_PROPAGATION_DELAY_SCOPE" "N"
					( Parent
						( ecsetMatchGroupRef "UPI_CPU0_CPU1_P0P0:MG_KTI_BUNDLE" )
					)
					( Origin gBackEnd )
				)
				( attribute "RELATIVE_PROPAGATION_DELAY" ",500.00 MIL"
					( Parent
						( ecsetMatchGroupRef "UPI_CPU0_CPU1_P0P0:MG_KTI_BUNDLE" )
					)
					( Units "uMatchProp" "ns" 1.000000)
					( Origin gBackEnd )
				)
				( attribute "RELATIVE_PROPAGATION_DELAY_SCOPE" "G"
					( Parent
						( ecsetMatchGroupRef "UPI_CPU0_CPU1_P0P0:MG_KTI_CPU0_CPU1_P0P0" )
					)
					( Origin gBackEnd )
				)
				( attribute "RELATIVE_PROPAGATION_DELAY" "-1055.00 MIL,1055.00 MIL"
					( Parent
						( ecsetMatchGroupRef "UPI_CPU0_CPU1_P0P0:MG_KTI_CPU0_CPU1_P0P0" )
					)
					( Units "uMatchProp" "ns" 1.000000)
					( Origin gBackEnd )
				)
			)
			( electricalCSetPinPair "DDR_CTRL_DLL14-19:U5D1.G52:J4G1.84"
				( attribute "RELATIVE_PROPAGATION_DELAY_SCOPE" "N"
					( Parent
						( ecsetMatchGroupRef "DDR_CTRL_DLL14-19:MG_DDR_CTRL" )
					)
					( Origin gBackEnd )
				)
				( attribute "RELATIVE_PROPAGATION_DELAY" "0.00 MIL,25.00 MIL"
					( Parent
						( ecsetMatchGroupRef "DDR_CTRL_DLL14-19:MG_DDR_CTRL" )
					)
					( Units "uMatchProp" "ns" 1.000000)
					( Origin gBackEnd )
				)
				( attribute "RELATIVE_PROPAGATION_DELAY_SCOPE" "C"
					( Parent
						( ecsetMatchGroupRef "DDR_CTRL_DLL14-19:MG_DDR_FAR_DIMM-CLK0" )
					)
					( Origin gBackEnd )
				)
				( attribute "RELATIVE_PROPAGATION_DELAY" "0.00 MIL,300.00 MIL"
					( Parent
						( ecsetMatchGroupRef "DDR_CTRL_DLL14-19:MG_DDR_FAR_DIMM-CLK0" )
					)
					( Units "uMatchProp" "ns" 1.000000)
					( Origin gBackEnd )
				)
			)
			( electricalCSetPinPair "DDR_F_CMD_DLL1-13:U5D1.F51:J6L1.228"
				( attribute "RELATIVE_PROPAGATION_DELAY_SCOPE" "C"
					( Parent
						( ecsetMatchGroupRef "DDR_F_CMD_DLL1-13:MG_DDR_NEAR_DIMM-CLK1" )
					)
					( Origin gBackEnd )
				)
				( attribute "RELATIVE_PROPAGATION_DELAY" "0.00 MIL,700.00 MIL"
					( Parent
						( ecsetMatchGroupRef "DDR_F_CMD_DLL1-13:MG_DDR_NEAR_DIMM-CLK1" )
					)
					( Units "uMatchProp" "ns" 1.000000)
					( Origin gBackEnd )
				)
				( attribute "RELATIVE_PROPAGATION_DELAY_SCOPE" "N"
					( Parent
						( ecsetMatchGroupRef "DDR_F_CMD_DLL1-13:MG_DDR_CMD_NEAR_DIMM" )
					)
					( Origin gBackEnd )
				)
				( attribute "RELATIVE_PROPAGATION_DELAY" "0.00 MIL,25.00 MIL"
					( Parent
						( ecsetMatchGroupRef "DDR_F_CMD_DLL1-13:MG_DDR_CMD_NEAR_DIMM" )
					)
					( Units "uMatchProp" "ns" 1.000000)
					( Origin gBackEnd )
				)
			)
			( electricalCSetPinPair "DDR_F_CMD_DLL1-13:U5D1.F51:J4A1.228"
				( attribute "RELATIVE_PROPAGATION_DELAY_SCOPE" "N"
					( Parent
						( ecsetMatchGroupRef "DDR_F_CMD_DLL1-13:MG_DDR_FAR_DIMM_CMD" )
					)
					( Origin gBackEnd )
				)
				( attribute "RELATIVE_PROPAGATION_DELAY" "0.00 MIL,25.00 MIL"
					( Parent
						( ecsetMatchGroupRef "DDR_F_CMD_DLL1-13:MG_DDR_FAR_DIMM_CMD" )
					)
					( Units "uMatchProp" "ns" 1.000000)
					( Origin gBackEnd )
				)
				( attribute "RELATIVE_PROPAGATION_DELAY_SCOPE" "C"
					( Parent
						( ecsetMatchGroupRef "DDR_F_CMD_DLL1-13:MG_DDR_FAR_DIMM-CLK0" )
					)
					( Origin gBackEnd )
				)
				( attribute "RELATIVE_PROPAGATION_DELAY" "0.00 MIL,700.00 MIL"
					( Parent
						( ecsetMatchGroupRef "DDR_F_CMD_DLL1-13:MG_DDR_FAR_DIMM-CLK0" )
					)
					( Units "uMatchProp" "ns" 1.000000)
					( Origin gBackEnd )
				)
			)
			( electricalCSetPinPair "DDR_E_CMD_DLL1-13:U5D1.F51:J6L2.228"
				( attribute "RELATIVE_PROPAGATION_DELAY_SCOPE" "C"
					( Parent
						( ecsetMatchGroupRef "DDR_E_CMD_DLL1-13:MG_DDR_NEAR_DIMM-CLK1" )
					)
					( Origin gBackEnd )
				)
				( attribute "RELATIVE_PROPAGATION_DELAY" "0.00 MIL,700.00 MIL"
					( Parent
						( ecsetMatchGroupRef "DDR_E_CMD_DLL1-13:MG_DDR_NEAR_DIMM-CLK1" )
					)
					( Units "uMatchProp" "ns" 1.000000)
					( Origin gBackEnd )
				)
				( attribute "RELATIVE_PROPAGATION_DELAY_SCOPE" "N"
					( Parent
						( ecsetMatchGroupRef "DDR_E_CMD_DLL1-13:MG_DDR_CMD_NEAR_DIMM" )
					)
					( Origin gBackEnd )
				)
				( attribute "RELATIVE_PROPAGATION_DELAY" "0.00 MIL,25.00 MIL"
					( Parent
						( ecsetMatchGroupRef "DDR_E_CMD_DLL1-13:MG_DDR_CMD_NEAR_DIMM" )
					)
					( Units "uMatchProp" "ns" 1.000000)
					( Origin gBackEnd )
				)
			)
			( electricalCSetPinPair "DDR_E_CMD_DLL1-13:U5D1.F51:J4A2.228"
				( attribute "RELATIVE_PROPAGATION_DELAY_SCOPE" "N"
					( Parent
						( ecsetMatchGroupRef "DDR_E_CMD_DLL1-13:MG_DDR_FAR_DIMM_CMD" )
					)
					( Origin gBackEnd )
				)
				( attribute "RELATIVE_PROPAGATION_DELAY" "0.00 MIL,25.00 MIL"
					( Parent
						( ecsetMatchGroupRef "DDR_E_CMD_DLL1-13:MG_DDR_FAR_DIMM_CMD" )
					)
					( Units "uMatchProp" "ns" 1.000000)
					( Origin gBackEnd )
				)
				( attribute "RELATIVE_PROPAGATION_DELAY_SCOPE" "C"
					( Parent
						( ecsetMatchGroupRef "DDR_E_CMD_DLL1-13:MG_DDR_FAR_DIMM-CLK0" )
					)
					( Origin gBackEnd )
				)
				( attribute "RELATIVE_PROPAGATION_DELAY" "0.00 MIL,700.00 MIL"
					( Parent
						( ecsetMatchGroupRef "DDR_E_CMD_DLL1-13:MG_DDR_FAR_DIMM-CLK0" )
					)
					( Units "uMatchProp" "ns" 1.000000)
					( Origin gBackEnd )
				)
			)
			( electricalCSetPinPair "DDR_D_CMD_DLL1-13:U5D1.F51:J6M1.228"
				( attribute "RELATIVE_PROPAGATION_DELAY_SCOPE" "C"
					( Parent
						( ecsetMatchGroupRef "DDR_D_CMD_DLL1-13:MG_DDR_NEAR_DIMM-CLK1" )
					)
					( Origin gBackEnd )
				)
				( attribute "RELATIVE_PROPAGATION_DELAY" "0.00 MIL,700.00 MIL"
					( Parent
						( ecsetMatchGroupRef "DDR_D_CMD_DLL1-13:MG_DDR_NEAR_DIMM-CLK1" )
					)
					( Units "uMatchProp" "ns" 1.000000)
					( Origin gBackEnd )
				)
				( attribute "RELATIVE_PROPAGATION_DELAY_SCOPE" "N"
					( Parent
						( ecsetMatchGroupRef "DDR_D_CMD_DLL1-13:MG_DDR_CMD_NEAR_DIMM" )
					)
					( Origin gBackEnd )
				)
				( attribute "RELATIVE_PROPAGATION_DELAY" "0.00 MIL,25.00 MIL"
					( Parent
						( ecsetMatchGroupRef "DDR_D_CMD_DLL1-13:MG_DDR_CMD_NEAR_DIMM" )
					)
					( Units "uMatchProp" "ns" 1.000000)
					( Origin gBackEnd )
				)
			)
			( electricalCSetPinPair "DDR_D_CMD_DLL1-13:U5D1.F51:J4B1.228"
				( attribute "RELATIVE_PROPAGATION_DELAY_SCOPE" "N"
					( Parent
						( ecsetMatchGroupRef "DDR_D_CMD_DLL1-13:MG_DDR_FAR_DIMM_CMD" )
					)
					( Origin gBackEnd )
				)
				( attribute "RELATIVE_PROPAGATION_DELAY" "0.00 MIL,25.00 MIL"
					( Parent
						( ecsetMatchGroupRef "DDR_D_CMD_DLL1-13:MG_DDR_FAR_DIMM_CMD" )
					)
					( Units "uMatchProp" "ns" 1.000000)
					( Origin gBackEnd )
				)
				( attribute "RELATIVE_PROPAGATION_DELAY_SCOPE" "C"
					( Parent
						( ecsetMatchGroupRef "DDR_D_CMD_DLL1-13:MG_DDR_FAR_DIMM-CLK0" )
					)
					( Origin gBackEnd )
				)
				( attribute "RELATIVE_PROPAGATION_DELAY" "0.00 MIL,700.00 MIL"
					( Parent
						( ecsetMatchGroupRef "DDR_D_CMD_DLL1-13:MG_DDR_FAR_DIMM-CLK0" )
					)
					( Units "uMatchProp" "ns" 1.000000)
					( Origin gBackEnd )
				)
			)
			( electricalCSetPinPair "DDR_DQS:U5D1.AJ84:J4G1.152"
				( attribute "RELATIVE_PROPAGATION_DELAY_SCOPE" "N"
					( Parent
						( ecsetMatchGroupRef "DDR_DQS:MG_DQ-DQS_FAR_DIMM" )
					)
					( Origin gBackEnd )
				)
				( attribute "RELATIVE_PROPAGATION_DELAY" ",5.00 MIL"
					( Parent
						( ecsetMatchGroupRef "DDR_DQS:MG_DQ-DQS_FAR_DIMM" )
					)
					( Units "uMatchProp" "ns" 1.000000)
					( Origin gBackEnd )
				)
			)
			( electricalCSetPinPair "DDR_DQS:U5D1.AJ84:J6T1.152"
				( attribute "RELATIVE_PROPAGATION_DELAY_SCOPE" "N"
					( Parent
						( ecsetMatchGroupRef "DDR_DQS:MG_DQ-DQS_NEAR_DIMM" )
					)
					( Origin gBackEnd )
				)
				( attribute "RELATIVE_PROPAGATION_DELAY" ",5.00 MIL"
					( Parent
						( ecsetMatchGroupRef "DDR_DQS:MG_DQ-DQS_NEAR_DIMM" )
					)
					( Units "uMatchProp" "ns" 1.000000)
					( Origin gBackEnd )
				)
			)
			( electricalCSetPinPair "DDR_A_CMD_DLL1-13:U5D1.F51:J6T1.228"
				( attribute "RELATIVE_PROPAGATION_DELAY_SCOPE" "N"
					( Parent
						( ecsetMatchGroupRef "DDR_A_CMD_DLL1-13:MG_DDR_CMD_NEAR_DIMM" )
					)
					( Origin gBackEnd )
				)
				( attribute "RELATIVE_PROPAGATION_DELAY" "0.00 MIL,25.00 MIL"
					( Parent
						( ecsetMatchGroupRef "DDR_A_CMD_DLL1-13:MG_DDR_CMD_NEAR_DIMM" )
					)
					( Units "uMatchProp" "ns" 1.000000)
					( Origin gBackEnd )
				)
				( attribute "RELATIVE_PROPAGATION_DELAY_SCOPE" "C"
					( Parent
						( ecsetMatchGroupRef "DDR_A_CMD_DLL1-13:MG_DDR_NEAR_DIMM-CLK1" )
					)
					( Origin gBackEnd )
				)
				( attribute "RELATIVE_PROPAGATION_DELAY" "0.00 MIL,700.00 MIL"
					( Parent
						( ecsetMatchGroupRef "DDR_A_CMD_DLL1-13:MG_DDR_NEAR_DIMM-CLK1" )
					)
					( Units "uMatchProp" "ns" 1.000000)
					( Origin gBackEnd )
				)
			)
			( electricalCSetPinPair "DDR_A_CMD_DLL1-13:U5D1.F51:J4G1.228"
				( attribute "RELATIVE_PROPAGATION_DELAY_SCOPE" "C"
					( Parent
						( ecsetMatchGroupRef "DDR_A_CMD_DLL1-13:MG_DDR_FAR_DIMM-CLK0" )
					)
					( Origin gBackEnd )
				)
				( attribute "RELATIVE_PROPAGATION_DELAY" "0.00 MIL,700.00 MIL"
					( Parent
						( ecsetMatchGroupRef "DDR_A_CMD_DLL1-13:MG_DDR_FAR_DIMM-CLK0" )
					)
					( Units "uMatchProp" "ns" 1.000000)
					( Origin gBackEnd )
				)
				( attribute "RELATIVE_PROPAGATION_DELAY_SCOPE" "N"
					( Parent
						( ecsetMatchGroupRef "DDR_A_CMD_DLL1-13:MG_DDR_FAR_DIMM_CMD" )
					)
					( Origin gBackEnd )
				)
				( attribute "RELATIVE_PROPAGATION_DELAY" "0.00 MIL,25.00 MIL"
					( Parent
						( ecsetMatchGroupRef "DDR_A_CMD_DLL1-13:MG_DDR_FAR_DIMM_CMD" )
					)
					( Units "uMatchProp" "ns" 1.000000)
					( Origin gBackEnd )
				)
			)
			( electricalCSetPinPair "DDR_DQ_NEW:U5D1.AN86:J6T1.5"
				( attribute "RELATIVE_PROPAGATION_DELAY_SCOPE" "N"
					( Parent
						( ecsetMatchGroupRef "DDR_DQ_NEW:MG_DQ_NEAR_DIMM" )
					)
					( Origin gBackEnd )
				)
				( attribute "RELATIVE_PROPAGATION_DELAY" "-50.00 MIL,50.00 MIL"
					( Parent
						( ecsetMatchGroupRef "DDR_DQ_NEW:MG_DQ_NEAR_DIMM" )
					)
					( Units "uMatchProp" "ns" 1.000000)
					( Origin gBackEnd )
				)
				( attribute "RELATIVE_PROPAGATION_DELAY_SCOPE" "N"
					( Parent
						( ecsetMatchGroupRef "DDR_DQ_NEW:MG_DQ-DQS_NEAR_DIMM" )
					)
					( Origin gBackEnd )
				)
				( attribute "RELATIVE_PROPAGATION_DELAY" "0.00 MIL,195.00 MIL"
					( Parent
						( ecsetMatchGroupRef "DDR_DQ_NEW:MG_DQ-DQS_NEAR_DIMM" )
					)
					( Units "uMatchProp" "ns" 1.000000)
					( Origin gBackEnd )
				)
			)
			( electricalCSetPinPair "DDR_DQ_NEW:U5D1.AN86:J4G1.5"
				( attribute "RELATIVE_PROPAGATION_DELAY_SCOPE" "N"
					( Parent
						( ecsetMatchGroupRef "DDR_DQ_NEW:MG_DQ_FAR_DIMM" )
					)
					( Origin gBackEnd )
				)
				( attribute "RELATIVE_PROPAGATION_DELAY" "-50.00 MIL,50.00 MIL"
					( Parent
						( ecsetMatchGroupRef "DDR_DQ_NEW:MG_DQ_FAR_DIMM" )
					)
					( Units "uMatchProp" "ns" 1.000000)
					( Origin gBackEnd )
				)
				( attribute "RELATIVE_PROPAGATION_DELAY_SCOPE" "N"
					( Parent
						( ecsetMatchGroupRef "DDR_DQ_NEW:MG_DQ-DQS_FAR_DIMM" )
					)
					( Origin gBackEnd )
				)
				( attribute "RELATIVE_PROPAGATION_DELAY" "0.00 MIL,195.00 MIL"
					( Parent
						( ecsetMatchGroupRef "DDR_DQ_NEW:MG_DQ-DQS_FAR_DIMM" )
					)
					( Units "uMatchProp" "ns" 1.000000)
					( Origin gBackEnd )
				)
			)
			( electricalCSetPinPair "DDR_CTRL_DLL20-24:U5D1.B51:J6T1.84"
				( attribute "RELATIVE_PROPAGATION_DELAY_SCOPE" "N"
					( Parent
						( ecsetMatchGroupRef "DDR_CTRL_DLL20-24:MG_DDR_CTRL" )
					)
					( Origin gBackEnd )
				)
				( attribute "RELATIVE_PROPAGATION_DELAY" "0.00 MIL,25.00 MIL"
					( Parent
						( ecsetMatchGroupRef "DDR_CTRL_DLL20-24:MG_DDR_CTRL" )
					)
					( Units "uMatchProp" "ns" 1.000000)
					( Origin gBackEnd )
				)
				( attribute "RELATIVE_PROPAGATION_DELAY_SCOPE" "C"
					( Parent
						( ecsetMatchGroupRef "DDR_CTRL_DLL20-24:MG_DDR_NEAR_DIMM-CLK1" )
					)
					( Origin gBackEnd )
				)
				( attribute "RELATIVE_PROPAGATION_DELAY" "0.00 MIL,300.00 MIL"
					( Parent
						( ecsetMatchGroupRef "DDR_CTRL_DLL20-24:MG_DDR_NEAR_DIMM-CLK1" )
					)
					( Units "uMatchProp" "ns" 1.000000)
					( Origin gBackEnd )
				)
			)
			( electricalCSetPinPair "DDR_B_CMD_DLL1-13:U5D1.F51:J6U1.228"
				( attribute "RELATIVE_PROPAGATION_DELAY_SCOPE" "C"
					( Parent
						( ecsetMatchGroupRef "DDR_B_CMD_DLL1-13:MG_DDR_NEAR_DIMM-CLK1" )
					)
					( Origin gBackEnd )
				)
				( attribute "RELATIVE_PROPAGATION_DELAY" "0.00 MIL,700.00 MIL"
					( Parent
						( ecsetMatchGroupRef "DDR_B_CMD_DLL1-13:MG_DDR_NEAR_DIMM-CLK1" )
					)
					( Units "uMatchProp" "ns" 1.000000)
					( Origin gBackEnd )
				)
				( attribute "RELATIVE_PROPAGATION_DELAY_SCOPE" "N"
					( Parent
						( ecsetMatchGroupRef "DDR_B_CMD_DLL1-13:MG_DDR_CMD_NEAR_DIMM" )
					)
					( Origin gBackEnd )
				)
				( attribute "RELATIVE_PROPAGATION_DELAY" "0.00 MIL,25.00 MIL"
					( Parent
						( ecsetMatchGroupRef "DDR_B_CMD_DLL1-13:MG_DDR_CMD_NEAR_DIMM" )
					)
					( Units "uMatchProp" "ns" 1.000000)
					( Origin gBackEnd )
				)
			)
			( electricalCSetPinPair "DDR_B_CMD_DLL1-13:U5D1.F51:J4G2.228"
				( attribute "RELATIVE_PROPAGATION_DELAY_SCOPE" "N"
					( Parent
						( ecsetMatchGroupRef "DDR_B_CMD_DLL1-13:MG_DDR_FAR_DIMM_CMD" )
					)
					( Origin gBackEnd )
				)
				( attribute "RELATIVE_PROPAGATION_DELAY" "0.00 MIL,25.00 MIL"
					( Parent
						( ecsetMatchGroupRef "DDR_B_CMD_DLL1-13:MG_DDR_FAR_DIMM_CMD" )
					)
					( Units "uMatchProp" "ns" 1.000000)
					( Origin gBackEnd )
				)
				( attribute "RELATIVE_PROPAGATION_DELAY_SCOPE" "C"
					( Parent
						( ecsetMatchGroupRef "DDR_B_CMD_DLL1-13:MG_DDR_FAR_DIMM-CLK0" )
					)
					( Origin gBackEnd )
				)
				( attribute "RELATIVE_PROPAGATION_DELAY" "0.00 MIL,700.00 MIL"
					( Parent
						( ecsetMatchGroupRef "DDR_B_CMD_DLL1-13:MG_DDR_FAR_DIMM-CLK0" )
					)
					( Units "uMatchProp" "ns" 1.000000)
					( Origin gBackEnd )
				)
			)
			( electricalCSetPinPair "DDR_C_CMD_DLL1-13:U5D1.F51:J6U2.228"
				( attribute "RELATIVE_PROPAGATION_DELAY_SCOPE" "C"
					( Parent
						( ecsetMatchGroupRef "DDR_C_CMD_DLL1-13:MG_DDR_NEAR_DIMM-CLK1" )
					)
					( Origin gBackEnd )
				)
				( attribute "RELATIVE_PROPAGATION_DELAY" "0.00 MIL,700.00 MIL"
					( Parent
						( ecsetMatchGroupRef "DDR_C_CMD_DLL1-13:MG_DDR_NEAR_DIMM-CLK1" )
					)
					( Units "uMatchProp" "ns" 1.000000)
					( Origin gBackEnd )
				)
				( attribute "RELATIVE_PROPAGATION_DELAY_SCOPE" "N"
					( Parent
						( ecsetMatchGroupRef "DDR_C_CMD_DLL1-13:MG_DDR_CMD_NEAR_DIMM" )
					)
					( Origin gBackEnd )
				)
				( attribute "RELATIVE_PROPAGATION_DELAY" "0.00 MIL,25.00 MIL"
					( Parent
						( ecsetMatchGroupRef "DDR_C_CMD_DLL1-13:MG_DDR_CMD_NEAR_DIMM" )
					)
					( Units "uMatchProp" "ns" 1.000000)
					( Origin gBackEnd )
				)
			)
			( electricalCSetPinPair "DDR_C_CMD_DLL1-13:U5D1.F51:J4G3.228"
				( attribute "RELATIVE_PROPAGATION_DELAY_SCOPE" "N"
					( Parent
						( ecsetMatchGroupRef "DDR_C_CMD_DLL1-13:MG_DDR_FAR_DIMM_CMD" )
					)
					( Origin gBackEnd )
				)
				( attribute "RELATIVE_PROPAGATION_DELAY" "0.00 MIL,25.00 MIL"
					( Parent
						( ecsetMatchGroupRef "DDR_C_CMD_DLL1-13:MG_DDR_FAR_DIMM_CMD" )
					)
					( Units "uMatchProp" "ns" 1.000000)
					( Origin gBackEnd )
				)
				( attribute "RELATIVE_PROPAGATION_DELAY_SCOPE" "C"
					( Parent
						( ecsetMatchGroupRef "DDR_C_CMD_DLL1-13:MG_DDR_FAR_DIMM-CLK0" )
					)
					( Origin gBackEnd )
				)
				( attribute "RELATIVE_PROPAGATION_DELAY" "0.00 MIL,700.00 MIL"
					( Parent
						( ecsetMatchGroupRef "DDR_C_CMD_DLL1-13:MG_DDR_FAR_DIMM-CLK0" )
					)
					( Units "uMatchProp" "ns" 1.000000)
					( Origin gBackEnd )
				)
			)
			( electricalCSetPinPair "PCIE_SLOT_C:J8G1.195:C7G5.2"
				( attribute "RELATIVE_PROPAGATION_DELAY_SCOPE" "L"
					( Parent
						( ecsetMatchGroupRef "PCIE_SLOT_C:MG_PCIE_L0" )
					)
					( Origin gBackEnd )
				)
				( attribute "RELATIVE_PROPAGATION_DELAY" ",5.00 MIL"
					( Parent
						( ecsetMatchGroupRef "PCIE_SLOT_C:MG_PCIE_L0" )
					)
					( Units "uMatchProp" "ns" 1.000000)
					( Origin gBackEnd )
				)
			)
			( electricalCSetPinPair "PCIE_SLOT_C:U5D1.BK5:C7G5.1"
				( attribute "RELATIVE_PROPAGATION_DELAY_SCOPE" "L"
					( Parent
						( ecsetMatchGroupRef "PCIE_SLOT_C:MG_PCIE_L1" )
					)
					( Origin gBackEnd )
				)
				( attribute "RELATIVE_PROPAGATION_DELAY" ",5.00 MIL"
					( Parent
						( ecsetMatchGroupRef "PCIE_SLOT_C:MG_PCIE_L1" )
					)
					( Units "uMatchProp" "ns" 1.000000)
					( Origin gBackEnd )
				)
			)
			( electricalCSetPinPair "PCIE_SLOT_C:U5D1.BK5:J8G1.195"
				( attribute "PROPAGATION_DELAY_MIN" "3000.00 MIL"
					( Units "uMaxMinProp" "ns" 1.000000)
					( Origin gBackEnd )
				)
				( attribute "PROPAGATION_DELAY_MAX" "16000.00 MIL"
					( Units "uMaxMinProp" "ns" 1.000000)
					( Origin gBackEnd )
				)
				( attribute "RELATIVE_PROPAGATION_DELAY_SCOPE" "N"
					( Parent
						( ecsetMatchGroupRef "PCIE_SLOT_C:MG" )
					)
					( Origin gBackEnd )
				)
				( attribute "RELATIVE_PROPAGATION_DELAY" ",500.00 MIL"
					( Parent
						( ecsetMatchGroupRef "PCIE_SLOT_C:MG" )
					)
					( Units "uMatchProp" "ns" 1.000000)
					( Origin gBackEnd )
				)
			)
			( electricalCSetPinPair "PCIE_SLOT_C_A:J8G1.195:C7G5.2"
				( attribute "RELATIVE_PROPAGATION_DELAY_SCOPE" "L"
					( Parent
						( ecsetMatchGroupRef "PCIE_SLOT_C_A:MG_PCIE_L0" )
					)
					( Origin gBackEnd )
				)
				( attribute "RELATIVE_PROPAGATION_DELAY" ",5.00 MIL"
					( Parent
						( ecsetMatchGroupRef "PCIE_SLOT_C_A:MG_PCIE_L0" )
					)
					( Units "uMatchProp" "ns" 1.000000)
					( Origin gBackEnd )
				)
			)
			( electricalCSetPinPair "PCIE_SLOT_C_A:U5D1.BK5:C7G5.1"
				( attribute "RELATIVE_PROPAGATION_DELAY_SCOPE" "L"
					( Parent
						( ecsetMatchGroupRef "PCIE_SLOT_C_A:MG_PCIE_L1" )
					)
					( Origin gBackEnd )
				)
				( attribute "RELATIVE_PROPAGATION_DELAY" ",5.00 MIL"
					( Parent
						( ecsetMatchGroupRef "PCIE_SLOT_C_A:MG_PCIE_L1" )
					)
					( Units "uMatchProp" "ns" 1.000000)
					( Origin gBackEnd )
				)
			)
			( electricalCSetPinPair "PCIE_SLOT_C_A:U5D1.BK5:J8G1.195"
				( attribute "PROPAGATION_DELAY_MIN" "3000.00 MIL"
					( Units "uMaxMinProp" "ns" 1.000000)
					( Origin gBackEnd )
				)
				( attribute "PROPAGATION_DELAY_MAX" "16000.00 MIL"
					( Units "uMaxMinProp" "ns" 1.000000)
					( Origin gBackEnd )
				)
			)
			( electricalCSetPinPair "PCIE_SLOT:U5D1.CT9:J8G1.106"
				( attribute "PROPAGATION_DELAY_MIN" "3000.00 MIL"
					( Units "uMaxMinProp" "ns" 1.000000)
					( Origin gBackEnd )
				)
				( attribute "PROPAGATION_DELAY_MAX" "16000.00 MIL"
					( Units "uMaxMinProp" "ns" 1.000000)
					( Origin gBackEnd )
				)
				( attribute "RELATIVE_PROPAGATION_DELAY_SCOPE" "N"
					( Parent
						( ecsetMatchGroupRef "PCIE_SLOT:MG" )
					)
					( Origin gBackEnd )
				)
				( attribute "RELATIVE_PROPAGATION_DELAY" ",500.00 MIL"
					( Parent
						( ecsetMatchGroupRef "PCIE_SLOT:MG" )
					)
					( Units "uMatchProp" "ns" 1.000000)
					( Origin gBackEnd )
				)
			)
			( electricalCSetPinPair "PCIE_SLOT_A:U5D1.CT9:J8G1.106"
				( attribute "PROPAGATION_DELAY_MIN" "3000.00 MIL"
					( Units "uMaxMinProp" "ns" 1.000000)
					( Origin gBackEnd )
				)
				( attribute "PROPAGATION_DELAY_MAX" "16000.00 MIL"
					( Units "uMaxMinProp" "ns" 1.000000)
					( Origin gBackEnd )
				)
			)
			( electricalCSetPinPair "SVID_ALERT1_CPU0_N:EU7A5.17:U5D1.DL44"
				( attribute "RELATIVE_PROPAGATION_DELAY_SCOPE" "G"
					( Parent
						( ecsetMatchGroupRef "SVID_ALERT1_CPU0_N:#SVID_CPU1_0_U36-EU75" )
					)
					( Origin gBackEnd )
				)
				( attribute "RELATIVE_PROPAGATION_DELAY" ",250.00 MIL"
					( Parent
						( ecsetMatchGroupRef "SVID_ALERT1_CPU0_N:#SVID_CPU1_0_U36-EU75" )
					)
					( Units "uMatchProp" "ns" 1.000000)
					( Origin gBackEnd )
				)
			)
			( electricalCSetPinPair "SVID_ALERT1_CPU0_N:EU7G1.17:U5D1.DL44"
				( attribute "RELATIVE_PROPAGATION_DELAY_SCOPE" "G"
					( Parent
						( ecsetMatchGroupRef "SVID_ALERT1_CPU0_N:#SVID_CPU1_0_U36-EU21" )
					)
					( Origin gBackEnd )
				)
				( attribute "RELATIVE_PROPAGATION_DELAY" ",250.00 MIL"
					( Parent
						( ecsetMatchGroupRef "SVID_ALERT1_CPU0_N:#SVID_CPU1_0_U36-EU21" )
					)
					( Units "uMatchProp" "ns" 1.000000)
					( Origin gBackEnd )
				)
			)
			( electricalCSetPinPair "SVID_ALERT1_CPU0_N:U5D1.DL44:R6B3.1"
				( attribute "PROPAGATION_DELAY_MAX" "4500.00 MIL"
					( Units "uMaxMinProp" "ns" 1.000000)
					( Origin gBackEnd )
				)
			)
			( electricalCSetPinPair "SVID_ALERT1_CPU0_N:R6B1.2:R6B3.2"
				( attribute "PROPAGATION_DELAY_MAX" "400.00 MIL"
					( Units "uMaxMinProp" "ns" 1.000000)
					( Origin gBackEnd )
				)
			)
			( electricalCSetPinPair "SVID_ALERT1_CPU0_N:EU7A5.17:R7A11.1"
				( attribute "PROPAGATION_DELAY_MAX" "1000.00 MIL"
					( Units "uMaxMinProp" "ns" 1.000000)
					( Origin gBackEnd )
				)
			)
			( electricalCSetPinPair "SVID_ALERT1_CPU0_N:EU7G1.17:R7G4.1"
				( attribute "PROPAGATION_DELAY_MAX" "1000.00 MIL"
					( Units "uMaxMinProp" "ns" 1.000000)
					( Origin gBackEnd )
				)
			)
			( electricalCSetPinPair "SVID_ALERT1_CPU0_N:R7G4.2:R6B3.2"
				( attribute "PROPAGATION_DELAY_MAX" "27000.00 MIL"
					( Units "uMaxMinProp" "ns" 1.000000)
					( Origin gBackEnd )
				)
			)
			( electricalCSetPinPair "SVID_CLK1_CPU0:U5D1.DG44:R7G24.1"
				( attribute "PROPAGATION_DELAY_MAX" "27000.00 MIL"
					( Units "uMaxMinProp" "ns" 1.000000)
					( Origin gBackEnd )
				)
			)
			( electricalCSetPinPair "SVID_CLK1_CPU0:U5D1.DG44:R6B5.1"
				( attribute "PROPAGATION_DELAY_MAX" "4500.00 MIL"
					( Units "uMaxMinProp" "ns" 1.000000)
					( Origin gBackEnd )
				)
			)
			( electricalCSetPinPair "SVID_CLK1_CPU0:R7A17.2:R3L13.2"
				( attribute "PROPAGATION_DELAY_MAX" "200.00 MIL"
					( Units "uMaxMinProp" "ns" 1.000000)
					( Origin gBackEnd )
				)
			)
			( electricalCSetPinPair "SVID_CLK1_CPU0:EU7A5.15:R7A17.1"
				( attribute "PROPAGATION_DELAY_MAX" "1000.00 MIL"
					( Units "uMaxMinProp" "ns" 1.000000)
					( Origin gBackEnd )
				)
			)
			( electricalCSetPinPair "SVID_CLK1_CPU0:EU7G1.15:R7G24.2"
				( attribute "PROPAGATION_DELAY_MAX" "1000.00 MIL"
					( Units "uMaxMinProp" "ns" 1.000000)
					( Origin gBackEnd )
				)
			)
			( electricalCSetPinPair "SVID_CLK1_CPU0:U5D1.DG44:EU7A5.15"
				( attribute "RELATIVE_PROPAGATION_DELAY_SCOPE" "G"
					( Parent
						( ecsetMatchGroupRef "SVID_CLK1_CPU0:#SVID_CPU1_0_U36-EU75" )
					)
					( Origin gBackEnd )
				)
				( attribute "RELATIVE_PROPAGATION_DELAY" ",250.00 MIL"
					( Parent
						( ecsetMatchGroupRef "SVID_CLK1_CPU0:#SVID_CPU1_0_U36-EU75" )
					)
					( Units "uMatchProp" "ns" 1.000000)
					( Origin gBackEnd )
				)
			)
			( electricalCSetPinPair "SVID_CLK1_CPU0:U5D1.DG44:EU7G1.15"
				( attribute "RELATIVE_PROPAGATION_DELAY_SCOPE" "G"
					( Parent
						( ecsetMatchGroupRef "SVID_CLK1_CPU0:#SVID_CPU1_0_U36-EU21" )
					)
					( Origin gBackEnd )
				)
				( attribute "RELATIVE_PROPAGATION_DELAY" ",250.00 MIL"
					( Parent
						( ecsetMatchGroupRef "SVID_CLK1_CPU0:#SVID_CPU1_0_U36-EU21" )
					)
					( Units "uMatchProp" "ns" 1.000000)
					( Origin gBackEnd )
				)
			)
			( electricalCSetPinPair "CLK_100M_CPU_MCP_&_REFCLK:EU4D2.39:U5D1.BB25"
				( attribute "RELATIVE_PROPAGATION_DELAY_SCOPE" "G"
					( Parent
						( ecsetMatchGroupRef "CLK_100M_CPU_MCP_&_REFCLK:MG_CLK_G1-BCLK" )
					)
					( Origin gBackEnd )
				)
				( attribute "RELATIVE_PROPAGATION_DELAY" "0.00 MIL,5000.00 MIL"
					( Parent
						( ecsetMatchGroupRef "CLK_100M_CPU_MCP_&_REFCLK:MG_CLK_G1-BCLK" )
					)
					( Units "uMatchProp" "ns" 1.000000)
					( Origin gBackEnd )
				)
			)
			( electricalCSetPinPair "SVID_DIO1_CPU0:EU7A5.16:U5D1.DJ44"
				( attribute "RELATIVE_PROPAGATION_DELAY_SCOPE" "G"
					( Parent
						( ecsetMatchGroupRef "SVID_DIO1_CPU0:#SVID_CPU1_0_U36-EU75" )
					)
					( Origin gBackEnd )
				)
				( attribute "RELATIVE_PROPAGATION_DELAY" ",250.00 MIL"
					( Parent
						( ecsetMatchGroupRef "SVID_DIO1_CPU0:#SVID_CPU1_0_U36-EU75" )
					)
					( Units "uMatchProp" "ns" 1.000000)
					( Origin gBackEnd )
				)
			)
			( electricalCSetPinPair "SVID_DIO1_CPU0:EU7G1.16:U5D1.DJ44"
				( attribute "RELATIVE_PROPAGATION_DELAY_SCOPE" "G"
					( Parent
						( ecsetMatchGroupRef "SVID_DIO1_CPU0:#SVID_CPU1_0_U36-EU21" )
					)
					( Origin gBackEnd )
				)
				( attribute "RELATIVE_PROPAGATION_DELAY" ",250.00 MIL"
					( Parent
						( ecsetMatchGroupRef "SVID_DIO1_CPU0:#SVID_CPU1_0_U36-EU21" )
					)
					( Units "uMatchProp" "ns" 1.000000)
					( Origin gBackEnd )
				)
			)
			( electricalCSetPinPair "SVID_DIO1_CPU0:U5D1.DJ44:R6B4.1"
				( attribute "PROPAGATION_DELAY_MAX" "4500.00 MIL"
					( Units "uMaxMinProp" "ns" 1.000000)
					( Origin gBackEnd )
				)
			)
			( electricalCSetPinPair "SVID_DIO1_CPU0:R7A12.2:R3L11.2"
				( attribute "PROPAGATION_DELAY_MAX" "200.00 MIL"
					( Units "uMaxMinProp" "ns" 1.000000)
					( Origin gBackEnd )
				)
			)
			( electricalCSetPinPair "SVID_DIO1_CPU0:R6B2.2:R6B4.2"
				( attribute "PROPAGATION_DELAY_MAX" "400.00 MIL"
					( Units "uMaxMinProp" "ns" 1.000000)
					( Origin gBackEnd )
				)
			)
			( electricalCSetPinPair "SVID_DIO1_CPU0:R3U2.2:R7G2.2"
				( attribute "PROPAGATION_DELAY_MAX" "2000.00 MIL"
					( Units "uMaxMinProp" "ns" 1.000000)
					( Origin gBackEnd )
				)
			)
			( electricalCSetPinPair "SVID_DIO1_CPU0:EU7A5.16:R7A12.1"
				( attribute "PROPAGATION_DELAY_MAX" "1000.00 MIL"
					( Units "uMaxMinProp" "ns" 1.000000)
					( Origin gBackEnd )
				)
			)
			( electricalCSetPinPair "SVID_DIO1_CPU0:EU7G1.16:R7G2.1"
				( attribute "PROPAGATION_DELAY_MAX" "1000.00 MIL"
					( Units "uMaxMinProp" "ns" 1.000000)
					( Origin gBackEnd )
				)
			)
			( electricalCSetPinPair "SVID_DIO1_CPU0:R7A12.1:R7G2.2"
				( attribute "PROPAGATION_DELAY_MAX" "27000.00 MIL"
					( Units "uMaxMinProp" "ns" 1.000000)
					( Origin gBackEnd )
				)
			)
			( electricalCSetPinPair "CATERR:R4R2.2:NET.T.1"
				( attribute "PROPAGATION_DELAY_MAX" "10000.00 MIL"
					( Units "uMaxMinProp" "ns" 1.000000)
					( Origin gBackEnd )
				)
			)
			( electricalCSetPinPair "CATERR:R4R2.2:U5D1.AL14"
				( attribute "PROPAGATION_DELAY_MAX" "2500.00 MIL"
					( Units "uMaxMinProp" "ns" 1.000000)
					( Origin gBackEnd )
				)
			)
			( electricalCSetPinPair "CATERR:R7P18.2:NET.T.1"
				( attribute "PROPAGATION_DELAY_MAX" "10000.00 MIL"
					( Units "uMaxMinProp" "ns" 1.000000)
					( Origin gBackEnd )
				)
			)
			( electricalCSetPinPair "CATERR:U2T4.2:NET.T.1"
				( attribute "PROPAGATION_DELAY_MAX" "500.00 MIL"
					( Units "uMaxMinProp" "ns" 1.000000)
					( Origin gBackEnd )
				)
			)
			( electricalCSetPinPair "CATERR:U2D1.AL14:R7P18.2"
				( attribute "PROPAGATION_DELAY_MAX" "2500.00 MIL"
					( Units "uMaxMinProp" "ns" 1.000000)
					( Origin gBackEnd )
				)
			)
			( electricalCSetPinPair "SVID_CLK1_CPU1:U2D1.DG44:EU1G2.15"
				( attribute "RELATIVE_PROPAGATION_DELAY_SCOPE" "G"
					( Parent
						( ecsetMatchGroupRef "SVID_CLK1_CPU1:#SVID_CPU1_1_U100-EU76" )
					)
					( Origin gBackEnd )
				)
				( attribute "RELATIVE_PROPAGATION_DELAY" ",250.00 MIL"
					( Parent
						( ecsetMatchGroupRef "SVID_CLK1_CPU1:#SVID_CPU1_1_U100-EU76" )
					)
					( Units "uMatchProp" "ns" 1.000000)
					( Origin gBackEnd )
				)
			)
			( electricalCSetPinPair "SVID_CLK1_CPU1:U2D1.DG44:EU1B1.15"
				( attribute "RELATIVE_PROPAGATION_DELAY_SCOPE" "G"
					( Parent
						( ecsetMatchGroupRef "SVID_CLK1_CPU1:#SVID_CPU1_1_U100-EU77" )
					)
					( Origin gBackEnd )
				)
				( attribute "RELATIVE_PROPAGATION_DELAY" ",250.00 MIL"
					( Parent
						( ecsetMatchGroupRef "SVID_CLK1_CPU1:#SVID_CPU1_1_U100-EU77" )
					)
					( Units "uMatchProp" "ns" 1.000000)
					( Origin gBackEnd )
				)
			)
			( electricalCSetPinPair "SVID_CLK1_CPU1:U2D1.DG44:R1C3.1"
				( attribute "PROPAGATION_DELAY_MAX" "4500.00 MIL"
					( Units "uMaxMinProp" "ns" 1.000000)
					( Origin gBackEnd )
				)
			)
			( electricalCSetPinPair "SVID_CLK1_CPU1:R1B8.1:R1C3.2"
				( attribute "PROPAGATION_DELAY_MAX" "27000.00 MIL"
					( Units "uMaxMinProp" "ns" 1.000000)
					( Origin gBackEnd )
				)
			)
			( electricalCSetPinPair "SVID_CLK1_CPU1:R9M6.2:R1B8.1"
				( attribute "PROPAGATION_DELAY_MAX" "200.00 MIL"
					( Units "uMaxMinProp" "ns" 1.000000)
					( Origin gBackEnd )
				)
			)
			( electricalCSetPinPair "SVID_CLK1_CPU1:EU1B1.15:R1B8.2"
				( attribute "PROPAGATION_DELAY_MAX" "1000.00 MIL"
					( Units "uMaxMinProp" "ns" 1.000000)
					( Origin gBackEnd )
				)
			)
			( electricalCSetPinPair "SVID_CLK1_CPU1:EU1G2.15:R1G7.2"
				( attribute "PROPAGATION_DELAY_MAX" "1000.00 MIL"
					( Units "uMaxMinProp" "ns" 1.000000)
					( Origin gBackEnd )
				)
			)
			( electricalCSetPinPair "SVID_DIO1_CPU1:EU1G2.16:U2D1.DJ44"
				( attribute "RELATIVE_PROPAGATION_DELAY_SCOPE" "G"
					( Parent
						( ecsetMatchGroupRef "SVID_DIO1_CPU1:#SVID_CPU1_1_U100-EU76" )
					)
					( Origin gBackEnd )
				)
				( attribute "RELATIVE_PROPAGATION_DELAY" ",250.00 MIL"
					( Parent
						( ecsetMatchGroupRef "SVID_DIO1_CPU1:#SVID_CPU1_1_U100-EU76" )
					)
					( Units "uMatchProp" "ns" 1.000000)
					( Origin gBackEnd )
				)
			)
			( electricalCSetPinPair "SVID_DIO1_CPU1:EU1B1.16:U2D1.DJ44"
				( attribute "RELATIVE_PROPAGATION_DELAY_SCOPE" "G"
					( Parent
						( ecsetMatchGroupRef "SVID_DIO1_CPU1:#SVID_CPU1_1_U100-EU77" )
					)
					( Origin gBackEnd )
				)
				( attribute "RELATIVE_PROPAGATION_DELAY" ",250.00 MIL"
					( Parent
						( ecsetMatchGroupRef "SVID_DIO1_CPU1:#SVID_CPU1_1_U100-EU77" )
					)
					( Units "uMatchProp" "ns" 1.000000)
					( Origin gBackEnd )
				)
			)
			( electricalCSetPinPair "SVID_DIO1_CPU1:U2D1.DJ44:R1C2.1"
				( attribute "PROPAGATION_DELAY_MAX" "4500.00 MIL"
					( Units "uMaxMinProp" "ns" 1.000000)
					( Origin gBackEnd )
				)
			)
			( electricalCSetPinPair "SVID_DIO1_CPU1:R9M7.2:R1B10.2"
				( attribute "PROPAGATION_DELAY_MAX" "200.00 MIL"
					( Units "uMaxMinProp" "ns" 1.000000)
					( Origin gBackEnd )
				)
			)
			( electricalCSetPinPair "SVID_DIO1_CPU1:R1G10.2:R9U3.2"
				( attribute "PROPAGATION_DELAY_MAX" "200.00 MIL"
					( Units "uMaxMinProp" "ns" 1.000000)
					( Origin gBackEnd )
				)
			)
			( electricalCSetPinPair "SVID_DIO1_CPU1:R1C2.2:R1G10.2"
				( attribute "PROPAGATION_DELAY_MAX" "27000.00 MIL"
					( Units "uMaxMinProp" "ns" 1.000000)
					( Origin gBackEnd )
				)
			)
			( electricalCSetPinPair "SVID_DIO1_CPU1:R1C2.2:R9N2.2"
				( attribute "PROPAGATION_DELAY_MAX" "400.00 MIL"
					( Units "uMaxMinProp" "ns" 1.000000)
					( Origin gBackEnd )
				)
			)
			( electricalCSetPinPair "SVID_DIO1_CPU1:EU1B1.16:R1B10.1"
				( attribute "PROPAGATION_DELAY_MAX" "1000.00 MIL"
					( Units "uMaxMinProp" "ns" 1.000000)
					( Origin gBackEnd )
				)
			)
			( electricalCSetPinPair "SVID_DIO1_CPU1:EU1G2.16:R1G10.1"
				( attribute "PROPAGATION_DELAY_MAX" "1000.00 MIL"
					( Units "uMaxMinProp" "ns" 1.000000)
					( Origin gBackEnd )
				)
			)
			( electricalCSetPinPair "CLS_SVID:EU1G2.16:U2D1.DJ44"
				( attribute "RELATIVE_PROPAGATION_DELAY_SCOPE" "G"
					( Parent
						( ecsetMatchGroupRef "CLS_SVID:#SVID_CPU1_1_U100-EU76" )
					)
					( Origin gBackEnd )
				)
				( attribute "RELATIVE_PROPAGATION_DELAY" ",250.00 MIL"
					( Parent
						( ecsetMatchGroupRef "CLS_SVID:#SVID_CPU1_1_U100-EU76" )
					)
					( Units "uMatchProp" "ns" 1.000000)
					( Origin gBackEnd )
				)
			)
			( electricalCSetPinPair "CLS_SVID:EU1B1.16:U2D1.DJ44"
				( attribute "RELATIVE_PROPAGATION_DELAY_SCOPE" "G"
					( Parent
						( ecsetMatchGroupRef "CLS_SVID:#SVID_CPU1_1_U100-EU77" )
					)
					( Origin gBackEnd )
				)
				( attribute "RELATIVE_PROPAGATION_DELAY" ",250.00 MIL"
					( Parent
						( ecsetMatchGroupRef "CLS_SVID:#SVID_CPU1_1_U100-EU77" )
					)
					( Units "uMatchProp" "ns" 1.000000)
					( Origin gBackEnd )
				)
			)
			( electricalCSetPinPair "CLS_SVID:U2D1.DJ44:R1C2.1"
				( attribute "PROPAGATION_DELAY_MAX" "4500.00 MIL"
					( Units "uMaxMinProp" "ns" 1.000000)
					( Origin gBackEnd )
				)
			)
			( electricalCSetPinPair "CLS_SVID:R1G10.1:EU1B1.16"
				( attribute "PROPAGATION_DELAY_MAX" "1000.00 MIL"
					( Units "uMaxMinProp" "ns" 1.000000)
					( Origin gBackEnd )
				)
			)
			( electricalCSetPinPair "CLS_SVID:R1G10.1:EU1G2.16"
				( attribute "PROPAGATION_DELAY_MAX" "1000.00 MIL"
					( Units "uMaxMinProp" "ns" 1.000000)
					( Origin gBackEnd )
				)
			)
			( electricalCSetPinPair "CLS_SVID:R1C2.2:R9N2.2"
				( attribute "PROPAGATION_DELAY_MAX" "400.00 MIL"
					( Units "uMaxMinProp" "ns" 1.000000)
					( Origin gBackEnd )
				)
			)
			( electricalCSetPinPair "SVID_CLK0_CPU1:U2D1.DC44:EU4D5.15"
				( attribute "RELATIVE_PROPAGATION_DELAY_SCOPE" "G"
					( Parent
						( ecsetMatchGroupRef "SVID_CLK0_CPU1:#SVID_CPU0_1_U100-EU111" )
					)
					( Origin gBackEnd )
				)
				( attribute "RELATIVE_PROPAGATION_DELAY" ",250.00 MIL"
					( Parent
						( ecsetMatchGroupRef "SVID_CLK0_CPU1:#SVID_CPU0_1_U100-EU111" )
					)
					( Units "uMatchProp" "ns" 1.000000)
					( Origin gBackEnd )
				)
			)
			( electricalCSetPinPair "SVID_CLK0_CPU1:U2D1.DC44:EU1C2.17"
				( attribute "RELATIVE_PROPAGATION_DELAY_SCOPE" "G"
					( Parent
						( ecsetMatchGroupRef "SVID_CLK0_CPU1:#SVID_CPU0_1_U100-EU47" )
					)
					( Origin gBackEnd )
				)
				( attribute "RELATIVE_PROPAGATION_DELAY" ",250.00 MIL"
					( Parent
						( ecsetMatchGroupRef "SVID_CLK0_CPU1:#SVID_CPU0_1_U100-EU47" )
					)
					( Units "uMatchProp" "ns" 1.000000)
					( Origin gBackEnd )
				)
			)
			( electricalCSetPinPair "SVID_CLK0_CPU1:U2D1.DC44:R3B5.1"
				( attribute "PROPAGATION_DELAY_MAX" "4500.00 MIL"
					( Units "uMaxMinProp" "ns" 1.000000)
					( Origin gBackEnd )
				)
			)
			( electricalCSetPinPair "SVID_CLK0_CPU1:R3B5.2:R1D9.1"
				( attribute "PROPAGATION_DELAY_MAX" "27000.00 MIL"
					( Units "uMaxMinProp" "ns" 1.000000)
					( Origin gBackEnd )
				)
			)
			( electricalCSetPinPair "SVID_CLK0_CPU1:R1D9.1:R9P2.2"
				( attribute "PROPAGATION_DELAY_MAX" "200.00 MIL"
					( Units "uMaxMinProp" "ns" 1.000000)
					( Origin gBackEnd )
				)
			)
			( electricalCSetPinPair "SVID_CLK0_CPU1:EU4D5.15:R4D51.2"
				( attribute "PROPAGATION_DELAY_MAX" "1000.00 MIL"
					( Units "uMaxMinProp" "ns" 1.000000)
					( Origin gBackEnd )
				)
			)
			( electricalCSetPinPair "SVID_CLK0_CPU1:EU1C2.17:R1D9.2"
				( attribute "PROPAGATION_DELAY_MAX" "1000.00 MIL"
					( Units "uMaxMinProp" "ns" 1.000000)
					( Origin gBackEnd )
				)
			)
			( electricalCSetPinPair "SVID_DIO0_CPU1:EU4D5.16:U2D1.DB45"
				( attribute "RELATIVE_PROPAGATION_DELAY_SCOPE" "G"
					( Parent
						( ecsetMatchGroupRef "SVID_DIO0_CPU1:#SVID_CPU0_1_U100-EU111" )
					)
					( Origin gBackEnd )
				)
				( attribute "RELATIVE_PROPAGATION_DELAY" ",250.00 MIL"
					( Parent
						( ecsetMatchGroupRef "SVID_DIO0_CPU1:#SVID_CPU0_1_U100-EU111" )
					)
					( Units "uMatchProp" "ns" 1.000000)
					( Origin gBackEnd )
				)
			)
			( electricalCSetPinPair "SVID_DIO0_CPU1:EU1C2.18:U2D1.DB45"
				( attribute "RELATIVE_PROPAGATION_DELAY_SCOPE" "G"
					( Parent
						( ecsetMatchGroupRef "SVID_DIO0_CPU1:#SVID_CPU0_1_U100-EU47" )
					)
					( Origin gBackEnd )
				)
				( attribute "RELATIVE_PROPAGATION_DELAY" ",250.00 MIL"
					( Parent
						( ecsetMatchGroupRef "SVID_DIO0_CPU1:#SVID_CPU0_1_U100-EU47" )
					)
					( Units "uMatchProp" "ns" 1.000000)
					( Origin gBackEnd )
				)
			)
			( electricalCSetPinPair "SVID_DIO0_CPU1:U2D1.DB45:R3B3.1"
				( attribute "PROPAGATION_DELAY_MAX" "4500.00 MIL"
					( Units "uMaxMinProp" "ns" 1.000000)
					( Origin gBackEnd )
				)
			)
			( electricalCSetPinPair "SVID_DIO0_CPU1:R3B3.2:R1D2.2"
				( attribute "PROPAGATION_DELAY_MAX" "27000.00 MIL"
					( Units "uMaxMinProp" "ns" 1.000000)
					( Origin gBackEnd )
				)
			)
			( electricalCSetPinPair "SVID_DIO0_CPU1:R3B3.2:R3B4.1"
				( attribute "PROPAGATION_DELAY_MAX" "400.00 MIL"
					( Units "uMaxMinProp" "ns" 1.000000)
					( Origin gBackEnd )
				)
			)
			( electricalCSetPinPair "SVID_DIO0_CPU1:R1D2.2:R9P1.2"
				( attribute "PROPAGATION_DELAY_MAX" "200.00 MIL"
					( Units "uMaxMinProp" "ns" 1.000000)
					( Origin gBackEnd )
				)
			)
			( electricalCSetPinPair "SVID_DIO0_CPU1:EU4D5.16:R4D54.2"
				( attribute "PROPAGATION_DELAY_MAX" "1000.00 MIL"
					( Units "uMaxMinProp" "ns" 1.000000)
					( Origin gBackEnd )
				)
			)
			( electricalCSetPinPair "SVID_DIO0_CPU1:EU1C2.18:R1D2.1"
				( attribute "PROPAGATION_DELAY_MAX" "1000.00 MIL"
					( Units "uMaxMinProp" "ns" 1.000000)
					( Origin gBackEnd )
				)
			)
			( electricalCSetPinPair "SVID_CPU1:U2D1.DL44:R1C1.1"
				( attribute "PROPAGATION_DELAY_MAX" "4500.00 MIL"
					( Units "uMaxMinProp" "ns" 1.000000)
					( Origin gBackEnd )
				)
			)
			( electricalCSetPinPair "SVID_CPU1:R1C1.2:R9N1.2"
				( attribute "PROPAGATION_DELAY_MAX" "400.00 MIL"
					( Units "uMaxMinProp" "ns" 1.000000)
					( Origin gBackEnd )
				)
			)
			( electricalCSetPinPair "SVID_ALERT1_CPU1_N:EU1G2.17:U2D1.DL44"
				( attribute "RELATIVE_PROPAGATION_DELAY_SCOPE" "G"
					( Parent
						( ecsetMatchGroupRef "SVID_ALERT1_CPU1_N:#SVID_CPU1_1_U100-EU76" )
					)
					( Origin gBackEnd )
				)
				( attribute "RELATIVE_PROPAGATION_DELAY" ",250.00 MIL"
					( Parent
						( ecsetMatchGroupRef "SVID_ALERT1_CPU1_N:#SVID_CPU1_1_U100-EU76" )
					)
					( Units "uMatchProp" "ns" 1.000000)
					( Origin gBackEnd )
				)
			)
			( electricalCSetPinPair "SVID_ALERT1_CPU1_N:EU1B1.17:U2D1.DL44"
				( attribute "RELATIVE_PROPAGATION_DELAY_SCOPE" "G"
					( Parent
						( ecsetMatchGroupRef "SVID_ALERT1_CPU1_N:#SVID_CPU1_1_U100-EU77" )
					)
					( Origin gBackEnd )
				)
				( attribute "RELATIVE_PROPAGATION_DELAY" ",250.00 MIL"
					( Parent
						( ecsetMatchGroupRef "SVID_ALERT1_CPU1_N:#SVID_CPU1_1_U100-EU77" )
					)
					( Units "uMatchProp" "ns" 1.000000)
					( Origin gBackEnd )
				)
			)
			( electricalCSetPinPair "SVID_ALERT1_CPU1_N:U2D1.DL44:R1C1.1"
				( attribute "PROPAGATION_DELAY_MAX" "4500.00 MIL"
					( Units "uMaxMinProp" "ns" 1.000000)
					( Origin gBackEnd )
				)
			)
			( electricalCSetPinPair "SVID_ALERT1_CPU1_N:R1G9.2:R1C1.2"
				( attribute "PROPAGATION_DELAY_MAX" "27000.00 MIL"
					( Units "uMaxMinProp" "ns" 1.000000)
					( Origin gBackEnd )
				)
			)
			( electricalCSetPinPair "SVID_ALERT1_CPU1_N:R1C1.2:R9N1.2"
				( attribute "PROPAGATION_DELAY_MAX" "400.00 MIL"
					( Units "uMaxMinProp" "ns" 1.000000)
					( Origin gBackEnd )
				)
			)
			( electricalCSetPinPair "SVID_ALERT1_CPU1_N:EU1B1.17:R1B11.1"
				( attribute "PROPAGATION_DELAY_MAX" "10000.00 MIL"
					( Units "uMaxMinProp" "ns" 1.000000)
					( Origin gBackEnd )
				)
			)
			( electricalCSetPinPair "SVID_ALERT1_CPU1_N:EU1G2.17:R1G9.1"
				( attribute "PROPAGATION_DELAY_MAX" "10000.00 MIL"
					( Units "uMaxMinProp" "ns" 1.000000)
					( Origin gBackEnd )
				)
			)
			( electricalCSetPinPair "SVID_ALERT0_CPU1_N:EU4D5.17:U2D1.DE44"
				( attribute "RELATIVE_PROPAGATION_DELAY_SCOPE" "G"
					( Parent
						( ecsetMatchGroupRef "SVID_ALERT0_CPU1_N:#SVID_CPU0_1_U100-EU111" )
					)
					( Origin gBackEnd )
				)
				( attribute "RELATIVE_PROPAGATION_DELAY" ",250.00 MIL"
					( Parent
						( ecsetMatchGroupRef "SVID_ALERT0_CPU1_N:#SVID_CPU0_1_U100-EU111" )
					)
					( Units "uMatchProp" "ns" 1.000000)
					( Origin gBackEnd )
				)
			)
			( electricalCSetPinPair "SVID_ALERT0_CPU1_N:EU1C2.19:U2D1.DE44"
				( attribute "RELATIVE_PROPAGATION_DELAY_SCOPE" "G"
					( Parent
						( ecsetMatchGroupRef "SVID_ALERT0_CPU1_N:#SVID_CPU0_1_U100-EU47" )
					)
					( Origin gBackEnd )
				)
				( attribute "RELATIVE_PROPAGATION_DELAY" ",250.00 MIL"
					( Parent
						( ecsetMatchGroupRef "SVID_ALERT0_CPU1_N:#SVID_CPU0_1_U100-EU47" )
					)
					( Units "uMatchProp" "ns" 1.000000)
					( Origin gBackEnd )
				)
			)
			( electricalCSetPinPair "SVID_ALERT0_CPU1_N:U2D1.DE44:R3B2.1"
				( attribute "PROPAGATION_DELAY_MAX" "4500.00 MIL"
					( Units "uMaxMinProp" "ns" 1.000000)
					( Origin gBackEnd )
				)
			)
			( electricalCSetPinPair "SVID_ALERT0_CPU1_N:R3B1.2:R3B2.1"
				( attribute "PROPAGATION_DELAY_MAX" "400.00 MIL"
					( Units "uMaxMinProp" "ns" 1.000000)
					( Origin gBackEnd )
				)
			)
			( electricalCSetPinPair "SVID_ALERT0_CPU1_N:R1D3.2:R3B1.2"
				( attribute "PROPAGATION_DELAY_MAX" "27000.00 MIL"
					( Units "uMaxMinProp" "ns" 1.000000)
					( Origin gBackEnd )
				)
			)
			( electricalCSetPinPair "SVID_ALERT0_CPU1_N:EU4D5.17:R4D56.1"
				( attribute "PROPAGATION_DELAY_MAX" "1000.00 MIL"
					( Units "uMaxMinProp" "ns" 1.000000)
					( Origin gBackEnd )
				)
			)
			( electricalCSetPinPair "SVID_ALERT0_CPU1_N:EU1C2.19:R1D3.1"
				( attribute "PROPAGATION_DELAY_MAX" "1000.00 MIL"
					( Units "uMaxMinProp" "ns" 1.000000)
					( Origin gBackEnd )
				)
			)
			( electricalCSetPinPair "DDR_J_CMD_DLL1-13:U2D1.F51:J9U2.228"
				( attribute "RELATIVE_PROPAGATION_DELAY_SCOPE" "N"
					( Parent
						( ecsetMatchGroupRef "DDR_J_CMD_DLL1-13:MG_DDR_CMD_NEAR_DIMM" )
					)
					( Origin gBackEnd )
				)
				( attribute "RELATIVE_PROPAGATION_DELAY" "0.00 MIL,25.00 MIL"
					( Parent
						( ecsetMatchGroupRef "DDR_J_CMD_DLL1-13:MG_DDR_CMD_NEAR_DIMM" )
					)
					( Units "uMatchProp" "ns" 1.000000)
					( Origin gBackEnd )
				)
				( attribute "RELATIVE_PROPAGATION_DELAY_SCOPE" "C"
					( Parent
						( ecsetMatchGroupRef "DDR_J_CMD_DLL1-13:MG_DDR_NEAR_DIMM-CLK1" )
					)
					( Origin gBackEnd )
				)
				( attribute "RELATIVE_PROPAGATION_DELAY" "0.00 MIL,700.00 MIL"
					( Parent
						( ecsetMatchGroupRef "DDR_J_CMD_DLL1-13:MG_DDR_NEAR_DIMM-CLK1" )
					)
					( Units "uMatchProp" "ns" 1.000000)
					( Origin gBackEnd )
				)
			)
			( electricalCSetPinPair "DDR_J_CMD_DLL1-13:U2D1.F51:J1G3.228"
				( attribute "RELATIVE_PROPAGATION_DELAY_SCOPE" "C"
					( Parent
						( ecsetMatchGroupRef "DDR_J_CMD_DLL1-13:MG_DDR_FAR_DIMM-CLK0" )
					)
					( Origin gBackEnd )
				)
				( attribute "RELATIVE_PROPAGATION_DELAY" "0.00 MIL,700.00 MIL"
					( Parent
						( ecsetMatchGroupRef "DDR_J_CMD_DLL1-13:MG_DDR_FAR_DIMM-CLK0" )
					)
					( Units "uMatchProp" "ns" 1.000000)
					( Origin gBackEnd )
				)
				( attribute "RELATIVE_PROPAGATION_DELAY_SCOPE" "N"
					( Parent
						( ecsetMatchGroupRef "DDR_J_CMD_DLL1-13:MG_DDR_FAR_DIMM_CMD" )
					)
					( Origin gBackEnd )
				)
				( attribute "RELATIVE_PROPAGATION_DELAY" "0.00 MIL,25.00 MIL"
					( Parent
						( ecsetMatchGroupRef "DDR_J_CMD_DLL1-13:MG_DDR_FAR_DIMM_CMD" )
					)
					( Units "uMatchProp" "ns" 1.000000)
					( Origin gBackEnd )
				)
			)
			( electricalCSetPinPair "DDR_H_CMD_DLL1-13:U2D1.F51:J9U1.228"
				( attribute "RELATIVE_PROPAGATION_DELAY_SCOPE" "N"
					( Parent
						( ecsetMatchGroupRef "DDR_H_CMD_DLL1-13:MG_DDR_CMD_NEAR_DIMM" )
					)
					( Origin gBackEnd )
				)
				( attribute "RELATIVE_PROPAGATION_DELAY" "0.00 MIL,25.00 MIL"
					( Parent
						( ecsetMatchGroupRef "DDR_H_CMD_DLL1-13:MG_DDR_CMD_NEAR_DIMM" )
					)
					( Units "uMatchProp" "ns" 1.000000)
					( Origin gBackEnd )
				)
				( attribute "RELATIVE_PROPAGATION_DELAY_SCOPE" "C"
					( Parent
						( ecsetMatchGroupRef "DDR_H_CMD_DLL1-13:MG_DDR_NEAR_DIMM-CLK1" )
					)
					( Origin gBackEnd )
				)
				( attribute "RELATIVE_PROPAGATION_DELAY" "0.00 MIL,700.00 MIL"
					( Parent
						( ecsetMatchGroupRef "DDR_H_CMD_DLL1-13:MG_DDR_NEAR_DIMM-CLK1" )
					)
					( Units "uMatchProp" "ns" 1.000000)
					( Origin gBackEnd )
				)
			)
			( electricalCSetPinPair "DDR_H_CMD_DLL1-13:U2D1.F51:J1G2.228"
				( attribute "RELATIVE_PROPAGATION_DELAY_SCOPE" "C"
					( Parent
						( ecsetMatchGroupRef "DDR_H_CMD_DLL1-13:MG_DDR_FAR_DIMM-CLK0" )
					)
					( Origin gBackEnd )
				)
				( attribute "RELATIVE_PROPAGATION_DELAY" "0.00 MIL,700.00 MIL"
					( Parent
						( ecsetMatchGroupRef "DDR_H_CMD_DLL1-13:MG_DDR_FAR_DIMM-CLK0" )
					)
					( Units "uMatchProp" "ns" 1.000000)
					( Origin gBackEnd )
				)
				( attribute "RELATIVE_PROPAGATION_DELAY_SCOPE" "N"
					( Parent
						( ecsetMatchGroupRef "DDR_H_CMD_DLL1-13:MG_DDR_FAR_DIMM_CMD" )
					)
					( Origin gBackEnd )
				)
				( attribute "RELATIVE_PROPAGATION_DELAY" "0.00 MIL,25.00 MIL"
					( Parent
						( ecsetMatchGroupRef "DDR_H_CMD_DLL1-13:MG_DDR_FAR_DIMM_CMD" )
					)
					( Units "uMatchProp" "ns" 1.000000)
					( Origin gBackEnd )
				)
			)
			( electricalCSetPinPair "DDR_G_CMD_DLL1-13:U2D1.F51:J9T1.228"
				( attribute "RELATIVE_PROPAGATION_DELAY_SCOPE" "C"
					( Parent
						( ecsetMatchGroupRef "DDR_G_CMD_DLL1-13:MG_DDR_NEAR_DIMM-CLK1" )
					)
					( Origin gBackEnd )
				)
				( attribute "RELATIVE_PROPAGATION_DELAY" "0.00 MIL,700.00 MIL"
					( Parent
						( ecsetMatchGroupRef "DDR_G_CMD_DLL1-13:MG_DDR_NEAR_DIMM-CLK1" )
					)
					( Units "uMatchProp" "ns" 1.000000)
					( Origin gBackEnd )
				)
				( attribute "RELATIVE_PROPAGATION_DELAY_SCOPE" "N"
					( Parent
						( ecsetMatchGroupRef "DDR_G_CMD_DLL1-13:MG_DDR_CMD_NEAR_DIMM" )
					)
					( Origin gBackEnd )
				)
				( attribute "RELATIVE_PROPAGATION_DELAY" "0.00 MIL,25.00 MIL"
					( Parent
						( ecsetMatchGroupRef "DDR_G_CMD_DLL1-13:MG_DDR_CMD_NEAR_DIMM" )
					)
					( Units "uMatchProp" "ns" 1.000000)
					( Origin gBackEnd )
				)
			)
			( electricalCSetPinPair "DDR_G_CMD_DLL1-13:U2D1.F51:J1G1.228"
				( attribute "RELATIVE_PROPAGATION_DELAY_SCOPE" "N"
					( Parent
						( ecsetMatchGroupRef "DDR_G_CMD_DLL1-13:MG_DDR_FAR_DIMM_CMD" )
					)
					( Origin gBackEnd )
				)
				( attribute "RELATIVE_PROPAGATION_DELAY" "0.00 MIL,25.00 MIL"
					( Parent
						( ecsetMatchGroupRef "DDR_G_CMD_DLL1-13:MG_DDR_FAR_DIMM_CMD" )
					)
					( Units "uMatchProp" "ns" 1.000000)
					( Origin gBackEnd )
				)
				( attribute "RELATIVE_PROPAGATION_DELAY_SCOPE" "C"
					( Parent
						( ecsetMatchGroupRef "DDR_G_CMD_DLL1-13:MG_DDR_FAR_DIMM-CLK0" )
					)
					( Origin gBackEnd )
				)
				( attribute "RELATIVE_PROPAGATION_DELAY" "0.00 MIL,700.00 MIL"
					( Parent
						( ecsetMatchGroupRef "DDR_G_CMD_DLL1-13:MG_DDR_FAR_DIMM-CLK0" )
					)
					( Units "uMatchProp" "ns" 1.000000)
					( Origin gBackEnd )
				)
			)
			( electricalCSetPinPair "DDR_K_CMD_DLL1-13:U2D1.F51:J9M1.228"
				( attribute "RELATIVE_PROPAGATION_DELAY_SCOPE" "N"
					( Parent
						( ecsetMatchGroupRef "DDR_K_CMD_DLL1-13:MG_DDR_CMD_NEAR_DIMM" )
					)
					( Origin gBackEnd )
				)
				( attribute "RELATIVE_PROPAGATION_DELAY" "0.00 MIL,25.00 MIL"
					( Parent
						( ecsetMatchGroupRef "DDR_K_CMD_DLL1-13:MG_DDR_CMD_NEAR_DIMM" )
					)
					( Units "uMatchProp" "ns" 1.000000)
					( Origin gBackEnd )
				)
				( attribute "RELATIVE_PROPAGATION_DELAY_SCOPE" "C"
					( Parent
						( ecsetMatchGroupRef "DDR_K_CMD_DLL1-13:MG_DDR_NEAR_DIMM-CLK1" )
					)
					( Origin gBackEnd )
				)
				( attribute "RELATIVE_PROPAGATION_DELAY" "0.00 MIL,700.00 MIL"
					( Parent
						( ecsetMatchGroupRef "DDR_K_CMD_DLL1-13:MG_DDR_NEAR_DIMM-CLK1" )
					)
					( Units "uMatchProp" "ns" 1.000000)
					( Origin gBackEnd )
				)
			)
			( electricalCSetPinPair "DDR_K_CMD_DLL1-13:U2D1.F51:J1B1.228"
				( attribute "RELATIVE_PROPAGATION_DELAY_SCOPE" "C"
					( Parent
						( ecsetMatchGroupRef "DDR_K_CMD_DLL1-13:MG_DDR_FAR_DIMM-CLK0" )
					)
					( Origin gBackEnd )
				)
				( attribute "RELATIVE_PROPAGATION_DELAY" "0.00 MIL,700.00 MIL"
					( Parent
						( ecsetMatchGroupRef "DDR_K_CMD_DLL1-13:MG_DDR_FAR_DIMM-CLK0" )
					)
					( Units "uMatchProp" "ns" 1.000000)
					( Origin gBackEnd )
				)
				( attribute "RELATIVE_PROPAGATION_DELAY_SCOPE" "N"
					( Parent
						( ecsetMatchGroupRef "DDR_K_CMD_DLL1-13:MG_DDR_FAR_DIMM_CMD" )
					)
					( Origin gBackEnd )
				)
				( attribute "RELATIVE_PROPAGATION_DELAY" "0.00 MIL,25.00 MIL"
					( Parent
						( ecsetMatchGroupRef "DDR_K_CMD_DLL1-13:MG_DDR_FAR_DIMM_CMD" )
					)
					( Units "uMatchProp" "ns" 1.000000)
					( Origin gBackEnd )
				)
			)
			( electricalCSetPinPair "DDR_L_CMD_DLL1-13:U2D1.F51:J9L2.228"
				( attribute "RELATIVE_PROPAGATION_DELAY_SCOPE" "N"
					( Parent
						( ecsetMatchGroupRef "DDR_L_CMD_DLL1-13:MG_DDR_CMD_NEAR_DIMM" )
					)
					( Origin gBackEnd )
				)
				( attribute "RELATIVE_PROPAGATION_DELAY" "0.00 MIL,25.00 MIL"
					( Parent
						( ecsetMatchGroupRef "DDR_L_CMD_DLL1-13:MG_DDR_CMD_NEAR_DIMM" )
					)
					( Units "uMatchProp" "ns" 1.000000)
					( Origin gBackEnd )
				)
				( attribute "RELATIVE_PROPAGATION_DELAY_SCOPE" "C"
					( Parent
						( ecsetMatchGroupRef "DDR_L_CMD_DLL1-13:MG_DDR_NEAR_DIMM-CLK1" )
					)
					( Origin gBackEnd )
				)
				( attribute "RELATIVE_PROPAGATION_DELAY" "0.00 MIL,700.00 MIL"
					( Parent
						( ecsetMatchGroupRef "DDR_L_CMD_DLL1-13:MG_DDR_NEAR_DIMM-CLK1" )
					)
					( Units "uMatchProp" "ns" 1.000000)
					( Origin gBackEnd )
				)
			)
			( electricalCSetPinPair "DDR_L_CMD_DLL1-13:U2D1.F51:J1A2.228"
				( attribute "RELATIVE_PROPAGATION_DELAY_SCOPE" "C"
					( Parent
						( ecsetMatchGroupRef "DDR_L_CMD_DLL1-13:MG_DDR_FAR_DIMM-CLK0" )
					)
					( Origin gBackEnd )
				)
				( attribute "RELATIVE_PROPAGATION_DELAY" "0.00 MIL,700.00 MIL"
					( Parent
						( ecsetMatchGroupRef "DDR_L_CMD_DLL1-13:MG_DDR_FAR_DIMM-CLK0" )
					)
					( Units "uMatchProp" "ns" 1.000000)
					( Origin gBackEnd )
				)
				( attribute "RELATIVE_PROPAGATION_DELAY_SCOPE" "N"
					( Parent
						( ecsetMatchGroupRef "DDR_L_CMD_DLL1-13:MG_DDR_FAR_DIMM_CMD" )
					)
					( Origin gBackEnd )
				)
				( attribute "RELATIVE_PROPAGATION_DELAY" "0.00 MIL,25.00 MIL"
					( Parent
						( ecsetMatchGroupRef "DDR_L_CMD_DLL1-13:MG_DDR_FAR_DIMM_CMD" )
					)
					( Units "uMatchProp" "ns" 1.000000)
					( Origin gBackEnd )
				)
			)
			( electricalCSetPinPair "DDR_M_CMD_DLL1-13:U2D1.F51:J9L1.228"
				( attribute "RELATIVE_PROPAGATION_DELAY_SCOPE" "N"
					( Parent
						( ecsetMatchGroupRef "DDR_M_CMD_DLL1-13:MG_DDR_CMD_NEAR_DIMM" )
					)
					( Origin gBackEnd )
				)
				( attribute "RELATIVE_PROPAGATION_DELAY" "0.00 MIL,25.00 MIL"
					( Parent
						( ecsetMatchGroupRef "DDR_M_CMD_DLL1-13:MG_DDR_CMD_NEAR_DIMM" )
					)
					( Units "uMatchProp" "ns" 1.000000)
					( Origin gBackEnd )
				)
				( attribute "RELATIVE_PROPAGATION_DELAY_SCOPE" "C"
					( Parent
						( ecsetMatchGroupRef "DDR_M_CMD_DLL1-13:MG_DDR_NEAR_DIMM-CLK1" )
					)
					( Origin gBackEnd )
				)
				( attribute "RELATIVE_PROPAGATION_DELAY" "0.00 MIL,700.00 MIL"
					( Parent
						( ecsetMatchGroupRef "DDR_M_CMD_DLL1-13:MG_DDR_NEAR_DIMM-CLK1" )
					)
					( Units "uMatchProp" "ns" 1.000000)
					( Origin gBackEnd )
				)
			)
			( electricalCSetPinPair "DDR_M_CMD_DLL1-13:U2D1.F51:J1A1.228"
				( attribute "RELATIVE_PROPAGATION_DELAY_SCOPE" "C"
					( Parent
						( ecsetMatchGroupRef "DDR_M_CMD_DLL1-13:MG_DDR_FAR_DIMM-CLK0" )
					)
					( Origin gBackEnd )
				)
				( attribute "RELATIVE_PROPAGATION_DELAY" "0.00 MIL,700.00 MIL"
					( Parent
						( ecsetMatchGroupRef "DDR_M_CMD_DLL1-13:MG_DDR_FAR_DIMM-CLK0" )
					)
					( Units "uMatchProp" "ns" 1.000000)
					( Origin gBackEnd )
				)
				( attribute "RELATIVE_PROPAGATION_DELAY_SCOPE" "N"
					( Parent
						( ecsetMatchGroupRef "DDR_M_CMD_DLL1-13:MG_DDR_FAR_DIMM_CMD" )
					)
					( Origin gBackEnd )
				)
				( attribute "RELATIVE_PROPAGATION_DELAY" "0.00 MIL,25.00 MIL"
					( Parent
						( ecsetMatchGroupRef "DDR_M_CMD_DLL1-13:MG_DDR_FAR_DIMM_CMD" )
					)
					( Units "uMatchProp" "ns" 1.000000)
					( Origin gBackEnd )
				)
			)
			( electricalCSet "@crescent_city_bb_fab1_lib.crescent_city_bb_fab1(sch_1):\SPI_PCH_IO2\"
				( groupRef "SPI_SWITCH_IO2:SPI_MUX-U3T1" )
				( groupRef "SPI_SWITCH_IO2:SPI_MUX-U7F1" )
				( pinPairRef "SPI_SWITCH_IO2:U2T1.4:U3T1.9" )
				( pinPairRef "SPI_SWITCH_IO2:U2T1.4:U7F1.9" )
				( attribute "RATSNEST_SCHEDULE" "TEMPLATE"
					( Status sLocked )
					( Origin gBackEnd )
				)
				( attribute "TOPOLOGY_TEMPLATE_REVISION" "1.0"
					( Origin gBackEnd )
				)
				( topologyData 33852
(SKIDL (Circuits ("MAIN" (Parts ("CRESCENT_CITY_902_20150507_Q.@@U2T1.4" IbisIOPkg (xy (5442.0 4237.0)) (refDes "U2T1") (model "Unknown") (Props (_SXDesignName "CRESCENT_CITY_902_20150507_Q") (brdx "15795 MIL") (brdy "1530 MIL") (bufferModel "CDSDefaultIO_2p5v") (cycle "1") (hold "1.0e-09") (mappingTag "") (offsets ("4" "0") ("5" "0")) (setup "2.0e-09") (state "tristate") (stimuli ("4" "local32") ("5" "local39")) (temperature "27") (termMap ("4" "Data") ("5" "Enable"))) (Terms ("CRESCENT_CITY_902_20150507_Q.X1579500Y153000L36LRATS" "4"))) ("CRESCENT_CITY_902_20150507_Q.@@U7F1.9" IbisIOPkg (xy (5496.5 4206.0)) (refDes "U7F1") (model "Unknown") (Props (_SXDesignName "CRESCENT_CITY_902_20150507_Q") (brdx "14920.2 MIL") (brdy "841.5 MIL") (bufferModel "CDSDefaultIO_2p5v") (cycle "1") (hold "1.0e-09") (mappingTag "") (offsets ("4" "0") ("5" "0")) (setup "2.0e-09") (state "tristate") (stimuli ("4" "local40") ("5" "local41")) (temperature "27") (termMap ("4" "Data") ("5" "Enable"))) (Terms ("CRESCENT_CITY_902_20150507_Q.X1492020Y84150L2LRATS" "9"))) ("CRESCENT_CITY_902_20150507_Q.@@U3T1.9" IbisIOPkg (xy (5496.0 4236.5)) (refDes "U3T1") (model "Unknown") (Props (_SXDesignName "CRESCENT_CITY_902_20150507_Q") (brdx "15275 MIL") (brdy "834 MIL") (bufferModel "CDSDefaultIO_2p5v") (cycle "1") (hold "1.0e-09") (mappingTag "") (offsets ("4" "0") ("5" "0")) (setup "2.0e-09") (state "tristate") (stimuli ("4" "local42") ("5" "local43")) (temperature "27") (termMap ("4" "Data") ("5" "Enable"))) (Terms ("CRESCENT_CITY_902_20150507_Q.X1527500Y83400L36LRATS" "9"))) ("CRESCENT_CITY_902_20150507_Q.@@R7F30.2.1" Resistor (xy (5469 4195)) (refDes "R7F30") (value "10000 Ohm") (Props (_SXDesignName "CRESCENT_CITY_902_20150507_Q")) (Terms ("CRESCENT_CITY_902_20150507_Q.X1502900Y73200L2RATS" "2") ("CRESCENT_CITY_902_20150507_Q.X1499400Y73200L2LRATS" "1"))) ("CRESCENT_CITY_902_20150507_Q.@@R3T12.1_SOURCE" Source (xy (5489.5 4222.5)) (refDes "P3V3_STBY_1") (value "3.3 V") (Props (_SXDesignName "CRESCENT_CITY_902_20150507_Q")) (Terms ("CRESCENT_CITY_902_20150507_Q.X1503100Y70500L36RATS" "1"))) ("CRESCENT_CITY_902_20150507_Q.@@R3T12.1.2" Resistor (xy (5482.0 4222.5)) (mirror x) (refDes "R3T12") (value "10000 Ohm") (Props (_SXDesignName "CRESCENT_CITY_902_20150507_Q")) (Terms ("CRESCENT_CITY_902_20150507_Q.X1503100Y70500L36RATS" "1") ("CRESCENT_CITY_902_20150507_Q.X1506600Y70500L36LRATS" "2"))) ("CRESCENT_CITY_902_20150507_Q.T@@RATS@@R7F28.2@@R7G1.2" TLine (xy (5468.0 4212.5)) (mirror x) (refDes "TL22") (Props (_SXDesignName "CRESCENT_CITY_902_20150507_Q") (impedance "48.412 ohm") length("40.00 MIL") (propDelay "0.00718 ns") (traceCount "1") (traceGeometry "Microstrip") (velocity "5571.02 mil/ns")) (Terms ("CRESCENT_CITY_902_20150507_Q.X1508000Y69000L2LRATS" "1") ("CRESCENT_CITY_902_20150507_Q.X1512000Y69000L2LRATS" "2"))) ("CRESCENT_CITY_902_20150507_Q.@@R7F30.2_SOURCE" Source (xy (5462 4195)) (refDes "GND_1") (value "0 V") (Props (_SXDesignName "CRESCENT_CITY_902_20150507_Q")) (Terms ("CRESCENT_CITY_902_20150507_Q.X1502900Y73200L2RATS" "1"))) ("CRESCENT_CITY_902_20150507_Q.T@@RATS@@R3T9.1@@U3T1.9" TLine (xy (5485.5 4231.5)) (refDes "TL23") (Props (_SXDesignName "CRESCENT_CITY_902_20150507_Q") (impedance "46.577 ohm") length("154.00 MIL") (propDelay "0.02766 ns") (traceCount "1") (traceGeometry "Microstrip") (velocity "5567.6 mil/ns")) (Terms ("CRESCENT_CITY_902_20150507_Q.X1523000Y72500L36LRATS" "1") ("CRESCENT_CITY_902_20150507_Q.X1527500Y83400L36LRATS" "2"))) ("CRESCENT_CITY_902_20150507_Q.@@R7F28.1_SOURCE" Source (xy (5494.5 4215.5)) (refDes "P3V3_STBY") (value "3.3 V") (Props (_SXDesignName "CRESCENT_CITY_902_20150507_Q")) (Terms ("CRESCENT_CITY_902_20150507_Q.X1508000Y72500L2RATS" "1"))) ("CRESCENT_CITY_902_20150507_Q.T@@RATS@@R3U1.1@@R7G1.1" TLine (xy (5454.0 4218.5)) (refDes "TL24") (orientation "270") (Props (_SXDesignName "CRESCENT_CITY_902_20150507_Q") (impedance "48.412 ohm") length("75.00 MIL") (propDelay "0.01347 ns") (traceCount "1") (traceGeometry "Microstrip") (velocity "5567.91 mil/ns")) (Terms ("idlNode_55" "1") ("CRESCENT_CITY_902_20150507_Q.X1515500Y69000L2LRATS" "2"))) ("CRESCENT_CITY_902_20150507_Q.@@R7G1.1.2" Resistor (xy (5457.0 4212.5)) (refDes "R7F37") (value "33.2 Ohm") (Props (_SXDesignName "CRESCENT_CITY_902_20150507_Q")) (Terms ("CRESCENT_CITY_902_20150507_Q.X1515500Y69000L2LRATS" "1") ("CRESCENT_CITY_902_20150507_Q.X1512000Y69000L2LRATS" "2"))) ("CRESCENT_CITY_902_20150507_Q.T@@RATS@@R7F30.1@@U7F1.9" TLine (xy (5475 4201)) (refDes "TL25") (Props (_SXDesignName "CRESCENT_CITY_902_20150507_Q") (impedance "48.412 ohm") length("183.30 MIL") (propDelay "0.03292 ns") (traceCount "1") (traceGeometry "Microstrip") (velocity "5568.03 mil/ns")) (Terms ("CRESCENT_CITY_902_20150507_Q.X1499400Y73200L2LRATS" "1") ("CRESCENT_CITY_902_20150507_Q.X1492020Y84150L2LRATS" "2"))) ("CRESCENT_CITY_902_20150507_Q.T@@RATS@@R7F30.1@@R7F28.2" TLine (xy (5470.0 4205.0)) (mirror x) (refDes "TL26") (orientation "270") (Props (_SXDesignName "CRESCENT_CITY_902_20150507_Q") (impedance "48.412 ohm") length("128.00 MIL") (propDelay "0.02299 ns") (traceCount "1") (traceGeometry "Microstrip") (velocity "5567.64 mil/ns")) (Terms ("CRESCENT_CITY_902_20150507_Q.X1499400Y73200L2LRATS" "1") ("CRESCENT_CITY_902_20150507_Q.X1508000Y69000L2LRATS" "2"))) ("CRESCENT_CITY_902_20150507_Q.@@R3U1.1.2" Resistor (xy (5457.0 4227.0)) (refDes "R3U1") (value "33.2 Ohm") (Props (_SXDesignName "CRESCENT_CITY_902_20150507_Q")) (Terms ("idlNode_55" "1") ("CRESCENT_CITY_902_20150507_Q.X1519500Y69000L36LRATS" "2"))) ("CRESCENT_CITY_902_20150507_Q.T@@RATS@@R3U1.2@@R3T12.2" TLine (xy (5473.5 4225.5)) (refDes "TL27") (orientation "270") (Props (_SXDesignName "CRESCENT_CITY_902_20150507_Q") (impedance "46.577 ohm") length("144.00 MIL") (propDelay "0.02586 ns") (traceCount "1") (traceGeometry "Microstrip") (velocity "5568.46 mil/ns")) (Terms ("CRESCENT_CITY_902_20150507_Q.X1519500Y69000L36LRATS" "1") ("CRESCENT_CITY_902_20150507_Q.X1506600Y70500L36LRATS" "2"))) ("CRESCENT_CITY_902_20150507_Q.@@R3T9.2_SOURCE" Source (xy (5491.0 4238.0)) (refDes "GND") (value "0 V") (Props (_SXDesignName "CRESCENT_CITY_902_20150507_Q")) (Terms ("CRESCENT_CITY_902_20150507_Q.X1519500Y72500L36RATS" "1"))) ("CRESCENT_CITY_902_20150507_Q.T@@RATS@@U2T1.4@@R3U1.1" TLine (xy (5443.0 4227.0)) (refDes "TL28") (Props (_SXDesignName "CRESCENT_CITY_902_20150507_Q") (impedance "46.577 ohm") length("1405.00 MIL") (propDelay "0.25235 ns") (traceCount "1") (traceGeometry "Microstrip") (velocity "5567.68 mil/ns")) (Terms ("CRESCENT_CITY_902_20150507_Q.X1579500Y153000L36LRATS" "1") ("idlNode_55" "2"))) ("CRESCENT_CITY_902_20150507_Q.@@R7F28.1.2" Resistor (xy (5486.0 4214.0)) (mirror x) (refDes "R7F28") (value "10000 Ohm") (Props (_SXDesignName "CRESCENT_CITY_902_20150507_Q")) (Terms ("CRESCENT_CITY_902_20150507_Q.X1508000Y72500L2RATS" "1") ("CRESCENT_CITY_902_20150507_Q.X1508000Y69000L2LRATS" "2"))) ("CRESCENT_CITY_902_20150507_Q.@@R3T9.2.1" Resistor (xy (5485.5 4238.0)) (mirror x) (refDes "R3T9") (value "10000 Ohm") (Props (_SXDesignName "CRESCENT_CITY_902_20150507_Q")) (Terms ("CRESCENT_CITY_902_20150507_Q.X1519500Y72500L36RATS" "2") ("CRESCENT_CITY_902_20150507_Q.X1523000Y72500L36LRATS" "1"))) ("CRESCENT_CITY_902_20150507_Q.T@@RATS@@R3T9.1@@R3U1.2" TLine (xy (5476.5 4231.5)) (mirror x) (refDes "TL29") (Props (_SXDesignName "CRESCENT_CITY_902_20150507_Q") (impedance "46.577 ohm") length("70.00 MIL") (propDelay "0.01257 ns") (traceCount "1") (traceGeometry "Microstrip") (velocity "5568.82 mil/ns")) (Terms ("CRESCENT_CITY_902_20150507_Q.X1523000Y72500L36LRATS" "1") ("CRESCENT_CITY_902_20150507_Q.X1519500Y69000L36LRATS" "2")))) (Nodes ("CRESCENT_CITY_902_20150507_Q.X1519500Y69000L36LRATS" (terms "CRESCENT_CITY_902_20150507_Q.T@@RATS@@R3T9.1@@R3U1.2.2" "CRESCENT_CITY_902_20150507_Q.T@@RATS@@R3U1.2@@R3T12.2.1" "CRESCENT_CITY_902_20150507_Q.@@R3U1.1.2.2")) ("CRESCENT_CITY_902_20150507_Q.X1499400Y73200L2LRATS" (terms "CRESCENT_CITY_902_20150507_Q.T@@RATS@@R7F30.1@@R7F28.2.1" "CRESCENT_CITY_902_20150507_Q.T@@RATS@@R7F30.1@@U7F1.9.1" "CRESCENT_CITY_902_20150507_Q.@@R7F30.2.1.2")) ("CRESCENT_CITY_902_20150507_Q.X1515500Y69000L2LRATS" (terms "CRESCENT_CITY_902_20150507_Q.@@R7G1.1.2.1" "CRESCENT_CITY_902_20150507_Q.T@@RATS@@R3U1.1@@R7G1.1.2")) ("idlNode_55" (terms "CRESCENT_CITY_902_20150507_Q.T@@RATS@@U2T1.4@@R3U1.1.2" "CRESCENT_CITY_902_20150507_Q.@@R3U1.1.2.1" "CRESCENT_CITY_902_20150507_Q.T@@RATS@@R3U1.1@@R7G1.1.1")) ("CRESCENT_CITY_902_20150507_Q.X1503100Y70500L36RATS" (terms "CRESCENT_CITY_902_20150507_Q.@@R3T12.1.2.1" "CRESCENT_CITY_902_20150507_Q.@@R3T12.1_SOURCE.1")) ("CRESCENT_CITY_902_20150507_Q.X1492020Y84150L2LRATS" (terms "CRESCENT_CITY_902_20150507_Q.T@@RATS@@R7F30.1@@U7F1.9.2" "CRESCENT_CITY_902_20150507_Q.@@U7F1.9.1")) ("CRESCENT_CITY_902_20150507_Q.X1508000Y69000L2LRATS" (terms "CRESCENT_CITY_902_20150507_Q.@@R7F28.1.2.2" "CRESCENT_CITY_902_20150507_Q.T@@RATS@@R7F30.1@@R7F28.2.2" "CRESCENT_CITY_902_20150507_Q.T@@RATS@@R7F28.2@@R7G1.2.1")) ("CRESCENT_CITY_902_20150507_Q.X1506600Y70500L36LRATS" (terms "CRESCENT_CITY_902_20150507_Q.T@@RATS@@R3U1.2@@R3T12.2.2" "CRESCENT_CITY_902_20150507_Q.@@R3T12.1.2.2")) ("CRESCENT_CITY_902_20150507_Q.X1512000Y69000L2LRATS" (terms "CRESCENT_CITY_902_20150507_Q.@@R7G1.1.2.2" "CRESCENT_CITY_902_20150507_Q.T@@RATS@@R7F28.2@@R7G1.2.2")) ("CRESCENT_CITY_902_20150507_Q.X1579500Y153000L36LRATS" (terms "CRESCENT_CITY_902_20150507_Q.T@@RATS@@U2T1.4@@R3U1.1.1" "CRESCENT_CITY_902_20150507_Q.@@U2T1.4.1")) ("CRESCENT_CITY_902_20150507_Q.X1519500Y72500L36RATS" (terms "CRESCENT_CITY_902_20150507_Q.@@R3T9.2.1.1" "CRESCENT_CITY_902_20150507_Q.@@R3T9.2_SOURCE.1")) ("CRESCENT_CITY_902_20150507_Q.X1523000Y72500L36LRATS" (terms "CRESCENT_CITY_902_20150507_Q.T@@RATS@@R3T9.1@@R3U1.2.1" "CRESCENT_CITY_902_20150507_Q.@@R3T9.2.1.2" "CRESCENT_CITY_902_20150507_Q.T@@RATS@@R3T9.1@@U3T1.9.1")) ("CRESCENT_CITY_902_20150507_Q.X1527500Y83400L36LRATS" (terms "CRESCENT_CITY_902_20150507_Q.T@@RATS@@R3T9.1@@U3T1.9.2" "CRESCENT_CITY_902_20150507_Q.@@U3T1.9.1")) ("CRESCENT_CITY_902_20150507_Q.X1508000Y72500L2RATS" (terms "CRESCENT_CITY_902_20150507_Q.@@R7F28.1.2.1" "CRESCENT_CITY_902_20150507_Q.@@R7F28.1_SOURCE.1")) ("CRESCENT_CITY_902_20150507_Q.X1502900Y73200L2RATS" (terms "CRESCENT_CITY_902_20150507_Q.@@R7F30.2_SOURCE.1" "CRESCENT_CITY_902_20150507_Q.@@R7F30.2.1.1"))) (Ports) (Stimuli ("local10" (scope local) (stimType periodic) (Props (periodicFreq "5e+007") (periodicJitter "0") (periodicPattern "1"))) ("local42" (scope local) (stimType periodic) (Props (periodicFreq "5e+007") (periodicJitter "0") (periodicPattern "1"))) ("local9" (scope local) (stimType periodic) (Props (periodicFreq "5e+007") (periodicJitter "0") (periodicPattern "1"))) ("local13" (scope local) (stimType periodic) (Props (periodicFreq "5e+007") (periodicJitter "0") (periodicPattern "1"))) ("local14" (scope local) (stimType periodic) (Props (periodicFreq "5e+007") (periodicJitter "0") (periodicPattern "1"))) ("local40" (scope local) (stimType periodic) (Props (periodicFreq "5e+007") (periodicJitter "0") (periodicPattern "1"))) ("local11" (scope local) (stimType periodic) (Props (periodicFreq "5e+007") (periodicJitter "0") (periodicPattern "1"))) ("local39" (scope local) (stimType periodic) (Props (periodicFreq "5e+007") (periodicJitter "0") (periodicPattern "1"))) ("local32" (scope local) (stimType periodic) (Props (periodicFreq "5e+007") (periodicJitter "0") (periodicPattern "1"))) ("local41" (scope local) (stimType periodic) (Props (periodicFreq "5e+007") (periodicJitter "0") (periodicPattern "1"))) ("local43" (scope local) (stimType periodic) (Props (periodicFreq "5e+007") (periodicJitter "0") (periodicPattern "1"))) ("local12" (scope local) (stimType periodic) (Props (periodicFreq "5e+007") (periodicJitter "0") (periodicPattern "1")))) (Notes) (Constraints ("RATSNEST_SCHEDULE" "TEMPLATE") ("RELATIVE_PROPAGATION_DELAY" ("SPI_U2T1-U3T1" "CRESCENT_CITY_902_20150507_Q U2T1.4" "CRESCENT_CITY_902_20150507_Q U3T1.9" "GLOBAL" "LENGTH" "0.00635" "DELAY" "") ("SPI_U2T1-U7F1" "CRESCENT_CITY_902_20150507_Q U2T1.4" "CRESCENT_CITY_902_20150507_Q U7F1.9" "GLOBAL" "LENGTH" "0.00635" "DELAY" ""))) (MeasurementSets ("EMI" ("EMIStatus" status("on")) ("PeakEmission" status("on")) ("PeakFrequency" status("on")) ("PulseFreq" status("on")) ("RiseTime" status("on")) ("VoltageSwing" status("on"))) ("Reflection" ("BufferDelayFall" status("off")) ("BufferDelayRise" status("off")) ("EyeHeight" status("off")) ("EyeJitter" status("off")) ("EyeWidth" status("off")) ("FirstIncidentFall" status("off")) ("FirstIncidentRise" status("off")) ("Glitch" status("on")) ("GlitchFall" status("off")) ("GlitchRise" status("off")) ("Monotonic" status("on")) ("MonotonicFall" status("off")) ("MonotonicRise" status("off")) ("NoiseMargin" status("on")) ("NoiseMarginHigh" status("off")) ("NoiseMarginLow" status("off")) ("OvershootHigh" status("on")) ("OvershootLow" status("on")) ("PropDelay" status("on")) ("SettleDelay" status("on")) ("SettleDelayFall" status("off")) ("SettleDelayRise" status("off")) ("SwitchDelay" status("on")) ("SwitchDelayFall" status("off")) ("SwitchDelayRise" status("off"))) ("Crosstalk" ("Crosstalk" status("on"))) ("Custom")) (VectorSets) (Props (XnetName "SPI_BIOS_SOCKET_IO2") (allDrivers "active") (autoSolve "Off") (customSimType "Reflection") (ftsMode ("Typ")) (rcvrSelect "all") (tlineDelayMode "length") (userRevision "1.0")))) (Subckts) (CrossSections ("CRESCENT_CITY_902_20150507_Q" (Props (SXDesignName "CRESCENT_CITY_902_20150507_Q")) (Layers ("" (layerType "SURFACE") (material "AIR") (thickness "0 mil") (dielectricConstant "1.000000") (lossTangent "0") (etchFactor "0.000000") (elecCondVal "0 mho/cm") (thermCondVal "0 w/cm-degC")) ("" (layerType "DIELECTRIC") (material "CONFORMAL_COAT") (thickness "0.5 mil") (dielectricConstant "3.800000") (lossTangent "0.035") (etchFactor "0.000000") (elecCondVal "0 mho/cm") (thermCondVal "0.012 w/cm-degC")) ("TOP" (layerType "CONDUCTOR") (material "COPPER") (thickness "  2.100000 mil") (width "4.00 MIL") (dielectricConstant "4.500000") (lossTangent "0") (etchFactor "70.000000") (elecCondVal "595900.000000 mho/cm") (thermCondVal "0 w/cm-degC") (signalDieConstant "3.800000") (signalLossTangent "0.035")) ("" (layerType "DIELECTRIC") (material "FR-4") (thickness "  2.670000 mil") (dielectricConstant "4.000000") (lossTangent "0.035") (etchFactor "0.000000") (elecCondVal "0 mho/cm") (thermCondVal "0.012 w/cm-degC")) ("L2_GND1" (layerType "PLANE") (material "COPPER") (isShield t) (thickness "  1.250000 mil") (dielectricConstant "4.500000") (lossTangent "0.035") (etchFactor "90.000000") (elecCondVal "595900.000000 mho/cm") (thermCondVal "0.012 w/cm-degC")) ("" (layerType "DIELECTRIC") (material "FR-4") (thickness "  9.000000 mil") (dielectricConstant "4.100000") (lossTangent "0.035") (etchFactor "0.000000") (elecCondVal "0 mho/cm") (thermCondVal "0.012 w/cm-degC")) ("L3_SIG1" (layerType "CONDUCTOR") (material "COPPER") (thickness "  1.250000 mil") (width "4.00 MIL") (dielectricConstant "4.500000") (lossTangent "0.035") (etchFactor "90.000000") (elecCondVal "595900.000000 mho/cm") (thermCondVal "0.012 w/cm-degC") (signalDieConstant "4.100000") (signalLossTangent "0.035")) ("" (layerType "DIELECTRIC") (material "FR-4") (thickness "  3.000000 mil") (dielectricConstant "4.500000") (lossTangent "0.035") (etchFactor "0.000000") (elecCondVal "0 mho/cm") (thermCondVal "0 w/cm-degC")) ("L4_GND2" (layerType "PLANE") (material "COPPER") (isShield t) (thickness "  1.250000 mil") (dielectricConstant "4.500000") (lossTangent "0.035") (etchFactor "90.000000") (elecCondVal "595900.000000 mho/cm") (thermCondVal "0 w/cm-degC")) ("" (layerType "DIELECTRIC") (material "FR-4") (thickness "  9.000000 mil") (dielectricConstant "4.000000") (lossTangent "0.035") (etchFactor "0.000000") (elecCondVal "0 mho/cm") (thermCondVal "0.012 w/cm-degC")) ("L5_SIG2" (layerType "CONDUCTOR") (material "COPPER") (thickness "  1.250000 mil") (width "4.00 MIL") (dielectricConstant "4.500000") (lossTangent "0.035") (etchFactor "90.000000") (elecCondVal "595900.000000 mho/cm") (thermCondVal "0.012 w/cm-degC") (signalDieConstant "4.000000") (signalLossTangent "0.035")) ("" (layerType "DIELECTRIC") (material "FR-4") (thickness "  3.000000 mil") (dielectricConstant "4.500000") (lossTangent "0.035") (etchFactor "0.000000") (elecCondVal "0 mho/cm") (thermCondVal "0 w/cm-degC")) ("L6_GND3" (layerType "PLANE") (material "COPPER") (isShield t) (thickness "  1.250000 mil") (dielectricConstant "4.500000") (lossTangent "0.035") (etchFactor "90.000000") (elecCondVal "595900.000000 mho/cm") (thermCondVal "0 w/cm-degC")) ("" (layerType "DIELECTRIC") (material "FR-4") (thickness "  4.500000 mil") (dielectricConstant "4.100000") (lossTangent "0.035") (etchFactor "0.000000") (elecCondVal "0 mho/cm") (thermCondVal "0.012 w/cm-degC")) ("L7_PWR1-SIG" (layerType "PLANE") (material "COPPER") (isShield t) (thickness "  2.610000 mil") (dielectricConstant "4.500000") (lossTangent "0.035") (etchFactor "90.000000") (elecCondVal "595900.000000 mho/cm") (thermCondVal "0.012 w/cm-degC")) ("" (layerType "DIELECTRIC") (material "FR-4") (thickness "  3.100000 mil") (dielectricConstant "4.500000") (lossTangent "0.035") (etchFactor "0.000000") (elecCondVal "0 mho/cm") (thermCondVal "0 w/cm-degC")) ("L8_GND_TEMP" (layerType "PLANE") (material "COPPER") (isShield t) (thickness "  1.250000 mil") (dielectricConstant "4.500000") (lossTangent "0.035") (etchFactor "90.000000") (elecCondVal "595900.000000 mho/cm") (thermCondVal "0 w/cm-degC")) ("" (layerType "DIELECTRIC") (material "FR-4") (thickness "  3.030000 mil") (dielectricConstant "4.500000") (lossTangent "0.035") (etchFactor "0.000000") (elecCondVal "0 mho/cm") (thermCondVal "0 w/cm-degC")) ("L9_SIG_TEMP" (layerType "CONDUCTOR") (material "COPPER") (thickness "  1.250000 mil") (width "3.52 MIL") (dielectricConstant "4.500000") (lossTangent "0.035") (etchFactor "90.000000") (elecCondVal "595900.000000 mho/cm") (thermCondVal "0 w/cm-degC") (signalDieConstant "4.500000") (signalLossTangent "0.035")) ("" (layerType "DIELECTRIC") (material "FR-4") (thickness "  5.000000 mil") (dielectricConstant "4.500000") (lossTangent "0.035") (etchFactor "0.000000") (elecCondVal "0 mho/cm") (thermCondVal "0 w/cm-degC")) ("L10_SIG_TEMP" (layerType "CONDUCTOR") (material "COPPER") (thickness "  1.250000 mil") (width "3.52 MIL") (dielectricConstant "4.500000") (lossTangent "0.035") (etchFactor "90.000000") (elecCondVal "595900.000000 mho/cm") (thermCondVal "0 w/cm-degC") (signalDieConstant "4.500000") (signalLossTangent "0.035")) ("" (layerType "DIELECTRIC") (material "FR-4") (thickness "  3.030000 mil") (dielectricConstant "4.500000") (lossTangent "0.035") (etchFactor "0.000000") (elecCondVal "0 mho/cm") (thermCondVal "0 w/cm-degC")) ("L11_GND_TEMP" (layerType "PLANE") (material "COPPER") (isShield t) (thickness "  1.250000 mil") (dielectricConstant "4.500000") (lossTangent "0.035") (etchFactor "90.000000") (elecCondVal "595900.000000 mho/cm") (thermCondVal "0 w/cm-degC")) ("" (layerType "DIELECTRIC") (material "FR-4") (thickness "  3.100000 mil") (dielectricConstant "4.000000") (lossTangent "0.035") (etchFactor "0.000000") (elecCondVal "0 mho/cm") (thermCondVal "0.012 w/cm-degC")) ("L12_PWR2-SIG" (layerType "PLANE") (material "COPPER") (isShield t) (thickness "  2.610000 mil") (dielectricConstant "4.500000") (lossTangent "0.035") (etchFactor "90.000000") (elecCondVal "595900.000000 mho/cm") (thermCondVal "0.012 w/cm-degC")) ("" (layerType "DIELECTRIC") (material "FR-4") (thickness "  4.500000 mil") (dielectricConstant "4.500000") (lossTangent "0.035") (etchFactor "0.000000") (elecCondVal "0 mho/cm") (thermCondVal "0 w/cm-degC")) ("L13_GND4" (layerType "PLANE") (material "COPPER") (isShield t) (thickness "  1.250000 mil") (dielectricConstant "4.500000") (lossTangent "0.035") (etchFactor "90.000000") (elecCondVal "595900.000000 mho/cm") (thermCondVal "0 w/cm-degC")) ("" (layerType "DIELECTRIC") (material "FR-4") (thickness "  3.000000 mil") (dielectricConstant "4.100000") (lossTangent "0.035") (etchFactor "0.000000") (elecCondVal "0 mho/cm") (thermCondVal "0.012 w/cm-degC")) ("L14_SIG3" (layerType "CONDUCTOR") (material "COPPER") (thickness "  1.250000 mil") (width "4.00 MIL") (dielectricConstant "4.500000") (lossTangent "0.035") (etchFactor "90.000000") (elecCondVal "595900.000000 mho/cm") (thermCondVal "0.012 w/cm-degC") (signalDieConstant "4.100000") (signalLossTangent "0.035")) ("" (layerType "DIELECTRIC") (material "FR-4") (thickness "  9.000000 mil") (dielectricConstant "4.500000") (lossTangent "0.035") (etchFactor "0.000000") (elecCondVal "0 mho/cm") (thermCondVal "0 w/cm-degC")) ("L15_GND5" (layerType "PLANE") (material "COPPER") (isShield t) (thickness "  1.250000 mil") (dielectricConstant "4.500000") (lossTangent "0.035") (etchFactor "90.000000") (elecCondVal "595900.000000 mho/cm") (thermCondVal "0 w/cm-degC")) ("" (layerType "DIELECTRIC") (material "FR-4") (thickness "  3.000000 mil") (dielectricConstant "4.500000") (lossTangent "0.035") (etchFactor "0.000000") (elecCondVal "0 mho/cm") (thermCondVal "0.012 w/cm-degC")) ("L16_SIG4" (layerType "CONDUCTOR") (material "COPPER") (thickness "  1.250000 mil") (width "4.00 MIL") (dielectricConstant "4.500000") (lossTangent "0.035") (etchFactor "90.000000") (elecCondVal "595900.000000 mho/cm") (thermCondVal "0.012 w/cm-degC") (signalDieConstant "4.500000") (signalLossTangent "0.035")) ("" (layerType "DIELECTRIC") (material "FR-4") (thickness "  9.000000 mil") (dielectricConstant "4.500000") (lossTangent "0.035") (etchFactor "0.000000") (elecCondVal "0 mho/cm") (thermCondVal "0 w/cm-degC")) ("L17_GND6" (layerType "PLANE") (material "COPPER") (isShield t) (thickness "  1.250000 mil") (dielectricConstant "4.500000") (lossTangent "0.035") (etchFactor "90.000000") (elecCondVal "595900.000000 mho/cm") (thermCondVal "0.012 w/cm-degC")) ("" (layerType "DIELECTRIC") (material "FR-4") (thickness "  2.670000 mil") (dielectricConstant "4.500000") (lossTangent "0.035") (etchFactor "0.000000") (elecCondVal "0 mho/cm") (thermCondVal "0.012 w/cm-degC")) ("BOTTOM" (layerType "CONDUCTOR") (material "COPPER") (thickness "  2.100000 mil") (width "4.00 MIL") (dielectricConstant "4.500000") (lossTangent "0") (etchFactor "70.000000") (elecCondVal "595900.000000 mho/cm") (thermCondVal "0 w/cm-degC") (signalDieConstant "3.800000") (signalLossTangent "0.035")) ("" (layerType "DIELECTRIC") (material "CONFORMAL_COAT") (thickness "0.5 mil") (dielectricConstant "3.800000") (lossTangent "0.035") (etchFactor "0.000000") (elecCondVal "0 mho/cm") (thermCondVal "0.012 w/cm-degC")) ("" (layerType "SURFACE") (material "AIR") (thickness "0 mil") (dielectricConstant "1.000000") (lossTangent "0") (etchFactor "0.000000") (elecCondVal "0 mho/cm") (thermCondVal "0 w/cm-degC"))))) (Props (DesUnits "mils 2") (LayerStack ("DIELECTRIC" "DIELECTRIC" "BOTTOM" "DIELECTRIC" "L17_GND6" "DIELECTRIC" "L16_SIG4" "DIELECTRIC" "L15_GND5" "DIELECTRIC" "L14_SIG3" "DIELECTRIC" "L13_GND4" "DIELECTRIC" "L12_PWR2-SIG" "DIELECTRIC" "L11_GND_TEMP" "DIELECTRIC" "L10_SIG_TEMP" "DIELECTRIC" "L9_SIG_TEMP" "DIELECTRIC" "L8_GND_TEMP" "DIELECTRIC" "L7_PWR1-SIG" "DIELECTRIC" "L6_GND3" "DIELECTRIC" "L5_SIG2" "DIELECTRIC" "L4_GND2" "DIELECTRIC" "L3_SIG1" "DIELECTRIC" "L2_GND1" "DIELECTRIC" "TOP" "DIELECTRIC" "DIELECTRIC")) (Revision "16.600")) (Params (DiffInputPkg ((temperature "27") (bufferModelNonInverting "CDSDefaultInput_2p5v") (bufferModelInverting "CDSDefaultInput_2p5v") (threshInputHighMin "1.7 V") (threshInputHighTyp "1.7  V") (threshInputHighMax "1.7  V") (threshInputLowMin "0.7  V") (threshInputLowTyp "0.7  V") (threshInputLowMax "0.7  V") (mappingTagNonInverting nil) (mappingTagInverting nil) (cycle "1"))) (IbisOutputPkg ((temperature "27") (bufferModel "CDSDefaultOutput_2p5v") (stimuli nil) (offsets nil) (state "tristate") (cycle "1") (termMap nil) (setup "2.0e-09") (hold "1.0e-09") (rise nil) (fall nil) (macroType nil) (voltage nil) (spice nil) (LEFDEFPinName nil) (LEFDEFPinType nil) (mappingTag nil))) (IbisIOPkg ((temperature "27") (bufferModel "CDSDefaultIO_2p5v") (stimuli nil) (offsets nil) (state "tristate") (cycle "1") (termMap nil) (setup "2.0e-09") (hold "1.0e-09") (rise nil) (fall nil) (macroType nil) (voltage nil) (spice nil) (LEFDEFPinName nil) (LEFDEFPinType nil) (mappingTag nil))) (IbisIOMacro ((temperature "27") (bufferModel "CDSDefaultIO_2p5v") (stimuli nil) (offsets nil) (state "tristate") (cycle "1") (termMap nil) (setup "2.0e-09") (hold "1.0e-09") (rise nil) (fall nil) (macroType nil) (voltage nil) (spice nil) (LEFDEFPinName nil) (LEFDEFPinType nil) (mappingTag nil))) (ESpiceDevice nil) (IbisInput ((temperature "27") (bufferModel "CDSDefaultInput_2p5v") (cycle "1") (LEFDEFPinName nil) (LEFDEFPinType nil) (mappingTag nil))) (ShuntTerm ((resistance "50 ohm") (voltage "5 V") (maxDelay "0.1 ns"))) (SeriesTerm ((resistance "22 ohm") (maxDelay "0.1 ns"))) (CurrentProbe nil) (idlCircuit ((allDrivers "active") (ftsMode '("Typ")) (rcvrSelect "all") (simMode "Reflection") (tlineDelayMode "time") (userRevision "1.0") (autoSolve "On"))) (TheveninTerm ((resistanceUp "180 ohm") (resistanceDown "270 ohm") (voltageUp "5 V") (voltageDown "0 V") (maxDelay "0.1 ns"))) (RCTerm ((resistance "50 ohm") (capacitance "20 pF") (voltage "5 V") (maxDelay "0.1 ns"))) (LowClampTerm ((cutoffVoltage "0.7 V") (voltage "0 V") (maxDelay "0.1 ns"))) (Cable (length("1 m"))) (HiClampTerm ((cutoffVoltage "0.7 V") (voltage "5 V") (maxDelay "0.1 ns"))) (DualClampTerm ((cutoffVoltageUp "0.7 V") (cutoffVoltageDown "0.7 V") (voltageUp "5 V") (voltageDown "0 V") (maxDelay "0.1 ns"))) (IbisInputPkg ((temperature "27") (bufferModel "CDSDefaultInput_2p5v") (cycle "1") (LEFDEFPinName nil) (LEFDEFPinType nil) (mappingTag nil))) (async ((asyncTimePoints "") (asyncInitState "1"))) (clocked ((clockRise "1e-09") (clockFall "1e-09") (clockFreq "100e6") (clockInitState "0") (clockDutyCycle "0.5") (clockJitter "0"))) (Diode ((cutoffVoltage "0.7 V"))) (IbisOutput ((temperature "27") (bufferModel "CDSDefaultOutput_2p5v") (stimuli nil) (offsets nil) (state "tristate") (cycle "1") (termMap nil) (setup "2.0e-09") (hold "1.0e-09") (rise nil) (fall nil) (macroType nil) (voltage nil) (spice nil) (LEFDEFPinName nil) (LEFDEFPinType nil) (mappingTag nil))) (periodic ((periodicFreq "100e6") (periodicPattern "10") (periodicJitter "0"))) (IbisIO ((temperature "27") (bufferModel "CDSDefaultIO_2p5v") (stimuli nil) (offsets nil) (state "tristate") (cycle "1") (termMap nil) (setup "2.0e-09") (hold "1.0e-09") (rise nil) (fall nil) (macroType nil) (voltage nil) (spice nil) (LEFDEFPinName nil) (LEFDEFPinType nil) (mappingTag nil))) (Via ((model "Unknown") (viaOutputFormat "Unknown") (viaPadstack nil) (viaTopLayer nil) (viaBottomLayer nil) (viaIsPower nil) (viaIsGround nil))) (CPWMS ((d1Thickness "10 mil") (d1Constant "4.5") (d1LossTangent "0.035") (d2Thickness "0.72 mil") (d2Constant "4.5") (d2LossTangent "0.035") (d3Thickness "0.0") (d3Constant "1") (d3LossTangent "0") length("1000 mil") (spacing "5 mil") (spacing2 "5 mil") (spacing3 "5 mil") (spacing4 "5 mil") (spacing5 "5 mil") (traceConductivity "595900 mho/cm") (traceGeometry "cpwms") (traceLayerName "") (traceThickness "0.72 mil") (traceType "single") (traceWidth "5.0 mil") (traceWidth2 "5.0 mil") (traceWidth3 "5.0 mil") (traceWidth4 "5.0 mil") (traceWidth5 "5.0 mil") (traceWidth6 "5.0 mil") (offset "0 mil") (traceCount "1") (impedance nil))) (Trace ((d1Thickness "10 mil") (d1Constant "4.5") (d1LossTangent "0.035") (d2Thickness "10 mil") (d2Constant "4.5") (d2LossTangent "0.035") (d3Thickness "0.0") (d3Constant "1.0") (d3LossTangent "0") length("1000 mil") (spacing "5 mil") (spacing2 "5 mil") (spacing3 "5 mil") (spacing4 "5 mil") (spacing5 "5 mil") (traceConductivity "595900 mho/cm") (traceGeometry "microstrip") (traceLayerName "") (traceThickness "0.72 mil") (traceType "single") (traceWidth "5.0 mil") (traceWidth2 "5.0 mil") (traceWidth3 "5.0 mil") (traceWidth4 "5.0 mil") (traceWidth5 "5.0 mil") (traceWidth6 "5.0 mil") (offset "0 mil") (traceCount "1") (impedance nil))) (Source ((voltage "5 V"))) (CPWSL ((d1Thickness "10 mil") (d1Constant "4.5") (d1LossTangent "0.035") (d2Thickness "0.72 mil") (d2Constant "4.5") (d2LossTangent "0.035") (d3Thickness "10 mil") (d3Constant "4.5") (d3LossTangent "0.035") length("1000 mil") (spacing "5 mil") (spacing2 "5 mil") (spacing3 "5 mil") (spacing4 "5 mil") (spacing5 "5 mil") (traceConductivity "595900 mho/cm") (traceGeometry "cpwms") (traceLayerName "") (traceThickness "0.72 mil") (traceType "single") (traceWidth "5.0 mil") (traceWidth2 "5.0 mil") (traceWidth3 "5.0 mil") (traceWidth4 "5.0 mil") (traceWidth5 "5.0 mil") (traceWidth6 "5.0 mil") (offset "0 mil") (traceCount "1") (impedance nil))) (RLGC (length("1000 mil"))) (Capacitor ((capacitance "10 pF") (orientation "0"))) (DiffIOPkg ((temperature "27") (bufferModelNonInverting "CDSDefaultIO_2p5v") (bufferModelInverting "CDSDefaultIO_2p5v") (stimuli nil) (offsets nil) (state "tristate") (cycle "1") (termMap nil) (setup "0.9e-09") (hold "0.4e-09") (rise nil) (fall nil) (threshInputHighMin "1.7 V") (threshInputHighTyp "1.7  V") (threshInputHighMax "1.7  V") (threshInputLowMin "0.7  V") (threshInputLowTyp "0.7  V") (threshInputLowMax "0.7 ") (threshOutputHighMin "2.365  V") (threshOutputHighTyp "2.5  V") (threshOutputHighMax "2.625  V") (threshOutputLowMin "1.275  V") (threshOutputLowTyp "1.7  V") (threshOutputLowMax "1.985  V") (mappingTagNonInverting nil) (mappingTagInverting nil) (spice nil))) (Inductor ((inductance "5 nH") (orientation "0"))) (DiffIO ((temperature "27") (bufferModelNonInverting "CDSDefaultIO_2p5v") (bufferModelInverting "CDSDefaultIO_2p5v") (stimuli nil) (offsets nil) (state "tristate") (cycle "1") (termMap nil) (setup "0.9e-09") (hold "0.4e-09") (rise nil) (fall nil) (threshInputHighMin "1.7 V") (threshInputHighTyp "1.7  V") (threshInputHighMax "1.7  V") (threshInputLowMin "0.7  V") (threshInputLowTyp "0.7  V") (threshInputLowMax "0.7 ") (threshOutputHighMin "2.365  V") (threshOutputHighTyp "2.5  V") (threshOutputHighMax "2.625  V") (threshOutputLowMin "1.275  V") (threshOutputLowTyp "1.7  V") (threshOutputLowMax "1.985  V") (mappingTagNonInverting nil) (mappingTagInverting nil) (spice nil))) (CPW ((d1Thickness "10 mil") (d1Constant "4.5") (d1LossTangent "0.035") (d2Thickness "0.72 mil") (d2Constant "1") (d2LossTangent "0") (d3Thickness "0.0") (d3Constant "1") (d3LossTangent "0") length("1000 mil") (spacing "5 mil") (spacing2 "5 mil") (spacing3 "5 mil") (spacing4 "5 mil") (spacing5 "5 mil") (traceConductivity "595900 mho/cm") (traceGeometry "cpwms") (traceLayerName "") (traceThickness "0.72 mil") (traceType "single") (traceWidth "5.0 mil") (traceWidth2 "5.0 mil") (traceWidth3 "5.0 mil") (traceWidth4 "5.0 mil") (traceWidth5 "5.0 mil") (traceWidth6 "5.0 mil") (offset "0 mil") (traceCount "1") (impedance nil))) (Connector nil) (TLine ((diffImpedance "100ohm") (diffVelocity "1.4142e+08M/s") (impedance "60ohm") length("2800 mil") (propDelay "0.5 ns") (velocity "5600 mil/ns") (traceCount "1") (traceGeometry "Microstrip") (impedanceMin nil) (impedanceMax nil) (lengthMin nil) (lengthMax nil) (propDelayMin nil) (propDelayMax nil) (impedanceSweepCount nil) (propDelaySweepCount nil) (velocitySweepCount nil) (lengthSweepCount nil) (matchSetName nil))) (sync ((syncFreq "100e6") (syncInitState "1") (syncPattern "10") (syncEdgeSwitch "rise"))) (IbisIO_OpenPullDown ((temperature "27") (bufferModel "CDSDefaultIO_2p5v") (stimuli nil) (offsets nil) (state "tristate") (cycle "1") (termMap nil) (setup "2.0e-09") (hold "1.0e-09") (rise nil) (fall nil) (macroType nil) (voltage nil) (spice nil) (LEFDEFPinName nil) (LEFDEFPinType nil) (mappingTag nil))) (DiffOutputPkg ((temperature "27") (bufferModelNonInverting "CDSDefaultOutput_2p5v") (bufferModelInverting "CDSDefaultOutput_2p5v") (stimuli nil) (offsets nil) (state "tristate") (cycle "1") (termMap nil) (setup "0.9e-09") (hold "0.4e-09") (rise nil) (fall nil) (threshOutputHighMin "2.375  V") (threshOutputHighTyp "2.5  V") (threshOutputHighMax "2.625  V") (threshOutputLowMin "1.275  V") (threshOutputLowTyp "1.7  V") (threshOutputLowMax "1.985  V") (mappingTagNonInverting nil) (mappingTagInverting nil) (spice nil))) (DiffInput ((temperature "27") (bufferModelNonInverting "CDSDefaultInput_2p5v") (bufferModelInverting "CDSDefaultInput_2p5v") (threshInputHighMin "1.7 V") (threshInputHighTyp "1.7  V") (threshInputHighMax "1.7  V") (threshInputLowMin "0.7  V") (threshInputLowTyp "0.7  V") (threshInputLowMax "0.7  V") (mappingTagNonInverting nil) (mappingTagInverting nil) (cycle "1"))) (Resistor ((resistance "50 ohm") (orientation "0"))) (DiffOutput ((temperature "27") (bufferModelNonInverting "CDSDefaultOutput_2p5v") (bufferModelInverting "CDSDefaultOutput_2p5v") (stimuli nil) (offsets nil) (state "tristate") (cycle "1") (termMap nil) (setup "0.9e-09") (hold "0.4e-09") (rise nil) (fall nil) (threshOutputHighMin "2.375  V") (threshOutputHighTyp "2.5  V") (threshOutputHighMax "2.625  V") (threshOutputLowMin "1.275  V") (threshOutputLowTyp "1.7  V") (threshOutputLowMax "1.985  V") (mappingTagNonInverting nil) (mappingTagInverting nil) (spice nil))) (IbisOutput_OpenPullUp ((temperature "27") (bufferModel "CDSDefaultOutput_2p5v") (stimuli nil) (offsets nil) (state "tristate") (cycle "1") (termMap nil) (setup "2.0e-09") (hold "1.0e-09") (rise nil) (fall nil) (macroType nil) (voltage nil) (spice nil) (LEFDEFPinName nil) (LEFDEFPinType nil) (mappingTag nil))) (IbisIO_OpenPullUp ((temperature "27") (bufferModel "CDSDefaultIO_2p5v") (stimuli nil) (offsets nil) (state "tristate") (cycle "1") (termMap nil) (setup "2.0e-09") (hold "1.0e-09") (rise nil) (fall nil) (macroType nil) (voltage nil) (spice nil) (LEFDEFPinName nil) (LEFDEFPinType nil) (mappingTag nil)))))
				)
				( objectStatus "SPI_SWITCH_IO2" )
			)
			( electricalCSet "@crescent_city_bb_fab1_lib.crescent_city_bb_fab1(sch_1):\SGPIO_PCH_SATA_CLOCK\"
				( pinPairRef "SGPIO_PCH:R2L11.2:R2N31.2" )
				( pinPairRef "SGPIO_PCH:R2N31.1:U7C1.AL7" )
				( pinPairRef "SGPIO_PCH:J8A1.1A2:R2L11.2" )
				( attribute "TOPOLOGY_TEMPLATE_REVISION" "1.0"
					( Origin gBackEnd )
				)
				( topologyData 24870
(SKIDL (Circuits ("MAIN" (Parts ("CRESCENT_CITY_195_20150129_6PIN.@@U22.AL7" IbisIOPkg (xy (5527 4221)) (refDes "U7C1") (model "Unknown") (Props (_SXDesignName "CRESCENT_CITY_195_20150129_6PIN") (brdx "15284.75 MIL") (brdy "3784.2 MIL") (bufferModel "CDSDefaultIO_2p5v") (cycle "1") (hold "1.0e-09") (mappingTag "") (offsets ("4" "0") ("5" "0")) (setup "2.0e-09") (state "tristate") (stimuli ("4" "local10") ("5" "local11")) (temperature "27") (termMap ("4" "Data") ("5" "Enable"))) (Terms ("CRESCENT_CITY_195_20150129_6PIN.X1528475Y378420L2LRATS" "AL7"))) ("CRESCENT_CITY_195_20150129_6PIN.@@J76.1A2" IbisIOPkg (xy (5502 4240)) (refDes "J8A1") (model "Unknown") (Props (_SXDesignName "CRESCENT_CITY_195_20150129_6PIN") (brdx "16910.47 MIL") (brdy "6155.12 MIL") (bufferModel "CDSDefaultIO_2p5v") (cycle "1") (hold "1.0e-09") (mappingTag "") (offsets ("4" "0") ("5" "0")) (setup "2.0e-09") (state "tristate") (stimuli ("4" "local12") ("5" "local13")) (temperature "27") (termMap ("4" "Data") ("5" "Enable"))) (Terms ("CRESCENT_CITY_195_20150129_6PIN.X1691047Y615512L2LRATS" "1A2"))) ("CRESCENT_CITY_195_20150129_6PIN.@@R358.1.2" Resistor (xy (5488 4229)) (refDes "R2L11") (value "2000 Ohm") (Props (_SXDesignName "CRESCENT_CITY_195_20150129_6PIN")) (Terms ("CRESCENT_CITY_195_20150129_6PIN.X1707000Y604500L28RATS" "1") ("CRESCENT_CITY_195_20150129_6PIN.X1703500Y604500L28LRATS" "2"))) ("CRESCENT_CITY_195_20150129_6PIN.@@R349.1.2" Resistor (xy (5497 4216)) (mirror x) (refDes "R2N31") (value "49.9 Ohm") (Props (_SXDesignName "CRESCENT_CITY_195_20150129_6PIN")) (Terms ("CRESCENT_CITY_195_20150129_6PIN.X1539750Y330000L2LRATS" "1") ("CRESCENT_CITY_195_20150129_6PIN.X1536250Y330000L2LRATS" "2"))) ("CRESCENT_CITY_195_20150129_6PIN.@@R358.1_SOURCE" Source (xy (5481 4229)) (refDes "P3V3_STBY") (value "3.3 V") (Props (_SXDesignName "CRESCENT_CITY_195_20150129_6PIN")) (Terms ("CRESCENT_CITY_195_20150129_6PIN.X1707000Y604500L28RATS" "1"))) ("CRESCENT_CITY_195_20150129_6PIN.T@@RATS@@J76.1A2@@R349.2" TLine (xy (5503 4222)) (mirror x) (refDes "TL4") (Props (_SXDesignName "CRESCENT_CITY_195_20150129_6PIN") (impedance "60 ohm") length("4403.07 MIL") (propDelay "0.790825 ns") (traceCount "1") (traceGeometry "Microstrip") (velocity "5567.68 mil/ns")) (Terms ("CRESCENT_CITY_195_20150129_6PIN.X1691047Y615512L2LRATS" "1") ("CRESCENT_CITY_195_20150129_6PIN.X1536250Y330000L2LRATS" "2"))) ("CRESCENT_CITY_195_20150129_6PIN.T@@RATS@@U22.AL7@@R349.1" TLine (xy (5512 4216)) (mirror x) (refDes "TL5") (Props (_SXDesignName "CRESCENT_CITY_195_20150129_6PIN") (impedance "48.412 ohm") length("596.95 MIL") (propDelay "0.10722 ns") (traceCount "1") (traceGeometry "Microstrip") (velocity "5567.52 mil/ns")) (Terms ("CRESCENT_CITY_195_20150129_6PIN.X1528475Y378420L2LRATS" "1") ("CRESCENT_CITY_195_20150129_6PIN.X1539750Y330000L2LRATS" "2"))) ("CRESCENT_CITY_195_20150129_6PIN.T@@RATS@@R358.2@@J76.1A2" TLine (xy (5497 4229)) (refDes "TL6") (Props (_SXDesignName "CRESCENT_CITY_195_20150129_6PIN") (impedance "46.577 ohm") length("234.65 MIL") (propDelay "0.04214 ns") (traceCount "1") (traceGeometry "Microstrip") (velocity "5568.35 mil/ns")) (Terms ("CRESCENT_CITY_195_20150129_6PIN.X1703500Y604500L28LRATS" "1") ("CRESCENT_CITY_195_20150129_6PIN.X1691047Y615512L2LRATS" "2")))) (Nodes ("CRESCENT_CITY_195_20150129_6PIN.X1691047Y615512L2LRATS" (terms "CRESCENT_CITY_195_20150129_6PIN.T@@RATS@@R358.2@@J76.1A2.2" "CRESCENT_CITY_195_20150129_6PIN.T@@RATS@@J76.1A2@@R349.2.1" "CRESCENT_CITY_195_20150129_6PIN.@@J76.1A2.1")) ("CRESCENT_CITY_195_20150129_6PIN.X1528475Y378420L2LRATS" (terms "CRESCENT_CITY_195_20150129_6PIN.T@@RATS@@U22.AL7@@R349.1.1" "CRESCENT_CITY_195_20150129_6PIN.@@U22.AL7.1")) ("CRESCENT_CITY_195_20150129_6PIN.X1536250Y330000L2LRATS" (terms "CRESCENT_CITY_195_20150129_6PIN.T@@RATS@@J76.1A2@@R349.2.2" "CRESCENT_CITY_195_20150129_6PIN.@@R349.1.2.2")) ("CRESCENT_CITY_195_20150129_6PIN.X1703500Y604500L28LRATS" (terms "CRESCENT_CITY_195_20150129_6PIN.T@@RATS@@R358.2@@J76.1A2.1" "CRESCENT_CITY_195_20150129_6PIN.@@R358.1.2.2")) ("CRESCENT_CITY_195_20150129_6PIN.X1707000Y604500L28RATS" (terms "CRESCENT_CITY_195_20150129_6PIN.@@R358.1_SOURCE.1" "CRESCENT_CITY_195_20150129_6PIN.@@R358.1.2.1")) ("CRESCENT_CITY_195_20150129_6PIN.X1539750Y330000L2LRATS" (terms "CRESCENT_CITY_195_20150129_6PIN.T@@RATS@@U22.AL7@@R349.1.2" "CRESCENT_CITY_195_20150129_6PIN.@@R349.1.2.1"))) (Ports) (Stimuli ("local10" (scope local) (stimType periodic) (Props (periodicFreq "5e+007") (periodicJitter "0") (periodicPattern "1"))) ("local13" (scope local) (stimType periodic) (Props (periodicFreq "5e+007") (periodicJitter "0") (periodicPattern "1"))) ("local11" (scope local) (stimType periodic) (Props (periodicFreq "5e+007") (periodicJitter "0") (periodicPattern "1"))) ("local12" (scope local) (stimType periodic) (Props (periodicFreq "5e+007") (periodicJitter "0") (periodicPattern "1")))) (Notes) (Constraints ("DELAY_RULE" ("CRESCENT_CITY_195_20150129_6PIN R358.2" "CRESCENT_CITY_195_20150129_6PIN R349.2" "LENGTH" "0.0254" "LENGTH" "0.381") ("CRESCENT_CITY_195_20150129_6PIN R349.1" "CRESCENT_CITY_195_20150129_6PIN U22.AL7" "LENGTH" "0.00254" "LENGTH" "0.0508") ("CRESCENT_CITY_195_20150129_6PIN J76.1A2" "CRESCENT_CITY_195_20150129_6PIN R358.2" "LENGTH" "0.00254" "LENGTH" "0.0254"))) (MeasurementSets ("EMI" ("EMIStatus" status("on")) ("PeakEmission" status("on")) ("PeakFrequency" status("on")) ("PulseFreq" status("on")) ("RiseTime" status("on")) ("VoltageSwing" status("on"))) ("Reflection" ("BufferDelayFall" status("off")) ("BufferDelayRise" status("off")) ("EyeHeight" status("off")) ("EyeJitter" status("off")) ("EyeWidth" status("off")) ("FirstIncidentFall" status("off")) ("FirstIncidentRise" status("off")) ("Glitch" status("on")) ("GlitchFall" status("off")) ("GlitchRise" status("off")) ("Monotonic" status("on")) ("MonotonicFall" status("off")) ("MonotonicRise" status("off")) ("NoiseMargin" status("on")) ("NoiseMarginHigh" status("off")) ("NoiseMarginLow" status("off")) ("OvershootHigh" status("on")) ("OvershootLow" status("on")) ("PropDelay" status("on")) ("SettleDelay" status("on")) ("SettleDelayFall" status("off")) ("SettleDelayRise" status("off")) ("SwitchDelay" status("on")) ("SwitchDelayFall" status("off")) ("SwitchDelayRise" status("off"))) ("Crosstalk" ("Crosstalk" status("on"))) ("Custom")) (VectorSets) (Props (XnetName "SGPIO_PCH_SATA_CLOCK") (allDrivers "active") (customSimType "Reflection") (ftsMode ("Typ")) (rcvrSelect "all") (tlineDelayMode "time") (userRevision "1.0")))) (Subckts) (CrossSections ("CRESCENT_CITY_195_20150129_6PIN" (Props (SXDesignName "CRESCENT_CITY_195_20150129_6PIN")) (Layers ("" (layerType "SURFACE") (material "AIR") (thickness "0 mil") (dielectricConstant "1.000000") (lossTangent "0") (etchFactor "0.000000") (elecCondVal "0 mho/cm") (thermCondVal "0 w/cm-degC")) ("" (layerType "DIELECTRIC") (material "CONFORMAL_COAT") (thickness "0.5 mil") (dielectricConstant "3.800000") (lossTangent "0.035") (etchFactor "0.000000") (elecCondVal "0 mho/cm") (thermCondVal "0.012 w/cm-degC")) ("TOP" (layerType "CONDUCTOR") (material "COPPER") (thickness "  2.100000 mil") (width "4.00 MIL") (dielectricConstant "4.500000") (lossTangent "0") (etchFactor "70.000000") (elecCondVal "595900.000000 mho/cm") (thermCondVal "0 w/cm-degC") (signalDieConstant "3.800000") (signalLossTangent "0.035")) ("" (layerType "DIELECTRIC") (material "FR-4") (thickness "  2.670000 mil") (dielectricConstant "4.000000") (lossTangent "0.035") (etchFactor "0.000000") (elecCondVal "0 mho/cm") (thermCondVal "0.012 w/cm-degC")) ("L2_GND1" (layerType "PLANE") (material "COPPER") (isShield t) (thickness "  1.250000 mil") (dielectricConstant "4.500000") (lossTangent "0.035") (etchFactor "90.000000") (elecCondVal "595900.000000 mho/cm") (thermCondVal "0.012 w/cm-degC")) ("" (layerType "DIELECTRIC") (material "FR-4") (thickness "  9.000000 mil") (dielectricConstant "4.100000") (lossTangent "0.035") (etchFactor "0.000000") (elecCondVal "0 mho/cm") (thermCondVal "0.012 w/cm-degC")) ("L3_SIG1" (layerType "CONDUCTOR") (material "COPPER") (thickness "  1.250000 mil") (width "4.00 MIL") (dielectricConstant "4.500000") (lossTangent "0.035") (etchFactor "90.000000") (elecCondVal "595900.000000 mho/cm") (thermCondVal "0.012 w/cm-degC") (signalDieConstant "4.100000") (signalLossTangent "0.035")) ("" (layerType "DIELECTRIC") (material "FR-4") (thickness "  3.000000 mil") (dielectricConstant "4.500000") (lossTangent "0.035") (etchFactor "0.000000") (elecCondVal "0 mho/cm") (thermCondVal "0 w/cm-degC")) ("L4_GND2" (layerType "PLANE") (material "COPPER") (isShield t) (thickness "  1.250000 mil") (dielectricConstant "4.500000") (lossTangent "0.035") (etchFactor "90.000000") (elecCondVal "595900.000000 mho/cm") (thermCondVal "0 w/cm-degC")) ("" (layerType "DIELECTRIC") (material "FR-4") (thickness "  9.000000 mil") (dielectricConstant "4.000000") (lossTangent "0.035") (etchFactor "0.000000") (elecCondVal "0 mho/cm") (thermCondVal "0.012 w/cm-degC")) ("L5_SIG2" (layerType "CONDUCTOR") (material "COPPER") (thickness "  1.250000 mil") (width "4.00 MIL") (dielectricConstant "4.500000") (lossTangent "0.035") (etchFactor "90.000000") (elecCondVal "595900.000000 mho/cm") (thermCondVal "0.012 w/cm-degC") (signalDieConstant "4.000000") (signalLossTangent "0.035")) ("" (layerType "DIELECTRIC") (material "FR-4") (thickness "  3.000000 mil") (dielectricConstant "4.500000") (lossTangent "0.035") (etchFactor "0.000000") (elecCondVal "0 mho/cm") (thermCondVal "0 w/cm-degC")) ("L6_GND3" (layerType "PLANE") (material "COPPER") (isShield t) (thickness "  1.250000 mil") (dielectricConstant "4.500000") (lossTangent "0.035") (etchFactor "90.000000") (elecCondVal "595900.000000 mho/cm") (thermCondVal "0 w/cm-degC")) ("" (layerType "DIELECTRIC") (material "FR-4") (thickness "  4.500000 mil") (dielectricConstant "4.100000") (lossTangent "0.035") (etchFactor "0.000000") (elecCondVal "0 mho/cm") (thermCondVal "0.012 w/cm-degC")) ("L7_PWR1-SIG" (layerType "PLANE") (material "COPPER") (isShield t) (thickness "  2.400000 mil") (dielectricConstant "4.500000") (lossTangent "0.035") (etchFactor "90.000000") (elecCondVal "595900.000000 mho/cm") (thermCondVal "0.012 w/cm-degC")) ("" (layerType "DIELECTRIC") (material "FR-4") (thickness "  4.600000 mil") (dielectricConstant "4.000000") (lossTangent "0.035") (etchFactor "0.000000") (elecCondVal "0 mho/cm") (thermCondVal "0.012 w/cm-degC")) ("L8_PWR2-SIG" (layerType "PLANE") (material "COPPER") (isShield t) (thickness "  2.400000 mil") (dielectricConstant "4.500000") (lossTangent "0.035") (etchFactor "90.000000") (elecCondVal "595900.000000 mho/cm") (thermCondVal "0.012 w/cm-degC")) ("" (layerType "DIELECTRIC") (material "FR-4") (thickness "  4.500000 mil") (dielectricConstant "4.500000") (lossTangent "0.035") (etchFactor "0.000000") (elecCondVal "0 mho/cm") (thermCondVal "0 w/cm-degC")) ("L9_GND4" (layerType "PLANE") (material "COPPER") (isShield t) (thickness "  1.250000 mil") (dielectricConstant "4.500000") (lossTangent "0.035") (etchFactor "90.000000") (elecCondVal "595900.000000 mho/cm") (thermCondVal "0 w/cm-degC")) ("" (layerType "DIELECTRIC") (material "FR-4") (thickness "  3.000000 mil") (dielectricConstant "4.100000") (lossTangent "0.035") (etchFactor "0.000000") (elecCondVal "0 mho/cm") (thermCondVal "0.012 w/cm-degC")) ("L10_SIG3" (layerType "CONDUCTOR") (material "COPPER") (thickness "  1.250000 mil") (width "4.00 MIL") (dielectricConstant "4.500000") (lossTangent "0.035") (etchFactor "90.000000") (elecCondVal "595900.000000 mho/cm") (thermCondVal "0.012 w/cm-degC") (signalDieConstant "4.100000") (signalLossTangent "0.035")) ("" (layerType "DIELECTRIC") (material "FR-4") (thickness "  9.000000 mil") (dielectricConstant "4.500000") (lossTangent "0.035") (etchFactor "0.000000") (elecCondVal "0 mho/cm") (thermCondVal "0 w/cm-degC")) ("L11_GND5" (layerType "PLANE") (material "COPPER") (isShield t) (thickness "  1.250000 mil") (dielectricConstant "4.500000") (lossTangent "0.035") (etchFactor "90.000000") (elecCondVal "595900.000000 mho/cm") (thermCondVal "0 w/cm-degC")) ("" (layerType "DIELECTRIC") (material "FR-4") (thickness "  3.000000 mil") (dielectricConstant "4.500000") (lossTangent "0.035") (etchFactor "0.000000") (elecCondVal "0 mho/cm") (thermCondVal "0.012 w/cm-degC")) ("L12_SIG4" (layerType "CONDUCTOR") (material "COPPER") (thickness "  1.250000 mil") (width "4.00 MIL") (dielectricConstant "4.500000") (lossTangent "0.035") (etchFactor "90.000000") (elecCondVal "595900.000000 mho/cm") (thermCondVal "0.012 w/cm-degC") (signalDieConstant "4.500000") (signalLossTangent "0.035")) ("" (layerType "DIELECTRIC") (material "FR-4") (thickness "  9.000000 mil") (dielectricConstant "4.500000") (lossTangent "0.035") (etchFactor "0.000000") (elecCondVal "0 mho/cm") (thermCondVal "0 w/cm-degC")) ("L13_GND6" (layerType "PLANE") (material "COPPER") (isShield t) (thickness "  1.250000 mil") (dielectricConstant "4.500000") (lossTangent "0.035") (etchFactor "90.000000") (elecCondVal "595900.000000 mho/cm") (thermCondVal "0.012 w/cm-degC")) ("" (layerType "DIELECTRIC") (material "FR-4") (thickness "  2.670000 mil") (dielectricConstant "4.500000") (lossTangent "0.035") (etchFactor "0.000000") (elecCondVal "0 mho/cm") (thermCondVal "0.012 w/cm-degC")) ("BOTTOM" (layerType "CONDUCTOR") (material "COPPER") (thickness "  2.100000 mil") (width "4.00 MIL") (dielectricConstant "4.500000") (lossTangent "0") (etchFactor "70.000000") (elecCondVal "595900.000000 mho/cm") (thermCondVal "0 w/cm-degC") (signalDieConstant "3.800000") (signalLossTangent "0.035")) ("" (layerType "DIELECTRIC") (material "CONFORMAL_COAT") (thickness "0.5 mil") (dielectricConstant "3.800000") (lossTangent "0.035") (etchFactor "0.000000") (elecCondVal "0 mho/cm") (thermCondVal "0.012 w/cm-degC")) ("" (layerType "SURFACE") (material "AIR") (thickness "0 mil") (dielectricConstant "1.000000") (lossTangent "0") (etchFactor "0.000000") (elecCondVal "0 mho/cm") (thermCondVal "0 w/cm-degC"))))) (Props (DesUnits "mils 2") (LayerStack ("DIELECTRIC" "DIELECTRIC" "BOTTOM" "DIELECTRIC" "L13_GND6" "DIELECTRIC" "L12_SIG4" "DIELECTRIC" "L11_GND5" "DIELECTRIC" "L10_SIG3" "DIELECTRIC" "L9_GND4" "DIELECTRIC" "L8_PWR2-SIG" "DIELECTRIC" "L7_PWR1-SIG" "DIELECTRIC" "L6_GND3" "DIELECTRIC" "L5_SIG2" "DIELECTRIC" "L4_GND2" "DIELECTRIC" "L3_SIG1" "DIELECTRIC" "L2_GND1" "DIELECTRIC" "TOP" "DIELECTRIC" "DIELECTRIC")) (Revision "16.600")) (Params (DiffOutputPkg ((temperature "27") (bufferModelNonInverting "CDSDefaultOutput_2p5v") (bufferModelInverting "CDSDefaultOutput_2p5v") (stimuli nil) (offsets nil) (state "tristate") (cycle "1") (termMap nil) (setup "0.9e-09") (hold "0.4e-09") (rise nil) (fall nil) (threshOutputHighMin "2.375  V") (threshOutputHighTyp "2.5  V") (threshOutputHighMax "2.625  V") (threshOutputLowMin "1.275  V") (threshOutputLowTyp "1.7  V") (threshOutputLowMax "1.985  V") (mappingTagNonInverting nil) (mappingTagInverting nil) (spice nil))) (HiClampTerm ((cutoffVoltage "0.7 V") (voltage "5 V") (maxDelay "0.1 ns"))) (LowClampTerm ((cutoffVoltage "0.7 V") (voltage "0 V") (maxDelay "0.1 ns"))) (DiffOutput ((temperature "27") (bufferModelNonInverting "CDSDefaultOutput_2p5v") (bufferModelInverting "CDSDefaultOutput_2p5v") (stimuli nil) (offsets nil) (state "tristate") (cycle "1") (termMap nil) (setup "0.9e-09") (hold "0.4e-09") (rise nil) (fall nil) (threshOutputHighMin "2.375  V") (threshOutputHighTyp "2.5  V") (threshOutputHighMax "2.625  V") (threshOutputLowMin "1.275  V") (threshOutputLowTyp "1.7  V") (threshOutputLowMax "1.985  V") (mappingTagNonInverting nil) (mappingTagInverting nil) (spice nil))) (Via ((model "Unknown") (viaOutputFormat "Unknown") (viaPadstack nil) (viaTopLayer nil) (viaBottomLayer nil) (viaIsPower nil) (viaIsGround nil))) (Resistor ((resistance "50 ohm") (orientation "0"))) (RCTerm ((resistance "50 ohm") (capacitance "20 pF") (voltage "5 V") (maxDelay "0.1 ns"))) (DiffIOPkg ((temperature "27") (bufferModelNonInverting "CDSDefaultIO_2p5v") (bufferModelInverting "CDSDefaultIO_2p5v") (stimuli nil) (offsets nil) (state "tristate") (cycle "1") (termMap nil) (setup "0.9e-09") (hold "0.4e-09") (rise nil) (fall nil) (threshInputHighMin "1.7 V") (threshInputHighTyp "1.7  V") (threshInputHighMax "1.7  V") (threshInputLowMin "0.7  V") (threshInputLowTyp "0.7  V") (threshInputLowMax "0.7 ") (threshOutputHighMin "2.365  V") (threshOutputHighTyp "2.5  V") (threshOutputHighMax "2.625  V") (threshOutputLowMin "1.275  V") (threshOutputLowTyp "1.7  V") (threshOutputLowMax "1.985  V") (mappingTagNonInverting nil) (mappingTagInverting nil) (spice nil))) (Trace ((d1Thickness "10 mil") (d1Constant "4.5") (d1LossTangent "0.035") (d2Thickness "10 mil") (d2Constant "4.5") (d2LossTangent "0.035") (d3Thickness "0.0") (d3Constant "1.0") (d3LossTangent "0") length("1000 mil") (spacing "5 mil") (spacing2 "5 mil") (spacing3 "5 mil") (spacing4 "5 mil") (spacing5 "5 mil") (traceConductivity "595900 mho/cm") (traceGeometry "microstrip") (traceLayerName "") (traceThickness "0.72 mil") (traceType "single") (traceWidth "5.0 mil") (traceWidth2 "5.0 mil") (traceWidth3 "5.0 mil") (traceWidth4 "5.0 mil") (traceWidth5 "5.0 mil") (traceWidth6 "5.0 mil") (offset "0 mil") (traceCount "1") (impedance nil))) (TheveninTerm ((resistanceUp "180 ohm") (resistanceDown "270 ohm") (voltageUp "5 V") (voltageDown "0 V") (maxDelay "0.1 ns"))) (DiffIO ((temperature "27") (bufferModelNonInverting "CDSDefaultIO_2p5v") (bufferModelInverting "CDSDefaultIO_2p5v") (stimuli nil) (offsets nil) (state "tristate") (cycle "1") (termMap nil) (setup "0.9e-09") (hold "0.4e-09") (rise nil) (fall nil) (threshInputHighMin "1.7 V") (threshInputHighTyp "1.7  V") (threshInputHighMax "1.7  V") (threshInputLowMin "0.7  V") (threshInputLowTyp "0.7  V") (threshInputLowMax "0.7 ") (threshOutputHighMin "2.365  V") (threshOutputHighTyp "2.5  V") (threshOutputHighMax "2.625  V") (threshOutputLowMin "1.275  V") (threshOutputLowTyp "1.7  V") (threshOutputLowMax "1.985  V") (mappingTagNonInverting nil) (mappingTagInverting nil) (spice nil))) (ShuntTerm ((resistance "50 ohm") (voltage "5 V") (maxDelay "0.1 ns"))) (Inductor ((inductance "5 nH") (orientation "0"))) (Capacitor ((capacitance "10 pF") (orientation "0"))) (RLGC (length("1000 mil"))) (Source ((voltage "5 V"))) (DiffInput ((temperature "27") (bufferModelNonInverting "CDSDefaultInput_2p5v") (bufferModelInverting "CDSDefaultInput_2p5v") (threshInputHighMin "1.7 V") (threshInputHighTyp "1.7  V") (threshInputHighMax "1.7  V") (threshInputLowMin "0.7  V") (threshInputLowTyp "0.7  V") (threshInputLowMax "0.7  V") (mappingTagNonInverting nil) (mappingTagInverting nil) (cycle "1"))) (CPW ((d1Thickness "10 mil") (d1Constant "4.5") (d1LossTangent "0.035") (d2Thickness "0.72 mil") (d2Constant "1") (d2LossTangent "0") (d3Thickness "0.0") (d3Constant "1") (d3LossTangent "0") length("1000 mil") (spacing "5 mil") (spacing2 "5 mil") (spacing3 "5 mil") (spacing4 "5 mil") (spacing5 "5 mil") (traceConductivity "595900 mho/cm") (traceGeometry "cpwms") (traceLayerName "") (traceThickness "0.72 mil") (traceType "single") (traceWidth "5.0 mil") (traceWidth2 "5.0 mil") (traceWidth3 "5.0 mil") (traceWidth4 "5.0 mil") (traceWidth5 "5.0 mil") (traceWidth6 "5.0 mil") (offset "0 mil") (traceCount "1") (impedance nil))) (Cable (length("1 m"))) (CPWMS ((d1Thickness "10 mil") (d1Constant "4.5") (d1LossTangent "0.035") (d2Thickness "0.72 mil") (d2Constant "4.5") (d2LossTangent "0.035") (d3Thickness "0.0") (d3Constant "1") (d3LossTangent "0") length("1000 mil") (spacing "5 mil") (spacing2 "5 mil") (spacing3 "5 mil") (spacing4 "5 mil") (spacing5 "5 mil") (traceConductivity "595900 mho/cm") (traceGeometry "cpwms") (traceLayerName "") (traceThickness "0.72 mil") (traceType "single") (traceWidth "5.0 mil") (traceWidth2 "5.0 mil") (traceWidth3 "5.0 mil") (traceWidth4 "5.0 mil") (traceWidth5 "5.0 mil") (traceWidth6 "5.0 mil") (offset "0 mil") (traceCount "1") (impedance nil))) (CPWSL ((d1Thickness "10 mil") (d1Constant "4.5") (d1LossTangent "0.035") (d2Thickness "0.72 mil") (d2Constant "4.5") (d2LossTangent "0.035") (d3Thickness "10 mil") (d3Constant "4.5") (d3LossTangent "0.035") length("1000 mil") (spacing "5 mil") (spacing2 "5 mil") (spacing3 "5 mil") (spacing4 "5 mil") (spacing5 "5 mil") (traceConductivity "595900 mho/cm") (traceGeometry "cpwms") (traceLayerName "") (traceThickness "0.72 mil") (traceType "single") (traceWidth "5.0 mil") (traceWidth2 "5.0 mil") (traceWidth3 "5.0 mil") (traceWidth4 "5.0 mil") (traceWidth5 "5.0 mil") (traceWidth6 "5.0 mil") (offset "0 mil") (traceCount "1") (impedance nil))) (ESpiceDevice nil) (Diode ((cutoffVoltage "0.7 V"))) (DualClampTerm ((cutoffVoltageUp "0.7 V") (cutoffVoltageDown "0.7 V") (voltageUp "5 V") (voltageDown "0 V") (maxDelay "0.1 ns"))) (IbisOutputPkg ((temperature "27") (bufferModel "CDSDefaultOutput_2p5v") (stimuli nil) (offsets nil) (state "tristate") (cycle "1") (termMap nil) (setup "2.0e-09") (hold "1.0e-09") (rise nil) (fall nil) (macroType nil) (voltage nil) (spice nil) (LEFDEFPinName nil) (LEFDEFPinType nil) (mappingTag nil))) (IbisIO_OpenPullDown ((temperature "27") (bufferModel "CDSDefaultIO_2p5v") (stimuli nil) (offsets nil) (state "tristate") (cycle "1") (termMap nil) (setup "2.0e-09") (hold "1.0e-09") (rise nil) (fall nil) (macroType nil) (voltage nil) (spice nil) (LEFDEFPinName nil) (LEFDEFPinType nil) (mappingTag nil))) (IbisInputPkg ((temperature "27") (bufferModel "CDSDefaultInput_2p5v") (cycle "1") (LEFDEFPinName nil) (LEFDEFPinType nil) (mappingTag nil))) (IbisIOMacro ((temperature "27") (bufferModel "CDSDefaultIO_2p5v") (stimuli nil) (offsets nil) (state "tristate") (cycle "1") (termMap nil) (setup "2.0e-09") (hold "1.0e-09") (rise nil) (fall nil) (macroType nil) (voltage nil) (spice nil) (LEFDEFPinName nil) (LEFDEFPinType nil) (mappingTag nil))) (IbisIO_OpenPullUp ((temperature "27") (bufferModel "CDSDefaultIO_2p5v") (stimuli nil) (offsets nil) (state "tristate") (cycle "1") (termMap nil) (setup "2.0e-09") (hold "1.0e-09") (rise nil) (fall nil) (macroType nil) (voltage nil) (spice nil) (LEFDEFPinName nil) (LEFDEFPinType nil) (mappingTag nil))) (IbisIOPkg ((temperature "27") (bufferModel "CDSDefaultIO_2p5v") (stimuli nil) (offsets nil) (state "tristate") (cycle "1") (termMap nil) (setup "2.0e-09") (hold "1.0e-09") (rise nil) (fall nil) (macroType nil) (voltage nil) (spice nil) (LEFDEFPinName nil) (LEFDEFPinType nil) (mappingTag nil))) (clocked ((clockRise "1e-09") (clockFall "1e-09") (clockFreq "100e6") (clockInitState "0") (clockDutyCycle "0.5") (clockJitter "0"))) (periodic ((periodicFreq "100e6") (periodicPattern "10") (periodicJitter "0"))) (IbisIO ((temperature "27") (bufferModel "CDSDefaultIO_2p5v") (stimuli nil) (offsets nil) (state "tristate") (cycle "1") (termMap nil) (setup "2.0e-09") (hold "1.0e-09") (rise nil) (fall nil) (macroType nil) (voltage nil) (spice nil) (LEFDEFPinName nil) (LEFDEFPinType nil) (mappingTag nil))) (async ((asyncTimePoints "") (asyncInitState "1"))) (IbisOutput ((temperature "27") (bufferModel "CDSDefaultOutput_2p5v") (stimuli nil) (offsets nil) (state "tristate") (cycle "1") (termMap nil) (setup "2.0e-09") (hold "1.0e-09") (rise nil) (fall nil) (macroType nil) (voltage nil) (spice nil) (LEFDEFPinName nil) (LEFDEFPinType nil) (mappingTag nil))) (TLine ((diffImpedance "100ohm") (diffVelocity "1.4142e+08M/s") (impedance "60ohm") length("2800 mil") (propDelay "0.5 ns") (velocity "5600 mil/ns") (traceCount "1") (traceGeometry "Microstrip") (impedanceMin nil) (impedanceMax nil) (lengthMin nil) (lengthMax nil) (propDelayMin nil) (propDelayMax nil) (impedanceSweepCount nil) (propDelaySweepCount nil) (velocitySweepCount nil) (lengthSweepCount nil) (matchSetName nil))) (CurrentProbe nil) (IbisInput ((temperature "27") (bufferModel "CDSDefaultInput_2p5v") (cycle "1") (LEFDEFPinName nil) (LEFDEFPinType nil) (mappingTag nil))) (SeriesTerm ((resistance "22 ohm") (maxDelay "0.1 ns"))) (Connector nil) (sync ((syncFreq "100e6") (syncInitState "1") (syncPattern "10") (syncEdgeSwitch "rise"))) (IbisOutput_OpenPullUp ((temperature "27") (bufferModel "CDSDefaultOutput_2p5v") (stimuli nil) (offsets nil) (state "tristate") (cycle "1") (termMap nil) (setup "2.0e-09") (hold "1.0e-09") (rise nil) (fall nil) (macroType nil) (voltage nil) (spice nil) (LEFDEFPinName nil) (LEFDEFPinType nil) (mappingTag nil))) (DiffInputPkg ((temperature "27") (bufferModelNonInverting "CDSDefaultInput_2p5v") (bufferModelInverting "CDSDefaultInput_2p5v") (threshInputHighMin "1.7 V") (threshInputHighTyp "1.7  V") (threshInputHighMax "1.7  V") (threshInputLowMin "0.7  V") (threshInputLowTyp "0.7  V") (threshInputLowMax "0.7  V") (mappingTagNonInverting nil) (mappingTagInverting nil) (cycle "1"))) (idlCircuit ((allDrivers "active") (ftsMode '("Typ")) (rcvrSelect "all") (simMode "Reflection") (tlineDelayMode "time") (userRevision "1.0") (autoSolve "On")))))
				)
				( objectStatus "SGPIO_PCH" )
			)
			( electricalCSet "@baseboard_fab2_lib.baseboard_fab2(sch_1):\DP_KR_P0_OCP_RX\"
				( pinPairRef "KR_OCP_RX:U7C1.BF31:C30.2" )
				( attribute "RATSNEST_SCHEDULE" "TEMPLATE"
					( Status sLocked )
					( Origin gBackEnd )
				)
				( attribute "DIFFP_GATHER_CONTROL" "IGNORE"
					( Origin gBackEnd )
				)
				( attribute "DIFFP_COUPLED_PLUS" "0.10"
					( Origin gBackEnd )
				)
				( attribute "DIFFP_COUPLED_MINUS" "0.10"
					( Origin gBackEnd )
				)
				( attribute "DIFFP_PHASE_TOL" "5 mil"
					( Units "uPhaseTol" "ns" 1.000000)
					( Origin gBackEnd )
				)
				( attribute "DIFFP_PHASE_MAX_LENGTH" "600.00"
					( Origin gBackEnd )
				)
				( attribute "DIFFP_PHASE_TOL_DYNAMIC" "25 mil"
					( Units "uPhaseTol" "mil" 1.000000)
					( Origin gBackEnd )
				)
				( attribute "DIFFP_NECK_GAP" "4.00"
					( Origin gBackEnd )
				)
				( attribute "MIN_NECK_WIDTH" "3.50"
					( Origin gBackEnd )
				)
				( attribute "TOPOLOGY_TEMPLATE_REVISION" "1.0"
					( Origin gBackEnd )
				)
				( topologyData 23703
(SKIDL (Circuits ("MAIN" (Parts ("CRESCENT_CITY_FAB2_2V060_20150717_A.@@J1.40" IbisIOPkg (xy (5527 4228)) (refDes "J8E4") (model "Unknown") (Props (_SXDesignName "CRESCENT_CITY_FAB2_2V060_20150717_A") (brdx "17942.91 MIL") (brdy "2444.96 MIL") (bufferModel "CDSDefaultIO_2p5v") (cycle "1") (hold "1.0e-09") (mappingTag "") (offsets ("4" "0") ("5" "0")) (setup "2.0e-09") (state "tristate") (stimuli ("4" "local10") ("5" "local11")) (temperature "27") (termMap ("4" "Data") ("5" "Enable"))) (Terms ("CRESCENT_CITY_FAB2_2V060_20150717_A.X1794291Y244496L2LRATS" "40"))) ("CRESCENT_CITY_FAB2_2V060_20150717_A.@@U7C1.BF31" IbisIOPkg (xy (5473.5 4228.0)) (refDes "U7C1") (model "Unknown") (Props (_SXDesignName "CRESCENT_CITY_FAB2_2V060_20150717_A") (brdx "15538.25 MIL") (brdy "4223.6 MIL") (bufferModel "CDSDefaultIO_2p5v") (cycle "1") (hold "1.0e-09") (mappingTag "") (offsets ("4" "0") ("5" "0")) (setup "2.0e-09") (state "tristate") (stimuli ("4" "local12") ("5" "local13")) (temperature "27") (termMap ("4" "Data") ("5" "Enable"))) (Terms ("CRESCENT_CITY_FAB2_2V060_20150717_A.X1553825Y422360L2LRATS" "BF31"))) ("CRESCENT_CITY_FAB2_2V060_20150717_A.@@C21.1.2" Capacitor (xy (5497 4223)) (mirror x) (refDes "C30") (value "100000 pF") (Props (_SXDesignName "CRESCENT_CITY_FAB2_2V060_20150717_A")) (Terms ("CRESCENT_CITY_FAB2_2V060_20150717_A.X2200000Y210000L2LRATS" "1") ("CRESCENT_CITY_FAB2_2V060_20150717_A.X2200000Y206500L2LRATS" "2"))) ("CRESCENT_CITY_FAB2_2V060_20150717_A.T@@RATS@@J1.40@@C21.1" TLine (xy (5512 4223)) (mirror x) (refDes "TL3") (Props (_SXDesignName "CRESCENT_CITY_FAB2_2V060_20150717_A") (impedance "60 ohm") length("4402.05 MIL") (propDelay "0.790638 ns") (traceCount "1") (traceGeometry "Microstrip") (velocity "5567.72 mil/ns")) (Terms ("CRESCENT_CITY_FAB2_2V060_20150717_A.X1794291Y244496L2LRATS" "1") ("CRESCENT_CITY_FAB2_2V060_20150717_A.X2200000Y210000L2LRATS" "2"))) ("CRESCENT_CITY_FAB2_2V060_20150717_A.T@@RATS@@U7C1.BF31@@C21.2" TLine (xy (5485.0 4223.0)) (refDes "TL4") (Props (_SXDesignName "CRESCENT_CITY_FAB2_2V060_20150717_A") (impedance "60 ohm") length("8620.35 MIL") (propDelay "1.54827 ns") (traceCount "1") (traceGeometry "Microstrip") (velocity "5567.72 mil/ns")) (Terms ("CRESCENT_CITY_FAB2_2V060_20150717_A.X1553825Y422360L2LRATS" "1") ("CRESCENT_CITY_FAB2_2V060_20150717_A.X2200000Y206500L2LRATS" "2")))) (Nodes ("CRESCENT_CITY_FAB2_2V060_20150717_A.X2200000Y206500L2LRATS" (terms "CRESCENT_CITY_FAB2_2V060_20150717_A.T@@RATS@@U7C1.BF31@@C21.2.2" "CRESCENT_CITY_FAB2_2V060_20150717_A.@@C21.1.2.2")) ("CRESCENT_CITY_FAB2_2V060_20150717_A.X2200000Y210000L2LRATS" (terms "CRESCENT_CITY_FAB2_2V060_20150717_A.T@@RATS@@J1.40@@C21.1.2" "CRESCENT_CITY_FAB2_2V060_20150717_A.@@C21.1.2.1")) ("CRESCENT_CITY_FAB2_2V060_20150717_A.X1553825Y422360L2LRATS" (terms "CRESCENT_CITY_FAB2_2V060_20150717_A.T@@RATS@@U7C1.BF31@@C21.2.1" "CRESCENT_CITY_FAB2_2V060_20150717_A.@@U7C1.BF31.1")) ("CRESCENT_CITY_FAB2_2V060_20150717_A.X1794291Y244496L2LRATS" (terms "CRESCENT_CITY_FAB2_2V060_20150717_A.T@@RATS@@J1.40@@C21.1.1" "CRESCENT_CITY_FAB2_2V060_20150717_A.@@J1.40.1"))) (Ports) (Stimuli ("local10" (scope local) (stimType periodic) (Props (periodicFreq "5e+007") (periodicJitter "0") (periodicPattern "1"))) ("local13" (scope local) (stimType periodic) (Props (periodicFreq "5e+007") (periodicJitter "0") (periodicPattern "1"))) ("local11" (scope local) (stimType periodic) (Props (periodicFreq "5e+007") (periodicJitter "0") (periodicPattern "1"))) ("local12" (scope local) (stimType periodic) (Props (periodicFreq "5e+007") (periodicJitter "0") (periodicPattern "1")))) (Notes) (Constraints ("DELAY_RULE" ("CRESCENT_CITY_FAB2_2V060_20150717_A U7C1.BF31" "CRESCENT_CITY_FAB2_2V060_20150717_A C21.2" "LENGTH" "" "LENGTH" "0.0254")) ("DP_GATHER_CONTROL" "IGNORE") ("DP_NECK_GAP" "0.0001016") ("DP_NECK_WIDTH" "8.89e-005") ("DP_NEGATIVE_COUPLED_TOLERANCE" "2.54e-006") ("DP_PHASE_MAX_LENGTH" "0.01524") ("DP_PHASE_TOLERANCE" ("LENGTH" "0.000127")) ("DP_PHASE_TOLERANCE_DYNAMIC" ("LENGTH" "0.000635")) ("DP_POSITIVE_COUPLED_TOLERANCE" "2.54e-006") ("RATSNEST_SCHEDULE" "TEMPLATE")) (MeasurementSets ("EMI" ("EMIStatus" status("on")) ("PeakEmission" status("on")) ("PeakFrequency" status("on")) ("PulseFreq" status("on")) ("RiseTime" status("on")) ("VoltageSwing" status("on"))) ("Reflection" ("BufferDelayFall" status("off")) ("BufferDelayRise" status("off")) ("EyeHeight" status("off")) ("EyeJitter" status("off")) ("EyeWidth" status("off")) ("FirstIncidentFall" status("off")) ("FirstIncidentRise" status("off")) ("Glitch" status("on")) ("GlitchFall" status("off")) ("GlitchRise" status("off")) ("Monotonic" status("on")) ("MonotonicFall" status("off")) ("MonotonicRise" status("off")) ("NoiseMargin" status("on")) ("NoiseMarginHigh" status("off")) ("NoiseMarginLow" status("off")) ("OvershootHigh" status("on")) ("OvershootLow" status("on")) ("PropDelay" status("on")) ("SettleDelay" status("on")) ("SettleDelayFall" status("off")) ("SettleDelayRise" status("off")) ("SwitchDelay" status("on")) ("SwitchDelayFall" status("off")) ("SwitchDelayRise" status("off"))) ("Crosstalk" ("Crosstalk" status("on"))) ("Custom")) (VectorSets) (Props (XnetName "KR_P0_OCP_RX_C_DP") (allDrivers "active") (customSimType "Reflection") (ftsMode ("Typ")) (rcvrSelect "all") (tlineDelayMode "time") (userRevision "1.0")))) (Subckts) (CrossSections ("CRESCENT_CITY_FAB2_2V060_20150717_A" (Props (SXDesignName "CRESCENT_CITY_FAB2_2V060_20150717_A")) (Layers ("" (layerType "SURFACE") (material "AIR") (thickness "0 mil") (dielectricConstant "1.000000") (lossTangent "0") (etchFactor "0.000000") (elecCondVal "0 mho/cm") (thermCondVal "0 w/cm-degC")) ("" (layerType "DIELECTRIC") (material "CONFORMAL_COAT") (thickness "0.5 mil") (dielectricConstant "3.800000") (lossTangent "0.035") (etchFactor "0.000000") (elecCondVal "0 mho/cm") (thermCondVal "0.012 w/cm-degC")) ("TOP" (layerType "CONDUCTOR") (material "COPPER") (thickness "  2.100000 mil") (width "4.00 MIL") (dielectricConstant "4.500000") (lossTangent "0") (etchFactor "70.000000") (elecCondVal "595900.000000 mho/cm") (thermCondVal "0 w/cm-degC") (signalDieConstant "3.800000") (signalLossTangent "0.035")) ("" (layerType "DIELECTRIC") (material "FR-4") (thickness "  2.670000 mil") (dielectricConstant "4.000000") (lossTangent "0.035") (etchFactor "0.000000") (elecCondVal "0 mho/cm") (thermCondVal "0.012 w/cm-degC")) ("L2_GND1" (layerType "PLANE") (material "COPPER") (isShield t) (thickness "  1.250000 mil") (dielectricConstant "4.500000") (lossTangent "0.035") (etchFactor "90.000000") (elecCondVal "595900.000000 mho/cm") (thermCondVal "0.012 w/cm-degC")) ("" (layerType "DIELECTRIC") (material "FR-4") (thickness "  9.000000 mil") (dielectricConstant "4.100000") (lossTangent "0.035") (etchFactor "0.000000") (elecCondVal "0 mho/cm") (thermCondVal "0.012 w/cm-degC")) ("L3_SIG1" (layerType "CONDUCTOR") (material "COPPER") (thickness "  1.250000 mil") (width "4.00 MIL") (dielectricConstant "4.500000") (lossTangent "0.035") (etchFactor "90.000000") (elecCondVal "595900.000000 mho/cm") (thermCondVal "0.012 w/cm-degC") (signalDieConstant "4.100000") (signalLossTangent "0.035")) ("" (layerType "DIELECTRIC") (material "FR-4") (thickness "  3.000000 mil") (dielectricConstant "4.500000") (lossTangent "0.035") (etchFactor "0.000000") (elecCondVal "0 mho/cm") (thermCondVal "0 w/cm-degC")) ("L4_GND2" (layerType "PLANE") (material "COPPER") (isShield t) (thickness "  1.250000 mil") (dielectricConstant "4.500000") (lossTangent "0.035") (etchFactor "90.000000") (elecCondVal "595900.000000 mho/cm") (thermCondVal "0 w/cm-degC")) ("" (layerType "DIELECTRIC") (material "FR-4") (thickness "  9.000000 mil") (dielectricConstant "4.000000") (lossTangent "0.035") (etchFactor "0.000000") (elecCondVal "0 mho/cm") (thermCondVal "0.012 w/cm-degC")) ("L5_SIG2" (layerType "CONDUCTOR") (material "COPPER") (thickness "  1.250000 mil") (width "4.00 MIL") (dielectricConstant "4.500000") (lossTangent "0.035") (etchFactor "90.000000") (elecCondVal "595900.000000 mho/cm") (thermCondVal "0.012 w/cm-degC") (signalDieConstant "4.000000") (signalLossTangent "0.035")) ("" (layerType "DIELECTRIC") (material "FR-4") (thickness "  3.000000 mil") (dielectricConstant "4.500000") (lossTangent "0.035") (etchFactor "0.000000") (elecCondVal "0 mho/cm") (thermCondVal "0 w/cm-degC")) ("L6_GND3" (layerType "PLANE") (material "COPPER") (isShield t) (thickness "  1.250000 mil") (dielectricConstant "4.500000") (lossTangent "0.035") (etchFactor "90.000000") (elecCondVal "595900.000000 mho/cm") (thermCondVal "0 w/cm-degC")) ("" (layerType "DIELECTRIC") (material "FR-4") (thickness "  4.500000 mil") (dielectricConstant "4.100000") (lossTangent "0.035") (etchFactor "0.000000") (elecCondVal "0 mho/cm") (thermCondVal "0.012 w/cm-degC")) ("L7_PWR1-SIG" (layerType "PLANE") (material "COPPER") (isShield t) (thickness "  2.400000 mil") (dielectricConstant "4.500000") (lossTangent "0.035") (etchFactor "90.000000") (elecCondVal "595900.000000 mho/cm") (thermCondVal "0.012 w/cm-degC")) ("" (layerType "DIELECTRIC") (material "FR-4") (thickness "  4.600000 mil") (dielectricConstant "4.000000") (lossTangent "0.035") (etchFactor "0.000000") (elecCondVal "0 mho/cm") (thermCondVal "0.012 w/cm-degC")) ("L8_PWR2-SIG" (layerType "PLANE") (material "COPPER") (isShield t) (thickness "  2.400000 mil") (dielectricConstant "4.500000") (lossTangent "0.035") (etchFactor "90.000000") (elecCondVal "595900.000000 mho/cm") (thermCondVal "0.012 w/cm-degC")) ("" (layerType "DIELECTRIC") (material "FR-4") (thickness "  4.500000 mil") (dielectricConstant "4.500000") (lossTangent "0.035") (etchFactor "0.000000") (elecCondVal "0 mho/cm") (thermCondVal "0 w/cm-degC")) ("L9_GND4" (layerType "PLANE") (material "COPPER") (isShield t) (thickness "  1.250000 mil") (dielectricConstant "4.500000") (lossTangent "0.035") (etchFactor "90.000000") (elecCondVal "595900.000000 mho/cm") (thermCondVal "0 w/cm-degC")) ("" (layerType "DIELECTRIC") (material "FR-4") (thickness "  3.000000 mil") (dielectricConstant "4.100000") (lossTangent "0.035") (etchFactor "0.000000") (elecCondVal "0 mho/cm") (thermCondVal "0.012 w/cm-degC")) ("L10_SIG3" (layerType "CONDUCTOR") (material "COPPER") (thickness "  1.250000 mil") (width "4.00 MIL") (dielectricConstant "4.500000") (lossTangent "0.035") (etchFactor "90.000000") (elecCondVal "595900.000000 mho/cm") (thermCondVal "0.012 w/cm-degC") (signalDieConstant "4.100000") (signalLossTangent "0.035")) ("" (layerType "DIELECTRIC") (material "FR-4") (thickness "  9.000000 mil") (dielectricConstant "4.500000") (lossTangent "0.035") (etchFactor "0.000000") (elecCondVal "0 mho/cm") (thermCondVal "0 w/cm-degC")) ("L11_GND5" (layerType "PLANE") (material "COPPER") (isShield t) (thickness "  1.250000 mil") (dielectricConstant "4.500000") (lossTangent "0.035") (etchFactor "90.000000") (elecCondVal "595900.000000 mho/cm") (thermCondVal "0 w/cm-degC")) ("" (layerType "DIELECTRIC") (material "FR-4") (thickness "  3.000000 mil") (dielectricConstant "4.500000") (lossTangent "0.035") (etchFactor "0.000000") (elecCondVal "0 mho/cm") (thermCondVal "0.012 w/cm-degC")) ("L12_SIG4" (layerType "CONDUCTOR") (material "COPPER") (thickness "  1.250000 mil") (width "4.00 MIL") (dielectricConstant "4.500000") (lossTangent "0.035") (etchFactor "90.000000") (elecCondVal "595900.000000 mho/cm") (thermCondVal "0.012 w/cm-degC") (signalDieConstant "4.500000") (signalLossTangent "0.035")) ("" (layerType "DIELECTRIC") (material "FR-4") (thickness "  9.000000 mil") (dielectricConstant "4.500000") (lossTangent "0.035") (etchFactor "0.000000") (elecCondVal "0 mho/cm") (thermCondVal "0 w/cm-degC")) ("L13_GND6" (layerType "PLANE") (material "COPPER") (isShield t) (thickness "  1.250000 mil") (dielectricConstant "4.500000") (lossTangent "0.035") (etchFactor "90.000000") (elecCondVal "595900.000000 mho/cm") (thermCondVal "0.012 w/cm-degC")) ("" (layerType "DIELECTRIC") (material "FR-4") (thickness "  2.670000 mil") (dielectricConstant "4.500000") (lossTangent "0.035") (etchFactor "0.000000") (elecCondVal "0 mho/cm") (thermCondVal "0.012 w/cm-degC")) ("BOTTOM" (layerType "CONDUCTOR") (material "COPPER") (thickness "  2.100000 mil") (width "4.00 MIL") (dielectricConstant "4.500000") (lossTangent "0") (etchFactor "70.000000") (elecCondVal "595900.000000 mho/cm") (thermCondVal "0 w/cm-degC") (signalDieConstant "3.800000") (signalLossTangent "0.035")) ("" (layerType "DIELECTRIC") (material "CONFORMAL_COAT") (thickness "0.5 mil") (dielectricConstant "3.800000") (lossTangent "0.035") (etchFactor "0.000000") (elecCondVal "0 mho/cm") (thermCondVal "0.012 w/cm-degC")) ("" (layerType "SURFACE") (material "AIR") (thickness "0 mil") (dielectricConstant "1.000000") (lossTangent "0") (etchFactor "0.000000") (elecCondVal "0 mho/cm") (thermCondVal "0 w/cm-degC"))))) (Props (DesUnits "mils 2") (LayerStack ("DIELECTRIC" "DIELECTRIC" "BOTTOM" "DIELECTRIC" "L13_GND6" "DIELECTRIC" "L12_SIG4" "DIELECTRIC" "L11_GND5" "DIELECTRIC" "L10_SIG3" "DIELECTRIC" "L9_GND4" "DIELECTRIC" "L8_PWR2-SIG" "DIELECTRIC" "L7_PWR1-SIG" "DIELECTRIC" "L6_GND3" "DIELECTRIC" "L5_SIG2" "DIELECTRIC" "L4_GND2" "DIELECTRIC" "L3_SIG1" "DIELECTRIC" "L2_GND1" "DIELECTRIC" "TOP" "DIELECTRIC" "DIELECTRIC")) (Revision "16.600")) (Params (IbisIOMacro ((temperature "27") (bufferModel "CDSDefaultIO_2p5v") (stimuli nil) (offsets nil) (state "tristate") (cycle "1") (termMap nil) (setup "2.0e-09") (hold "1.0e-09") (rise nil) (fall nil) (macroType nil) (voltage nil) (spice nil) (LEFDEFPinName nil) (LEFDEFPinType nil) (mappingTag nil))) (periodic ((periodicFreq "100e6") (periodicPattern "10") (periodicJitter "0"))) (Trace ((d1Thickness "10 mil") (d1Constant "4.5") (d1LossTangent "0.035") (d2Thickness "10 mil") (d2Constant "4.5") (d2LossTangent "0.035") (d3Thickness "0.0") (d3Constant "1.0") (d3LossTangent "0") length("1000 mil") (spacing "5 mil") (spacing2 "5 mil") (spacing3 "5 mil") (spacing4 "5 mil") (spacing5 "5 mil") (traceConductivity "595900 mho/cm") (traceGeometry "microstrip") (traceLayerName "") (traceThickness "0.72 mil") (traceType "single") (traceWidth "5.0 mil") (traceWidth2 "5.0 mil") (traceWidth3 "5.0 mil") (traceWidth4 "5.0 mil") (traceWidth5 "5.0 mil") (traceWidth6 "5.0 mil") (offset "0 mil") (traceCount "1") (impedance nil))) (async ((asyncTimePoints "") (asyncInitState "1"))) (Resistor ((resistance "50 ohm") (orientation "0"))) (Inductor ((inductance "5 nH") (orientation "0"))) (sync ((syncFreq "100e6") (syncInitState "1") (syncPattern "10") (syncEdgeSwitch "rise"))) (Capacitor ((capacitance "10 pF") (orientation "0"))) (Via ((model "Unknown") (viaOutputFormat "Unknown") (viaPadstack nil) (viaTopLayer nil) (viaBottomLayer nil) (viaIsPower nil) (viaIsGround nil))) (CPW ((d1Thickness "10 mil") (d1Constant "4.5") (d1LossTangent "0.035") (d2Thickness "0.72 mil") (d2Constant "1") (d2LossTangent "0") (d3Thickness "0.0") (d3Constant "1") (d3LossTangent "0") length("1000 mil") (spacing "5 mil") (spacing2 "5 mil") (spacing3 "5 mil") (spacing4 "5 mil") (spacing5 "5 mil") (traceConductivity "595900 mho/cm") (traceGeometry "cpwms") (traceLayerName "") (traceThickness "0.72 mil") (traceType "single") (traceWidth "5.0 mil") (traceWidth2 "5.0 mil") (traceWidth3 "5.0 mil") (traceWidth4 "5.0 mil") (traceWidth5 "5.0 mil") (traceWidth6 "5.0 mil") (offset "0 mil") (traceCount "1") (impedance nil))) (ESpiceDevice nil) (Diode ((cutoffVoltage "0.7 V"))) (CPWSL ((d1Thickness "10 mil") (d1Constant "4.5") (d1LossTangent "0.035") (d2Thickness "0.72 mil") (d2Constant "4.5") (d2LossTangent "0.035") (d3Thickness "10 mil") (d3Constant "4.5") (d3LossTangent "0.035") length("1000 mil") (spacing "5 mil") (spacing2 "5 mil") (spacing3 "5 mil") (spacing4 "5 mil") (spacing5 "5 mil") (traceConductivity "595900 mho/cm") (traceGeometry "cpwms") (traceLayerName "") (traceThickness "0.72 mil") (traceType "single") (traceWidth "5.0 mil") (traceWidth2 "5.0 mil") (traceWidth3 "5.0 mil") (traceWidth4 "5.0 mil") (traceWidth5 "5.0 mil") (traceWidth6 "5.0 mil") (offset "0 mil") (traceCount "1") (impedance nil))) (CPWMS ((d1Thickness "10 mil") (d1Constant "4.5") (d1LossTangent "0.035") (d2Thickness "0.72 mil") (d2Constant "4.5") (d2LossTangent "0.035") (d3Thickness "0.0") (d3Constant "1") (d3LossTangent "0") length("1000 mil") (spacing "5 mil") (spacing2 "5 mil") (spacing3 "5 mil") (spacing4 "5 mil") (spacing5 "5 mil") (traceConductivity "595900 mho/cm") (traceGeometry "cpwms") (traceLayerName "") (traceThickness "0.72 mil") (traceType "single") (traceWidth "5.0 mil") (traceWidth2 "5.0 mil") (traceWidth3 "5.0 mil") (traceWidth4 "5.0 mil") (traceWidth5 "5.0 mil") (traceWidth6 "5.0 mil") (offset "0 mil") (traceCount "1") (impedance nil))) (Source ((voltage "5 V"))) (DiffOutput ((temperature "27") (bufferModelNonInverting "CDSDefaultOutput_2p5v") (bufferModelInverting "CDSDefaultOutput_2p5v") (stimuli nil) (offsets nil) (state "tristate") (cycle "1") (termMap nil) (setup "0.9e-09") (hold "0.4e-09") (rise nil) (fall nil) (threshOutputHighMin "2.375  V") (threshOutputHighTyp "2.5  V") (threshOutputHighMax "2.625  V") (threshOutputLowMin "1.275  V") (threshOutputLowTyp "1.7  V") (threshOutputLowMax "1.985  V") (mappingTagNonInverting nil) (mappingTagInverting nil) (spice nil))) (RLGC (length("1000 mil"))) (IbisOutputPkg ((temperature "27") (bufferModel "CDSDefaultOutput_2p5v") (stimuli nil) (offsets nil) (state "tristate") (cycle "1") (termMap nil) (setup "2.0e-09") (hold "1.0e-09") (rise nil) (fall nil) (macroType nil) (voltage nil) (spice nil) (LEFDEFPinName nil) (LEFDEFPinType nil) (mappingTag nil))) (clocked ((clockRise "1e-09") (clockFall "1e-09") (clockFreq "100e6") (clockInitState "0") (clockDutyCycle "0.5") (clockJitter "0"))) (CurrentProbe nil) (IbisIOPkg ((temperature "27") (bufferModel "CDSDefaultIO_2p5v") (stimuli nil) (offsets nil) (state "tristate") (cycle "1") (termMap nil) (setup "2.0e-09") (hold "1.0e-09") (rise nil) (fall nil) (macroType nil) (voltage nil) (spice nil) (LEFDEFPinName nil) (LEFDEFPinType nil) (mappingTag nil))) (TLine ((diffImpedance "100ohm") (diffVelocity "1.4142e+08M/s") (impedance "60ohm") length("2800 mil") (propDelay "0.5 ns") (velocity "5600 mil/ns") (traceCount "1") (traceGeometry "Microstrip") (impedanceMin nil) (impedanceMax nil) (lengthMin nil) (lengthMax nil) (propDelayMin nil) (propDelayMax nil) (impedanceSweepCount nil) (propDelaySweepCount nil) (velocitySweepCount nil) (lengthSweepCount nil) (matchSetName nil))) (Cable (length("1 m"))) (DiffOutputPkg ((temperature "27") (bufferModelNonInverting "CDSDefaultOutput_2p5v") (bufferModelInverting "CDSDefaultOutput_2p5v") (stimuli nil) (offsets nil) (state "tristate") (cycle "1") (termMap nil) (setup "0.9e-09") (hold "0.4e-09") (rise nil) (fall nil) (threshOutputHighMin "2.375  V") (threshOutputHighTyp "2.5  V") (threshOutputHighMax "2.625  V") (threshOutputLowMin "1.275  V") (threshOutputLowTyp "1.7  V") (threshOutputLowMax "1.985  V") (mappingTagNonInverting nil) (mappingTagInverting nil) (spice nil))) (ShuntTerm ((resistance "50 ohm") (voltage "5 V") (maxDelay "0.1 ns"))) (DiffIOPkg ((temperature "27") (bufferModelNonInverting "CDSDefaultIO_2p5v") (bufferModelInverting "CDSDefaultIO_2p5v") (stimuli nil) (offsets nil) (state "tristate") (cycle "1") (termMap nil) (setup "0.9e-09") (hold "0.4e-09") (rise nil) (fall nil) (threshInputHighMin "1.7 V") (threshInputHighTyp "1.7  V") (threshInputHighMax "1.7  V") (threshInputLowMin "0.7  V") (threshInputLowTyp "0.7  V") (threshInputLowMax "0.7 ") (threshOutputHighMin "2.365  V") (threshOutputHighTyp "2.5  V") (threshOutputHighMax "2.625  V") (threshOutputLowMin "1.275  V") (threshOutputLowTyp "1.7  V") (threshOutputLowMax "1.985  V") (mappingTagNonInverting nil) (mappingTagInverting nil) (spice nil))) (DiffIO ((temperature "27") (bufferModelNonInverting "CDSDefaultIO_2p5v") (bufferModelInverting "CDSDefaultIO_2p5v") (stimuli nil) (offsets nil) (state "tristate") (cycle "1") (termMap nil) (setup "0.9e-09") (hold "0.4e-09") (rise nil) (fall nil) (threshInputHighMin "1.7 V") (threshInputHighTyp "1.7  V") (threshInputHighMax "1.7  V") (threshInputLowMin "0.7  V") (threshInputLowTyp "0.7  V") (threshInputLowMax "0.7 ") (threshOutputHighMin "2.365  V") (threshOutputHighTyp "2.5  V") (threshOutputHighMax "2.625  V") (threshOutputLowMin "1.275  V") (threshOutputLowTyp "1.7  V") (threshOutputLowMax "1.985  V") (mappingTagNonInverting nil) (mappingTagInverting nil) (spice nil))) (LowClampTerm ((cutoffVoltage "0.7 V") (voltage "0 V") (maxDelay "0.1 ns"))) (Connector nil) (DiffInputPkg ((temperature "27") (bufferModelNonInverting "CDSDefaultInput_2p5v") (bufferModelInverting "CDSDefaultInput_2p5v") (threshInputHighMin "1.7 V") (threshInputHighTyp "1.7  V") (threshInputHighMax "1.7  V") (threshInputLowMin "0.7  V") (threshInputLowTyp "0.7  V") (threshInputLowMax "0.7  V") (mappingTagNonInverting nil) (mappingTagInverting nil) (cycle "1"))) (TheveninTerm ((resistanceUp "180 ohm") (resistanceDown "270 ohm") (voltageUp "5 V") (voltageDown "0 V") (maxDelay "0.1 ns"))) (RCTerm ((resistance "50 ohm") (capacitance "20 pF") (voltage "5 V") (maxDelay "0.1 ns"))) (DiffInput ((temperature "27") (bufferModelNonInverting "CDSDefaultInput_2p5v") (bufferModelInverting "CDSDefaultInput_2p5v") (threshInputHighMin "1.7 V") (threshInputHighTyp "1.7  V") (threshInputHighMax "1.7  V") (threshInputLowMin "0.7  V") (threshInputLowTyp "0.7  V") (threshInputLowMax "0.7  V") (mappingTagNonInverting nil) (mappingTagInverting nil) (cycle "1"))) (IbisInputPkg ((temperature "27") (bufferModel "CDSDefaultInput_2p5v") (cycle "1") (LEFDEFPinName nil) (LEFDEFPinType nil) (mappingTag nil))) (DualClampTerm ((cutoffVoltageUp "0.7 V") (cutoffVoltageDown "0.7 V") (voltageUp "5 V") (voltageDown "0 V") (maxDelay "0.1 ns"))) (IbisInput ((temperature "27") (bufferModel "CDSDefaultInput_2p5v") (cycle "1") (LEFDEFPinName nil) (LEFDEFPinType nil) (mappingTag nil))) (SeriesTerm ((resistance "22 ohm") (maxDelay "0.1 ns"))) (HiClampTerm ((cutoffVoltage "0.7 V") (voltage "5 V") (maxDelay "0.1 ns"))) (IbisOutput ((temperature "27") (bufferModel "CDSDefaultOutput_2p5v") (stimuli nil) (offsets nil) (state "tristate") (cycle "1") (termMap nil) (setup "2.0e-09") (hold "1.0e-09") (rise nil) (fall nil) (macroType nil) (voltage nil) (spice nil) (LEFDEFPinName nil) (LEFDEFPinType nil) (mappingTag nil))) (idlCircuit ((allDrivers "active") (ftsMode '("Typ")) (rcvrSelect "all") (simMode "Reflection") (tlineDelayMode "time") (userRevision "1.0") (autoSolve "On"))) (IbisIO_OpenPullDown ((temperature "27") (bufferModel "CDSDefaultIO_2p5v") (stimuli nil) (offsets nil) (state "tristate") (cycle "1") (termMap nil) (setup "2.0e-09") (hold "1.0e-09") (rise nil) (fall nil) (macroType nil) (voltage nil) (spice nil) (LEFDEFPinName nil) (LEFDEFPinType nil) (mappingTag nil))) (IbisIO_OpenPullUp ((temperature "27") (bufferModel "CDSDefaultIO_2p5v") (stimuli nil) (offsets nil) (state "tristate") (cycle "1") (termMap nil) (setup "2.0e-09") (hold "1.0e-09") (rise nil) (fall nil) (macroType nil) (voltage nil) (spice nil) (LEFDEFPinName nil) (LEFDEFPinType nil) (mappingTag nil))) (IbisOutput_OpenPullUp ((temperature "27") (bufferModel "CDSDefaultOutput_2p5v") (stimuli nil) (offsets nil) (state "tristate") (cycle "1") (termMap nil) (setup "2.0e-09") (hold "1.0e-09") (rise nil) (fall nil) (macroType nil) (voltage nil) (spice nil) (LEFDEFPinName nil) (LEFDEFPinType nil) (mappingTag nil))) (IbisIO ((temperature "27") (bufferModel "CDSDefaultIO_2p5v") (stimuli nil) (offsets nil) (state "tristate") (cycle "1") (termMap nil) (setup "2.0e-09") (hold "1.0e-09") (rise nil) (fall nil) (macroType nil) (voltage nil) (spice nil) (LEFDEFPinName nil) (LEFDEFPinType nil) (mappingTag nil)))))
				)
				( objectStatus "KR_OCP_RX" )
			)
			( electricalCSet "@baseboard_fab2_lib.baseboard_fab2(sch_1):\KR_OCP_TX\"
				( attribute "PROPAGATION_DELAY_PATH_TYPE" "AD:AR"
					( Origin gBackEnd )
				)
				( attribute "PROPAGATION_DELAY_MIN" "3000.00 MIL"
					( Units "uMaxMinProp" "ns" 1.000000)
					( Origin gBackEnd )
				)
				( attribute "PROPAGATION_DELAY_MAX" "5000.00 MIL"
					( Units "uMaxMinProp" "ns" 1.000000)
					( Origin gBackEnd )
				)
				( attribute "DIFFP_GATHER_CONTROL" "IGNORE"
					( Origin gBackEnd )
				)
				( attribute "DIFFP_UNCOUPLED_LENGTH" "100.00"
					( Origin gBackEnd )
				)
				( attribute "DIFFP_COUPLED_PLUS" "0.10"
					( Origin gBackEnd )
				)
				( attribute "DIFFP_COUPLED_MINUS" "0.10"
					( Origin gBackEnd )
				)
				( attribute "DIFFP_PHASE_TOL" "5 mil"
					( Units "uPhaseTol" "ns" 1.000000)
					( Origin gBackEnd )
				)
				( attribute "DIFFP_PHASE_MAX_LENGTH" "600.00"
					( Origin gBackEnd )
				)
				( attribute "DIFFP_PHASE_TOL_DYNAMIC" "25 mil"
					( Units "uPhaseTol" "mil" 1.000000)
					( Origin gBackEnd )
				)
				( attribute "DIFFP_NECK_GAP" "4.00"
					( Origin gBackEnd )
				)
				( attribute "MIN_NECK_WIDTH" "3.50"
					( Origin gBackEnd )
				)
				( attribute "TOPOLOGY_TEMPLATE_REVISION" "1.0"
					( Origin gBackEnd )
				)
				( topologyData 22483
(SKIDL (Circuits ("MAIN" (Parts ("CRESCENT_CITY_FAB2_2V060_20150717_A.@@U7C1.BR27" IbisIOPkg (xy (5522 4240)) (refDes "U7C1") (model "Unknown") (Props (_SXDesignName "CRESCENT_CITY_FAB2_2V060_20150717_A") (brdx "15694.25 MIL") (brdy "4156 MIL") (bufferModel "CDSDefaultIO_2p5v") (cycle "1") (hold "1.0e-09") (mappingTag "") (offsets ("4" "0") ("5" "0")) (setup "2.0e-09") (state "tristate") (stimuli ("4" "local14") ("5" "local15")) (temperature "27") (termMap ("4" "Data") ("5" "Enable"))) (Terms ("CRESCENT_CITY_FAB2_2V060_20150717_A.X1569425Y415600L2LRATS" "BR27"))) ("CRESCENT_CITY_FAB2_2V060_20150717_A.@@J1.16" IbisIOPkg (xy (5502 4240)) (refDes "J8E4") (model "Unknown") (Props (_SXDesignName "CRESCENT_CITY_FAB2_2V060_20150717_A") (brdx "17564.95 MIL") (brdy "2444.96 MIL") (bufferModel "CDSDefaultIO_2p5v") (cycle "1") (hold "1.0e-09") (mappingTag "") (offsets ("4" "0") ("5" "0")) (setup "2.0e-09") (state "tristate") (stimuli ("4" "local16") ("5" "local17")) (temperature "27") (termMap ("4" "Data") ("5" "Enable"))) (Terms ("CRESCENT_CITY_FAB2_2V060_20150717_A.X1756495Y244496L2LRATS" "16"))) ("CRESCENT_CITY_FAB2_2V060_20150717_A.T@@RATS@@J1.16@@U7C1.BR27" TLine (xy (5513 4235)) (refDes "TL5") (Props (_SXDesignName "CRESCENT_CITY_FAB2_2V060_20150717_A") (impedance "60 ohm") length("3581.71 MIL") (propDelay "0.643305 ns") (traceCount "1") (traceGeometry "Microstrip") (velocity "5567.68 mil/ns")) (Terms ("CRESCENT_CITY_FAB2_2V060_20150717_A.X1756495Y244496L2LRATS" "1") ("CRESCENT_CITY_FAB2_2V060_20150717_A.X1569425Y415600L2LRATS" "2")))) (Nodes ("CRESCENT_CITY_FAB2_2V060_20150717_A.X1756495Y244496L2LRATS" (terms "CRESCENT_CITY_FAB2_2V060_20150717_A.T@@RATS@@J1.16@@U7C1.BR27.1" "CRESCENT_CITY_FAB2_2V060_20150717_A.@@J1.16.1")) ("CRESCENT_CITY_FAB2_2V060_20150717_A.X1569425Y415600L2LRATS" (terms "CRESCENT_CITY_FAB2_2V060_20150717_A.T@@RATS@@J1.16@@U7C1.BR27.2" "CRESCENT_CITY_FAB2_2V060_20150717_A.@@U7C1.BR27.1"))) (Ports) (Stimuli ("local15" (scope local) (stimType periodic) (Props (periodicFreq "5e+007") (periodicJitter "0") (periodicPattern "1"))) ("local14" (scope local) (stimType periodic) (Props (periodicFreq "5e+007") (periodicJitter "0") (periodicPattern "1"))) ("local16" (scope local) (stimType periodic) (Props (periodicFreq "5e+007") (periodicJitter "0") (periodicPattern "1"))) ("local17" (scope local) (stimType periodic) (Props (periodicFreq "5e+007") (periodicJitter "0") (periodicPattern "1")))) (Notes) (Constraints ("DELAY_RULE" ("ALL DRVRS" "ALL RCVRS" "LENGTH" "0.0762" "LENGTH" "0.127")) ("DP_GATHER_CONTROL" "IGNORE") ("DP_MAX_UNCOUPLED_LENGTH" "0.00254") ("DP_NECK_GAP" "0.0001016") ("DP_NECK_WIDTH" "8.89e-005") ("DP_NEGATIVE_COUPLED_TOLERANCE" "2.54e-006") ("DP_PHASE_MAX_LENGTH" "0.01524") ("DP_PHASE_TOLERANCE" ("LENGTH" "0.000127")) ("DP_PHASE_TOLERANCE_DYNAMIC" ("LENGTH" "0.000635")) ("DP_POSITIVE_COUPLED_TOLERANCE" "2.54e-006")) (MeasurementSets ("EMI" ("EMIStatus" status("on")) ("PeakEmission" status("on")) ("PeakFrequency" status("on")) ("PulseFreq" status("on")) ("RiseTime" status("on")) ("VoltageSwing" status("on"))) ("Reflection" ("BufferDelayFall" status("off")) ("BufferDelayRise" status("off")) ("EyeHeight" status("off")) ("EyeJitter" status("off")) ("EyeWidth" status("off")) ("FirstIncidentFall" status("off")) ("FirstIncidentRise" status("off")) ("Glitch" status("on")) ("GlitchFall" status("off")) ("GlitchRise" status("off")) ("Monotonic" status("on")) ("MonotonicFall" status("off")) ("MonotonicRise" status("off")) ("NoiseMargin" status("on")) ("NoiseMarginHigh" status("off")) ("NoiseMarginLow" status("off")) ("OvershootHigh" status("on")) ("OvershootLow" status("on")) ("PropDelay" status("on")) ("SettleDelay" status("on")) ("SettleDelayFall" status("off")) ("SettleDelayRise" status("off")) ("SwitchDelay" status("on")) ("SwitchDelayFall" status("off")) ("SwitchDelayRise" status("off"))) ("Crosstalk" ("Crosstalk" status("on"))) ("Custom")) (VectorSets) (Props (XnetName "KR_P0_OCP_TX_DP") (allDrivers "active") (customSimType "Reflection") (ftsMode ("Typ")) (rcvrSelect "all") (tlineDelayMode "time") (userRevision "1.0")))) (Subckts) (CrossSections ("CRESCENT_CITY_FAB2_2V060_20150717_A" (Props (SXDesignName "CRESCENT_CITY_FAB2_2V060_20150717_A")) (Layers ("" (layerType "SURFACE") (material "AIR") (thickness "0 mil") (dielectricConstant "1.000000") (lossTangent "0") (etchFactor "0.000000") (elecCondVal "0 mho/cm") (thermCondVal "0 w/cm-degC")) ("" (layerType "DIELECTRIC") (material "CONFORMAL_COAT") (thickness "0.5 mil") (dielectricConstant "3.800000") (lossTangent "0.035") (etchFactor "0.000000") (elecCondVal "0 mho/cm") (thermCondVal "0.012 w/cm-degC")) ("TOP" (layerType "CONDUCTOR") (material "COPPER") (thickness "  2.100000 mil") (width "4.00 MIL") (dielectricConstant "4.500000") (lossTangent "0") (etchFactor "70.000000") (elecCondVal "595900.000000 mho/cm") (thermCondVal "0 w/cm-degC") (signalDieConstant "3.800000") (signalLossTangent "0.035")) ("" (layerType "DIELECTRIC") (material "FR-4") (thickness "  2.670000 mil") (dielectricConstant "4.000000") (lossTangent "0.035") (etchFactor "0.000000") (elecCondVal "0 mho/cm") (thermCondVal "0.012 w/cm-degC")) ("L2_GND1" (layerType "PLANE") (material "COPPER") (isShield t) (thickness "  1.250000 mil") (dielectricConstant "4.500000") (lossTangent "0.035") (etchFactor "90.000000") (elecCondVal "595900.000000 mho/cm") (thermCondVal "0.012 w/cm-degC")) ("" (layerType "DIELECTRIC") (material "FR-4") (thickness "  9.000000 mil") (dielectricConstant "4.100000") (lossTangent "0.035") (etchFactor "0.000000") (elecCondVal "0 mho/cm") (thermCondVal "0.012 w/cm-degC")) ("L3_SIG1" (layerType "CONDUCTOR") (material "COPPER") (thickness "  1.250000 mil") (width "4.00 MIL") (dielectricConstant "4.500000") (lossTangent "0.035") (etchFactor "90.000000") (elecCondVal "595900.000000 mho/cm") (thermCondVal "0.012 w/cm-degC") (signalDieConstant "4.100000") (signalLossTangent "0.035")) ("" (layerType "DIELECTRIC") (material "FR-4") (thickness "  3.000000 mil") (dielectricConstant "4.500000") (lossTangent "0.035") (etchFactor "0.000000") (elecCondVal "0 mho/cm") (thermCondVal "0 w/cm-degC")) ("L4_GND2" (layerType "PLANE") (material "COPPER") (isShield t) (thickness "  1.250000 mil") (dielectricConstant "4.500000") (lossTangent "0.035") (etchFactor "90.000000") (elecCondVal "595900.000000 mho/cm") (thermCondVal "0 w/cm-degC")) ("" (layerType "DIELECTRIC") (material "FR-4") (thickness "  9.000000 mil") (dielectricConstant "4.000000") (lossTangent "0.035") (etchFactor "0.000000") (elecCondVal "0 mho/cm") (thermCondVal "0.012 w/cm-degC")) ("L5_SIG2" (layerType "CONDUCTOR") (material "COPPER") (thickness "  1.250000 mil") (width "4.00 MIL") (dielectricConstant "4.500000") (lossTangent "0.035") (etchFactor "90.000000") (elecCondVal "595900.000000 mho/cm") (thermCondVal "0.012 w/cm-degC") (signalDieConstant "4.000000") (signalLossTangent "0.035")) ("" (layerType "DIELECTRIC") (material "FR-4") (thickness "  3.000000 mil") (dielectricConstant "4.500000") (lossTangent "0.035") (etchFactor "0.000000") (elecCondVal "0 mho/cm") (thermCondVal "0 w/cm-degC")) ("L6_GND3" (layerType "PLANE") (material "COPPER") (isShield t) (thickness "  1.250000 mil") (dielectricConstant "4.500000") (lossTangent "0.035") (etchFactor "90.000000") (elecCondVal "595900.000000 mho/cm") (thermCondVal "0 w/cm-degC")) ("" (layerType "DIELECTRIC") (material "FR-4") (thickness "  4.500000 mil") (dielectricConstant "4.100000") (lossTangent "0.035") (etchFactor "0.000000") (elecCondVal "0 mho/cm") (thermCondVal "0.012 w/cm-degC")) ("L7_PWR1-SIG" (layerType "PLANE") (material "COPPER") (isShield t) (thickness "  2.400000 mil") (dielectricConstant "4.500000") (lossTangent "0.035") (etchFactor "90.000000") (elecCondVal "595900.000000 mho/cm") (thermCondVal "0.012 w/cm-degC")) ("" (layerType "DIELECTRIC") (material "FR-4") (thickness "  4.600000 mil") (dielectricConstant "4.000000") (lossTangent "0.035") (etchFactor "0.000000") (elecCondVal "0 mho/cm") (thermCondVal "0.012 w/cm-degC")) ("L8_PWR2-SIG" (layerType "PLANE") (material "COPPER") (isShield t) (thickness "  2.400000 mil") (dielectricConstant "4.500000") (lossTangent "0.035") (etchFactor "90.000000") (elecCondVal "595900.000000 mho/cm") (thermCondVal "0.012 w/cm-degC")) ("" (layerType "DIELECTRIC") (material "FR-4") (thickness "  4.500000 mil") (dielectricConstant "4.500000") (lossTangent "0.035") (etchFactor "0.000000") (elecCondVal "0 mho/cm") (thermCondVal "0 w/cm-degC")) ("L9_GND4" (layerType "PLANE") (material "COPPER") (isShield t) (thickness "  1.250000 mil") (dielectricConstant "4.500000") (lossTangent "0.035") (etchFactor "90.000000") (elecCondVal "595900.000000 mho/cm") (thermCondVal "0 w/cm-degC")) ("" (layerType "DIELECTRIC") (material "FR-4") (thickness "  3.000000 mil") (dielectricConstant "4.100000") (lossTangent "0.035") (etchFactor "0.000000") (elecCondVal "0 mho/cm") (thermCondVal "0.012 w/cm-degC")) ("L10_SIG3" (layerType "CONDUCTOR") (material "COPPER") (thickness "  1.250000 mil") (width "4.00 MIL") (dielectricConstant "4.500000") (lossTangent "0.035") (etchFactor "90.000000") (elecCondVal "595900.000000 mho/cm") (thermCondVal "0.012 w/cm-degC") (signalDieConstant "4.100000") (signalLossTangent "0.035")) ("" (layerType "DIELECTRIC") (material "FR-4") (thickness "  9.000000 mil") (dielectricConstant "4.500000") (lossTangent "0.035") (etchFactor "0.000000") (elecCondVal "0 mho/cm") (thermCondVal "0 w/cm-degC")) ("L11_GND5" (layerType "PLANE") (material "COPPER") (isShield t) (thickness "  1.250000 mil") (dielectricConstant "4.500000") (lossTangent "0.035") (etchFactor "90.000000") (elecCondVal "595900.000000 mho/cm") (thermCondVal "0 w/cm-degC")) ("" (layerType "DIELECTRIC") (material "FR-4") (thickness "  3.000000 mil") (dielectricConstant "4.500000") (lossTangent "0.035") (etchFactor "0.000000") (elecCondVal "0 mho/cm") (thermCondVal "0.012 w/cm-degC")) ("L12_SIG4" (layerType "CONDUCTOR") (material "COPPER") (thickness "  1.250000 mil") (width "4.00 MIL") (dielectricConstant "4.500000") (lossTangent "0.035") (etchFactor "90.000000") (elecCondVal "595900.000000 mho/cm") (thermCondVal "0.012 w/cm-degC") (signalDieConstant "4.500000") (signalLossTangent "0.035")) ("" (layerType "DIELECTRIC") (material "FR-4") (thickness "  9.000000 mil") (dielectricConstant "4.500000") (lossTangent "0.035") (etchFactor "0.000000") (elecCondVal "0 mho/cm") (thermCondVal "0 w/cm-degC")) ("L13_GND6" (layerType "PLANE") (material "COPPER") (isShield t) (thickness "  1.250000 mil") (dielectricConstant "4.500000") (lossTangent "0.035") (etchFactor "90.000000") (elecCondVal "595900.000000 mho/cm") (thermCondVal "0.012 w/cm-degC")) ("" (layerType "DIELECTRIC") (material "FR-4") (thickness "  2.670000 mil") (dielectricConstant "4.500000") (lossTangent "0.035") (etchFactor "0.000000") (elecCondVal "0 mho/cm") (thermCondVal "0.012 w/cm-degC")) ("BOTTOM" (layerType "CONDUCTOR") (material "COPPER") (thickness "  2.100000 mil") (width "4.00 MIL") (dielectricConstant "4.500000") (lossTangent "0") (etchFactor "70.000000") (elecCondVal "595900.000000 mho/cm") (thermCondVal "0 w/cm-degC") (signalDieConstant "3.800000") (signalLossTangent "0.035")) ("" (layerType "DIELECTRIC") (material "CONFORMAL_COAT") (thickness "0.5 mil") (dielectricConstant "3.800000") (lossTangent "0.035") (etchFactor "0.000000") (elecCondVal "0 mho/cm") (thermCondVal "0.012 w/cm-degC")) ("" (layerType "SURFACE") (material "AIR") (thickness "0 mil") (dielectricConstant "1.000000") (lossTangent "0") (etchFactor "0.000000") (elecCondVal "0 mho/cm") (thermCondVal "0 w/cm-degC"))))) (Props (DesUnits "mils 2") (LayerStack ("DIELECTRIC" "DIELECTRIC" "BOTTOM" "DIELECTRIC" "L13_GND6" "DIELECTRIC" "L12_SIG4" "DIELECTRIC" "L11_GND5" "DIELECTRIC" "L10_SIG3" "DIELECTRIC" "L9_GND4" "DIELECTRIC" "L8_PWR2-SIG" "DIELECTRIC" "L7_PWR1-SIG" "DIELECTRIC" "L6_GND3" "DIELECTRIC" "L5_SIG2" "DIELECTRIC" "L4_GND2" "DIELECTRIC" "L3_SIG1" "DIELECTRIC" "L2_GND1" "DIELECTRIC" "TOP" "DIELECTRIC" "DIELECTRIC")) (Revision "16.600")) (Params (IbisIOMacro ((temperature "27") (bufferModel "CDSDefaultIO_2p5v") (stimuli nil) (offsets nil) (state "tristate") (cycle "1") (termMap nil) (setup "2.0e-09") (hold "1.0e-09") (rise nil) (fall nil) (macroType nil) (voltage nil) (spice nil) (LEFDEFPinName nil) (LEFDEFPinType nil) (mappingTag nil))) (periodic ((periodicFreq "100e6") (periodicPattern "10") (periodicJitter "0"))) (Trace ((d1Thickness "10 mil") (d1Constant "4.5") (d1LossTangent "0.035") (d2Thickness "10 mil") (d2Constant "4.5") (d2LossTangent "0.035") (d3Thickness "0.0") (d3Constant "1.0") (d3LossTangent "0") length("1000 mil") (spacing "5 mil") (spacing2 "5 mil") (spacing3 "5 mil") (spacing4 "5 mil") (spacing5 "5 mil") (traceConductivity "595900 mho/cm") (traceGeometry "microstrip") (traceLayerName "") (traceThickness "0.72 mil") (traceType "single") (traceWidth "5.0 mil") (traceWidth2 "5.0 mil") (traceWidth3 "5.0 mil") (traceWidth4 "5.0 mil") (traceWidth5 "5.0 mil") (traceWidth6 "5.0 mil") (offset "0 mil") (traceCount "1") (impedance nil))) (async ((asyncTimePoints "") (asyncInitState "1"))) (Resistor ((resistance "50 ohm") (orientation "0"))) (Inductor ((inductance "5 nH") (orientation "0"))) (sync ((syncFreq "100e6") (syncInitState "1") (syncPattern "10") (syncEdgeSwitch "rise"))) (Capacitor ((capacitance "10 pF") (orientation "0"))) (Via ((model "Unknown") (viaOutputFormat "Unknown") (viaPadstack nil) (viaTopLayer nil) (viaBottomLayer nil) (viaIsPower nil) (viaIsGround nil))) (CPW ((d1Thickness "10 mil") (d1Constant "4.5") (d1LossTangent "0.035") (d2Thickness "0.72 mil") (d2Constant "1") (d2LossTangent "0") (d3Thickness "0.0") (d3Constant "1") (d3LossTangent "0") length("1000 mil") (spacing "5 mil") (spacing2 "5 mil") (spacing3 "5 mil") (spacing4 "5 mil") (spacing5 "5 mil") (traceConductivity "595900 mho/cm") (traceGeometry "cpwms") (traceLayerName "") (traceThickness "0.72 mil") (traceType "single") (traceWidth "5.0 mil") (traceWidth2 "5.0 mil") (traceWidth3 "5.0 mil") (traceWidth4 "5.0 mil") (traceWidth5 "5.0 mil") (traceWidth6 "5.0 mil") (offset "0 mil") (traceCount "1") (impedance nil))) (ESpiceDevice nil) (Diode ((cutoffVoltage "0.7 V"))) (CPWSL ((d1Thickness "10 mil") (d1Constant "4.5") (d1LossTangent "0.035") (d2Thickness "0.72 mil") (d2Constant "4.5") (d2LossTangent "0.035") (d3Thickness "10 mil") (d3Constant "4.5") (d3LossTangent "0.035") length("1000 mil") (spacing "5 mil") (spacing2 "5 mil") (spacing3 "5 mil") (spacing4 "5 mil") (spacing5 "5 mil") (traceConductivity "595900 mho/cm") (traceGeometry "cpwms") (traceLayerName "") (traceThickness "0.72 mil") (traceType "single") (traceWidth "5.0 mil") (traceWidth2 "5.0 mil") (traceWidth3 "5.0 mil") (traceWidth4 "5.0 mil") (traceWidth5 "5.0 mil") (traceWidth6 "5.0 mil") (offset "0 mil") (traceCount "1") (impedance nil))) (CPWMS ((d1Thickness "10 mil") (d1Constant "4.5") (d1LossTangent "0.035") (d2Thickness "0.72 mil") (d2Constant "4.5") (d2LossTangent "0.035") (d3Thickness "0.0") (d3Constant "1") (d3LossTangent "0") length("1000 mil") (spacing "5 mil") (spacing2 "5 mil") (spacing3 "5 mil") (spacing4 "5 mil") (spacing5 "5 mil") (traceConductivity "595900 mho/cm") (traceGeometry "cpwms") (traceLayerName "") (traceThickness "0.72 mil") (traceType "single") (traceWidth "5.0 mil") (traceWidth2 "5.0 mil") (traceWidth3 "5.0 mil") (traceWidth4 "5.0 mil") (traceWidth5 "5.0 mil") (traceWidth6 "5.0 mil") (offset "0 mil") (traceCount "1") (impedance nil))) (Source ((voltage "5 V"))) (DiffOutput ((temperature "27") (bufferModelNonInverting "CDSDefaultOutput_2p5v") (bufferModelInverting "CDSDefaultOutput_2p5v") (stimuli nil) (offsets nil) (state "tristate") (cycle "1") (termMap nil) (setup "0.9e-09") (hold "0.4e-09") (rise nil) (fall nil) (threshOutputHighMin "2.375  V") (threshOutputHighTyp "2.5  V") (threshOutputHighMax "2.625  V") (threshOutputLowMin "1.275  V") (threshOutputLowTyp "1.7  V") (threshOutputLowMax "1.985  V") (mappingTagNonInverting nil) (mappingTagInverting nil) (spice nil))) (RLGC (length("1000 mil"))) (IbisOutputPkg ((temperature "27") (bufferModel "CDSDefaultOutput_2p5v") (stimuli nil) (offsets nil) (state "tristate") (cycle "1") (termMap nil) (setup "2.0e-09") (hold "1.0e-09") (rise nil) (fall nil) (macroType nil) (voltage nil) (spice nil) (LEFDEFPinName nil) (LEFDEFPinType nil) (mappingTag nil))) (clocked ((clockRise "1e-09") (clockFall "1e-09") (clockFreq "100e6") (clockInitState "0") (clockDutyCycle "0.5") (clockJitter "0"))) (CurrentProbe nil) (IbisIOPkg ((temperature "27") (bufferModel "CDSDefaultIO_2p5v") (stimuli nil) (offsets nil) (state "tristate") (cycle "1") (termMap nil) (setup "2.0e-09") (hold "1.0e-09") (rise nil) (fall nil) (macroType nil) (voltage nil) (spice nil) (LEFDEFPinName nil) (LEFDEFPinType nil) (mappingTag nil))) (TLine ((diffImpedance "100ohm") (diffVelocity "1.4142e+08M/s") (impedance "60ohm") length("2800 mil") (propDelay "0.5 ns") (velocity "5600 mil/ns") (traceCount "1") (traceGeometry "Microstrip") (impedanceMin nil) (impedanceMax nil) (lengthMin nil) (lengthMax nil) (propDelayMin nil) (propDelayMax nil) (impedanceSweepCount nil) (propDelaySweepCount nil) (velocitySweepCount nil) (lengthSweepCount nil) (matchSetName nil))) (Cable (length("1 m"))) (DiffOutputPkg ((temperature "27") (bufferModelNonInverting "CDSDefaultOutput_2p5v") (bufferModelInverting "CDSDefaultOutput_2p5v") (stimuli nil) (offsets nil) (state "tristate") (cycle "1") (termMap nil) (setup "0.9e-09") (hold "0.4e-09") (rise nil) (fall nil) (threshOutputHighMin "2.375  V") (threshOutputHighTyp "2.5  V") (threshOutputHighMax "2.625  V") (threshOutputLowMin "1.275  V") (threshOutputLowTyp "1.7  V") (threshOutputLowMax "1.985  V") (mappingTagNonInverting nil) (mappingTagInverting nil) (spice nil))) (ShuntTerm ((resistance "50 ohm") (voltage "5 V") (maxDelay "0.1 ns"))) (DiffIOPkg ((temperature "27") (bufferModelNonInverting "CDSDefaultIO_2p5v") (bufferModelInverting "CDSDefaultIO_2p5v") (stimuli nil) (offsets nil) (state "tristate") (cycle "1") (termMap nil) (setup "0.9e-09") (hold "0.4e-09") (rise nil) (fall nil) (threshInputHighMin "1.7 V") (threshInputHighTyp "1.7  V") (threshInputHighMax "1.7  V") (threshInputLowMin "0.7  V") (threshInputLowTyp "0.7  V") (threshInputLowMax "0.7 ") (threshOutputHighMin "2.365  V") (threshOutputHighTyp "2.5  V") (threshOutputHighMax "2.625  V") (threshOutputLowMin "1.275  V") (threshOutputLowTyp "1.7  V") (threshOutputLowMax "1.985  V") (mappingTagNonInverting nil) (mappingTagInverting nil) (spice nil))) (DiffIO ((temperature "27") (bufferModelNonInverting "CDSDefaultIO_2p5v") (bufferModelInverting "CDSDefaultIO_2p5v") (stimuli nil) (offsets nil) (state "tristate") (cycle "1") (termMap nil) (setup "0.9e-09") (hold "0.4e-09") (rise nil) (fall nil) (threshInputHighMin "1.7 V") (threshInputHighTyp "1.7  V") (threshInputHighMax "1.7  V") (threshInputLowMin "0.7  V") (threshInputLowTyp "0.7  V") (threshInputLowMax "0.7 ") (threshOutputHighMin "2.365  V") (threshOutputHighTyp "2.5  V") (threshOutputHighMax "2.625  V") (threshOutputLowMin "1.275  V") (threshOutputLowTyp "1.7  V") (threshOutputLowMax "1.985  V") (mappingTagNonInverting nil) (mappingTagInverting nil) (spice nil))) (LowClampTerm ((cutoffVoltage "0.7 V") (voltage "0 V") (maxDelay "0.1 ns"))) (Connector nil) (DiffInputPkg ((temperature "27") (bufferModelNonInverting "CDSDefaultInput_2p5v") (bufferModelInverting "CDSDefaultInput_2p5v") (threshInputHighMin "1.7 V") (threshInputHighTyp "1.7  V") (threshInputHighMax "1.7  V") (threshInputLowMin "0.7  V") (threshInputLowTyp "0.7  V") (threshInputLowMax "0.7  V") (mappingTagNonInverting nil) (mappingTagInverting nil) (cycle "1"))) (TheveninTerm ((resistanceUp "180 ohm") (resistanceDown "270 ohm") (voltageUp "5 V") (voltageDown "0 V") (maxDelay "0.1 ns"))) (RCTerm ((resistance "50 ohm") (capacitance "20 pF") (voltage "5 V") (maxDelay "0.1 ns"))) (DiffInput ((temperature "27") (bufferModelNonInverting "CDSDefaultInput_2p5v") (bufferModelInverting "CDSDefaultInput_2p5v") (threshInputHighMin "1.7 V") (threshInputHighTyp "1.7  V") (threshInputHighMax "1.7  V") (threshInputLowMin "0.7  V") (threshInputLowTyp "0.7  V") (threshInputLowMax "0.7  V") (mappingTagNonInverting nil) (mappingTagInverting nil) (cycle "1"))) (IbisInputPkg ((temperature "27") (bufferModel "CDSDefaultInput_2p5v") (cycle "1") (LEFDEFPinName nil) (LEFDEFPinType nil) (mappingTag nil))) (DualClampTerm ((cutoffVoltageUp "0.7 V") (cutoffVoltageDown "0.7 V") (voltageUp "5 V") (voltageDown "0 V") (maxDelay "0.1 ns"))) (IbisInput ((temperature "27") (bufferModel "CDSDefaultInput_2p5v") (cycle "1") (LEFDEFPinName nil) (LEFDEFPinType nil) (mappingTag nil))) (SeriesTerm ((resistance "22 ohm") (maxDelay "0.1 ns"))) (HiClampTerm ((cutoffVoltage "0.7 V") (voltage "5 V") (maxDelay "0.1 ns"))) (IbisOutput ((temperature "27") (bufferModel "CDSDefaultOutput_2p5v") (stimuli nil) (offsets nil) (state "tristate") (cycle "1") (termMap nil) (setup "2.0e-09") (hold "1.0e-09") (rise nil) (fall nil) (macroType nil) (voltage nil) (spice nil) (LEFDEFPinName nil) (LEFDEFPinType nil) (mappingTag nil))) (idlCircuit ((allDrivers "active") (ftsMode '("Typ")) (rcvrSelect "all") (simMode "Reflection") (tlineDelayMode "time") (userRevision "1.0") (autoSolve "On"))) (IbisIO_OpenPullDown ((temperature "27") (bufferModel "CDSDefaultIO_2p5v") (stimuli nil) (offsets nil) (state "tristate") (cycle "1") (termMap nil) (setup "2.0e-09") (hold "1.0e-09") (rise nil) (fall nil) (macroType nil) (voltage nil) (spice nil) (LEFDEFPinName nil) (LEFDEFPinType nil) (mappingTag nil))) (IbisIO_OpenPullUp ((temperature "27") (bufferModel "CDSDefaultIO_2p5v") (stimuli nil) (offsets nil) (state "tristate") (cycle "1") (termMap nil) (setup "2.0e-09") (hold "1.0e-09") (rise nil) (fall nil) (macroType nil) (voltage nil) (spice nil) (LEFDEFPinName nil) (LEFDEFPinType nil) (mappingTag nil))) (IbisOutput_OpenPullUp ((temperature "27") (bufferModel "CDSDefaultOutput_2p5v") (stimuli nil) (offsets nil) (state "tristate") (cycle "1") (termMap nil) (setup "2.0e-09") (hold "1.0e-09") (rise nil) (fall nil) (macroType nil) (voltage nil) (spice nil) (LEFDEFPinName nil) (LEFDEFPinType nil) (mappingTag nil))) (IbisIO ((temperature "27") (bufferModel "CDSDefaultIO_2p5v") (stimuli nil) (offsets nil) (state "tristate") (cycle "1") (termMap nil) (setup "2.0e-09") (hold "1.0e-09") (rise nil) (fall nil) (macroType nil) (voltage nil) (spice nil) (LEFDEFPinName nil) (LEFDEFPinType nil) (mappingTag nil)))))
				)
				( objectStatus "KR_OCP_TX" )
			)
			( electricalCSet "@baseboard_fab2_lib.baseboard_fab2(sch_1):\SVID_DIO0_CPU0\"
				( groupRef "SVID_DIO0_CPU0:#SVID_CPU0_0_U36-EU109" )
				( groupRef "SVID_DIO0_CPU0:#SVID_CPU0_0_U36-EU43" )
				( pinPairRef "SVID_DIO0_CPU0:U5D1.DB45:R6N11.1" )
				( pinPairRef "SVID_DIO0_CPU0:R3P11.1:R6N11.2" )
				( pinPairRef "SVID_DIO0_CPU0:R6N2.1:R6N11.2" )
				( pinPairRef "SVID_DIO0_CPU0:EU3P1.16:R3P11.2" )
				( pinPairRef "SVID_DIO0_CPU0:EU4D4.18:R4D66.1" )
				( pinPairRef "SVID_DIO0_CPU0:R3P11.1:R3P13.2" )
				( pinPairRef "SVID_DIO0_CPU0:EU3P1.16:U5D1.DB45" )
				( pinPairRef "SVID_DIO0_CPU0:EU4D4.18:U5D1.DB45" )
				( attribute "TOPOLOGY_TEMPLATE_REVISION" "1.0"
					( Origin gBackEnd )
				)
				( topologyData 33385
(SKIDL (Circuits ("MAIN" (Parts ("CRESCENT_CITY_195_20150128_Q.@@EU43.18" IbisIOPkg (xy (5546 4214)) (refDes "EU4D4") (model "Unknown") (Props (_SXDesignName "CRESCENT_CITY_195_20150128_Q") (brdx "7247.13 MIL") (brdy "2636 MIL") (bufferModel "CDSDefaultIO_2p5v") (cycle "1") (hold "1.0e-09") (mappingTag "") (offsets ("4" "0") ("5" "0")) (setup "2.0e-09") (state "tristate") (stimuli ("4" "local61") ("5" "local62")) (temperature "27") (termMap ("4" "Data") ("5" "Enable"))) (Terms ("CRESCENT_CITY_195_20150128_Q.X724713Y263600L2LRATS" "18"))) ("CRESCENT_CITY_195_20150128_Q.@@J130.B20" IbisIOPkg (xy (5515 4228)) (refDes "J6B1") (model "Unknown") (Props (_SXDesignName "CRESCENT_CITY_195_20150128_Q") (brdx "13926 MIL") (brdy "4500 MIL") (bufferModel "CDSDefaultIO_2p5v") (cycle "1") (hold "1.0e-09") (mappingTag "") (offsets ("4" "0") ("5" "0")) (setup "2.0e-09") (state "tristate") (stimuli ("4" "local63") ("5" "local64")) (temperature "27") (termMap ("4" "Data") ("5" "Enable"))) (Terms ("CRESCENT_CITY_195_20150128_Q.X1392600Y450000L2LRATS" "B20"))) ("CRESCENT_CITY_195_20150128_Q.@@EU109.16" IbisIOPkg (xy (5502 4240)) (refDes "EU3P1") (model "Unknown") (Props (_SXDesignName "CRESCENT_CITY_195_20150128_Q") (brdx "13346.5 MIL") (brdy "3450.87 MIL") (bufferModel "CDSDefaultIO_2p5v") (cycle "1") (hold "1.0e-09") (mappingTag "") (offsets ("4" "0") ("5" "0")) (setup "2.0e-09") (state "tristate") (stimuli ("4" "local65") ("5" "local66")) (temperature "27") (termMap ("4" "Data") ("5" "Enable"))) (Terms ("CRESCENT_CITY_195_20150128_Q.X1334650Y345087L30LRATS" "16"))) ("CRESCENT_CITY_195_20150128_Q.@@U36.DB45" IbisIOPkg (xy (5530 4193)) (refDes "U5D1") (model "Unknown") (Props (_SXDesignName "CRESCENT_CITY_195_20150128_Q") (brdx "10549.14 MIL") (brdy "3534.09 MIL") (bufferModel "CDSDefaultIO_2p5v") (cycle "1") (hold "1.0e-09") (mappingTag "") (offsets ("4" "0") ("5" "0")) (setup "2.0e-09") (state "tristate") (stimuli ("4" "local67") ("5" "local68")) (temperature "27") (termMap ("4" "Data") ("5" "Enable"))) (Terms ("CRESCENT_CITY_195_20150128_Q.X1054914Y353409L2LRATS" "DB45"))) ("CRESCENT_CITY_195_20150128_Q.@@R1368.1.2" Resistor (xy (5507 4202)) (refDes "R4E10") (value "100 Ohm") (Props (_SXDesignName "CRESCENT_CITY_195_20150128_Q")) (Terms ("CRESCENT_CITY_195_20150128_Q.X723500Y244000L2RATS" "1") ("CRESCENT_CITY_195_20150128_Q.X723500Y247500L2LRATS" "2"))) ("CRESCENT_CITY_195_20150128_Q.T@@RATS@@R1195.1@@U36.DB45" TLine (xy (5521 4188)) (refDes "TL82") (Props (_SXDesignName "CRESCENT_CITY_195_20150128_Q") (impedance "50.521 ohm") length("3134.55 MIL") (propDelay "0.56299 ns") (traceCount "1") (traceGeometry "Microstrip") (velocity "5567.68 mil/ns")) (Terms ("CRESCENT_CITY_195_20150128_Q.X804250Y416200L2LRATS" "1") ("CRESCENT_CITY_195_20150128_Q.X1054914Y353409L2LRATS" "2"))) ("CRESCENT_CITY_195_20150128_Q.@@R1195.1.2" Resistor (xy (5506 4188)) (mirror x) (refDes "R6N11") (value "2.2e-007 Ohm") (Props (_SXDesignName "CRESCENT_CITY_195_20150128_Q")) (Terms ("CRESCENT_CITY_195_20150128_Q.X804250Y416200L2LRATS" "1") ("CRESCENT_CITY_195_20150128_Q.X800750Y416200L2LRATS" "2"))) ("CRESCENT_CITY_195_20150128_Q.T@@RATS@@EU43.18@@R1360.1" TLine (xy (5531 4209)) (mirror x) (refDes "TL83") (Props (_SXDesignName "CRESCENT_CITY_195_20150128_Q") (impedance "48.412 ohm") length("88.13 MIL") (propDelay "0.01583 ns") (traceCount "1") (traceGeometry "Microstrip") (velocity "5567.28 mil/ns")) (Terms ("CRESCENT_CITY_195_20150128_Q.X724713Y263600L2LRATS" "1") ("CRESCENT_CITY_195_20150128_Q.X723500Y256000L2LRATS" "2"))) ("CRESCENT_CITY_195_20150128_Q.@@R1175.2.1" Resistor (xy (5482 4196)) (refDes "R6N2") (value "100 Ohm") (Props (_SXDesignName "CRESCENT_CITY_195_20150128_Q")) (Terms ("CRESCENT_CITY_195_20150128_Q.X804250Y416200L30RATS" "2") ("CRESCENT_CITY_195_20150128_Q.X800750Y416200L30LRATS" "1"))) ("CRESCENT_CITY_195_20150128_Q.@@R1360.1.2" Resistor (xy (5516 4209)) (mirror x) (refDes "R4D66") (value "2.2e-007 Ohm") (Props (_SXDesignName "CRESCENT_CITY_195_20150128_Q")) (Terms ("CRESCENT_CITY_195_20150128_Q.X723500Y256000L2LRATS" "1") ("CRESCENT_CITY_195_20150128_Q.X723500Y252500L2LRATS" "2"))) ("CRESCENT_CITY_195_20150128_Q.T@@RATS@@R1195.2@@R1360.2" TLine (xy (5506 4209)) (refDes "TL84") (Props (_SXDesignName "CRESCENT_CITY_195_20150128_Q") (impedance "48.412 ohm") length("2409.50 MIL") (propDelay "0.43276 ns") (traceCount "1") (traceGeometry "Microstrip") (velocity "5567.76 mil/ns")) (Terms ("CRESCENT_CITY_195_20150128_Q.X800750Y416200L2LRATS" "1") ("CRESCENT_CITY_195_20150128_Q.X723500Y252500L2LRATS" "2"))) ("CRESCENT_CITY_195_20150128_Q.T@@RATS@@R1195.2@@R2860.2" TLine (xy (5491 4209)) (mirror x) (refDes "TL85") (Props (_SXDesignName "CRESCENT_CITY_195_20150128_Q") (impedance "60 ohm") length("5904.49 MIL") (propDelay "1.06049 ns") (traceCount "1") (traceGeometry "Microstrip") (velocity "5567.72 mil/ns")) (Terms ("CRESCENT_CITY_195_20150128_Q.X800750Y416200L2LRATS" "1") ("CRESCENT_CITY_195_20150128_Q.X1321800Y346800L30LRATS" "2"))) ("CRESCENT_CITY_195_20150128_Q.T@@RATS@@R2861.1@@J130.B20" TLine (xy (5506 4223)) (refDes "TL86") (Props (_SXDesignName "CRESCENT_CITY_195_20150128_Q") (impedance "60 ohm") length("1730.00 MIL") (propDelay "0.31072 ns") (traceCount "1") (traceGeometry "Microstrip") (velocity "5567.72 mil/ns")) (Terms ("CRESCENT_CITY_195_20150128_Q.X1325300Y344300L30LRATS" "1") ("CRESCENT_CITY_195_20150128_Q.X1392600Y450000L2LRATS" "2"))) ("CRESCENT_CITY_195_20150128_Q.@@R1175.2_SOURCE" Source (xy (5475 4196)) (refDes "PVCCIO_CPU0_1") (value "1.05 V") (Props (_SXDesignName "CRESCENT_CITY_195_20150128_Q")) (Terms ("CRESCENT_CITY_195_20150128_Q.X804250Y416200L30RATS" "1"))) ("CRESCENT_CITY_195_20150128_Q.@@R2861.2.1" Resistor (xy (5497 4223)) (refDes "R3P11") (value "2.2e-007 Ohm") (Props (_SXDesignName "CRESCENT_CITY_195_20150128_Q")) (Terms ("CRESCENT_CITY_195_20150128_Q.X1328800Y344300L30LRATS" "2") ("CRESCENT_CITY_195_20150128_Q.X1325300Y344300L30LRATS" "1"))) ("CRESCENT_CITY_195_20150128_Q.T@@RATS@@R1195.2@@R1175.1" TLine (xy (5497 4196)) (mirror x) (refDes "TL87") (Props (_SXDesignName "CRESCENT_CITY_195_20150128_Q") (impedance "48.412 ohm") (propDelay "1.79607e-006 ns") (traceCount "1") (traceGeometry "Microstrip")) (Terms ("CRESCENT_CITY_195_20150128_Q.X800750Y416200L2LRATS" "1") ("CRESCENT_CITY_195_20150128_Q.X800750Y416200L30LRATS" "2"))) ("CRESCENT_CITY_195_20150128_Q.@@R2860.1_SOURCE" Source (xy (5481 4216)) (refDes "PVCCIO_CPU0_2") (value "1.05 V") (Props (_SXDesignName "CRESCENT_CITY_195_20150128_Q")) (Terms ("CRESCENT_CITY_195_20150128_Q.X1321800Y343300L30RATS" "1"))) ("CRESCENT_CITY_195_20150128_Q.@@R2860.1.2" Resistor (xy (5488 4216)) (refDes "R3P13") (value "100 Ohm") (Props (_SXDesignName "CRESCENT_CITY_195_20150128_Q")) (Terms ("CRESCENT_CITY_195_20150128_Q.X1321800Y343300L30RATS" "1") ("CRESCENT_CITY_195_20150128_Q.X1321800Y346800L30LRATS" "2"))) ("CRESCENT_CITY_195_20150128_Q.T@@RATS@@R2861.2@@EU109.16" TLine (xy (5497 4229)) (refDes "TL88") (Props (_SXDesignName "CRESCENT_CITY_195_20150128_Q") (impedance "47.863 ohm") length("66.37 MIL") (propDelay "0.01192 ns") (traceCount "1") (traceGeometry "Microstrip") (velocity "5567.95 mil/ns")) (Terms ("CRESCENT_CITY_195_20150128_Q.X1328800Y344300L30LRATS" "1") ("CRESCENT_CITY_195_20150128_Q.X1334650Y345087L30LRATS" "2"))) ("CRESCENT_CITY_195_20150128_Q.@@R1368.1_SOURCE" Source (xy (5500 4202)) (refDes "PVCCIO_CPU0") (value "1.05 V") (Props (_SXDesignName "CRESCENT_CITY_195_20150128_Q")) (Terms ("CRESCENT_CITY_195_20150128_Q.X723500Y244000L2RATS" "1"))) ("CRESCENT_CITY_195_20150128_Q.T@@RATS@@R1360.2@@R1368.2" TLine (xy (5522 4202)) (mirror x) (refDes "TL89") (Props (_SXDesignName "CRESCENT_CITY_195_20150128_Q") (impedance "48.412 ohm") length("50.00 MIL") (propDelay "0.00898 ns") (traceCount "1") (traceGeometry "Microstrip") (velocity "5567.91 mil/ns")) (Terms ("CRESCENT_CITY_195_20150128_Q.X723500Y252500L2LRATS" "1") ("CRESCENT_CITY_195_20150128_Q.X723500Y247500L2LRATS" "2"))) ("CRESCENT_CITY_195_20150128_Q.T@@RATS@@R2860.2@@R2861.1" TLine (xy (5497 4216)) (refDes "TL90") (Props (_SXDesignName "CRESCENT_CITY_195_20150128_Q") (impedance "46.577 ohm") length("60.00 MIL") (propDelay "0.01078 ns") (traceCount "1") (traceGeometry "Microstrip") (velocity "5565.87 mil/ns")) (Terms ("CRESCENT_CITY_195_20150128_Q.X1321800Y346800L30LRATS" "1") ("CRESCENT_CITY_195_20150128_Q.X1325300Y344300L30LRATS" "2")))) (Nodes ("CRESCENT_CITY_195_20150128_Q.X723500Y256000L2LRATS" (terms "CRESCENT_CITY_195_20150128_Q.@@R1360.1.2.1" "CRESCENT_CITY_195_20150128_Q.T@@RATS@@EU43.18@@R1360.1.2")) ("CRESCENT_CITY_195_20150128_Q.X800750Y416200L30LRATS" (terms "CRESCENT_CITY_195_20150128_Q.T@@RATS@@R1195.2@@R1175.1.2" "CRESCENT_CITY_195_20150128_Q.@@R1175.2.1.2")) ("CRESCENT_CITY_195_20150128_Q.X723500Y252500L2LRATS" (terms "CRESCENT_CITY_195_20150128_Q.T@@RATS@@R1360.2@@R1368.2.1" "CRESCENT_CITY_195_20150128_Q.T@@RATS@@R1195.2@@R1360.2.2" "CRESCENT_CITY_195_20150128_Q.@@R1360.1.2.2")) ("CRESCENT_CITY_195_20150128_Q.X1054914Y353409L2LRATS" (terms "CRESCENT_CITY_195_20150128_Q.T@@RATS@@R1195.1@@U36.DB45.2" "CRESCENT_CITY_195_20150128_Q.@@U36.DB45.1")) ("CRESCENT_CITY_195_20150128_Q.X723500Y244000L2RATS" (terms "CRESCENT_CITY_195_20150128_Q.@@R1368.1_SOURCE.1" "CRESCENT_CITY_195_20150128_Q.@@R1368.1.2.1")) ("CRESCENT_CITY_195_20150128_Q.X724713Y263600L2LRATS" (terms "CRESCENT_CITY_195_20150128_Q.T@@RATS@@EU43.18@@R1360.1.1" "CRESCENT_CITY_195_20150128_Q.@@EU43.18.1")) ("CRESCENT_CITY_195_20150128_Q.X1321800Y346800L30LRATS" (terms "CRESCENT_CITY_195_20150128_Q.T@@RATS@@R2860.2@@R2861.1.1" "CRESCENT_CITY_195_20150128_Q.@@R2860.1.2.2" "CRESCENT_CITY_195_20150128_Q.T@@RATS@@R1195.2@@R2860.2.2")) ("CRESCENT_CITY_195_20150128_Q.X1328800Y344300L30LRATS" (terms "CRESCENT_CITY_195_20150128_Q.T@@RATS@@R2861.2@@EU109.16.1" "CRESCENT_CITY_195_20150128_Q.@@R2861.2.1.1")) ("CRESCENT_CITY_195_20150128_Q.X1325300Y344300L30LRATS" (terms "CRESCENT_CITY_195_20150128_Q.T@@RATS@@R2860.2@@R2861.1.2" "CRESCENT_CITY_195_20150128_Q.@@R2861.2.1.2" "CRESCENT_CITY_195_20150128_Q.T@@RATS@@R2861.1@@J130.B20.1")) ("CRESCENT_CITY_195_20150128_Q.X1334650Y345087L30LRATS" (terms "CRESCENT_CITY_195_20150128_Q.T@@RATS@@R2861.2@@EU109.16.2" "CRESCENT_CITY_195_20150128_Q.@@EU109.16.1")) ("CRESCENT_CITY_195_20150128_Q.X1321800Y343300L30RATS" (terms "CRESCENT_CITY_195_20150128_Q.@@R2860.1.2.1" "CRESCENT_CITY_195_20150128_Q.@@R2860.1_SOURCE.1")) ("CRESCENT_CITY_195_20150128_Q.X804250Y416200L30RATS" (terms "CRESCENT_CITY_195_20150128_Q.@@R1175.2_SOURCE.1" "CRESCENT_CITY_195_20150128_Q.@@R1175.2.1.1")) ("CRESCENT_CITY_195_20150128_Q.X800750Y416200L2LRATS" (terms "CRESCENT_CITY_195_20150128_Q.T@@RATS@@R1195.2@@R1175.1.1" "CRESCENT_CITY_195_20150128_Q.T@@RATS@@R1195.2@@R2860.2.1" "CRESCENT_CITY_195_20150128_Q.T@@RATS@@R1195.2@@R1360.2.1" "CRESCENT_CITY_195_20150128_Q.@@R1195.1.2.2")) ("CRESCENT_CITY_195_20150128_Q.X723500Y247500L2LRATS" (terms "CRESCENT_CITY_195_20150128_Q.T@@RATS@@R1360.2@@R1368.2.2" "CRESCENT_CITY_195_20150128_Q.@@R1368.1.2.2")) ("CRESCENT_CITY_195_20150128_Q.X1392600Y450000L2LRATS" (terms "CRESCENT_CITY_195_20150128_Q.T@@RATS@@R2861.1@@J130.B20.2" "CRESCENT_CITY_195_20150128_Q.@@J130.B20.1")) ("CRESCENT_CITY_195_20150128_Q.X804250Y416200L2LRATS" (terms "CRESCENT_CITY_195_20150128_Q.@@R1195.1.2.1" "CRESCENT_CITY_195_20150128_Q.T@@RATS@@R1195.1@@U36.DB45.1"))) (Ports) (Stimuli ("local67" (scope local) (stimType periodic) (Props (periodicFreq "5e+007") (periodicJitter "0") (periodicPattern "1"))) ("local62" (scope local) (stimType periodic) (Props (periodicFreq "5e+007") (periodicJitter "0") (periodicPattern "1"))) ("local66" (scope local) (stimType periodic) (Props (periodicFreq "5e+007") (periodicJitter "0") (periodicPattern "1"))) ("local68" (scope local) (stimType periodic) (Props (periodicFreq "5e+007") (periodicJitter "0") (periodicPattern "1"))) ("local63" (scope local) (stimType periodic) (Props (periodicFreq "5e+007") (periodicJitter "0") (periodicPattern "1"))) ("local61" (scope local) (stimType periodic) (Props (periodicFreq "5e+007") (periodicJitter "0") (periodicPattern "1"))) ("local65" (scope local) (stimType periodic) (Props (periodicFreq "5e+007") (periodicJitter "0") (periodicPattern "1"))) ("local64" (scope local) (stimType periodic) (Props (periodicFreq "5e+007") (periodicJitter "0") (periodicPattern "1")))) (Notes) (Constraints ("DELAY_RULE" ("CRESCENT_CITY_195_20150128_Q U36.DB45" "CRESCENT_CITY_195_20150128_Q R1195.1" "LENGTH" "" "LENGTH" "0.1143") ("CRESCENT_CITY_195_20150128_Q R2861.1" "CRESCENT_CITY_195_20150128_Q R2860.2" "LENGTH" "" "LENGTH" "0.00508") ("CRESCENT_CITY_195_20150128_Q R2861.1" "CRESCENT_CITY_195_20150128_Q R1195.2" "LENGTH" "" "LENGTH" "0.6858") ("CRESCENT_CITY_195_20150128_Q R1175.1" "CRESCENT_CITY_195_20150128_Q R1195.2" "LENGTH" "" "LENGTH" "0.01016") ("CRESCENT_CITY_195_20150128_Q EU109.16" "CRESCENT_CITY_195_20150128_Q R2861.2" "LENGTH" "" "LENGTH" "0.0254") ("CRESCENT_CITY_195_20150128_Q EU43.18" "CRESCENT_CITY_195_20150128_Q R1360.1" "LENGTH" "" "LENGTH" "0.0254")) ("RELATIVE_PROPAGATION_DELAY" ("#SVID_CPU0_0_U36-EU43" "CRESCENT_CITY_195_20150128_Q EU43.18" "CRESCENT_CITY_195_20150128_Q U36.DB45" "GLOBAL" "LENGTH" "0.00635" "NONE" "") ("#SVID_CPU0_0_U36-EU109" "CRESCENT_CITY_195_20150128_Q EU109.16" "CRESCENT_CITY_195_20150128_Q U36.DB45" "GLOBAL" "LENGTH" "0.00635" "NONE" ""))) (MeasurementSets ("EMI" ("EMIStatus" status("on")) ("PeakEmission" status("on")) ("PeakFrequency" status("on")) ("PulseFreq" status("on")) ("RiseTime" status("on")) ("VoltageSwing" status("on"))) ("Reflection" ("BufferDelayFall" status("off")) ("BufferDelayRise" status("off")) ("EyeHeight" status("off")) ("EyeJitter" status("off")) ("EyeWidth" status("off")) ("FirstIncidentFall" status("off")) ("FirstIncidentRise" status("off")) ("Glitch" status("on")) ("GlitchFall" status("off")) ("GlitchRise" status("off")) ("Monotonic" status("on")) ("MonotonicFall" status("off")) ("MonotonicRise" status("off")) ("NoiseMargin" status("on")) ("NoiseMarginHigh" status("off")) ("NoiseMarginLow" status("off")) ("OvershootHigh" status("on")) ("OvershootLow" status("on")) ("PropDelay" status("on")) ("SettleDelay" status("on")) ("SettleDelayFall" status("off")) ("SettleDelayRise" status("off")) ("SwitchDelay" status("on")) ("SwitchDelayFall" status("off")) ("SwitchDelayRise" status("off"))) ("Crosstalk" ("Crosstalk" status("on"))) ("Custom")) (VectorSets) (Props (XnetName "SVID_DIO0_CPU0") (allDrivers "active") (customSimType "Reflection") (ftsMode ("Typ")) (rcvrSelect "all") (tlineDelayMode "time") (userRevision "1.0")))) (Subckts) (CrossSections ("CRESCENT_CITY_195_20150128_Q" (Props (SXDesignName "CRESCENT_CITY_195_20150128_Q")) (Layers ("" (layerType "SURFACE") (material "AIR") (thickness "0 mil") (dielectricConstant "1.000000") (lossTangent "0") (etchFactor "0.000000") (elecCondVal "0 mho/cm") (thermCondVal "0 w/cm-degC")) ("" (layerType "DIELECTRIC") (material "CONFORMAL_COAT") (thickness "0.5 mil") (dielectricConstant "3.800000") (lossTangent "0.035") (etchFactor "0.000000") (elecCondVal "0 mho/cm") (thermCondVal "0.012 w/cm-degC")) ("TOP" (layerType "CONDUCTOR") (material "COPPER") (thickness "  2.100000 mil") (width "4.00 MIL") (dielectricConstant "4.500000") (lossTangent "0") (etchFactor "70.000000") (elecCondVal "595900.000000 mho/cm") (thermCondVal "0 w/cm-degC") (signalDieConstant "3.800000") (signalLossTangent "0.035")) ("" (layerType "DIELECTRIC") (material "FR-4") (thickness "  2.670000 mil") (dielectricConstant "4.000000") (lossTangent "0.035") (etchFactor "0.000000") (elecCondVal "0 mho/cm") (thermCondVal "0.012 w/cm-degC")) ("L2_GND1" (layerType "PLANE") (material "COPPER") (isShield t) (thickness "  1.250000 mil") (dielectricConstant "4.500000") (lossTangent "0.035") (etchFactor "90.000000") (elecCondVal "595900.000000 mho/cm") (thermCondVal "0.012 w/cm-degC")) ("" (layerType "DIELECTRIC") (material "FR-4") (thickness "  9.000000 mil") (dielectricConstant "4.100000") (lossTangent "0.035") (etchFactor "0.000000") (elecCondVal "0 mho/cm") (thermCondVal "0.012 w/cm-degC")) ("L3_SIG1" (layerType "CONDUCTOR") (material "COPPER") (thickness "  1.250000 mil") (width "4.00 MIL") (dielectricConstant "4.500000") (lossTangent "0.035") (etchFactor "90.000000") (elecCondVal "595900.000000 mho/cm") (thermCondVal "0.012 w/cm-degC") (signalDieConstant "4.100000") (signalLossTangent "0.035")) ("" (layerType "DIELECTRIC") (material "FR-4") (thickness "  3.000000 mil") (dielectricConstant "4.500000") (lossTangent "0.035") (etchFactor "0.000000") (elecCondVal "0 mho/cm") (thermCondVal "0 w/cm-degC")) ("L4_GND2" (layerType "PLANE") (material "COPPER") (isShield t) (thickness "  1.250000 mil") (dielectricConstant "4.500000") (lossTangent "0.035") (etchFactor "90.000000") (elecCondVal "595900.000000 mho/cm") (thermCondVal "0 w/cm-degC")) ("" (layerType "DIELECTRIC") (material "FR-4") (thickness "  9.000000 mil") (dielectricConstant "4.000000") (lossTangent "0.035") (etchFactor "0.000000") (elecCondVal "0 mho/cm") (thermCondVal "0.012 w/cm-degC")) ("L5_SIG2" (layerType "CONDUCTOR") (material "COPPER") (thickness "  1.250000 mil") (width "4.00 MIL") (dielectricConstant "4.500000") (lossTangent "0.035") (etchFactor "90.000000") (elecCondVal "595900.000000 mho/cm") (thermCondVal "0.012 w/cm-degC") (signalDieConstant "4.000000") (signalLossTangent "0.035")) ("" (layerType "DIELECTRIC") (material "FR-4") (thickness "  3.000000 mil") (dielectricConstant "4.500000") (lossTangent "0.035") (etchFactor "0.000000") (elecCondVal "0 mho/cm") (thermCondVal "0 w/cm-degC")) ("L6_GND3" (layerType "PLANE") (material "COPPER") (isShield t) (thickness "  1.250000 mil") (dielectricConstant "4.500000") (lossTangent "0.035") (etchFactor "90.000000") (elecCondVal "595900.000000 mho/cm") (thermCondVal "0 w/cm-degC")) ("" (layerType "DIELECTRIC") (material "FR-4") (thickness "  4.500000 mil") (dielectricConstant "4.100000") (lossTangent "0.035") (etchFactor "0.000000") (elecCondVal "0 mho/cm") (thermCondVal "0.012 w/cm-degC")) ("L7_PWR1-SIG" (layerType "PLANE") (material "COPPER") (isShield t) (thickness "  2.400000 mil") (dielectricConstant "4.500000") (lossTangent "0.035") (etchFactor "90.000000") (elecCondVal "595900.000000 mho/cm") (thermCondVal "0.012 w/cm-degC")) ("" (layerType "DIELECTRIC") (material "FR-4") (thickness "  4.600000 mil") (dielectricConstant "4.000000") (lossTangent "0.035") (etchFactor "0.000000") (elecCondVal "0 mho/cm") (thermCondVal "0.012 w/cm-degC")) ("L8_PWR2-SIG" (layerType "PLANE") (material "COPPER") (isShield t) (thickness "  2.400000 mil") (dielectricConstant "4.500000") (lossTangent "0.035") (etchFactor "90.000000") (elecCondVal "595900.000000 mho/cm") (thermCondVal "0.012 w/cm-degC")) ("" (layerType "DIELECTRIC") (material "FR-4") (thickness "  8.000000 mil") (dielectricConstant "4.500000") (lossTangent "0.035") (etchFactor "0.000000") (elecCondVal "0 mho/cm") (thermCondVal "0 w/cm-degC")) ("" (layerType "DIELECTRIC") (material "FR-4") (thickness "  8.000000 mil") (dielectricConstant "4.500000") (lossTangent "0.035") (etchFactor "0.000000") (elecCondVal "0 mho/cm") (thermCondVal "0 w/cm-degC")) ("" (layerType "DIELECTRIC") (material "FR-4") (thickness "  4.500000 mil") (dielectricConstant "4.500000") (lossTangent "0.035") (etchFactor "0.000000") (elecCondVal "0 mho/cm") (thermCondVal "0 w/cm-degC")) ("L9_GND4" (layerType "PLANE") (material "COPPER") (isShield t) (thickness "  1.250000 mil") (dielectricConstant "4.500000") (lossTangent "0.035") (etchFactor "90.000000") (elecCondVal "595900.000000 mho/cm") (thermCondVal "0 w/cm-degC")) ("" (layerType "DIELECTRIC") (material "FR-4") (thickness "  3.000000 mil") (dielectricConstant "4.100000") (lossTangent "0.035") (etchFactor "0.000000") (elecCondVal "0 mho/cm") (thermCondVal "0.012 w/cm-degC")) ("L10_SIG3" (layerType "CONDUCTOR") (material "COPPER") (thickness "  1.250000 mil") (width "4.00 MIL") (dielectricConstant "4.500000") (lossTangent "0.035") (etchFactor "90.000000") (elecCondVal "595900.000000 mho/cm") (thermCondVal "0.012 w/cm-degC") (signalDieConstant "4.100000") (signalLossTangent "0.035")) ("" (layerType "DIELECTRIC") (material "FR-4") (thickness "  9.000000 mil") (dielectricConstant "4.500000") (lossTangent "0.035") (etchFactor "0.000000") (elecCondVal "0 mho/cm") (thermCondVal "0 w/cm-degC")) ("L11_GND5" (layerType "PLANE") (material "COPPER") (isShield t) (thickness "  1.250000 mil") (dielectricConstant "4.500000") (lossTangent "0.035") (etchFactor "90.000000") (elecCondVal "595900.000000 mho/cm") (thermCondVal "0 w/cm-degC")) ("" (layerType "DIELECTRIC") (material "FR-4") (thickness "  3.000000 mil") (dielectricConstant "4.500000") (lossTangent "0.035") (etchFactor "0.000000") (elecCondVal "0 mho/cm") (thermCondVal "0.012 w/cm-degC")) ("L12_SIG4" (layerType "CONDUCTOR") (material "COPPER") (thickness "  1.250000 mil") (width "4.00 MIL") (dielectricConstant "4.500000") (lossTangent "0.035") (etchFactor "90.000000") (elecCondVal "595900.000000 mho/cm") (thermCondVal "0.012 w/cm-degC") (signalDieConstant "4.500000") (signalLossTangent "0.035")) ("" (layerType "DIELECTRIC") (material "FR-4") (thickness "  9.000000 mil") (dielectricConstant "4.500000") (lossTangent "0.035") (etchFactor "0.000000") (elecCondVal "0 mho/cm") (thermCondVal "0 w/cm-degC")) ("L13_GND6" (layerType "PLANE") (material "COPPER") (isShield t) (thickness "  1.250000 mil") (dielectricConstant "4.500000") (lossTangent "0.035") (etchFactor "90.000000") (elecCondVal "595900.000000 mho/cm") (thermCondVal "0.012 w/cm-degC")) ("" (layerType "DIELECTRIC") (material "FR-4") (thickness "  2.670000 mil") (dielectricConstant "4.500000") (lossTangent "0.035") (etchFactor "0.000000") (elecCondVal "0 mho/cm") (thermCondVal "0.012 w/cm-degC")) ("BOTTOM" (layerType "CONDUCTOR") (material "COPPER") (thickness "  2.100000 mil") (width "4.00 MIL") (dielectricConstant "4.500000") (lossTangent "0") (etchFactor "70.000000") (elecCondVal "595900.000000 mho/cm") (thermCondVal "0 w/cm-degC") (signalDieConstant "3.800000") (signalLossTangent "0.035")) ("" (layerType "DIELECTRIC") (material "CONFORMAL_COAT") (thickness "0.5 mil") (dielectricConstant "3.800000") (lossTangent "0.035") (etchFactor "0.000000") (elecCondVal "0 mho/cm") (thermCondVal "0.012 w/cm-degC")) ("" (layerType "SURFACE") (material "AIR") (thickness "0 mil") (dielectricConstant "1.000000") (lossTangent "0") (etchFactor "0.000000") (elecCondVal "0 mho/cm") (thermCondVal "0 w/cm-degC"))))) (Props (DesUnits "mils 2") (LayerStack ("DIELECTRIC" "DIELECTRIC" "BOTTOM" "DIELECTRIC" "L13_GND6" "DIELECTRIC" "L12_SIG4" "DIELECTRIC" "L11_GND5" "DIELECTRIC" "L10_SIG3" "DIELECTRIC" "L9_GND4" "DIELECTRIC" "DIELECTRIC" "DIELECTRIC" "L8_PWR2-SIG" "DIELECTRIC" "L7_PWR1-SIG" "DIELECTRIC" "L6_GND3" "DIELECTRIC" "L5_SIG2" "DIELECTRIC" "L4_GND2" "DIELECTRIC" "L3_SIG1" "DIELECTRIC" "L2_GND1" "DIELECTRIC" "TOP" "DIELECTRIC" "DIELECTRIC")) (Revision "16.600")) (Params (DiffOutputPkg ((temperature "27") (bufferModelNonInverting "CDSDefaultOutput_2p5v") (bufferModelInverting "CDSDefaultOutput_2p5v") (stimuli nil) (offsets nil) (state "tristate") (cycle "1") (termMap nil) (setup "0.9e-09") (hold "0.4e-09") (rise nil) (fall nil) (threshOutputHighMin "2.375  V") (threshOutputHighTyp "2.5  V") (threshOutputHighMax "2.625  V") (threshOutputLowMin "1.275  V") (threshOutputLowTyp "1.7  V") (threshOutputLowMax "1.985  V") (mappingTagNonInverting nil) (mappingTagInverting nil) (spice nil))) (HiClampTerm ((cutoffVoltage "0.7 V") (voltage "5 V") (maxDelay "0.1 ns"))) (LowClampTerm ((cutoffVoltage "0.7 V") (voltage "0 V") (maxDelay "0.1 ns"))) (DiffOutput ((temperature "27") (bufferModelNonInverting "CDSDefaultOutput_2p5v") (bufferModelInverting "CDSDefaultOutput_2p5v") (stimuli nil) (offsets nil) (state "tristate") (cycle "1") (termMap nil) (setup "0.9e-09") (hold "0.4e-09") (rise nil) (fall nil) (threshOutputHighMin "2.375  V") (threshOutputHighTyp "2.5  V") (threshOutputHighMax "2.625  V") (threshOutputLowMin "1.275  V") (threshOutputLowTyp "1.7  V") (threshOutputLowMax "1.985  V") (mappingTagNonInverting nil) (mappingTagInverting nil) (spice nil))) (Via ((model "Unknown") (viaOutputFormat "Unknown") (viaPadstack nil) (viaTopLayer nil) (viaBottomLayer nil) (viaIsPower nil) (viaIsGround nil))) (Resistor ((resistance "50 ohm") (orientation "0"))) (RCTerm ((resistance "50 ohm") (capacitance "20 pF") (voltage "5 V") (maxDelay "0.1 ns"))) (DiffIOPkg ((temperature "27") (bufferModelNonInverting "CDSDefaultIO_2p5v") (bufferModelInverting "CDSDefaultIO_2p5v") (stimuli nil) (offsets nil) (state "tristate") (cycle "1") (termMap nil) (setup "0.9e-09") (hold "0.4e-09") (rise nil) (fall nil) (threshInputHighMin "1.7 V") (threshInputHighTyp "1.7  V") (threshInputHighMax "1.7  V") (threshInputLowMin "0.7  V") (threshInputLowTyp "0.7  V") (threshInputLowMax "0.7 ") (threshOutputHighMin "2.365  V") (threshOutputHighTyp "2.5  V") (threshOutputHighMax "2.625  V") (threshOutputLowMin "1.275  V") (threshOutputLowTyp "1.7  V") (threshOutputLowMax "1.985  V") (mappingTagNonInverting nil) (mappingTagInverting nil) (spice nil))) (Trace ((d1Thickness "10 mil") (d1Constant "4.5") (d1LossTangent "0.035") (d2Thickness "10 mil") (d2Constant "4.5") (d2LossTangent "0.035") (d3Thickness "0.0") (d3Constant "1.0") (d3LossTangent "0") length("1000 mil") (spacing "5 mil") (spacing2 "5 mil") (spacing3 "5 mil") (spacing4 "5 mil") (spacing5 "5 mil") (traceConductivity "595900 mho/cm") (traceGeometry "microstrip") (traceLayerName "") (traceThickness "0.72 mil") (traceType "single") (traceWidth "5.0 mil") (traceWidth2 "5.0 mil") (traceWidth3 "5.0 mil") (traceWidth4 "5.0 mil") (traceWidth5 "5.0 mil") (traceWidth6 "5.0 mil") (offset "0 mil") (traceCount "1") (impedance nil))) (TheveninTerm ((resistanceUp "180 ohm") (resistanceDown "270 ohm") (voltageUp "5 V") (voltageDown "0 V") (maxDelay "0.1 ns"))) (DiffIO ((temperature "27") (bufferModelNonInverting "CDSDefaultIO_2p5v") (bufferModelInverting "CDSDefaultIO_2p5v") (stimuli nil) (offsets nil) (state "tristate") (cycle "1") (termMap nil) (setup "0.9e-09") (hold "0.4e-09") (rise nil) (fall nil) (threshInputHighMin "1.7 V") (threshInputHighTyp "1.7  V") (threshInputHighMax "1.7  V") (threshInputLowMin "0.7  V") (threshInputLowTyp "0.7  V") (threshInputLowMax "0.7 ") (threshOutputHighMin "2.365  V") (threshOutputHighTyp "2.5  V") (threshOutputHighMax "2.625  V") (threshOutputLowMin "1.275  V") (threshOutputLowTyp "1.7  V") (threshOutputLowMax "1.985  V") (mappingTagNonInverting nil) (mappingTagInverting nil) (spice nil))) (ShuntTerm ((resistance "50 ohm") (voltage "5 V") (maxDelay "0.1 ns"))) (Inductor ((inductance "5 nH") (orientation "0"))) (Capacitor ((capacitance "10 pF") (orientation "0"))) (RLGC (length("1000 mil"))) (Source ((voltage "5 V"))) (DiffInput ((temperature "27") (bufferModelNonInverting "CDSDefaultInput_2p5v") (bufferModelInverting "CDSDefaultInput_2p5v") (threshInputHighMin "1.7 V") (threshInputHighTyp "1.7  V") (threshInputHighMax "1.7  V") (threshInputLowMin "0.7  V") (threshInputLowTyp "0.7  V") (threshInputLowMax "0.7  V") (mappingTagNonInverting nil) (mappingTagInverting nil) (cycle "1"))) (Cable (length("1 m"))) (CPWSL ((d1Thickness "10 mil") (d1Constant "4.5") (d1LossTangent "0.035") (d2Thickness "0.72 mil") (d2Constant "4.5") (d2LossTangent "0.035") (d3Thickness "10 mil") (d3Constant "4.5") (d3LossTangent "0.035") length("1000 mil") (spacing "5 mil") (spacing2 "5 mil") (spacing3 "5 mil") (spacing4 "5 mil") (spacing5 "5 mil") (traceConductivity "595900 mho/cm") (traceGeometry "cpwms") (traceLayerName "") (traceThickness "0.72 mil") (traceType "single") (traceWidth "5.0 mil") (traceWidth2 "5.0 mil") (traceWidth3 "5.0 mil") (traceWidth4 "5.0 mil") (traceWidth5 "5.0 mil") (traceWidth6 "5.0 mil") (offset "0 mil") (traceCount "1") (impedance nil))) (ESpiceDevice nil) (CPWMS ((d1Thickness "10 mil") (d1Constant "4.5") (d1LossTangent "0.035") (d2Thickness "0.72 mil") (d2Constant "4.5") (d2LossTangent "0.035") (d3Thickness "0.0") (d3Constant "1") (d3LossTangent "0") length("1000 mil") (spacing "5 mil") (spacing2 "5 mil") (spacing3 "5 mil") (spacing4 "5 mil") (spacing5 "5 mil") (traceConductivity "595900 mho/cm") (traceGeometry "cpwms") (traceLayerName "") (traceThickness "0.72 mil") (traceType "single") (traceWidth "5.0 mil") (traceWidth2 "5.0 mil") (traceWidth3 "5.0 mil") (traceWidth4 "5.0 mil") (traceWidth5 "5.0 mil") (traceWidth6 "5.0 mil") (offset "0 mil") (traceCount "1") (impedance nil))) (Diode ((cutoffVoltage "0.7 V"))) (CPW ((d1Thickness "10 mil") (d1Constant "4.5") (d1LossTangent "0.035") (d2Thickness "0.72 mil") (d2Constant "1") (d2LossTangent "0") (d3Thickness "0.0") (d3Constant "1") (d3LossTangent "0") length("1000 mil") (spacing "5 mil") (spacing2 "5 mil") (spacing3 "5 mil") (spacing4 "5 mil") (spacing5 "5 mil") (traceConductivity "595900 mho/cm") (traceGeometry "cpwms") (traceLayerName "") (traceThickness "0.72 mil") (traceType "single") (traceWidth "5.0 mil") (traceWidth2 "5.0 mil") (traceWidth3 "5.0 mil") (traceWidth4 "5.0 mil") (traceWidth5 "5.0 mil") (traceWidth6 "5.0 mil") (offset "0 mil") (traceCount "1") (impedance nil))) (DualClampTerm ((cutoffVoltageUp "0.7 V") (cutoffVoltageDown "0.7 V") (voltageUp "5 V") (voltageDown "0 V") (maxDelay "0.1 ns"))) (IbisOutputPkg ((temperature "27") (bufferModel "CDSDefaultOutput_2p5v") (stimuli nil) (offsets nil) (state "tristate") (cycle "1") (termMap nil) (setup "2.0e-09") (hold "1.0e-09") (rise nil) (fall nil) (macroType nil) (voltage nil) (spice nil) (LEFDEFPinName nil) (LEFDEFPinType nil) (mappingTag nil))) (IbisIO_OpenPullDown ((temperature "27") (bufferModel "CDSDefaultIO_2p5v") (stimuli nil) (offsets nil) (state "tristate") (cycle "1") (termMap nil) (setup "2.0e-09") (hold "1.0e-09") (rise nil) (fall nil) (macroType nil) (voltage nil) (spice nil) (LEFDEFPinName nil) (LEFDEFPinType nil) (mappingTag nil))) (IbisInputPkg ((temperature "27") (bufferModel "CDSDefaultInput_2p5v") (cycle "1") (LEFDEFPinName nil) (LEFDEFPinType nil) (mappingTag nil))) (IbisIOMacro ((temperature "27") (bufferModel "CDSDefaultIO_2p5v") (stimuli nil) (offsets nil) (state "tristate") (cycle "1") (termMap nil) (setup "2.0e-09") (hold "1.0e-09") (rise nil) (fall nil) (macroType nil) (voltage nil) (spice nil) (LEFDEFPinName nil) (LEFDEFPinType nil) (mappingTag nil))) (IbisIO_OpenPullUp ((temperature "27") (bufferModel "CDSDefaultIO_2p5v") (stimuli nil) (offsets nil) (state "tristate") (cycle "1") (termMap nil) (setup "2.0e-09") (hold "1.0e-09") (rise nil) (fall nil) (macroType nil) (voltage nil) (spice nil) (LEFDEFPinName nil) (LEFDEFPinType nil) (mappingTag nil))) (IbisIOPkg ((temperature "27") (bufferModel "CDSDefaultIO_2p5v") (stimuli nil) (offsets nil) (state "tristate") (cycle "1") (termMap nil) (setup "2.0e-09") (hold "1.0e-09") (rise nil) (fall nil) (macroType nil) (voltage nil) (spice nil) (LEFDEFPinName nil) (LEFDEFPinType nil) (mappingTag nil))) (clocked ((clockRise "1e-09") (clockFall "1e-09") (clockFreq "100e6") (clockInitState "0") (clockDutyCycle "0.5") (clockJitter "0"))) (periodic ((periodicFreq "100e6") (periodicPattern "10") (periodicJitter "0"))) (IbisIO ((temperature "27") (bufferModel "CDSDefaultIO_2p5v") (stimuli nil) (offsets nil) (state "tristate") (cycle "1") (termMap nil) (setup "2.0e-09") (hold "1.0e-09") (rise nil) (fall nil) (macroType nil) (voltage nil) (spice nil) (LEFDEFPinName nil) (LEFDEFPinType nil) (mappingTag nil))) (async ((asyncTimePoints "") (asyncInitState "1"))) (IbisOutput ((temperature "27") (bufferModel "CDSDefaultOutput_2p5v") (stimuli nil) (offsets nil) (state "tristate") (cycle "1") (termMap nil) (setup "2.0e-09") (hold "1.0e-09") (rise nil) (fall nil) (macroType nil) (voltage nil) (spice nil) (LEFDEFPinName nil) (LEFDEFPinType nil) (mappingTag nil))) (TLine ((diffImpedance "100ohm") (diffVelocity "1.4142e+08M/s") (impedance "60ohm") length("2800 mil") (propDelay "0.5 ns") (velocity "5600 mil/ns") (traceCount "1") (traceGeometry "Microstrip") (impedanceMin nil) (impedanceMax nil) (lengthMin nil) (lengthMax nil) (propDelayMin nil) (propDelayMax nil) (impedanceSweepCount nil) (propDelaySweepCount nil) (velocitySweepCount nil) (lengthSweepCount nil) (matchSetName nil))) (CurrentProbe nil) (IbisInput ((temperature "27") (bufferModel "CDSDefaultInput_2p5v") (cycle "1") (LEFDEFPinName nil) (LEFDEFPinType nil) (mappingTag nil))) (SeriesTerm ((resistance "22 ohm") (maxDelay "0.1 ns"))) (Connector nil) (sync ((syncFreq "100e6") (syncInitState "1") (syncPattern "10") (syncEdgeSwitch "rise"))) (IbisOutput_OpenPullUp ((temperature "27") (bufferModel "CDSDefaultOutput_2p5v") (stimuli nil) (offsets nil) (state "tristate") (cycle "1") (termMap nil) (setup "2.0e-09") (hold "1.0e-09") (rise nil) (fall nil) (macroType nil) (voltage nil) (spice nil) (LEFDEFPinName nil) (LEFDEFPinType nil) (mappingTag nil))) (DiffInputPkg ((temperature "27") (bufferModelNonInverting "CDSDefaultInput_2p5v") (bufferModelInverting "CDSDefaultInput_2p5v") (threshInputHighMin "1.7 V") (threshInputHighTyp "1.7  V") (threshInputHighMax "1.7  V") (threshInputLowMin "0.7  V") (threshInputLowTyp "0.7  V") (threshInputLowMax "0.7  V") (mappingTagNonInverting nil) (mappingTagInverting nil) (cycle "1"))) (idlCircuit ((allDrivers "active") (ftsMode '("Typ")) (rcvrSelect "all") (simMode "Reflection") (tlineDelayMode "time") (userRevision "1.0") (autoSolve "On")))))
				)
				( objectStatus "SVID_DIO0_CPU0" )
			)
			( electricalCSet "@baseboard_fab2_lib.baseboard_fab2(sch_1):\SVID_ALERT0_CPU0_N\"
				( groupRef "SVID_ALERT0_CPU0_N:#SVID_CPU0_0_U36-EU109" )
				( groupRef "SVID_ALERT0_CPU0_N:#SVID_CPU0_0_U36-EU43" )
				( pinPairRef "SVID_ALERT0_CPU0_N:U5D1.DE44:R6N10.1" )
				( pinPairRef "SVID_ALERT0_CPU0_N:R6N10.2:R3P1.2" )
				( pinPairRef "SVID_ALERT0_CPU0_N:R6N1.1:R6N10.2" )
				( pinPairRef "SVID_ALERT0_CPU0_N:EU3P1.17:R3P1.1" )
				( pinPairRef "SVID_ALERT0_CPU0_N:EU4D4.19:R4D67.1" )
				( pinPairRef "SVID_ALERT0_CPU0_N:EU3P1.17:U5D1.DE44" )
				( pinPairRef "SVID_ALERT0_CPU0_N:EU4D4.19:U5D1.DE44" )
				( attribute "TOPOLOGY_TEMPLATE_REVISION" "1.0"
					( Origin gBackEnd )
				)
				( topologyData 29871
(SKIDL (Circuits ("MAIN" (Parts ("CRESCENT_CITY_195_20150128_Q.@@J130.C20" IbisIOPkg (xy (5582 4225)) (refDes "J6B1") (model "Unknown") (Props (_SXDesignName "CRESCENT_CITY_195_20150128_Q") (brdx "13926 MIL") (brdy "4450 MIL") (bufferModel "CDSDefaultIO_2p5v") (cycle "1") (hold "1.0e-09") (mappingTag "") (offsets ("4" "0") ("5" "0")) (setup "2.0e-09") (state "tristate") (stimuli ("4" "local19") ("5" "local20")) (temperature "27") (termMap ("4" "Data") ("5" "Enable"))) (Terms ("CRESCENT_CITY_195_20150128_Q.X1392600Y445000L2LRATS" "C20"))) ("CRESCENT_CITY_195_20150128_Q.@@EU109.17" IbisOutputPkg (xy (5544 4212)) (refDes "EU3P1") (model "Unknown") (Props (_SXDesignName "CRESCENT_CITY_195_20150128_Q") (brdx "13346.5 MIL") (brdy "3466.62 MIL") (bufferModel "CDSDefaultOutput_2p5v") (cycle "1") (hold "1.0e-09") (mappingTag "") (offsets ("4" "0")) (setup "2.0e-09") (state "tristate") (stimuli ("4" "local21")) (temperature "27") (termMap ("4" "Data"))) (Terms ("CRESCENT_CITY_195_20150128_Q.X1334650Y346662L30LRATS" "17"))) ("CRESCENT_CITY_195_20150128_Q.@@U36.DE44" IbisInputPkg (xy (5583 4235)) (refDes "U5D1") (model "Unknown") (Props (_SXDesignName "CRESCENT_CITY_195_20150128_Q") (brdx "10582.94 MIL") (brdy "3592.6 MIL") (bufferModel "CDSDefaultInput_2p5v") (mappingTag "") (temperature "27")) (Terms ("CRESCENT_CITY_195_20150128_Q.X1058294Y359260L2LRATS" "DE44"))) ("CRESCENT_CITY_195_20150128_Q.@@EU43.19" IbisOutputPkg (xy (5498 4235)) (refDes "EU4D4") (model "Unknown") (Props (_SXDesignName "CRESCENT_CITY_195_20150128_Q") (brdx "7262.87 MIL") (brdy "2636 MIL") (bufferModel "CDSDefaultOutput_2p5v") (cycle "1") (hold "1.0e-09") (mappingTag "") (offsets ("4" "0")) (setup "2.0e-09") (state "tristate") (stimuli ("4" "local22")) (temperature "27") (termMap ("4" "Data"))) (Terms ("CRESCENT_CITY_195_20150128_Q.X726287Y263600L2LRATS" "19"))) ("CRESCENT_CITY_195_20150128_Q.T@@RATS@@R2840.1@@EU109.17" TLine (xy (5558 4212)) (mirror x) (refDes "TL35") (Props (_SXDesignName "CRESCENT_CITY_195_20150128_Q") (impedance "47.863 ohm") length("69.88 MIL") (propDelay "0.01255 ns") (traceCount "1") (traceGeometry "Microstrip") (velocity "5568.11 mil/ns")) (Terms ("CRESCENT_CITY_195_20150128_Q.X1328800Y347800L30LRATS" "1") ("CRESCENT_CITY_195_20150128_Q.X1334650Y346662L30LRATS" "2"))) ("CRESCENT_CITY_195_20150128_Q.T@@RATS@@R1179.1@@R2840.2" TLine (xy (5545 4220)) (refDes "TL36") (Props (_SXDesignName "CRESCENT_CITY_195_20150128_Q") (impedance "60 ohm") length("5964.49 MIL") (propDelay "1.07127 ns") (traceCount "1") (traceGeometry "Microstrip") (velocity "5567.68 mil/ns")) (Terms ("CRESCENT_CITY_195_20150128_Q.X800750Y419700L30LRATS" "1") ("CRESCENT_CITY_195_20150128_Q.X1325300Y347800L30LRATS" "2"))) ("CRESCENT_CITY_195_20150128_Q.T@@RATS@@R1179.1@@R1363.2" TLine (xy (5530 4235)) (mirror x) (refDes "TL37") (Props (_SXDesignName "CRESCENT_CITY_195_20150128_Q") (impedance "48.412 ohm") length("2414.50 MIL") (propDelay "0.43366 ns") (traceCount "1") (traceGeometry "Microstrip") (velocity "5567.72 mil/ns")) (Terms ("CRESCENT_CITY_195_20150128_Q.X800750Y419700L30LRATS" "1") ("CRESCENT_CITY_195_20150128_Q.X726500Y252500L2LRATS" "2"))) ("CRESCENT_CITY_195_20150128_Q.@@R1197.1.2" Resistor (xy (5554 4235)) (mirror x) (refDes "R6N10") (value "220 Ohm") (Props (_SXDesignName "CRESCENT_CITY_195_20150128_Q")) (Terms ("CRESCENT_CITY_195_20150128_Q.X804250Y419700L2LRATS" "1") ("CRESCENT_CITY_195_20150128_Q.X800750Y419700L2LRATS" "2"))) ("CRESCENT_CITY_195_20150128_Q.T@@RATS@@U36.DE44@@R1197.1" TLine (xy (5569 4235)) (mirror x) (refDes "TL38") (Props (_SXDesignName "CRESCENT_CITY_195_20150128_Q") (impedance "50.521 ohm") length("3144.84 MIL") (propDelay "0.56483 ns") (traceCount "1") (traceGeometry "Microstrip") (velocity "5567.76 mil/ns")) (Terms ("CRESCENT_CITY_195_20150128_Q.X1058294Y359260L2LRATS" "1") ("CRESCENT_CITY_195_20150128_Q.X804250Y419700L2LRATS" "2"))) ("CRESCENT_CITY_195_20150128_Q.@@R1363.1.2" Resistor (xy (5521 4235)) (refDes "R4D67") (value "2.2e-007 Ohm") (Props (_SXDesignName "CRESCENT_CITY_195_20150128_Q")) (Terms ("CRESCENT_CITY_195_20150128_Q.X726500Y256000L2LRATS" "1") ("CRESCENT_CITY_195_20150128_Q.X726500Y252500L2LRATS" "2"))) ("CRESCENT_CITY_195_20150128_Q.T@@RATS@@R1179.1@@R1197.2" TLine (xy (5545 4235)) (refDes "TL39") (Props (_SXDesignName "CRESCENT_CITY_195_20150128_Q") (impedance "48.412 ohm") (propDelay "1.79607e-006 ns") (traceCount "1") (traceGeometry "Microstrip")) (Terms ("CRESCENT_CITY_195_20150128_Q.X800750Y419700L30LRATS" "1") ("CRESCENT_CITY_195_20150128_Q.X800750Y419700L2LRATS" "2"))) ("CRESCENT_CITY_195_20150128_Q.T@@RATS@@R2840.2@@J130.C20" TLine (xy (5573 4220)) (refDes "TL40") (Props (_SXDesignName "CRESCENT_CITY_195_20150128_Q") (impedance "60 ohm") length("1645.02 MIL") (propDelay "0.295453 ns") (traceCount "1") (traceGeometry "Microstrip") (velocity "5567.8 mil/ns")) (Terms ("CRESCENT_CITY_195_20150128_Q.X1325300Y347800L30LRATS" "1") ("CRESCENT_CITY_195_20150128_Q.X1392600Y445000L2LRATS" "2"))) ("CRESCENT_CITY_195_20150128_Q.T@@RATS@@R1363.1@@EU43.19" TLine (xy (5506 4235)) (mirror x) (refDes "TL41") (Props (_SXDesignName "CRESCENT_CITY_195_20150128_Q") (impedance "48.412 ohm") length("78.13 MIL") (propDelay "0.01403 ns") (traceCount "1") (traceGeometry "Microstrip") (velocity "5568.78 mil/ns")) (Terms ("CRESCENT_CITY_195_20150128_Q.X726500Y256000L2LRATS" "1") ("CRESCENT_CITY_195_20150128_Q.X726287Y263600L2LRATS" "2"))) ("CRESCENT_CITY_195_20150128_Q.@@R1179.2_SOURCE" Source (xy (5523 4229)) (refDes "PVCCIO_CPU0") (value "1.05 V") (Props (_SXDesignName "CRESCENT_CITY_195_20150128_Q")) (Terms ("CRESCENT_CITY_195_20150128_Q.X804250Y419700L30RATS" "1"))) ("CRESCENT_CITY_195_20150128_Q.@@R1179.2.1" Resistor (xy (5530 4229)) (refDes "R6N1") (value "49.9 Ohm") (Props (_SXDesignName "CRESCENT_CITY_195_20150128_Q")) (Terms ("CRESCENT_CITY_195_20150128_Q.X804250Y419700L30RATS" "2") ("CRESCENT_CITY_195_20150128_Q.X800750Y419700L30LRATS" "1"))) ("CRESCENT_CITY_195_20150128_Q.@@R2840.1.2" Resistor (xy (5567 4212)) (refDes "R3P1") (value "2.2e-007 Ohm") (Props (_SXDesignName "CRESCENT_CITY_195_20150128_Q")) (Terms ("CRESCENT_CITY_195_20150128_Q.X1328800Y347800L30LRATS" "1") ("CRESCENT_CITY_195_20150128_Q.X1325300Y347800L30LRATS" "2")))) (Nodes ("CRESCENT_CITY_195_20150128_Q.X804250Y419700L2LRATS" (terms "CRESCENT_CITY_195_20150128_Q.T@@RATS@@U36.DE44@@R1197.1.2" "CRESCENT_CITY_195_20150128_Q.@@R1197.1.2.1")) ("CRESCENT_CITY_195_20150128_Q.X1334650Y346662L30LRATS" (terms "CRESCENT_CITY_195_20150128_Q.T@@RATS@@R2840.1@@EU109.17.2" "CRESCENT_CITY_195_20150128_Q.@@EU109.17.1")) ("CRESCENT_CITY_195_20150128_Q.X800750Y419700L30LRATS" (terms "CRESCENT_CITY_195_20150128_Q.@@R1179.2.1.2" "CRESCENT_CITY_195_20150128_Q.T@@RATS@@R1179.1@@R1197.2.1" "CRESCENT_CITY_195_20150128_Q.T@@RATS@@R1179.1@@R1363.2.1" "CRESCENT_CITY_195_20150128_Q.T@@RATS@@R1179.1@@R2840.2.1")) ("CRESCENT_CITY_195_20150128_Q.X1325300Y347800L30LRATS" (terms "CRESCENT_CITY_195_20150128_Q.@@R2840.1.2.2" "CRESCENT_CITY_195_20150128_Q.T@@RATS@@R2840.2@@J130.C20.1" "CRESCENT_CITY_195_20150128_Q.T@@RATS@@R1179.1@@R2840.2.2")) ("CRESCENT_CITY_195_20150128_Q.X726500Y256000L2LRATS" (terms "CRESCENT_CITY_195_20150128_Q.T@@RATS@@R1363.1@@EU43.19.1" "CRESCENT_CITY_195_20150128_Q.@@R1363.1.2.1")) ("CRESCENT_CITY_195_20150128_Q.X1328800Y347800L30LRATS" (terms "CRESCENT_CITY_195_20150128_Q.@@R2840.1.2.1" "CRESCENT_CITY_195_20150128_Q.T@@RATS@@R2840.1@@EU109.17.1")) ("CRESCENT_CITY_195_20150128_Q.X1058294Y359260L2LRATS" (terms "CRESCENT_CITY_195_20150128_Q.T@@RATS@@U36.DE44@@R1197.1.1" "CRESCENT_CITY_195_20150128_Q.@@U36.DE44.1")) ("CRESCENT_CITY_195_20150128_Q.X800750Y419700L2LRATS" (terms "CRESCENT_CITY_195_20150128_Q.T@@RATS@@R1179.1@@R1197.2.2" "CRESCENT_CITY_195_20150128_Q.@@R1197.1.2.2")) ("CRESCENT_CITY_195_20150128_Q.X1392600Y445000L2LRATS" (terms "CRESCENT_CITY_195_20150128_Q.T@@RATS@@R2840.2@@J130.C20.2" "CRESCENT_CITY_195_20150128_Q.@@J130.C20.1")) ("CRESCENT_CITY_195_20150128_Q.X726500Y252500L2LRATS" (terms "CRESCENT_CITY_195_20150128_Q.@@R1363.1.2.2" "CRESCENT_CITY_195_20150128_Q.T@@RATS@@R1179.1@@R1363.2.2")) ("CRESCENT_CITY_195_20150128_Q.X726287Y263600L2LRATS" (terms "CRESCENT_CITY_195_20150128_Q.T@@RATS@@R1363.1@@EU43.19.2" "CRESCENT_CITY_195_20150128_Q.@@EU43.19.1")) ("CRESCENT_CITY_195_20150128_Q.X804250Y419700L30RATS" (terms "CRESCENT_CITY_195_20150128_Q.@@R1179.2.1.1" "CRESCENT_CITY_195_20150128_Q.@@R1179.2_SOURCE.1"))) (Ports) (Stimuli ("local22" (scope local) (stimType periodic) (Props (periodicFreq "5e+007") (periodicJitter "0") (periodicPattern "1"))) ("local20" (scope local) (stimType periodic) (Props (periodicFreq "5e+007") (periodicJitter "0") (periodicPattern "1"))) ("local21" (scope local) (stimType periodic) (Props (periodicFreq "5e+007") (periodicJitter "0") (periodicPattern "1"))) ("local19" (scope local) (stimType periodic) (Props (periodicFreq "5e+007") (periodicJitter "0") (periodicPattern "1")))) (Notes) (Constraints ("DELAY_RULE" ("CRESCENT_CITY_195_20150128_Q U36.DE44" "CRESCENT_CITY_195_20150128_Q R1197.1" "LENGTH" "" "LENGTH" "0.1143") ("CRESCENT_CITY_195_20150128_Q R1197.2" "CRESCENT_CITY_195_20150128_Q R2840.2" "LENGTH" "" "LENGTH" "0.6858") ("CRESCENT_CITY_195_20150128_Q R1179.1" "CRESCENT_CITY_195_20150128_Q R1197.2" "LENGTH" "" "LENGTH" "0.01016") ("CRESCENT_CITY_195_20150128_Q EU109.17" "CRESCENT_CITY_195_20150128_Q R2840.1" "LENGTH" "" "LENGTH" "0.0254") ("CRESCENT_CITY_195_20150128_Q EU43.19" "CRESCENT_CITY_195_20150128_Q R1363.1" "LENGTH" "" "LENGTH" "0.0254")) ("RELATIVE_PROPAGATION_DELAY" ("#SVID_CPU0_0_U36-EU109" "CRESCENT_CITY_195_20150128_Q EU109.17" "CRESCENT_CITY_195_20150128_Q U36.DE44" "GLOBAL" "LENGTH" "0.00635" "NONE" "") ("#SVID_CPU0_0_U36-EU43" "CRESCENT_CITY_195_20150128_Q EU43.19" "CRESCENT_CITY_195_20150128_Q U36.DE44" "GLOBAL" "LENGTH" "0.00635" "NONE" ""))) (MeasurementSets ("EMI" ("EMIStatus" status("on")) ("PeakEmission" status("on")) ("PeakFrequency" status("on")) ("PulseFreq" status("on")) ("RiseTime" status("on")) ("VoltageSwing" status("on"))) ("Reflection" ("BufferDelayFall" status("off")) ("BufferDelayRise" status("off")) ("EyeHeight" status("off")) ("EyeJitter" status("off")) ("EyeWidth" status("off")) ("FirstIncidentFall" status("off")) ("FirstIncidentRise" status("off")) ("Glitch" status("on")) ("GlitchFall" status("off")) ("GlitchRise" status("off")) ("Monotonic" status("on")) ("MonotonicFall" status("off")) ("MonotonicRise" status("off")) ("NoiseMargin" status("on")) ("NoiseMarginHigh" status("off")) ("NoiseMarginLow" status("off")) ("OvershootHigh" status("on")) ("OvershootLow" status("on")) ("PropDelay" status("on")) ("SettleDelay" status("on")) ("SettleDelayFall" status("off")) ("SettleDelayRise" status("off")) ("SwitchDelay" status("on")) ("SwitchDelayFall" status("off")) ("SwitchDelayRise" status("off"))) ("Crosstalk" ("Crosstalk" status("on"))) ("Custom")) (VectorSets) (Props (XnetName "SVID_ALERT0_CPU0_N") (allDrivers "active") (customSimType "Reflection") (ftsMode ("Typ")) (rcvrSelect "all") (tlineDelayMode "time") (userRevision "1.0")))) (Subckts) (CrossSections ("CRESCENT_CITY_195_20150128_Q" (Props (SXDesignName "CRESCENT_CITY_195_20150128_Q")) (Layers ("" (layerType "SURFACE") (material "AIR") (thickness "0 mil") (dielectricConstant "1.000000") (lossTangent "0") (etchFactor "0.000000") (elecCondVal "0 mho/cm") (thermCondVal "0 w/cm-degC")) ("" (layerType "DIELECTRIC") (material "CONFORMAL_COAT") (thickness "0.5 mil") (dielectricConstant "3.800000") (lossTangent "0.035") (etchFactor "0.000000") (elecCondVal "0 mho/cm") (thermCondVal "0.012 w/cm-degC")) ("TOP" (layerType "CONDUCTOR") (material "COPPER") (thickness "  2.100000 mil") (width "4.00 MIL") (dielectricConstant "4.500000") (lossTangent "0") (etchFactor "70.000000") (elecCondVal "595900.000000 mho/cm") (thermCondVal "0 w/cm-degC") (signalDieConstant "3.800000") (signalLossTangent "0.035")) ("" (layerType "DIELECTRIC") (material "FR-4") (thickness "  2.670000 mil") (dielectricConstant "4.000000") (lossTangent "0.035") (etchFactor "0.000000") (elecCondVal "0 mho/cm") (thermCondVal "0.012 w/cm-degC")) ("L2_GND1" (layerType "PLANE") (material "COPPER") (isShield t) (thickness "  1.250000 mil") (dielectricConstant "4.500000") (lossTangent "0.035") (etchFactor "90.000000") (elecCondVal "595900.000000 mho/cm") (thermCondVal "0.012 w/cm-degC")) ("" (layerType "DIELECTRIC") (material "FR-4") (thickness "  9.000000 mil") (dielectricConstant "4.100000") (lossTangent "0.035") (etchFactor "0.000000") (elecCondVal "0 mho/cm") (thermCondVal "0.012 w/cm-degC")) ("L3_SIG1" (layerType "CONDUCTOR") (material "COPPER") (thickness "  1.250000 mil") (width "4.00 MIL") (dielectricConstant "4.500000") (lossTangent "0.035") (etchFactor "90.000000") (elecCondVal "595900.000000 mho/cm") (thermCondVal "0.012 w/cm-degC") (signalDieConstant "4.100000") (signalLossTangent "0.035")) ("" (layerType "DIELECTRIC") (material "FR-4") (thickness "  3.000000 mil") (dielectricConstant "4.500000") (lossTangent "0.035") (etchFactor "0.000000") (elecCondVal "0 mho/cm") (thermCondVal "0 w/cm-degC")) ("L4_GND2" (layerType "PLANE") (material "COPPER") (isShield t) (thickness "  1.250000 mil") (dielectricConstant "4.500000") (lossTangent "0.035") (etchFactor "90.000000") (elecCondVal "595900.000000 mho/cm") (thermCondVal "0 w/cm-degC")) ("" (layerType "DIELECTRIC") (material "FR-4") (thickness "  9.000000 mil") (dielectricConstant "4.000000") (lossTangent "0.035") (etchFactor "0.000000") (elecCondVal "0 mho/cm") (thermCondVal "0.012 w/cm-degC")) ("L5_SIG2" (layerType "CONDUCTOR") (material "COPPER") (thickness "  1.250000 mil") (width "4.00 MIL") (dielectricConstant "4.500000") (lossTangent "0.035") (etchFactor "90.000000") (elecCondVal "595900.000000 mho/cm") (thermCondVal "0.012 w/cm-degC") (signalDieConstant "4.000000") (signalLossTangent "0.035")) ("" (layerType "DIELECTRIC") (material "FR-4") (thickness "  3.000000 mil") (dielectricConstant "4.500000") (lossTangent "0.035") (etchFactor "0.000000") (elecCondVal "0 mho/cm") (thermCondVal "0 w/cm-degC")) ("L6_GND3" (layerType "PLANE") (material "COPPER") (isShield t) (thickness "  1.250000 mil") (dielectricConstant "4.500000") (lossTangent "0.035") (etchFactor "90.000000") (elecCondVal "595900.000000 mho/cm") (thermCondVal "0 w/cm-degC")) ("" (layerType "DIELECTRIC") (material "FR-4") (thickness "  4.500000 mil") (dielectricConstant "4.100000") (lossTangent "0.035") (etchFactor "0.000000") (elecCondVal "0 mho/cm") (thermCondVal "0.012 w/cm-degC")) ("L7_PWR1-SIG" (layerType "PLANE") (material "COPPER") (isShield t) (thickness "  2.400000 mil") (dielectricConstant "4.500000") (lossTangent "0.035") (etchFactor "90.000000") (elecCondVal "595900.000000 mho/cm") (thermCondVal "0.012 w/cm-degC")) ("" (layerType "DIELECTRIC") (material "FR-4") (thickness "  4.600000 mil") (dielectricConstant "4.000000") (lossTangent "0.035") (etchFactor "0.000000") (elecCondVal "0 mho/cm") (thermCondVal "0.012 w/cm-degC")) ("L8_PWR2-SIG" (layerType "PLANE") (material "COPPER") (isShield t) (thickness "  2.400000 mil") (dielectricConstant "4.500000") (lossTangent "0.035") (etchFactor "90.000000") (elecCondVal "595900.000000 mho/cm") (thermCondVal "0.012 w/cm-degC")) ("" (layerType "DIELECTRIC") (material "FR-4") (thickness "  8.000000 mil") (dielectricConstant "4.500000") (lossTangent "0.035") (etchFactor "0.000000") (elecCondVal "0 mho/cm") (thermCondVal "0 w/cm-degC")) ("" (layerType "DIELECTRIC") (material "FR-4") (thickness "  8.000000 mil") (dielectricConstant "4.500000") (lossTangent "0.035") (etchFactor "0.000000") (elecCondVal "0 mho/cm") (thermCondVal "0 w/cm-degC")) ("" (layerType "DIELECTRIC") (material "FR-4") (thickness "  4.500000 mil") (dielectricConstant "4.500000") (lossTangent "0.035") (etchFactor "0.000000") (elecCondVal "0 mho/cm") (thermCondVal "0 w/cm-degC")) ("L9_GND4" (layerType "PLANE") (material "COPPER") (isShield t) (thickness "  1.250000 mil") (dielectricConstant "4.500000") (lossTangent "0.035") (etchFactor "90.000000") (elecCondVal "595900.000000 mho/cm") (thermCondVal "0 w/cm-degC")) ("" (layerType "DIELECTRIC") (material "FR-4") (thickness "  3.000000 mil") (dielectricConstant "4.100000") (lossTangent "0.035") (etchFactor "0.000000") (elecCondVal "0 mho/cm") (thermCondVal "0.012 w/cm-degC")) ("L10_SIG3" (layerType "CONDUCTOR") (material "COPPER") (thickness "  1.250000 mil") (width "4.00 MIL") (dielectricConstant "4.500000") (lossTangent "0.035") (etchFactor "90.000000") (elecCondVal "595900.000000 mho/cm") (thermCondVal "0.012 w/cm-degC") (signalDieConstant "4.100000") (signalLossTangent "0.035")) ("" (layerType "DIELECTRIC") (material "FR-4") (thickness "  9.000000 mil") (dielectricConstant "4.500000") (lossTangent "0.035") (etchFactor "0.000000") (elecCondVal "0 mho/cm") (thermCondVal "0 w/cm-degC")) ("L11_GND5" (layerType "PLANE") (material "COPPER") (isShield t) (thickness "  1.250000 mil") (dielectricConstant "4.500000") (lossTangent "0.035") (etchFactor "90.000000") (elecCondVal "595900.000000 mho/cm") (thermCondVal "0 w/cm-degC")) ("" (layerType "DIELECTRIC") (material "FR-4") (thickness "  3.000000 mil") (dielectricConstant "4.500000") (lossTangent "0.035") (etchFactor "0.000000") (elecCondVal "0 mho/cm") (thermCondVal "0.012 w/cm-degC")) ("L12_SIG4" (layerType "CONDUCTOR") (material "COPPER") (thickness "  1.250000 mil") (width "4.00 MIL") (dielectricConstant "4.500000") (lossTangent "0.035") (etchFactor "90.000000") (elecCondVal "595900.000000 mho/cm") (thermCondVal "0.012 w/cm-degC") (signalDieConstant "4.500000") (signalLossTangent "0.035")) ("" (layerType "DIELECTRIC") (material "FR-4") (thickness "  9.000000 mil") (dielectricConstant "4.500000") (lossTangent "0.035") (etchFactor "0.000000") (elecCondVal "0 mho/cm") (thermCondVal "0 w/cm-degC")) ("L13_GND6" (layerType "PLANE") (material "COPPER") (isShield t) (thickness "  1.250000 mil") (dielectricConstant "4.500000") (lossTangent "0.035") (etchFactor "90.000000") (elecCondVal "595900.000000 mho/cm") (thermCondVal "0.012 w/cm-degC")) ("" (layerType "DIELECTRIC") (material "FR-4") (thickness "  2.670000 mil") (dielectricConstant "4.500000") (lossTangent "0.035") (etchFactor "0.000000") (elecCondVal "0 mho/cm") (thermCondVal "0.012 w/cm-degC")) ("BOTTOM" (layerType "CONDUCTOR") (material "COPPER") (thickness "  2.100000 mil") (width "4.00 MIL") (dielectricConstant "4.500000") (lossTangent "0") (etchFactor "70.000000") (elecCondVal "595900.000000 mho/cm") (thermCondVal "0 w/cm-degC") (signalDieConstant "3.800000") (signalLossTangent "0.035")) ("" (layerType "DIELECTRIC") (material "CONFORMAL_COAT") (thickness "0.5 mil") (dielectricConstant "3.800000") (lossTangent "0.035") (etchFactor "0.000000") (elecCondVal "0 mho/cm") (thermCondVal "0.012 w/cm-degC")) ("" (layerType "SURFACE") (material "AIR") (thickness "0 mil") (dielectricConstant "1.000000") (lossTangent "0") (etchFactor "0.000000") (elecCondVal "0 mho/cm") (thermCondVal "0 w/cm-degC"))))) (Props (DesUnits "mils 2") (LayerStack ("DIELECTRIC" "DIELECTRIC" "BOTTOM" "DIELECTRIC" "L13_GND6" "DIELECTRIC" "L12_SIG4" "DIELECTRIC" "L11_GND5" "DIELECTRIC" "L10_SIG3" "DIELECTRIC" "L9_GND4" "DIELECTRIC" "DIELECTRIC" "DIELECTRIC" "L8_PWR2-SIG" "DIELECTRIC" "L7_PWR1-SIG" "DIELECTRIC" "L6_GND3" "DIELECTRIC" "L5_SIG2" "DIELECTRIC" "L4_GND2" "DIELECTRIC" "L3_SIG1" "DIELECTRIC" "L2_GND1" "DIELECTRIC" "TOP" "DIELECTRIC" "DIELECTRIC")) (Revision "16.600")) (Params (DiffOutputPkg ((temperature "27") (bufferModelNonInverting "CDSDefaultOutput_2p5v") (bufferModelInverting "CDSDefaultOutput_2p5v") (stimuli nil) (offsets nil) (state "tristate") (cycle "1") (termMap nil) (setup "0.9e-09") (hold "0.4e-09") (rise nil) (fall nil) (threshOutputHighMin "2.375  V") (threshOutputHighTyp "2.5  V") (threshOutputHighMax "2.625  V") (threshOutputLowMin "1.275  V") (threshOutputLowTyp "1.7  V") (threshOutputLowMax "1.985  V") (mappingTagNonInverting nil) (mappingTagInverting nil) (spice nil))) (HiClampTerm ((cutoffVoltage "0.7 V") (voltage "5 V") (maxDelay "0.1 ns"))) (LowClampTerm ((cutoffVoltage "0.7 V") (voltage "0 V") (maxDelay "0.1 ns"))) (DiffOutput ((temperature "27") (bufferModelNonInverting "CDSDefaultOutput_2p5v") (bufferModelInverting "CDSDefaultOutput_2p5v") (stimuli nil) (offsets nil) (state "tristate") (cycle "1") (termMap nil) (setup "0.9e-09") (hold "0.4e-09") (rise nil) (fall nil) (threshOutputHighMin "2.375  V") (threshOutputHighTyp "2.5  V") (threshOutputHighMax "2.625  V") (threshOutputLowMin "1.275  V") (threshOutputLowTyp "1.7  V") (threshOutputLowMax "1.985  V") (mappingTagNonInverting nil) (mappingTagInverting nil) (spice nil))) (Via ((model "Unknown") (viaOutputFormat "Unknown") (viaPadstack nil) (viaTopLayer nil) (viaBottomLayer nil) (viaIsPower nil) (viaIsGround nil))) (Resistor ((resistance "50 ohm") (orientation "0"))) (RCTerm ((resistance "50 ohm") (capacitance "20 pF") (voltage "5 V") (maxDelay "0.1 ns"))) (DiffIOPkg ((temperature "27") (bufferModelNonInverting "CDSDefaultIO_2p5v") (bufferModelInverting "CDSDefaultIO_2p5v") (stimuli nil) (offsets nil) (state "tristate") (cycle "1") (termMap nil) (setup "0.9e-09") (hold "0.4e-09") (rise nil) (fall nil) (threshInputHighMin "1.7 V") (threshInputHighTyp "1.7  V") (threshInputHighMax "1.7  V") (threshInputLowMin "0.7  V") (threshInputLowTyp "0.7  V") (threshInputLowMax "0.7 ") (threshOutputHighMin "2.365  V") (threshOutputHighTyp "2.5  V") (threshOutputHighMax "2.625  V") (threshOutputLowMin "1.275  V") (threshOutputLowTyp "1.7  V") (threshOutputLowMax "1.985  V") (mappingTagNonInverting nil) (mappingTagInverting nil) (spice nil))) (Trace ((d1Thickness "10 mil") (d1Constant "4.5") (d1LossTangent "0.035") (d2Thickness "10 mil") (d2Constant "4.5") (d2LossTangent "0.035") (d3Thickness "0.0") (d3Constant "1.0") (d3LossTangent "0") length("1000 mil") (spacing "5 mil") (spacing2 "5 mil") (spacing3 "5 mil") (spacing4 "5 mil") (spacing5 "5 mil") (traceConductivity "595900 mho/cm") (traceGeometry "microstrip") (traceLayerName "") (traceThickness "0.72 mil") (traceType "single") (traceWidth "5.0 mil") (traceWidth2 "5.0 mil") (traceWidth3 "5.0 mil") (traceWidth4 "5.0 mil") (traceWidth5 "5.0 mil") (traceWidth6 "5.0 mil") (offset "0 mil") (traceCount "1") (impedance nil))) (TheveninTerm ((resistanceUp "180 ohm") (resistanceDown "270 ohm") (voltageUp "5 V") (voltageDown "0 V") (maxDelay "0.1 ns"))) (DiffIO ((temperature "27") (bufferModelNonInverting "CDSDefaultIO_2p5v") (bufferModelInverting "CDSDefaultIO_2p5v") (stimuli nil) (offsets nil) (state "tristate") (cycle "1") (termMap nil) (setup "0.9e-09") (hold "0.4e-09") (rise nil) (fall nil) (threshInputHighMin "1.7 V") (threshInputHighTyp "1.7  V") (threshInputHighMax "1.7  V") (threshInputLowMin "0.7  V") (threshInputLowTyp "0.7  V") (threshInputLowMax "0.7 ") (threshOutputHighMin "2.365  V") (threshOutputHighTyp "2.5  V") (threshOutputHighMax "2.625  V") (threshOutputLowMin "1.275  V") (threshOutputLowTyp "1.7  V") (threshOutputLowMax "1.985  V") (mappingTagNonInverting nil) (mappingTagInverting nil) (spice nil))) (ShuntTerm ((resistance "50 ohm") (voltage "5 V") (maxDelay "0.1 ns"))) (Inductor ((inductance "5 nH") (orientation "0"))) (Capacitor ((capacitance "10 pF") (orientation "0"))) (RLGC (length("1000 mil"))) (Source ((voltage "5 V"))) (DiffInput ((temperature "27") (bufferModelNonInverting "CDSDefaultInput_2p5v") (bufferModelInverting "CDSDefaultInput_2p5v") (threshInputHighMin "1.7 V") (threshInputHighTyp "1.7  V") (threshInputHighMax "1.7  V") (threshInputLowMin "0.7  V") (threshInputLowTyp "0.7  V") (threshInputLowMax "0.7  V") (mappingTagNonInverting nil) (mappingTagInverting nil) (cycle "1"))) (Cable (length("1 m"))) (CPWSL ((d1Thickness "10 mil") (d1Constant "4.5") (d1LossTangent "0.035") (d2Thickness "0.72 mil") (d2Constant "4.5") (d2LossTangent "0.035") (d3Thickness "10 mil") (d3Constant "4.5") (d3LossTangent "0.035") length("1000 mil") (spacing "5 mil") (spacing2 "5 mil") (spacing3 "5 mil") (spacing4 "5 mil") (spacing5 "5 mil") (traceConductivity "595900 mho/cm") (traceGeometry "cpwms") (traceLayerName "") (traceThickness "0.72 mil") (traceType "single") (traceWidth "5.0 mil") (traceWidth2 "5.0 mil") (traceWidth3 "5.0 mil") (traceWidth4 "5.0 mil") (traceWidth5 "5.0 mil") (traceWidth6 "5.0 mil") (offset "0 mil") (traceCount "1") (impedance nil))) (ESpiceDevice nil) (CPWMS ((d1Thickness "10 mil") (d1Constant "4.5") (d1LossTangent "0.035") (d2Thickness "0.72 mil") (d2Constant "4.5") (d2LossTangent "0.035") (d3Thickness "0.0") (d3Constant "1") (d3LossTangent "0") length("1000 mil") (spacing "5 mil") (spacing2 "5 mil") (spacing3 "5 mil") (spacing4 "5 mil") (spacing5 "5 mil") (traceConductivity "595900 mho/cm") (traceGeometry "cpwms") (traceLayerName "") (traceThickness "0.72 mil") (traceType "single") (traceWidth "5.0 mil") (traceWidth2 "5.0 mil") (traceWidth3 "5.0 mil") (traceWidth4 "5.0 mil") (traceWidth5 "5.0 mil") (traceWidth6 "5.0 mil") (offset "0 mil") (traceCount "1") (impedance nil))) (Diode ((cutoffVoltage "0.7 V"))) (CPW ((d1Thickness "10 mil") (d1Constant "4.5") (d1LossTangent "0.035") (d2Thickness "0.72 mil") (d2Constant "1") (d2LossTangent "0") (d3Thickness "0.0") (d3Constant "1") (d3LossTangent "0") length("1000 mil") (spacing "5 mil") (spacing2 "5 mil") (spacing3 "5 mil") (spacing4 "5 mil") (spacing5 "5 mil") (traceConductivity "595900 mho/cm") (traceGeometry "cpwms") (traceLayerName "") (traceThickness "0.72 mil") (traceType "single") (traceWidth "5.0 mil") (traceWidth2 "5.0 mil") (traceWidth3 "5.0 mil") (traceWidth4 "5.0 mil") (traceWidth5 "5.0 mil") (traceWidth6 "5.0 mil") (offset "0 mil") (traceCount "1") (impedance nil))) (DualClampTerm ((cutoffVoltageUp "0.7 V") (cutoffVoltageDown "0.7 V") (voltageUp "5 V") (voltageDown "0 V") (maxDelay "0.1 ns"))) (IbisOutputPkg ((temperature "27") (bufferModel "CDSDefaultOutput_2p5v") (stimuli nil) (offsets nil) (state "tristate") (cycle "1") (termMap nil) (setup "2.0e-09") (hold "1.0e-09") (rise nil) (fall nil) (macroType nil) (voltage nil) (spice nil) (LEFDEFPinName nil) (LEFDEFPinType nil) (mappingTag nil))) (IbisIO_OpenPullDown ((temperature "27") (bufferModel "CDSDefaultIO_2p5v") (stimuli nil) (offsets nil) (state "tristate") (cycle "1") (termMap nil) (setup "2.0e-09") (hold "1.0e-09") (rise nil) (fall nil) (macroType nil) (voltage nil) (spice nil) (LEFDEFPinName nil) (LEFDEFPinType nil) (mappingTag nil))) (IbisInputPkg ((temperature "27") (bufferModel "CDSDefaultInput_2p5v") (cycle "1") (LEFDEFPinName nil) (LEFDEFPinType nil) (mappingTag nil))) (IbisIOMacro ((temperature "27") (bufferModel "CDSDefaultIO_2p5v") (stimuli nil) (offsets nil) (state "tristate") (cycle "1") (termMap nil) (setup "2.0e-09") (hold "1.0e-09") (rise nil) (fall nil) (macroType nil) (voltage nil) (spice nil) (LEFDEFPinName nil) (LEFDEFPinType nil) (mappingTag nil))) (IbisIO_OpenPullUp ((temperature "27") (bufferModel "CDSDefaultIO_2p5v") (stimuli nil) (offsets nil) (state "tristate") (cycle "1") (termMap nil) (setup "2.0e-09") (hold "1.0e-09") (rise nil) (fall nil) (macroType nil) (voltage nil) (spice nil) (LEFDEFPinName nil) (LEFDEFPinType nil) (mappingTag nil))) (IbisIOPkg ((temperature "27") (bufferModel "CDSDefaultIO_2p5v") (stimuli nil) (offsets nil) (state "tristate") (cycle "1") (termMap nil) (setup "2.0e-09") (hold "1.0e-09") (rise nil) (fall nil) (macroType nil) (voltage nil) (spice nil) (LEFDEFPinName nil) (LEFDEFPinType nil) (mappingTag nil))) (clocked ((clockRise "1e-09") (clockFall "1e-09") (clockFreq "100e6") (clockInitState "0") (clockDutyCycle "0.5") (clockJitter "0"))) (periodic ((periodicFreq "100e6") (periodicPattern "10") (periodicJitter "0"))) (IbisIO ((temperature "27") (bufferModel "CDSDefaultIO_2p5v") (stimuli nil) (offsets nil) (state "tristate") (cycle "1") (termMap nil) (setup "2.0e-09") (hold "1.0e-09") (rise nil) (fall nil) (macroType nil) (voltage nil) (spice nil) (LEFDEFPinName nil) (LEFDEFPinType nil) (mappingTag nil))) (async ((asyncTimePoints "") (asyncInitState "1"))) (IbisOutput ((temperature "27") (bufferModel "CDSDefaultOutput_2p5v") (stimuli nil) (offsets nil) (state "tristate") (cycle "1") (termMap nil) (setup "2.0e-09") (hold "1.0e-09") (rise nil) (fall nil) (macroType nil) (voltage nil) (spice nil) (LEFDEFPinName nil) (LEFDEFPinType nil) (mappingTag nil))) (TLine ((diffImpedance "100ohm") (diffVelocity "1.4142e+08M/s") (impedance "60ohm") length("2800 mil") (propDelay "0.5 ns") (velocity "5600 mil/ns") (traceCount "1") (traceGeometry "Microstrip") (impedanceMin nil) (impedanceMax nil) (lengthMin nil) (lengthMax nil) (propDelayMin nil) (propDelayMax nil) (impedanceSweepCount nil) (propDelaySweepCount nil) (velocitySweepCount nil) (lengthSweepCount nil) (matchSetName nil))) (CurrentProbe nil) (IbisInput ((temperature "27") (bufferModel "CDSDefaultInput_2p5v") (cycle "1") (LEFDEFPinName nil) (LEFDEFPinType nil) (mappingTag nil))) (SeriesTerm ((resistance "22 ohm") (maxDelay "0.1 ns"))) (Connector nil) (sync ((syncFreq "100e6") (syncInitState "1") (syncPattern "10") (syncEdgeSwitch "rise"))) (IbisOutput_OpenPullUp ((temperature "27") (bufferModel "CDSDefaultOutput_2p5v") (stimuli nil) (offsets nil) (state "tristate") (cycle "1") (termMap nil) (setup "2.0e-09") (hold "1.0e-09") (rise nil) (fall nil) (macroType nil) (voltage nil) (spice nil) (LEFDEFPinName nil) (LEFDEFPinType nil) (mappingTag nil))) (DiffInputPkg ((temperature "27") (bufferModelNonInverting "CDSDefaultInput_2p5v") (bufferModelInverting "CDSDefaultInput_2p5v") (threshInputHighMin "1.7 V") (threshInputHighTyp "1.7  V") (threshInputHighMax "1.7  V") (threshInputLowMin "0.7  V") (threshInputLowTyp "0.7  V") (threshInputLowMax "0.7  V") (mappingTagNonInverting nil) (mappingTagInverting nil) (cycle "1"))) (idlCircuit ((allDrivers "active") (ftsMode '("Typ")) (rcvrSelect "all") (simMode "Reflection") (tlineDelayMode "time") (userRevision "1.0") (autoSolve "On")))))
				)
				( objectStatus "SVID_ALERT0_CPU0_N" )
			)
			( electricalCSet "@crescent_city_bb_fab1_lib.crescent_city_bb_fab1(sch_1):\SPI_NIC_SCLK\"
				( groupRef "SPI_NIC_SCLK:SPI_NIC" )
				( pinPairRef "SPI_NIC_SCLK:U9E1.6:EU9E1.13" )
				( attribute "TOPOLOGY_TEMPLATE_REVISION" "1.0"
					( Origin gBackEnd )
				)
				( topologyData 24648
(SKIDL (Circuits ("MAIN" (Parts ("CRESCENT_CITY_902_20150507_Q.@@EU9E1.13" IbisOutputPkg (xy (5498 4235)) (refDes "EU9E1") (model "Unknown") (Props (_SXDesignName "CRESCENT_CITY_902_20150507_Q") (brdx "19352 MIL") (brdy "1853.58 MIL") (bufferModel "CDSDefaultOutput_2p5v") (cycle "1") (hold "1.0e-09") (mappingTag "") (offsets ("4" "0")) (setup "2.0e-09") (state "tristate") (stimuli ("4" "local102")) (temperature "27") (termMap ("4" "Data"))) (Terms ("CRESCENT_CITY_902_20150507_Q.X1935200Y185358L2LRATS" "13"))) ("CRESCENT_CITY_902_20150507_Q.@@U9E1.6" IbisInputPkg (xy (5544 4235)) (refDes "U9E1") (model "Unknown") (Props (_SXDesignName "CRESCENT_CITY_902_20150507_Q") (brdx "19578.9 MIL") (brdy "1746 MIL") (bufferModel "CDSDefaultInput_2p5v") (mappingTag "") (temperature "27")) (Terms ("CRESCENT_CITY_902_20150507_Q.X1957890Y174600L2LRATS" "6"))) ("CRESCENT_CITY_902_20150507_Q.T@@RATS@@R9E8.1@@EU9E1.13" TLine (xy (5506 4235)) (mirror x) (refDes "TL85") (Props (_SXDesignName "CRESCENT_CITY_902_20150507_Q") (impedance "48.412 ohm") length("109.81 MIL") (propDelay "0.01972 ns") (traceCount "1") (traceGeometry "Microstrip") (velocity "5568.46 mil/ns")) (Terms ("CRESCENT_CITY_902_20150507_Q.X1943539Y188000L2LRATS" "1") ("CRESCENT_CITY_902_20150507_Q.X1935200Y185358L2LRATS" "2"))) ("CRESCENT_CITY_902_20150507_Q.T@@RATS@@U9E1.6@@R9E8.2" TLine (xy (5530 4235)) (mirror x) (refDes "TL86") (Props (_SXDesignName "CRESCENT_CITY_902_20150507_Q") (impedance "48.412 ohm") length("242.51 MIL") (propDelay "0.04356 ns") (traceCount "1") (traceGeometry "Microstrip") (velocity "5567.24 mil/ns")) (Terms ("CRESCENT_CITY_902_20150507_Q.X1957890Y174600L2LRATS" "1") ("CRESCENT_CITY_902_20150507_Q.X1947039Y188000L2LRATS" "2"))) ("CRESCENT_CITY_902_20150507_Q.@@R9E8.1.2" Resistor (xy (5521 4235)) (refDes "R9E8") (value "33.2 Ohm") (Props (_SXDesignName "CRESCENT_CITY_902_20150507_Q")) (Terms ("CRESCENT_CITY_902_20150507_Q.X1943539Y188000L2LRATS" "1") ("CRESCENT_CITY_902_20150507_Q.X1947039Y188000L2LRATS" "2")))) (Nodes ("CRESCENT_CITY_902_20150507_Q.X1957890Y174600L2LRATS" (terms "CRESCENT_CITY_902_20150507_Q.T@@RATS@@U9E1.6@@R9E8.2.1" "CRESCENT_CITY_902_20150507_Q.@@U9E1.6.1")) ("CRESCENT_CITY_902_20150507_Q.X1947039Y188000L2LRATS" (terms "CRESCENT_CITY_902_20150507_Q.@@R9E8.1.2.2" "CRESCENT_CITY_902_20150507_Q.T@@RATS@@U9E1.6@@R9E8.2.2")) ("CRESCENT_CITY_902_20150507_Q.X1943539Y188000L2LRATS" (terms "CRESCENT_CITY_902_20150507_Q.@@R9E8.1.2.1" "CRESCENT_CITY_902_20150507_Q.T@@RATS@@R9E8.1@@EU9E1.13.1")) ("CRESCENT_CITY_902_20150507_Q.X1935200Y185358L2LRATS" (terms "CRESCENT_CITY_902_20150507_Q.T@@RATS@@R9E8.1@@EU9E1.13.2" "CRESCENT_CITY_902_20150507_Q.@@EU9E1.13.1"))) (Ports) (Stimuli ("local102" (scope local) (stimType periodic) (Props (periodicFreq "5e+007") (periodicJitter "0") (periodicPattern "1")))) (Notes) (Constraints ("RELATIVE_PROPAGATION_DELAY" ("SPI-NIC" "CRESCENT_CITY_902_20150507_Q U9E1.6" "CRESCENT_CITY_902_20150507_Q EU9E1.13" "GLOBAL" "LENGTH" "0.00635" "LENGTH" "0"))) (MeasurementSets ("EMI" ("EMIStatus" status("on")) ("PeakEmission" status("on")) ("PeakFrequency" status("on")) ("PulseFreq" status("on")) ("RiseTime" status("on")) ("VoltageSwing" status("on"))) ("Reflection" ("BufferDelayFall" status("off")) ("BufferDelayRise" status("off")) ("EyeHeight" status("off")) ("EyeJitter" status("off")) ("EyeWidth" status("off")) ("FirstIncidentFall" status("off")) ("FirstIncidentRise" status("off")) ("Glitch" status("on")) ("GlitchFall" status("off")) ("GlitchRise" status("off")) ("Monotonic" status("on")) ("MonotonicFall" status("off")) ("MonotonicRise" status("off")) ("NoiseMargin" status("on")) ("NoiseMarginHigh" status("off")) ("NoiseMarginLow" status("off")) ("OvershootHigh" status("on")) ("OvershootLow" status("on")) ("PropDelay" status("on")) ("SettleDelay" status("on")) ("SettleDelayFall" status("off")) ("SettleDelayRise" status("off")) ("SwitchDelay" status("on")) ("SwitchDelayFall" status("off")) ("SwitchDelayRise" status("off"))) ("Crosstalk" ("Crosstalk" status("on"))) ("Custom")) (VectorSets) (Props (XnetName "SPI_NIC_SCLK") (allDrivers "active") (customSimType "Reflection") (ftsMode ("Typ")) (rcvrSelect "all") (tlineDelayMode "time") (userRevision "1.0")))) (Subckts) (CrossSections ("CRESCENT_CITY_902_20150507_Q" (Props (SXDesignName "CRESCENT_CITY_902_20150507_Q")) (Layers ("" (layerType "SURFACE") (material "AIR") (thickness "0 mil") (dielectricConstant "1.000000") (lossTangent "0") (etchFactor "0.000000") (elecCondVal "0 mho/cm") (thermCondVal "0 w/cm-degC")) ("" (layerType "DIELECTRIC") (material "CONFORMAL_COAT") (thickness "0.5 mil") (dielectricConstant "3.800000") (lossTangent "0.035") (etchFactor "0.000000") (elecCondVal "0 mho/cm") (thermCondVal "0.012 w/cm-degC")) ("TOP" (layerType "CONDUCTOR") (material "COPPER") (thickness "  2.100000 mil") (width "4.00 MIL") (dielectricConstant "4.500000") (lossTangent "0") (etchFactor "70.000000") (elecCondVal "595900.000000 mho/cm") (thermCondVal "0 w/cm-degC") (signalDieConstant "3.800000") (signalLossTangent "0.035")) ("" (layerType "DIELECTRIC") (material "FR-4") (thickness "  2.670000 mil") (dielectricConstant "4.000000") (lossTangent "0.035") (etchFactor "0.000000") (elecCondVal "0 mho/cm") (thermCondVal "0.012 w/cm-degC")) ("L2_GND1" (layerType "PLANE") (material "COPPER") (isShield t) (thickness "  1.250000 mil") (dielectricConstant "4.500000") (lossTangent "0.035") (etchFactor "90.000000") (elecCondVal "595900.000000 mho/cm") (thermCondVal "0.012 w/cm-degC")) ("" (layerType "DIELECTRIC") (material "FR-4") (thickness "  9.000000 mil") (dielectricConstant "4.100000") (lossTangent "0.035") (etchFactor "0.000000") (elecCondVal "0 mho/cm") (thermCondVal "0.012 w/cm-degC")) ("L3_SIG1" (layerType "CONDUCTOR") (material "COPPER") (thickness "  1.250000 mil") (width "4.00 MIL") (dielectricConstant "4.500000") (lossTangent "0.035") (etchFactor "90.000000") (elecCondVal "595900.000000 mho/cm") (thermCondVal "0.012 w/cm-degC") (signalDieConstant "4.100000") (signalLossTangent "0.035")) ("" (layerType "DIELECTRIC") (material "FR-4") (thickness "  3.000000 mil") (dielectricConstant "4.500000") (lossTangent "0.035") (etchFactor "0.000000") (elecCondVal "0 mho/cm") (thermCondVal "0 w/cm-degC")) ("L4_GND2" (layerType "PLANE") (material "COPPER") (isShield t) (thickness "  1.250000 mil") (dielectricConstant "4.500000") (lossTangent "0.035") (etchFactor "90.000000") (elecCondVal "595900.000000 mho/cm") (thermCondVal "0 w/cm-degC")) ("" (layerType "DIELECTRIC") (material "FR-4") (thickness "  9.000000 mil") (dielectricConstant "4.000000") (lossTangent "0.035") (etchFactor "0.000000") (elecCondVal "0 mho/cm") (thermCondVal "0.012 w/cm-degC")) ("L5_SIG2" (layerType "CONDUCTOR") (material "COPPER") (thickness "  1.250000 mil") (width "4.00 MIL") (dielectricConstant "4.500000") (lossTangent "0.035") (etchFactor "90.000000") (elecCondVal "595900.000000 mho/cm") (thermCondVal "0.012 w/cm-degC") (signalDieConstant "4.000000") (signalLossTangent "0.035")) ("" (layerType "DIELECTRIC") (material "FR-4") (thickness "  3.000000 mil") (dielectricConstant "4.500000") (lossTangent "0.035") (etchFactor "0.000000") (elecCondVal "0 mho/cm") (thermCondVal "0 w/cm-degC")) ("L6_GND3" (layerType "PLANE") (material "COPPER") (isShield t) (thickness "  1.250000 mil") (dielectricConstant "4.500000") (lossTangent "0.035") (etchFactor "90.000000") (elecCondVal "595900.000000 mho/cm") (thermCondVal "0 w/cm-degC")) ("" (layerType "DIELECTRIC") (material "FR-4") (thickness "  4.500000 mil") (dielectricConstant "4.100000") (lossTangent "0.035") (etchFactor "0.000000") (elecCondVal "0 mho/cm") (thermCondVal "0.012 w/cm-degC")) ("L7_PWR1-SIG" (layerType "PLANE") (material "COPPER") (isShield t) (thickness "  2.610000 mil") (dielectricConstant "4.500000") (lossTangent "0.035") (etchFactor "90.000000") (elecCondVal "595900.000000 mho/cm") (thermCondVal "0.012 w/cm-degC")) ("" (layerType "DIELECTRIC") (material "FR-4") (thickness "  3.100000 mil") (dielectricConstant "4.500000") (lossTangent "0.035") (etchFactor "0.000000") (elecCondVal "0 mho/cm") (thermCondVal "0 w/cm-degC")) ("L8_GND_TEMP" (layerType "PLANE") (material "COPPER") (isShield t) (thickness "  1.250000 mil") (dielectricConstant "4.500000") (lossTangent "0.035") (etchFactor "90.000000") (elecCondVal "595900.000000 mho/cm") (thermCondVal "0 w/cm-degC")) ("" (layerType "DIELECTRIC") (material "FR-4") (thickness "  3.030000 mil") (dielectricConstant "4.500000") (lossTangent "0.035") (etchFactor "0.000000") (elecCondVal "0 mho/cm") (thermCondVal "0 w/cm-degC")) ("L9_SIG_TEMP" (layerType "CONDUCTOR") (material "COPPER") (thickness "  1.250000 mil") (width "3.52 MIL") (dielectricConstant "4.500000") (lossTangent "0.035") (etchFactor "90.000000") (elecCondVal "595900.000000 mho/cm") (thermCondVal "0 w/cm-degC") (signalDieConstant "4.500000") (signalLossTangent "0.035")) ("" (layerType "DIELECTRIC") (material "FR-4") (thickness "  5.000000 mil") (dielectricConstant "4.500000") (lossTangent "0.035") (etchFactor "0.000000") (elecCondVal "0 mho/cm") (thermCondVal "0 w/cm-degC")) ("L10_SIG_TEMP" (layerType "CONDUCTOR") (material "COPPER") (thickness "  1.250000 mil") (width "3.52 MIL") (dielectricConstant "4.500000") (lossTangent "0.035") (etchFactor "90.000000") (elecCondVal "595900.000000 mho/cm") (thermCondVal "0 w/cm-degC") (signalDieConstant "4.500000") (signalLossTangent "0.035")) ("" (layerType "DIELECTRIC") (material "FR-4") (thickness "  3.030000 mil") (dielectricConstant "4.500000") (lossTangent "0.035") (etchFactor "0.000000") (elecCondVal "0 mho/cm") (thermCondVal "0 w/cm-degC")) ("L11_GND_TEMP" (layerType "PLANE") (material "COPPER") (isShield t) (thickness "  1.250000 mil") (dielectricConstant "4.500000") (lossTangent "0.035") (etchFactor "90.000000") (elecCondVal "595900.000000 mho/cm") (thermCondVal "0 w/cm-degC")) ("" (layerType "DIELECTRIC") (material "FR-4") (thickness "  3.100000 mil") (dielectricConstant "4.000000") (lossTangent "0.035") (etchFactor "0.000000") (elecCondVal "0 mho/cm") (thermCondVal "0.012 w/cm-degC")) ("L12_PWR2-SIG" (layerType "PLANE") (material "COPPER") (isShield t) (thickness "  2.610000 mil") (dielectricConstant "4.500000") (lossTangent "0.035") (etchFactor "90.000000") (elecCondVal "595900.000000 mho/cm") (thermCondVal "0.012 w/cm-degC")) ("" (layerType "DIELECTRIC") (material "FR-4") (thickness "  4.500000 mil") (dielectricConstant "4.500000") (lossTangent "0.035") (etchFactor "0.000000") (elecCondVal "0 mho/cm") (thermCondVal "0 w/cm-degC")) ("L13_GND4" (layerType "PLANE") (material "COPPER") (isShield t) (thickness "  1.250000 mil") (dielectricConstant "4.500000") (lossTangent "0.035") (etchFactor "90.000000") (elecCondVal "595900.000000 mho/cm") (thermCondVal "0 w/cm-degC")) ("" (layerType "DIELECTRIC") (material "FR-4") (thickness "  3.000000 mil") (dielectricConstant "4.100000") (lossTangent "0.035") (etchFactor "0.000000") (elecCondVal "0 mho/cm") (thermCondVal "0.012 w/cm-degC")) ("L14_SIG3" (layerType "CONDUCTOR") (material "COPPER") (thickness "  1.250000 mil") (width "4.00 MIL") (dielectricConstant "4.500000") (lossTangent "0.035") (etchFactor "90.000000") (elecCondVal "595900.000000 mho/cm") (thermCondVal "0.012 w/cm-degC") (signalDieConstant "4.100000") (signalLossTangent "0.035")) ("" (layerType "DIELECTRIC") (material "FR-4") (thickness "  9.000000 mil") (dielectricConstant "4.500000") (lossTangent "0.035") (etchFactor "0.000000") (elecCondVal "0 mho/cm") (thermCondVal "0 w/cm-degC")) ("L15_GND5" (layerType "PLANE") (material "COPPER") (isShield t) (thickness "  1.250000 mil") (dielectricConstant "4.500000") (lossTangent "0.035") (etchFactor "90.000000") (elecCondVal "595900.000000 mho/cm") (thermCondVal "0 w/cm-degC")) ("" (layerType "DIELECTRIC") (material "FR-4") (thickness "  3.000000 mil") (dielectricConstant "4.500000") (lossTangent "0.035") (etchFactor "0.000000") (elecCondVal "0 mho/cm") (thermCondVal "0.012 w/cm-degC")) ("L16_SIG4" (layerType "CONDUCTOR") (material "COPPER") (thickness "  1.250000 mil") (width "4.00 MIL") (dielectricConstant "4.500000") (lossTangent "0.035") (etchFactor "90.000000") (elecCondVal "595900.000000 mho/cm") (thermCondVal "0.012 w/cm-degC") (signalDieConstant "4.500000") (signalLossTangent "0.035")) ("" (layerType "DIELECTRIC") (material "FR-4") (thickness "  9.000000 mil") (dielectricConstant "4.500000") (lossTangent "0.035") (etchFactor "0.000000") (elecCondVal "0 mho/cm") (thermCondVal "0 w/cm-degC")) ("L17_GND6" (layerType "PLANE") (material "COPPER") (isShield t) (thickness "  1.250000 mil") (dielectricConstant "4.500000") (lossTangent "0.035") (etchFactor "90.000000") (elecCondVal "595900.000000 mho/cm") (thermCondVal "0.012 w/cm-degC")) ("" (layerType "DIELECTRIC") (material "FR-4") (thickness "  2.670000 mil") (dielectricConstant "4.500000") (lossTangent "0.035") (etchFactor "0.000000") (elecCondVal "0 mho/cm") (thermCondVal "0.012 w/cm-degC")) ("BOTTOM" (layerType "CONDUCTOR") (material "COPPER") (thickness "  2.100000 mil") (width "4.00 MIL") (dielectricConstant "4.500000") (lossTangent "0") (etchFactor "70.000000") (elecCondVal "595900.000000 mho/cm") (thermCondVal "0 w/cm-degC") (signalDieConstant "3.800000") (signalLossTangent "0.035")) ("" (layerType "DIELECTRIC") (material "CONFORMAL_COAT") (thickness "0.5 mil") (dielectricConstant "3.800000") (lossTangent "0.035") (etchFactor "0.000000") (elecCondVal "0 mho/cm") (thermCondVal "0.012 w/cm-degC")) ("" (layerType "SURFACE") (material "AIR") (thickness "0 mil") (dielectricConstant "1.000000") (lossTangent "0") (etchFactor "0.000000") (elecCondVal "0 mho/cm") (thermCondVal "0 w/cm-degC"))))) (Props (DesUnits "mils 2") (LayerStack ("DIELECTRIC" "DIELECTRIC" "BOTTOM" "DIELECTRIC" "L17_GND6" "DIELECTRIC" "L16_SIG4" "DIELECTRIC" "L15_GND5" "DIELECTRIC" "L14_SIG3" "DIELECTRIC" "L13_GND4" "DIELECTRIC" "L12_PWR2-SIG" "DIELECTRIC" "L11_GND_TEMP" "DIELECTRIC" "L10_SIG_TEMP" "DIELECTRIC" "L9_SIG_TEMP" "DIELECTRIC" "L8_GND_TEMP" "DIELECTRIC" "L7_PWR1-SIG" "DIELECTRIC" "L6_GND3" "DIELECTRIC" "L5_SIG2" "DIELECTRIC" "L4_GND2" "DIELECTRIC" "L3_SIG1" "DIELECTRIC" "L2_GND1" "DIELECTRIC" "TOP" "DIELECTRIC" "DIELECTRIC")) (Revision "16.600")) (Params (DiffInputPkg ((temperature "27") (bufferModelNonInverting "CDSDefaultInput_2p5v") (bufferModelInverting "CDSDefaultInput_2p5v") (threshInputHighMin "1.7 V") (threshInputHighTyp "1.7  V") (threshInputHighMax "1.7  V") (threshInputLowMin "0.7  V") (threshInputLowTyp "0.7  V") (threshInputLowMax "0.7  V") (mappingTagNonInverting nil) (mappingTagInverting nil) (cycle "1"))) (IbisOutputPkg ((temperature "27") (bufferModel "CDSDefaultOutput_2p5v") (stimuli nil) (offsets nil) (state "tristate") (cycle "1") (termMap nil) (setup "2.0e-09") (hold "1.0e-09") (rise nil) (fall nil) (macroType nil) (voltage nil) (spice nil) (LEFDEFPinName nil) (LEFDEFPinType nil) (mappingTag nil))) (IbisIOPkg ((temperature "27") (bufferModel "CDSDefaultIO_2p5v") (stimuli nil) (offsets nil) (state "tristate") (cycle "1") (termMap nil) (setup "2.0e-09") (hold "1.0e-09") (rise nil) (fall nil) (macroType nil) (voltage nil) (spice nil) (LEFDEFPinName nil) (LEFDEFPinType nil) (mappingTag nil))) (IbisIOMacro ((temperature "27") (bufferModel "CDSDefaultIO_2p5v") (stimuli nil) (offsets nil) (state "tristate") (cycle "1") (termMap nil) (setup "2.0e-09") (hold "1.0e-09") (rise nil) (fall nil) (macroType nil) (voltage nil) (spice nil) (LEFDEFPinName nil) (LEFDEFPinType nil) (mappingTag nil))) (ESpiceDevice nil) (IbisInput ((temperature "27") (bufferModel "CDSDefaultInput_2p5v") (cycle "1") (LEFDEFPinName nil) (LEFDEFPinType nil) (mappingTag nil))) (ShuntTerm ((resistance "50 ohm") (voltage "5 V") (maxDelay "0.1 ns"))) (SeriesTerm ((resistance "22 ohm") (maxDelay "0.1 ns"))) (CurrentProbe nil) (idlCircuit ((allDrivers "active") (ftsMode '("Typ")) (rcvrSelect "all") (simMode "Reflection") (tlineDelayMode "time") (userRevision "1.0") (autoSolve "On"))) (TheveninTerm ((resistanceUp "180 ohm") (resistanceDown "270 ohm") (voltageUp "5 V") (voltageDown "0 V") (maxDelay "0.1 ns"))) (RCTerm ((resistance "50 ohm") (capacitance "20 pF") (voltage "5 V") (maxDelay "0.1 ns"))) (LowClampTerm ((cutoffVoltage "0.7 V") (voltage "0 V") (maxDelay "0.1 ns"))) (Cable (length("1 m"))) (HiClampTerm ((cutoffVoltage "0.7 V") (voltage "5 V") (maxDelay "0.1 ns"))) (DualClampTerm ((cutoffVoltageUp "0.7 V") (cutoffVoltageDown "0.7 V") (voltageUp "5 V") (voltageDown "0 V") (maxDelay "0.1 ns"))) (IbisInputPkg ((temperature "27") (bufferModel "CDSDefaultInput_2p5v") (cycle "1") (LEFDEFPinName nil) (LEFDEFPinType nil) (mappingTag nil))) (async ((asyncTimePoints "") (asyncInitState "1"))) (clocked ((clockRise "1e-09") (clockFall "1e-09") (clockFreq "100e6") (clockInitState "0") (clockDutyCycle "0.5") (clockJitter "0"))) (Diode ((cutoffVoltage "0.7 V"))) (IbisOutput ((temperature "27") (bufferModel "CDSDefaultOutput_2p5v") (stimuli nil) (offsets nil) (state "tristate") (cycle "1") (termMap nil) (setup "2.0e-09") (hold "1.0e-09") (rise nil) (fall nil) (macroType nil) (voltage nil) (spice nil) (LEFDEFPinName nil) (LEFDEFPinType nil) (mappingTag nil))) (periodic ((periodicFreq "100e6") (periodicPattern "10") (periodicJitter "0"))) (IbisIO ((temperature "27") (bufferModel "CDSDefaultIO_2p5v") (stimuli nil) (offsets nil) (state "tristate") (cycle "1") (termMap nil) (setup "2.0e-09") (hold "1.0e-09") (rise nil) (fall nil) (macroType nil) (voltage nil) (spice nil) (LEFDEFPinName nil) (LEFDEFPinType nil) (mappingTag nil))) (Via ((model "Unknown") (viaOutputFormat "Unknown") (viaPadstack nil) (viaTopLayer nil) (viaBottomLayer nil) (viaIsPower nil) (viaIsGround nil))) (CPWMS ((d1Thickness "10 mil") (d1Constant "4.5") (d1LossTangent "0.035") (d2Thickness "0.72 mil") (d2Constant "4.5") (d2LossTangent "0.035") (d3Thickness "0.0") (d3Constant "1") (d3LossTangent "0") length("1000 mil") (spacing "5 mil") (spacing2 "5 mil") (spacing3 "5 mil") (spacing4 "5 mil") (spacing5 "5 mil") (traceConductivity "595900 mho/cm") (traceGeometry "cpwms") (traceLayerName "") (traceThickness "0.72 mil") (traceType "single") (traceWidth "5.0 mil") (traceWidth2 "5.0 mil") (traceWidth3 "5.0 mil") (traceWidth4 "5.0 mil") (traceWidth5 "5.0 mil") (traceWidth6 "5.0 mil") (offset "0 mil") (traceCount "1") (impedance nil))) (Trace ((d1Thickness "10 mil") (d1Constant "4.5") (d1LossTangent "0.035") (d2Thickness "10 mil") (d2Constant "4.5") (d2LossTangent "0.035") (d3Thickness "0.0") (d3Constant "1.0") (d3LossTangent "0") length("1000 mil") (spacing "5 mil") (spacing2 "5 mil") (spacing3 "5 mil") (spacing4 "5 mil") (spacing5 "5 mil") (traceConductivity "595900 mho/cm") (traceGeometry "microstrip") (traceLayerName "") (traceThickness "0.72 mil") (traceType "single") (traceWidth "5.0 mil") (traceWidth2 "5.0 mil") (traceWidth3 "5.0 mil") (traceWidth4 "5.0 mil") (traceWidth5 "5.0 mil") (traceWidth6 "5.0 mil") (offset "0 mil") (traceCount "1") (impedance nil))) (Source ((voltage "5 V"))) (CPWSL ((d1Thickness "10 mil") (d1Constant "4.5") (d1LossTangent "0.035") (d2Thickness "0.72 mil") (d2Constant "4.5") (d2LossTangent "0.035") (d3Thickness "10 mil") (d3Constant "4.5") (d3LossTangent "0.035") length("1000 mil") (spacing "5 mil") (spacing2 "5 mil") (spacing3 "5 mil") (spacing4 "5 mil") (spacing5 "5 mil") (traceConductivity "595900 mho/cm") (traceGeometry "cpwms") (traceLayerName "") (traceThickness "0.72 mil") (traceType "single") (traceWidth "5.0 mil") (traceWidth2 "5.0 mil") (traceWidth3 "5.0 mil") (traceWidth4 "5.0 mil") (traceWidth5 "5.0 mil") (traceWidth6 "5.0 mil") (offset "0 mil") (traceCount "1") (impedance nil))) (RLGC (length("1000 mil"))) (Capacitor ((capacitance "10 pF") (orientation "0"))) (DiffIOPkg ((temperature "27") (bufferModelNonInverting "CDSDefaultIO_2p5v") (bufferModelInverting "CDSDefaultIO_2p5v") (stimuli nil) (offsets nil) (state "tristate") (cycle "1") (termMap nil) (setup "0.9e-09") (hold "0.4e-09") (rise nil) (fall nil) (threshInputHighMin "1.7 V") (threshInputHighTyp "1.7  V") (threshInputHighMax "1.7  V") (threshInputLowMin "0.7  V") (threshInputLowTyp "0.7  V") (threshInputLowMax "0.7 ") (threshOutputHighMin "2.365  V") (threshOutputHighTyp "2.5  V") (threshOutputHighMax "2.625  V") (threshOutputLowMin "1.275  V") (threshOutputLowTyp "1.7  V") (threshOutputLowMax "1.985  V") (mappingTagNonInverting nil) (mappingTagInverting nil) (spice nil))) (Inductor ((inductance "5 nH") (orientation "0"))) (DiffIO ((temperature "27") (bufferModelNonInverting "CDSDefaultIO_2p5v") (bufferModelInverting "CDSDefaultIO_2p5v") (stimuli nil) (offsets nil) (state "tristate") (cycle "1") (termMap nil) (setup "0.9e-09") (hold "0.4e-09") (rise nil) (fall nil) (threshInputHighMin "1.7 V") (threshInputHighTyp "1.7  V") (threshInputHighMax "1.7  V") (threshInputLowMin "0.7  V") (threshInputLowTyp "0.7  V") (threshInputLowMax "0.7 ") (threshOutputHighMin "2.365  V") (threshOutputHighTyp "2.5  V") (threshOutputHighMax "2.625  V") (threshOutputLowMin "1.275  V") (threshOutputLowTyp "1.7  V") (threshOutputLowMax "1.985  V") (mappingTagNonInverting nil) (mappingTagInverting nil) (spice nil))) (CPW ((d1Thickness "10 mil") (d1Constant "4.5") (d1LossTangent "0.035") (d2Thickness "0.72 mil") (d2Constant "1") (d2LossTangent "0") (d3Thickness "0.0") (d3Constant "1") (d3LossTangent "0") length("1000 mil") (spacing "5 mil") (spacing2 "5 mil") (spacing3 "5 mil") (spacing4 "5 mil") (spacing5 "5 mil") (traceConductivity "595900 mho/cm") (traceGeometry "cpwms") (traceLayerName "") (traceThickness "0.72 mil") (traceType "single") (traceWidth "5.0 mil") (traceWidth2 "5.0 mil") (traceWidth3 "5.0 mil") (traceWidth4 "5.0 mil") (traceWidth5 "5.0 mil") (traceWidth6 "5.0 mil") (offset "0 mil") (traceCount "1") (impedance nil))) (Connector nil) (TLine ((diffImpedance "100ohm") (diffVelocity "1.4142e+08M/s") (impedance "60ohm") length("2800 mil") (propDelay "0.5 ns") (velocity "5600 mil/ns") (traceCount "1") (traceGeometry "Microstrip") (impedanceMin nil) (impedanceMax nil) (lengthMin nil) (lengthMax nil) (propDelayMin nil) (propDelayMax nil) (impedanceSweepCount nil) (propDelaySweepCount nil) (velocitySweepCount nil) (lengthSweepCount nil) (matchSetName nil))) (sync ((syncFreq "100e6") (syncInitState "1") (syncPattern "10") (syncEdgeSwitch "rise"))) (IbisIO_OpenPullDown ((temperature "27") (bufferModel "CDSDefaultIO_2p5v") (stimuli nil) (offsets nil) (state "tristate") (cycle "1") (termMap nil) (setup "2.0e-09") (hold "1.0e-09") (rise nil) (fall nil) (macroType nil) (voltage nil) (spice nil) (LEFDEFPinName nil) (LEFDEFPinType nil) (mappingTag nil))) (DiffOutputPkg ((temperature "27") (bufferModelNonInverting "CDSDefaultOutput_2p5v") (bufferModelInverting "CDSDefaultOutput_2p5v") (stimuli nil) (offsets nil) (state "tristate") (cycle "1") (termMap nil) (setup "0.9e-09") (hold "0.4e-09") (rise nil) (fall nil) (threshOutputHighMin "2.375  V") (threshOutputHighTyp "2.5  V") (threshOutputHighMax "2.625  V") (threshOutputLowMin "1.275  V") (threshOutputLowTyp "1.7  V") (threshOutputLowMax "1.985  V") (mappingTagNonInverting nil) (mappingTagInverting nil) (spice nil))) (DiffInput ((temperature "27") (bufferModelNonInverting "CDSDefaultInput_2p5v") (bufferModelInverting "CDSDefaultInput_2p5v") (threshInputHighMin "1.7 V") (threshInputHighTyp "1.7  V") (threshInputHighMax "1.7  V") (threshInputLowMin "0.7  V") (threshInputLowTyp "0.7  V") (threshInputLowMax "0.7  V") (mappingTagNonInverting nil) (mappingTagInverting nil) (cycle "1"))) (Resistor ((resistance "50 ohm") (orientation "0"))) (DiffOutput ((temperature "27") (bufferModelNonInverting "CDSDefaultOutput_2p5v") (bufferModelInverting "CDSDefaultOutput_2p5v") (stimuli nil) (offsets nil) (state "tristate") (cycle "1") (termMap nil) (setup "0.9e-09") (hold "0.4e-09") (rise nil) (fall nil) (threshOutputHighMin "2.375  V") (threshOutputHighTyp "2.5  V") (threshOutputHighMax "2.625  V") (threshOutputLowMin "1.275  V") (threshOutputLowTyp "1.7  V") (threshOutputLowMax "1.985  V") (mappingTagNonInverting nil) (mappingTagInverting nil) (spice nil))) (IbisOutput_OpenPullUp ((temperature "27") (bufferModel "CDSDefaultOutput_2p5v") (stimuli nil) (offsets nil) (state "tristate") (cycle "1") (termMap nil) (setup "2.0e-09") (hold "1.0e-09") (rise nil) (fall nil) (macroType nil) (voltage nil) (spice nil) (LEFDEFPinName nil) (LEFDEFPinType nil) (mappingTag nil))) (IbisIO_OpenPullUp ((temperature "27") (bufferModel "CDSDefaultIO_2p5v") (stimuli nil) (offsets nil) (state "tristate") (cycle "1") (termMap nil) (setup "2.0e-09") (hold "1.0e-09") (rise nil) (fall nil) (macroType nil) (voltage nil) (spice nil) (LEFDEFPinName nil) (LEFDEFPinType nil) (mappingTag nil)))))
				)
				( objectStatus "SPI_NIC_SCLK" )
			)
			( electricalCSet "@crescent_city_bb_fab1_lib.crescent_city_bb_fab1(sch_1):\SPI_CS0_PRIMARY_R_N\"
				( groupRef "SPI_CS0_PRIMARY_R_N:SPI_MUX-U7F1" )
				( groupRef "SPI_CS0_PRIMARY_R_N:SPI_MUX-U3T1" )
				( pinPairRef "SPI_CS0_PRIMARY_R_N:U8F1.9:U7F1.7" )
				( pinPairRef "SPI_CS0_PRIMARY_R_N:U8F1.9:U3T1.7" )
				( attribute "TOPOLOGY_TEMPLATE_REVISION" "1.0"
					( Origin gBackEnd )
				)
				( topologyData 33105
(SKIDL (Circuits ("MAIN" (Parts ("CRESCENT_CITY_902_20150507_Q.@@U7F1.7" IbisInputPkg (xy (5489 4221)) (refDes "U7F1") (model "Unknown") (Props (_SXDesignName "CRESCENT_CITY_902_20150507_Q") (brdx "14970.2 MIL") (brdy "1217.5 MIL") (bufferModel "CDSDefaultInput_2p5v") (mappingTag "") (temperature "27")) (Terms ("CRESCENT_CITY_902_20150507_Q.X1497020Y121750L2LRATS" "7"))) ("CRESCENT_CITY_902_20150507_Q.@@U8F1.9" IbisIOPkg (xy (5502 4240)) (refDes "U8F1") (model "Unknown") (Props (_SXDesignName "CRESCENT_CITY_902_20150507_Q") (brdx "15795 MIL") (brdy "1445 MIL") (bufferModel "CDSDefaultIO_2p5v") (cycle "1") (hold "1.0e-09") (mappingTag "") (offsets ("4" "0") ("5" "0")) (setup "2.0e-09") (state "tristate") (stimuli ("4" "local100") ("5" "local101")) (temperature "27") (termMap ("4" "Data") ("5" "Enable"))) (Terms ("CRESCENT_CITY_902_20150507_Q.X1579500Y144500L2LRATS" "9"))) ("CRESCENT_CITY_902_20150507_Q.@@U3T1.7" IbisInputPkg (xy (5480 4206)) (refDes "U3T1") (model "Unknown") (Props (_SXDesignName "CRESCENT_CITY_902_20150507_Q") (brdx "15225 MIL") (brdy "1210 MIL") (bufferModel "CDSDefaultInput_2p5v") (mappingTag "") (temperature "27")) (Terms ("CRESCENT_CITY_902_20150507_Q.X1522500Y121000L36LRATS" "7"))) ("CRESCENT_CITY_902_20150507_Q.T@@RATS@@R7F5.2@@U7F1.7" TLine (xy (5475 4214)) (refDes "TL76") (Props (_SXDesignName "CRESCENT_CITY_902_20150507_Q") (impedance "48.412 ohm") length("132.70 MIL") (propDelay "0.02383 ns") (traceCount "1") (traceGeometry "Microstrip") (velocity "5568.62 mil/ns")) (Terms ("CRESCENT_CITY_902_20150507_Q.X1496000Y134000L2LRATS" "1") ("CRESCENT_CITY_902_20150507_Q.X1497020Y121750L2LRATS" "2"))) ("CRESCENT_CITY_902_20150507_Q.T@@RATS@@U8F1.9@@R2T8.2" TLine (xy (5503 4229)) (mirror x) (refDes "TL77") (Props (_SXDesignName "CRESCENT_CITY_902_20150507_Q") (impedance "48.412 ohm") length("290.00 MIL") (propDelay "0.05209 ns") (traceCount "1") (traceGeometry "Microstrip") (velocity "5567.28 mil/ns")) (Terms ("CRESCENT_CITY_902_20150507_Q.X1579500Y144500L2LRATS" "1") ("CRESCENT_CITY_902_20150507_Q.X1575000Y120000L36LRATS" "2"))) ("CRESCENT_CITY_902_20150507_Q.@@R2T9.1.2" Resistor (xy (5457 4206)) (refDes "R2T9") (value "75 Ohm") (Props (_SXDesignName "CRESCENT_CITY_902_20150507_Q")) (Terms ("CRESCENT_CITY_902_20150507_Q.X1556800Y120500L36LRATS" "1") ("CRESCENT_CITY_902_20150507_Q.X1553300Y120500L36LRATS" "2"))) ("CRESCENT_CITY_902_20150507_Q.T@@RATS@@U2T3.4@@R2T13.1" TLine (xy (5451 4221)) (refDes "TL78") (Props (_SXDesignName "CRESCENT_CITY_902_20150507_Q") (impedance "46.577 ohm") length("54.18 MIL") (propDelay "0.00973 ns") (traceCount "1") (traceGeometry "Microstrip") (velocity "5568.35 mil/ns")) (Terms ("CRESCENT_CITY_902_20150507_Q.X1562000Y109882L36LRATS" "1") ("CRESCENT_CITY_902_20150507_Q.X1556600Y109900L36LRATS" "2"))) ("CRESCENT_CITY_902_20150507_Q.@@R3T5.1_SOURCE" Source (xy (5450 4199)) (refDes "P3V3_STBY_1") (value "3.3 V") (Props (_SXDesignName "CRESCENT_CITY_902_20150507_Q")) (Terms ("CRESCENT_CITY_902_20150507_Q.X1519500Y132000L36RATS" "1"))) ("CRESCENT_CITY_902_20150507_Q.T@@RATS@@U7F1.7@@R2T13.2" TLine (xy (5475 4221)) (mirror x) (refDes "TL79") (Props (_SXDesignName "CRESCENT_CITY_902_20150507_Q") (impedance "48.412 ohm") length("679.30 MIL") (propDelay "0.12201 ns") (traceCount "1") (traceGeometry "Microstrip") (velocity "5567.56 mil/ns")) (Terms ("CRESCENT_CITY_902_20150507_Q.X1497020Y121750L2LRATS" "1") ("CRESCENT_CITY_902_20150507_Q.X1553100Y109900L36LRATS" "2"))) ("CRESCENT_CITY_902_20150507_Q.T@@RATS@@R2T8.2@@U2T2.2" TLine (xy (5488 4229)) (mirror x) (refDes "TL80") (Props (_SXDesignName "CRESCENT_CITY_902_20150507_Q") (impedance "46.577 ohm") length("88.41 MIL") (propDelay "0.01588 ns") (traceCount "1") (traceGeometry "Microstrip") (velocity "5567.36 mil/ns")) (Terms ("CRESCENT_CITY_902_20150507_Q.X1575000Y120000L36LRATS" "1") ("CRESCENT_CITY_902_20150507_Q.X1569000Y122841L36LRATS" "2"))) ("CRESCENT_CITY_902_20150507_Q.@@U2T2.2.4" Resistor (xy (5433 4206)) (refDes "U2T2") (value "1 Ohm") (Props (_SXDesignName "CRESCENT_CITY_902_20150507_Q")) (Terms ("CRESCENT_CITY_902_20150507_Q.X1569000Y122841L36LRATS" "2") ("CRESCENT_CITY_902_20150507_Q.X1562000Y120282L36LRATS" "4"))) ("CRESCENT_CITY_902_20150507_Q.@@R7F5.1_SOURCE" Source (xy (5459 4214)) (refDes "P3V3_STBY_2") (value "3.3 V") (Props (_SXDesignName "CRESCENT_CITY_902_20150507_Q")) (Terms ("CRESCENT_CITY_902_20150507_Q.X1499500Y134000L2RATS" "1"))) ("CRESCENT_CITY_902_20150507_Q.@@R2T8.1_SOURCE" Source (xy (5481 4199)) (refDes "P3V3_STBY") (value "3.3 V") (Props (_SXDesignName "CRESCENT_CITY_902_20150507_Q")) (Terms ("CRESCENT_CITY_902_20150507_Q.X1578500Y120000L36RATS" "1"))) ("CRESCENT_CITY_902_20150507_Q.@@R2T13.2.1" Resistor (xy (5460 4221)) (mirror x) (refDes "R2T13") (value "200 Ohm") (Props (_SXDesignName "CRESCENT_CITY_902_20150507_Q")) (Terms ("CRESCENT_CITY_902_20150507_Q.X1553100Y109900L36LRATS" "2") ("CRESCENT_CITY_902_20150507_Q.X1556600Y109900L36LRATS" "1"))) ("CRESCENT_CITY_902_20150507_Q.T@@RATS@@R2T9.1@@U2T2.4" TLine (xy (5442 4206)) (mirror x) (refDes "TL81") (Props (_SXDesignName "CRESCENT_CITY_902_20150507_Q") (impedance "46.577 ohm") length("54.18 MIL") (propDelay "0.00973 ns") (traceCount "1") (traceGeometry "Microstrip") (velocity "5568.35 mil/ns")) (Terms ("CRESCENT_CITY_902_20150507_Q.X1556800Y120500L36LRATS" "1") ("CRESCENT_CITY_902_20150507_Q.X1562000Y120282L36LRATS" "2"))) ("CRESCENT_CITY_902_20150507_Q.T@@RATS@@U3T1.7@@R2T9.2" TLine (xy (5466 4206)) (mirror x) (refDes "TL82") (Props (_SXDesignName "CRESCENT_CITY_902_20150507_Q") (impedance "46.577 ohm") length("313.00 MIL") (propDelay "0.05622 ns") (traceCount "1") (traceGeometry "Microstrip") (velocity "5567.4 mil/ns")) (Terms ("CRESCENT_CITY_902_20150507_Q.X1522500Y121000L36LRATS" "1") ("CRESCENT_CITY_902_20150507_Q.X1553300Y120500L36LRATS" "2"))) ("CRESCENT_CITY_902_20150507_Q.@@R7F5.1.2" Resistor (xy (5466 4214)) (refDes "R7F5") (value "4750 Ohm") (Props (_SXDesignName "CRESCENT_CITY_902_20150507_Q")) (Terms ("CRESCENT_CITY_902_20150507_Q.X1499500Y134000L2RATS" "1") ("CRESCENT_CITY_902_20150507_Q.X1496000Y134000L2LRATS" "2"))) ("CRESCENT_CITY_902_20150507_Q.@@R2T8.1.2" Resistor (xy (5488 4199)) (refDes "R2T8") (value "10000 Ohm") (Props (_SXDesignName "CRESCENT_CITY_902_20150507_Q")) (Terms ("CRESCENT_CITY_902_20150507_Q.X1578500Y120000L36RATS" "1") ("CRESCENT_CITY_902_20150507_Q.X1575000Y120000L36LRATS" "2"))) ("CRESCENT_CITY_902_20150507_Q.T@@RATS@@U2T2.2@@U2T3.2" TLine (xy (5433 4221)) (refDes "TL83") (Props (_SXDesignName "CRESCENT_CITY_902_20150507_Q") (impedance "46.577 ohm") length("104.00 MIL") (propDelay "0.01868 ns") (traceCount "1") (traceGeometry "Microstrip") (velocity "5567.44 mil/ns")) (Terms ("CRESCENT_CITY_902_20150507_Q.X1569000Y122841L36LRATS" "1") ("CRESCENT_CITY_902_20150507_Q.X1569000Y112441L36LRATS" "2"))) ("CRESCENT_CITY_902_20150507_Q.T@@RATS@@U3T1.7@@R3T5.2" TLine (xy (5472 4199)) (mirror x) (refDes "TL84") (Props (_SXDesignName "CRESCENT_CITY_902_20150507_Q") (impedance "46.577 ohm") length("115.00 MIL") (propDelay "0.02065 ns") (traceCount "1") (traceGeometry "Microstrip") (velocity "5569.02 mil/ns")) (Terms ("CRESCENT_CITY_902_20150507_Q.X1522500Y121000L36LRATS" "1") ("CRESCENT_CITY_902_20150507_Q.X1523000Y132000L36LRATS" "2"))) ("CRESCENT_CITY_902_20150507_Q.@@R3T5.1.2" Resistor (xy (5457 4199)) (refDes "R3T5") (value "4750 Ohm") (Props (_SXDesignName "CRESCENT_CITY_902_20150507_Q")) (Terms ("CRESCENT_CITY_902_20150507_Q.X1519500Y132000L36RATS" "1") ("CRESCENT_CITY_902_20150507_Q.X1523000Y132000L36LRATS" "2"))) ("CRESCENT_CITY_902_20150507_Q.@@U2T3.2.4" Resistor (xy (5442 4221)) (refDes "U2T3") (value "1 Ohm") (Props (_SXDesignName "CRESCENT_CITY_902_20150507_Q")) (Terms ("CRESCENT_CITY_902_20150507_Q.X1569000Y112441L36LRATS" "2") ("CRESCENT_CITY_902_20150507_Q.X1562000Y109882L36LRATS" "4")))) (Nodes ("CRESCENT_CITY_902_20150507_Q.X1556600Y109900L36LRATS" (terms "CRESCENT_CITY_902_20150507_Q.@@R2T13.2.1.2" "CRESCENT_CITY_902_20150507_Q.T@@RATS@@U2T3.4@@R2T13.1.2")) ("CRESCENT_CITY_902_20150507_Q.X1556800Y120500L36LRATS" (terms "CRESCENT_CITY_902_20150507_Q.T@@RATS@@R2T9.1@@U2T2.4.1" "CRESCENT_CITY_902_20150507_Q.@@R2T9.1.2.1")) ("CRESCENT_CITY_902_20150507_Q.X1496000Y134000L2LRATS" (terms "CRESCENT_CITY_902_20150507_Q.@@R7F5.1.2.2" "CRESCENT_CITY_902_20150507_Q.T@@RATS@@R7F5.2@@U7F1.7.1")) ("CRESCENT_CITY_902_20150507_Q.X1497020Y121750L2LRATS" (terms "CRESCENT_CITY_902_20150507_Q.T@@RATS@@U7F1.7@@R2T13.2.1" "CRESCENT_CITY_902_20150507_Q.T@@RATS@@R7F5.2@@U7F1.7.2" "CRESCENT_CITY_902_20150507_Q.@@U7F1.7.1")) ("CRESCENT_CITY_902_20150507_Q.X1553100Y109900L36LRATS" (terms "CRESCENT_CITY_902_20150507_Q.@@R2T13.2.1.1" "CRESCENT_CITY_902_20150507_Q.T@@RATS@@U7F1.7@@R2T13.2.2")) ("CRESCENT_CITY_902_20150507_Q.X1499500Y134000L2RATS" (terms "CRESCENT_CITY_902_20150507_Q.@@R7F5.1.2.1" "CRESCENT_CITY_902_20150507_Q.@@R7F5.1_SOURCE.1")) ("CRESCENT_CITY_902_20150507_Q.X1522500Y121000L36LRATS" (terms "CRESCENT_CITY_902_20150507_Q.T@@RATS@@U3T1.7@@R3T5.2.1" "CRESCENT_CITY_902_20150507_Q.T@@RATS@@U3T1.7@@R2T9.2.1" "CRESCENT_CITY_902_20150507_Q.@@U3T1.7.1")) ("CRESCENT_CITY_902_20150507_Q.X1569000Y112441L36LRATS" (terms "CRESCENT_CITY_902_20150507_Q.@@U2T3.2.4.1" "CRESCENT_CITY_902_20150507_Q.T@@RATS@@U2T2.2@@U2T3.2.2")) ("CRESCENT_CITY_902_20150507_Q.X1562000Y109882L36LRATS" (terms "CRESCENT_CITY_902_20150507_Q.@@U2T3.2.4.2" "CRESCENT_CITY_902_20150507_Q.T@@RATS@@U2T3.4@@R2T13.1.1")) ("CRESCENT_CITY_902_20150507_Q.X1523000Y132000L36LRATS" (terms "CRESCENT_CITY_902_20150507_Q.@@R3T5.1.2.2" "CRESCENT_CITY_902_20150507_Q.T@@RATS@@U3T1.7@@R3T5.2.2")) ("CRESCENT_CITY_902_20150507_Q.X1575000Y120000L36LRATS" (terms "CRESCENT_CITY_902_20150507_Q.@@R2T8.1.2.2" "CRESCENT_CITY_902_20150507_Q.T@@RATS@@R2T8.2@@U2T2.2.1" "CRESCENT_CITY_902_20150507_Q.T@@RATS@@U8F1.9@@R2T8.2.2")) ("CRESCENT_CITY_902_20150507_Q.X1569000Y122841L36LRATS" (terms "CRESCENT_CITY_902_20150507_Q.T@@RATS@@U2T2.2@@U2T3.2.1" "CRESCENT_CITY_902_20150507_Q.@@U2T2.2.4.1" "CRESCENT_CITY_902_20150507_Q.T@@RATS@@R2T8.2@@U2T2.2.2")) ("CRESCENT_CITY_902_20150507_Q.X1519500Y132000L36RATS" (terms "CRESCENT_CITY_902_20150507_Q.@@R3T5.1.2.1" "CRESCENT_CITY_902_20150507_Q.@@R3T5.1_SOURCE.1")) ("CRESCENT_CITY_902_20150507_Q.X1553300Y120500L36LRATS" (terms "CRESCENT_CITY_902_20150507_Q.T@@RATS@@U3T1.7@@R2T9.2.2" "CRESCENT_CITY_902_20150507_Q.@@R2T9.1.2.2")) ("CRESCENT_CITY_902_20150507_Q.X1579500Y144500L2LRATS" (terms "CRESCENT_CITY_902_20150507_Q.T@@RATS@@U8F1.9@@R2T8.2.1" "CRESCENT_CITY_902_20150507_Q.@@U8F1.9.1")) ("CRESCENT_CITY_902_20150507_Q.X1578500Y120000L36RATS" (terms "CRESCENT_CITY_902_20150507_Q.@@R2T8.1.2.1" "CRESCENT_CITY_902_20150507_Q.@@R2T8.1_SOURCE.1")) ("CRESCENT_CITY_902_20150507_Q.X1562000Y120282L36LRATS" (terms "CRESCENT_CITY_902_20150507_Q.T@@RATS@@R2T9.1@@U2T2.4.2" "CRESCENT_CITY_902_20150507_Q.@@U2T2.2.4.2"))) (Ports) (Stimuli ("local101" (scope local) (stimType periodic) (Props (periodicFreq "5e+007") (periodicJitter "0") (periodicPattern "1"))) ("local100" (scope local) (stimType periodic) (Props (periodicFreq "5e+007") (periodicJitter "0") (periodicPattern "1")))) (Notes) (Constraints ("RELATIVE_PROPAGATION_DELAY" ("SPI_MUX-U7F1" "CRESCENT_CITY_902_20150507_Q U8F1.9" "CRESCENT_CITY_902_20150507_Q U7F1.7" "GLOBAL" "LENGTH" "0.00635" "LENGTH" "0") ("SPI_MUX-U3T1" "CRESCENT_CITY_902_20150507_Q U8F1.9" "CRESCENT_CITY_902_20150507_Q U3T1.7" "GLOBAL" "LENGTH" "0.00635" "LENGTH" "0"))) (MeasurementSets ("EMI" ("EMIStatus" status("on")) ("PeakEmission" status("on")) ("PeakFrequency" status("on")) ("PulseFreq" status("on")) ("RiseTime" status("on")) ("VoltageSwing" status("on"))) ("Reflection" ("BufferDelayFall" status("off")) ("BufferDelayRise" status("off")) ("EyeHeight" status("off")) ("EyeJitter" status("off")) ("EyeWidth" status("off")) ("FirstIncidentFall" status("off")) ("FirstIncidentRise" status("off")) ("Glitch" status("on")) ("GlitchFall" status("off")) ("GlitchRise" status("off")) ("Monotonic" status("on")) ("MonotonicFall" status("off")) ("MonotonicRise" status("off")) ("NoiseMargin" status("on")) ("NoiseMarginHigh" status("off")) ("NoiseMarginLow" status("off")) ("OvershootHigh" status("on")) ("OvershootLow" status("on")) ("PropDelay" status("on")) ("SettleDelay" status("on")) ("SettleDelayFall" status("off")) ("SettleDelayRise" status("off")) ("SwitchDelay" status("on")) ("SwitchDelayFall" status("off")) ("SwitchDelayRise" status("off"))) ("Crosstalk" ("Crosstalk" status("on"))) ("Custom")) (VectorSets) (Props (XnetName "SPI_CS0_PRIMARY_R_N") (allDrivers "active") (customSimType "Reflection") (ftsMode ("Typ")) (rcvrSelect "all") (tlineDelayMode "time") (userRevision "1.0")))) (Subckts) (CrossSections ("CRESCENT_CITY_902_20150507_Q" (Props (SXDesignName "CRESCENT_CITY_902_20150507_Q")) (Layers ("" (layerType "SURFACE") (material "AIR") (thickness "0 mil") (dielectricConstant "1.000000") (lossTangent "0") (etchFactor "0.000000") (elecCondVal "0 mho/cm") (thermCondVal "0 w/cm-degC")) ("" (layerType "DIELECTRIC") (material "CONFORMAL_COAT") (thickness "0.5 mil") (dielectricConstant "3.800000") (lossTangent "0.035") (etchFactor "0.000000") (elecCondVal "0 mho/cm") (thermCondVal "0.012 w/cm-degC")) ("TOP" (layerType "CONDUCTOR") (material "COPPER") (thickness "  2.100000 mil") (width "4.00 MIL") (dielectricConstant "4.500000") (lossTangent "0") (etchFactor "70.000000") (elecCondVal "595900.000000 mho/cm") (thermCondVal "0 w/cm-degC") (signalDieConstant "3.800000") (signalLossTangent "0.035")) ("" (layerType "DIELECTRIC") (material "FR-4") (thickness "  2.670000 mil") (dielectricConstant "4.000000") (lossTangent "0.035") (etchFactor "0.000000") (elecCondVal "0 mho/cm") (thermCondVal "0.012 w/cm-degC")) ("L2_GND1" (layerType "PLANE") (material "COPPER") (isShield t) (thickness "  1.250000 mil") (dielectricConstant "4.500000") (lossTangent "0.035") (etchFactor "90.000000") (elecCondVal "595900.000000 mho/cm") (thermCondVal "0.012 w/cm-degC")) ("" (layerType "DIELECTRIC") (material "FR-4") (thickness "  9.000000 mil") (dielectricConstant "4.100000") (lossTangent "0.035") (etchFactor "0.000000") (elecCondVal "0 mho/cm") (thermCondVal "0.012 w/cm-degC")) ("L3_SIG1" (layerType "CONDUCTOR") (material "COPPER") (thickness "  1.250000 mil") (width "4.00 MIL") (dielectricConstant "4.500000") (lossTangent "0.035") (etchFactor "90.000000") (elecCondVal "595900.000000 mho/cm") (thermCondVal "0.012 w/cm-degC") (signalDieConstant "4.100000") (signalLossTangent "0.035")) ("" (layerType "DIELECTRIC") (material "FR-4") (thickness "  3.000000 mil") (dielectricConstant "4.500000") (lossTangent "0.035") (etchFactor "0.000000") (elecCondVal "0 mho/cm") (thermCondVal "0 w/cm-degC")) ("L4_GND2" (layerType "PLANE") (material "COPPER") (isShield t) (thickness "  1.250000 mil") (dielectricConstant "4.500000") (lossTangent "0.035") (etchFactor "90.000000") (elecCondVal "595900.000000 mho/cm") (thermCondVal "0 w/cm-degC")) ("" (layerType "DIELECTRIC") (material "FR-4") (thickness "  9.000000 mil") (dielectricConstant "4.000000") (lossTangent "0.035") (etchFactor "0.000000") (elecCondVal "0 mho/cm") (thermCondVal "0.012 w/cm-degC")) ("L5_SIG2" (layerType "CONDUCTOR") (material "COPPER") (thickness "  1.250000 mil") (width "4.00 MIL") (dielectricConstant "4.500000") (lossTangent "0.035") (etchFactor "90.000000") (elecCondVal "595900.000000 mho/cm") (thermCondVal "0.012 w/cm-degC") (signalDieConstant "4.000000") (signalLossTangent "0.035")) ("" (layerType "DIELECTRIC") (material "FR-4") (thickness "  3.000000 mil") (dielectricConstant "4.500000") (lossTangent "0.035") (etchFactor "0.000000") (elecCondVal "0 mho/cm") (thermCondVal "0 w/cm-degC")) ("L6_GND3" (layerType "PLANE") (material "COPPER") (isShield t) (thickness "  1.250000 mil") (dielectricConstant "4.500000") (lossTangent "0.035") (etchFactor "90.000000") (elecCondVal "595900.000000 mho/cm") (thermCondVal "0 w/cm-degC")) ("" (layerType "DIELECTRIC") (material "FR-4") (thickness "  4.500000 mil") (dielectricConstant "4.100000") (lossTangent "0.035") (etchFactor "0.000000") (elecCondVal "0 mho/cm") (thermCondVal "0.012 w/cm-degC")) ("L7_PWR1-SIG" (layerType "PLANE") (material "COPPER") (isShield t) (thickness "  2.610000 mil") (dielectricConstant "4.500000") (lossTangent "0.035") (etchFactor "90.000000") (elecCondVal "595900.000000 mho/cm") (thermCondVal "0.012 w/cm-degC")) ("" (layerType "DIELECTRIC") (material "FR-4") (thickness "  3.100000 mil") (dielectricConstant "4.500000") (lossTangent "0.035") (etchFactor "0.000000") (elecCondVal "0 mho/cm") (thermCondVal "0 w/cm-degC")) ("L8_GND_TEMP" (layerType "PLANE") (material "COPPER") (isShield t) (thickness "  1.250000 mil") (dielectricConstant "4.500000") (lossTangent "0.035") (etchFactor "90.000000") (elecCondVal "595900.000000 mho/cm") (thermCondVal "0 w/cm-degC")) ("" (layerType "DIELECTRIC") (material "FR-4") (thickness "  3.030000 mil") (dielectricConstant "4.500000") (lossTangent "0.035") (etchFactor "0.000000") (elecCondVal "0 mho/cm") (thermCondVal "0 w/cm-degC")) ("L9_SIG_TEMP" (layerType "CONDUCTOR") (material "COPPER") (thickness "  1.250000 mil") (width "3.52 MIL") (dielectricConstant "4.500000") (lossTangent "0.035") (etchFactor "90.000000") (elecCondVal "595900.000000 mho/cm") (thermCondVal "0 w/cm-degC") (signalDieConstant "4.500000") (signalLossTangent "0.035")) ("" (layerType "DIELECTRIC") (material "FR-4") (thickness "  5.000000 mil") (dielectricConstant "4.500000") (lossTangent "0.035") (etchFactor "0.000000") (elecCondVal "0 mho/cm") (thermCondVal "0 w/cm-degC")) ("L10_SIG_TEMP" (layerType "CONDUCTOR") (material "COPPER") (thickness "  1.250000 mil") (width "3.52 MIL") (dielectricConstant "4.500000") (lossTangent "0.035") (etchFactor "90.000000") (elecCondVal "595900.000000 mho/cm") (thermCondVal "0 w/cm-degC") (signalDieConstant "4.500000") (signalLossTangent "0.035")) ("" (layerType "DIELECTRIC") (material "FR-4") (thickness "  3.030000 mil") (dielectricConstant "4.500000") (lossTangent "0.035") (etchFactor "0.000000") (elecCondVal "0 mho/cm") (thermCondVal "0 w/cm-degC")) ("L11_GND_TEMP" (layerType "PLANE") (material "COPPER") (isShield t) (thickness "  1.250000 mil") (dielectricConstant "4.500000") (lossTangent "0.035") (etchFactor "90.000000") (elecCondVal "595900.000000 mho/cm") (thermCondVal "0 w/cm-degC")) ("" (layerType "DIELECTRIC") (material "FR-4") (thickness "  3.100000 mil") (dielectricConstant "4.000000") (lossTangent "0.035") (etchFactor "0.000000") (elecCondVal "0 mho/cm") (thermCondVal "0.012 w/cm-degC")) ("L12_PWR2-SIG" (layerType "PLANE") (material "COPPER") (isShield t) (thickness "  2.610000 mil") (dielectricConstant "4.500000") (lossTangent "0.035") (etchFactor "90.000000") (elecCondVal "595900.000000 mho/cm") (thermCondVal "0.012 w/cm-degC")) ("" (layerType "DIELECTRIC") (material "FR-4") (thickness "  4.500000 mil") (dielectricConstant "4.500000") (lossTangent "0.035") (etchFactor "0.000000") (elecCondVal "0 mho/cm") (thermCondVal "0 w/cm-degC")) ("L13_GND4" (layerType "PLANE") (material "COPPER") (isShield t) (thickness "  1.250000 mil") (dielectricConstant "4.500000") (lossTangent "0.035") (etchFactor "90.000000") (elecCondVal "595900.000000 mho/cm") (thermCondVal "0 w/cm-degC")) ("" (layerType "DIELECTRIC") (material "FR-4") (thickness "  3.000000 mil") (dielectricConstant "4.100000") (lossTangent "0.035") (etchFactor "0.000000") (elecCondVal "0 mho/cm") (thermCondVal "0.012 w/cm-degC")) ("L14_SIG3" (layerType "CONDUCTOR") (material "COPPER") (thickness "  1.250000 mil") (width "4.00 MIL") (dielectricConstant "4.500000") (lossTangent "0.035") (etchFactor "90.000000") (elecCondVal "595900.000000 mho/cm") (thermCondVal "0.012 w/cm-degC") (signalDieConstant "4.100000") (signalLossTangent "0.035")) ("" (layerType "DIELECTRIC") (material "FR-4") (thickness "  9.000000 mil") (dielectricConstant "4.500000") (lossTangent "0.035") (etchFactor "0.000000") (elecCondVal "0 mho/cm") (thermCondVal "0 w/cm-degC")) ("L15_GND5" (layerType "PLANE") (material "COPPER") (isShield t) (thickness "  1.250000 mil") (dielectricConstant "4.500000") (lossTangent "0.035") (etchFactor "90.000000") (elecCondVal "595900.000000 mho/cm") (thermCondVal "0 w/cm-degC")) ("" (layerType "DIELECTRIC") (material "FR-4") (thickness "  3.000000 mil") (dielectricConstant "4.500000") (lossTangent "0.035") (etchFactor "0.000000") (elecCondVal "0 mho/cm") (thermCondVal "0.012 w/cm-degC")) ("L16_SIG4" (layerType "CONDUCTOR") (material "COPPER") (thickness "  1.250000 mil") (width "4.00 MIL") (dielectricConstant "4.500000") (lossTangent "0.035") (etchFactor "90.000000") (elecCondVal "595900.000000 mho/cm") (thermCondVal "0.012 w/cm-degC") (signalDieConstant "4.500000") (signalLossTangent "0.035")) ("" (layerType "DIELECTRIC") (material "FR-4") (thickness "  9.000000 mil") (dielectricConstant "4.500000") (lossTangent "0.035") (etchFactor "0.000000") (elecCondVal "0 mho/cm") (thermCondVal "0 w/cm-degC")) ("L17_GND6" (layerType "PLANE") (material "COPPER") (isShield t) (thickness "  1.250000 mil") (dielectricConstant "4.500000") (lossTangent "0.035") (etchFactor "90.000000") (elecCondVal "595900.000000 mho/cm") (thermCondVal "0.012 w/cm-degC")) ("" (layerType "DIELECTRIC") (material "FR-4") (thickness "  2.670000 mil") (dielectricConstant "4.500000") (lossTangent "0.035") (etchFactor "0.000000") (elecCondVal "0 mho/cm") (thermCondVal "0.012 w/cm-degC")) ("BOTTOM" (layerType "CONDUCTOR") (material "COPPER") (thickness "  2.100000 mil") (width "4.00 MIL") (dielectricConstant "4.500000") (lossTangent "0") (etchFactor "70.000000") (elecCondVal "595900.000000 mho/cm") (thermCondVal "0 w/cm-degC") (signalDieConstant "3.800000") (signalLossTangent "0.035")) ("" (layerType "DIELECTRIC") (material "CONFORMAL_COAT") (thickness "0.5 mil") (dielectricConstant "3.800000") (lossTangent "0.035") (etchFactor "0.000000") (elecCondVal "0 mho/cm") (thermCondVal "0.012 w/cm-degC")) ("" (layerType "SURFACE") (material "AIR") (thickness "0 mil") (dielectricConstant "1.000000") (lossTangent "0") (etchFactor "0.000000") (elecCondVal "0 mho/cm") (thermCondVal "0 w/cm-degC"))))) (Props (DesUnits "mils 2") (LayerStack ("DIELECTRIC" "DIELECTRIC" "BOTTOM" "DIELECTRIC" "L17_GND6" "DIELECTRIC" "L16_SIG4" "DIELECTRIC" "L15_GND5" "DIELECTRIC" "L14_SIG3" "DIELECTRIC" "L13_GND4" "DIELECTRIC" "L12_PWR2-SIG" "DIELECTRIC" "L11_GND_TEMP" "DIELECTRIC" "L10_SIG_TEMP" "DIELECTRIC" "L9_SIG_TEMP" "DIELECTRIC" "L8_GND_TEMP" "DIELECTRIC" "L7_PWR1-SIG" "DIELECTRIC" "L6_GND3" "DIELECTRIC" "L5_SIG2" "DIELECTRIC" "L4_GND2" "DIELECTRIC" "L3_SIG1" "DIELECTRIC" "L2_GND1" "DIELECTRIC" "TOP" "DIELECTRIC" "DIELECTRIC")) (Revision "16.600")) (Params (DiffInputPkg ((temperature "27") (bufferModelNonInverting "CDSDefaultInput_2p5v") (bufferModelInverting "CDSDefaultInput_2p5v") (threshInputHighMin "1.7 V") (threshInputHighTyp "1.7  V") (threshInputHighMax "1.7  V") (threshInputLowMin "0.7  V") (threshInputLowTyp "0.7  V") (threshInputLowMax "0.7  V") (mappingTagNonInverting nil) (mappingTagInverting nil) (cycle "1"))) (IbisOutputPkg ((temperature "27") (bufferModel "CDSDefaultOutput_2p5v") (stimuli nil) (offsets nil) (state "tristate") (cycle "1") (termMap nil) (setup "2.0e-09") (hold "1.0e-09") (rise nil) (fall nil) (macroType nil) (voltage nil) (spice nil) (LEFDEFPinName nil) (LEFDEFPinType nil) (mappingTag nil))) (IbisIOPkg ((temperature "27") (bufferModel "CDSDefaultIO_2p5v") (stimuli nil) (offsets nil) (state "tristate") (cycle "1") (termMap nil) (setup "2.0e-09") (hold "1.0e-09") (rise nil) (fall nil) (macroType nil) (voltage nil) (spice nil) (LEFDEFPinName nil) (LEFDEFPinType nil) (mappingTag nil))) (IbisIOMacro ((temperature "27") (bufferModel "CDSDefaultIO_2p5v") (stimuli nil) (offsets nil) (state "tristate") (cycle "1") (termMap nil) (setup "2.0e-09") (hold "1.0e-09") (rise nil) (fall nil) (macroType nil) (voltage nil) (spice nil) (LEFDEFPinName nil) (LEFDEFPinType nil) (mappingTag nil))) (ESpiceDevice nil) (IbisInput ((temperature "27") (bufferModel "CDSDefaultInput_2p5v") (cycle "1") (LEFDEFPinName nil) (LEFDEFPinType nil) (mappingTag nil))) (ShuntTerm ((resistance "50 ohm") (voltage "5 V") (maxDelay "0.1 ns"))) (SeriesTerm ((resistance "22 ohm") (maxDelay "0.1 ns"))) (CurrentProbe nil) (idlCircuit ((allDrivers "active") (ftsMode '("Typ")) (rcvrSelect "all") (simMode "Reflection") (tlineDelayMode "time") (userRevision "1.0") (autoSolve "On"))) (TheveninTerm ((resistanceUp "180 ohm") (resistanceDown "270 ohm") (voltageUp "5 V") (voltageDown "0 V") (maxDelay "0.1 ns"))) (RCTerm ((resistance "50 ohm") (capacitance "20 pF") (voltage "5 V") (maxDelay "0.1 ns"))) (LowClampTerm ((cutoffVoltage "0.7 V") (voltage "0 V") (maxDelay "0.1 ns"))) (Cable (length("1 m"))) (HiClampTerm ((cutoffVoltage "0.7 V") (voltage "5 V") (maxDelay "0.1 ns"))) (DualClampTerm ((cutoffVoltageUp "0.7 V") (cutoffVoltageDown "0.7 V") (voltageUp "5 V") (voltageDown "0 V") (maxDelay "0.1 ns"))) (IbisInputPkg ((temperature "27") (bufferModel "CDSDefaultInput_2p5v") (cycle "1") (LEFDEFPinName nil) (LEFDEFPinType nil) (mappingTag nil))) (async ((asyncTimePoints "") (asyncInitState "1"))) (clocked ((clockRise "1e-09") (clockFall "1e-09") (clockFreq "100e6") (clockInitState "0") (clockDutyCycle "0.5") (clockJitter "0"))) (Diode ((cutoffVoltage "0.7 V"))) (IbisOutput ((temperature "27") (bufferModel "CDSDefaultOutput_2p5v") (stimuli nil) (offsets nil) (state "tristate") (cycle "1") (termMap nil) (setup "2.0e-09") (hold "1.0e-09") (rise nil) (fall nil) (macroType nil) (voltage nil) (spice nil) (LEFDEFPinName nil) (LEFDEFPinType nil) (mappingTag nil))) (periodic ((periodicFreq "100e6") (periodicPattern "10") (periodicJitter "0"))) (IbisIO ((temperature "27") (bufferModel "CDSDefaultIO_2p5v") (stimuli nil) (offsets nil) (state "tristate") (cycle "1") (termMap nil) (setup "2.0e-09") (hold "1.0e-09") (rise nil) (fall nil) (macroType nil) (voltage nil) (spice nil) (LEFDEFPinName nil) (LEFDEFPinType nil) (mappingTag nil))) (Via ((model "Unknown") (viaOutputFormat "Unknown") (viaPadstack nil) (viaTopLayer nil) (viaBottomLayer nil) (viaIsPower nil) (viaIsGround nil))) (CPWMS ((d1Thickness "10 mil") (d1Constant "4.5") (d1LossTangent "0.035") (d2Thickness "0.72 mil") (d2Constant "4.5") (d2LossTangent "0.035") (d3Thickness "0.0") (d3Constant "1") (d3LossTangent "0") length("1000 mil") (spacing "5 mil") (spacing2 "5 mil") (spacing3 "5 mil") (spacing4 "5 mil") (spacing5 "5 mil") (traceConductivity "595900 mho/cm") (traceGeometry "cpwms") (traceLayerName "") (traceThickness "0.72 mil") (traceType "single") (traceWidth "5.0 mil") (traceWidth2 "5.0 mil") (traceWidth3 "5.0 mil") (traceWidth4 "5.0 mil") (traceWidth5 "5.0 mil") (traceWidth6 "5.0 mil") (offset "0 mil") (traceCount "1") (impedance nil))) (Trace ((d1Thickness "10 mil") (d1Constant "4.5") (d1LossTangent "0.035") (d2Thickness "10 mil") (d2Constant "4.5") (d2LossTangent "0.035") (d3Thickness "0.0") (d3Constant "1.0") (d3LossTangent "0") length("1000 mil") (spacing "5 mil") (spacing2 "5 mil") (spacing3 "5 mil") (spacing4 "5 mil") (spacing5 "5 mil") (traceConductivity "595900 mho/cm") (traceGeometry "microstrip") (traceLayerName "") (traceThickness "0.72 mil") (traceType "single") (traceWidth "5.0 mil") (traceWidth2 "5.0 mil") (traceWidth3 "5.0 mil") (traceWidth4 "5.0 mil") (traceWidth5 "5.0 mil") (traceWidth6 "5.0 mil") (offset "0 mil") (traceCount "1") (impedance nil))) (Source ((voltage "5 V"))) (CPWSL ((d1Thickness "10 mil") (d1Constant "4.5") (d1LossTangent "0.035") (d2Thickness "0.72 mil") (d2Constant "4.5") (d2LossTangent "0.035") (d3Thickness "10 mil") (d3Constant "4.5") (d3LossTangent "0.035") length("1000 mil") (spacing "5 mil") (spacing2 "5 mil") (spacing3 "5 mil") (spacing4 "5 mil") (spacing5 "5 mil") (traceConductivity "595900 mho/cm") (traceGeometry "cpwms") (traceLayerName "") (traceThickness "0.72 mil") (traceType "single") (traceWidth "5.0 mil") (traceWidth2 "5.0 mil") (traceWidth3 "5.0 mil") (traceWidth4 "5.0 mil") (traceWidth5 "5.0 mil") (traceWidth6 "5.0 mil") (offset "0 mil") (traceCount "1") (impedance nil))) (RLGC (length("1000 mil"))) (Capacitor ((capacitance "10 pF") (orientation "0"))) (DiffIOPkg ((temperature "27") (bufferModelNonInverting "CDSDefaultIO_2p5v") (bufferModelInverting "CDSDefaultIO_2p5v") (stimuli nil) (offsets nil) (state "tristate") (cycle "1") (termMap nil) (setup "0.9e-09") (hold "0.4e-09") (rise nil) (fall nil) (threshInputHighMin "1.7 V") (threshInputHighTyp "1.7  V") (threshInputHighMax "1.7  V") (threshInputLowMin "0.7  V") (threshInputLowTyp "0.7  V") (threshInputLowMax "0.7 ") (threshOutputHighMin "2.365  V") (threshOutputHighTyp "2.5  V") (threshOutputHighMax "2.625  V") (threshOutputLowMin "1.275  V") (threshOutputLowTyp "1.7  V") (threshOutputLowMax "1.985  V") (mappingTagNonInverting nil) (mappingTagInverting nil) (spice nil))) (Inductor ((inductance "5 nH") (orientation "0"))) (DiffIO ((temperature "27") (bufferModelNonInverting "CDSDefaultIO_2p5v") (bufferModelInverting "CDSDefaultIO_2p5v") (stimuli nil) (offsets nil) (state "tristate") (cycle "1") (termMap nil) (setup "0.9e-09") (hold "0.4e-09") (rise nil) (fall nil) (threshInputHighMin "1.7 V") (threshInputHighTyp "1.7  V") (threshInputHighMax "1.7  V") (threshInputLowMin "0.7  V") (threshInputLowTyp "0.7  V") (threshInputLowMax "0.7 ") (threshOutputHighMin "2.365  V") (threshOutputHighTyp "2.5  V") (threshOutputHighMax "2.625  V") (threshOutputLowMin "1.275  V") (threshOutputLowTyp "1.7  V") (threshOutputLowMax "1.985  V") (mappingTagNonInverting nil) (mappingTagInverting nil) (spice nil))) (CPW ((d1Thickness "10 mil") (d1Constant "4.5") (d1LossTangent "0.035") (d2Thickness "0.72 mil") (d2Constant "1") (d2LossTangent "0") (d3Thickness "0.0") (d3Constant "1") (d3LossTangent "0") length("1000 mil") (spacing "5 mil") (spacing2 "5 mil") (spacing3 "5 mil") (spacing4 "5 mil") (spacing5 "5 mil") (traceConductivity "595900 mho/cm") (traceGeometry "cpwms") (traceLayerName "") (traceThickness "0.72 mil") (traceType "single") (traceWidth "5.0 mil") (traceWidth2 "5.0 mil") (traceWidth3 "5.0 mil") (traceWidth4 "5.0 mil") (traceWidth5 "5.0 mil") (traceWidth6 "5.0 mil") (offset "0 mil") (traceCount "1") (impedance nil))) (Connector nil) (TLine ((diffImpedance "100ohm") (diffVelocity "1.4142e+08M/s") (impedance "60ohm") length("2800 mil") (propDelay "0.5 ns") (velocity "5600 mil/ns") (traceCount "1") (traceGeometry "Microstrip") (impedanceMin nil) (impedanceMax nil) (lengthMin nil) (lengthMax nil) (propDelayMin nil) (propDelayMax nil) (impedanceSweepCount nil) (propDelaySweepCount nil) (velocitySweepCount nil) (lengthSweepCount nil) (matchSetName nil))) (sync ((syncFreq "100e6") (syncInitState "1") (syncPattern "10") (syncEdgeSwitch "rise"))) (IbisIO_OpenPullDown ((temperature "27") (bufferModel "CDSDefaultIO_2p5v") (stimuli nil) (offsets nil) (state "tristate") (cycle "1") (termMap nil) (setup "2.0e-09") (hold "1.0e-09") (rise nil) (fall nil) (macroType nil) (voltage nil) (spice nil) (LEFDEFPinName nil) (LEFDEFPinType nil) (mappingTag nil))) (DiffOutputPkg ((temperature "27") (bufferModelNonInverting "CDSDefaultOutput_2p5v") (bufferModelInverting "CDSDefaultOutput_2p5v") (stimuli nil) (offsets nil) (state "tristate") (cycle "1") (termMap nil) (setup "0.9e-09") (hold "0.4e-09") (rise nil) (fall nil) (threshOutputHighMin "2.375  V") (threshOutputHighTyp "2.5  V") (threshOutputHighMax "2.625  V") (threshOutputLowMin "1.275  V") (threshOutputLowTyp "1.7  V") (threshOutputLowMax "1.985  V") (mappingTagNonInverting nil) (mappingTagInverting nil) (spice nil))) (DiffInput ((temperature "27") (bufferModelNonInverting "CDSDefaultInput_2p5v") (bufferModelInverting "CDSDefaultInput_2p5v") (threshInputHighMin "1.7 V") (threshInputHighTyp "1.7  V") (threshInputHighMax "1.7  V") (threshInputLowMin "0.7  V") (threshInputLowTyp "0.7  V") (threshInputLowMax "0.7  V") (mappingTagNonInverting nil) (mappingTagInverting nil) (cycle "1"))) (Resistor ((resistance "50 ohm") (orientation "0"))) (DiffOutput ((temperature "27") (bufferModelNonInverting "CDSDefaultOutput_2p5v") (bufferModelInverting "CDSDefaultOutput_2p5v") (stimuli nil) (offsets nil) (state "tristate") (cycle "1") (termMap nil) (setup "0.9e-09") (hold "0.4e-09") (rise nil) (fall nil) (threshOutputHighMin "2.375  V") (threshOutputHighTyp "2.5  V") (threshOutputHighMax "2.625  V") (threshOutputLowMin "1.275  V") (threshOutputLowTyp "1.7  V") (threshOutputLowMax "1.985  V") (mappingTagNonInverting nil) (mappingTagInverting nil) (spice nil))) (IbisOutput_OpenPullUp ((temperature "27") (bufferModel "CDSDefaultOutput_2p5v") (stimuli nil) (offsets nil) (state "tristate") (cycle "1") (termMap nil) (setup "2.0e-09") (hold "1.0e-09") (rise nil) (fall nil) (macroType nil) (voltage nil) (spice nil) (LEFDEFPinName nil) (LEFDEFPinType nil) (mappingTag nil))) (IbisIO_OpenPullUp ((temperature "27") (bufferModel "CDSDefaultIO_2p5v") (stimuli nil) (offsets nil) (state "tristate") (cycle "1") (termMap nil) (setup "2.0e-09") (hold "1.0e-09") (rise nil) (fall nil) (macroType nil) (voltage nil) (spice nil) (LEFDEFPinName nil) (LEFDEFPinType nil) (mappingTag nil)))))
				)
				( objectStatus "SPI_CS0_PRIMARY_R_N" )
			)
			( electricalCSet "@crescent_city_bb_fab1_lib.crescent_city_bb_fab1(sch_1):\SPI_PCH_IO2_1\"
				( groupRef "SPI_PCH_IO2:SPI_PCH-MUX" )
				( pinPairRef "SPI_PCH_IO2:U7C1.F5:U2T1.2" )
				( attribute "RATSNEST_SCHEDULE" "MIN_TREE"
					( Status sLocked )
					( Origin gBackEnd )
				)
				( attribute "TOPOLOGY_TEMPLATE_REVISION" "1.0"
					( Origin gBackEnd )
				)
				( topologyData 28571
(SKIDL (Circuits ("MAIN" (Parts ("CRESCENT_CITY_902_20150507_Q.@@U2T1.2" IbisIOPkg (xy (5484 4220)) (refDes "U2T1") (model "Unknown") (Props (_SXDesignName "CRESCENT_CITY_902_20150507_Q") (brdx "15795 MIL") (brdy "1580 MIL") (bufferModel "CDSDefaultIO_2p5v") (cycle "1") (hold "1.0e-09") (mappingTag "") (offsets ("4" "0") ("5" "0")) (setup "2.0e-09") (state "tristate") (stimuli ("4" "local96") ("5" "local97")) (temperature "27") (termMap ("4" "Data") ("5" "Enable"))) (Terms ("CRESCENT_CITY_902_20150507_Q.X1579500Y158000L36LRATS" "2"))) ("CRESCENT_CITY_902_20150507_Q.@@J9A3.1" Connector (xy (5471 4208)) (refDes "J9A3") (Props (_SXDesignName "CRESCENT_CITY_902_20150507_Q") (brdx "18222.76 MIL") (brdy "5343.46 MIL") (pin_use "1")) (Terms ("CRESCENT_CITY_902_20150507_Q.X1822276Y534346L2LRATS" "1"))) ("CRESCENT_CITY_902_20150507_Q.@@U7C1.F5" IbisIOPkg (xy (5502 4240)) (refDes "U7C1") (model "Unknown") (Props (_SXDesignName "CRESCENT_CITY_902_20150507_Q") (brdx "14826.73 MIL") (brdy "3740.3 MIL") (bufferModel "CDSDefaultIO_2p5v") (cycle "1") (hold "1.0e-09") (mappingTag "") (offsets ("4" "0") ("5" "0")) (setup "2.0e-09") (state "tristate") (stimuli ("4" "local98") ("5" "local99")) (temperature "27") (termMap ("4" "Data") ("5" "Enable"))) (Terms ("CRESCENT_CITY_902_20150507_Q.X1482673Y374030L2LRATS" "F5"))) ("CRESCENT_CITY_902_20150507_Q.@@R2R11.2_SOURCE" Source (xy (5444 4229)) (refDes "GND") (value "0 V") (Props (_SXDesignName "CRESCENT_CITY_902_20150507_Q")) (Terms ("CRESCENT_CITY_902_20150507_Q.X1591500Y159000L36RATS" "1"))) ("CRESCENT_CITY_902_20150507_Q.T@@RATS@@R2R12.1@@R2R11.1" TLine (xy (5466 4229)) (mirror x) (refDes "TL71") (Props (_SXDesignName "CRESCENT_CITY_902_20150507_Q") (impedance "46.577 ohm") length("40.00 MIL") (propDelay "0.00718 ns") (traceCount "1") (traceGeometry "Microstrip") (velocity "5571.02 mil/ns")) (Terms ("CRESCENT_CITY_902_20150507_Q.X1587500Y162500L36LRATS" "1") ("CRESCENT_CITY_902_20150507_Q.X1591500Y162500L36LRATS" "2"))) ("CRESCENT_CITY_902_20150507_Q.@@R2R11.2.1" Resistor (xy (5451 4229)) (refDes "R2R11") (value "10000 Ohm") (Props (_SXDesignName "CRESCENT_CITY_902_20150507_Q")) (Terms ("CRESCENT_CITY_902_20150507_Q.X1591500Y159000L36RATS" "2") ("CRESCENT_CITY_902_20150507_Q.X1591500Y162500L36LRATS" "1"))) ("CRESCENT_CITY_902_20150507_Q.T@@RATS@@J9A3.1@@R2P2.2" TLine (xy (5479 4205)) (refDes "TL72") (Props (_SXDesignName "CRESCENT_CITY_902_20150507_Q") (impedance "48.412 ohm") length("4390.71 MIL") (propDelay "0.7886 ns") (traceCount "1") (traceGeometry "Microstrip") (velocity "5567.72 mil/ns")) (Terms ("CRESCENT_CITY_902_20150507_Q.X1822276Y534346L2LRATS" "1") ("CRESCENT_CITY_902_20150507_Q.X1590402Y327151L36LRATS" "2"))) ("CRESCENT_CITY_902_20150507_Q.@@R2P2.2.1" Resistor (xy (5488 4205)) (refDes "R2P2") (value "1000 Ohm") (Props (_SXDesignName "CRESCENT_CITY_902_20150507_Q")) (Terms ("CRESCENT_CITY_902_20150507_Q.X1590402Y327151L36LRATS" "2") ("CRESCENT_CITY_902_20150507_Q.X1586902Y327151L36LRATS" "1"))) ("CRESCENT_CITY_902_20150507_Q.T@@RATS@@U7C1.F5@@R2P2.1" TLine (xy (5503 4229)) (mirror x) (refDes "TL73") (Props (_SXDesignName "CRESCENT_CITY_902_20150507_Q") (impedance "52.449 ohm") length("1511.08 MIL") (propDelay "0.2714 ns") (traceCount "1") (traceGeometry "Microstrip") (velocity "5567.72 mil/ns")) (Terms ("CRESCENT_CITY_902_20150507_Q.X1482673Y374030L2LRATS" "1") ("CRESCENT_CITY_902_20150507_Q.X1586902Y327151L36LRATS" "2"))) ("CRESCENT_CITY_902_20150507_Q.T@@RATS@@R2R12.2@@U2T1.2" TLine (xy (5475 4215)) (refDes "TL74") (Props (_SXDesignName "CRESCENT_CITY_902_20150507_Q") (impedance "46.577 ohm") length("90.00 MIL") (propDelay "0.01616 ns") (traceCount "1") (traceGeometry "Microstrip") (velocity "5569.29 mil/ns")) (Terms ("CRESCENT_CITY_902_20150507_Q.X1587500Y159000L36LRATS" "1") ("CRESCENT_CITY_902_20150507_Q.X1579500Y158000L36LRATS" "2"))) ("CRESCENT_CITY_902_20150507_Q.@@R2R12.2.1" Resistor (xy (5460 4215)) (mirror x) (refDes "R2R12") (value "33.2 Ohm") (Props (_SXDesignName "CRESCENT_CITY_902_20150507_Q")) (Terms ("CRESCENT_CITY_902_20150507_Q.X1587500Y159000L36LRATS" "2") ("CRESCENT_CITY_902_20150507_Q.X1587500Y162500L36LRATS" "1"))) ("CRESCENT_CITY_902_20150507_Q.T@@RATS@@R2P2.1@@R2R12.1" TLine (xy (5488 4229)) (mirror x) (refDes "TL75") (Props (_SXDesignName "CRESCENT_CITY_902_20150507_Q") (impedance "46.577 ohm") length("1652.49 MIL") (propDelay "0.2968 ns") (traceCount "1") (traceGeometry "Microstrip") (velocity "5567.68 mil/ns")) (Terms ("CRESCENT_CITY_902_20150507_Q.X1586902Y327151L36LRATS" "1") ("CRESCENT_CITY_902_20150507_Q.X1587500Y162500L36LRATS" "2")))) (Nodes ("CRESCENT_CITY_902_20150507_Q.X1482673Y374030L2LRATS" (terms "CRESCENT_CITY_902_20150507_Q.T@@RATS@@U7C1.F5@@R2P2.1.1" "CRESCENT_CITY_902_20150507_Q.@@U7C1.F5.1")) ("CRESCENT_CITY_902_20150507_Q.X1822276Y534346L2LRATS" (terms "CRESCENT_CITY_902_20150507_Q.T@@RATS@@J9A3.1@@R2P2.2.1" "CRESCENT_CITY_902_20150507_Q.@@J9A3.1.1")) ("CRESCENT_CITY_902_20150507_Q.X1590402Y327151L36LRATS" (terms "CRESCENT_CITY_902_20150507_Q.@@R2P2.2.1.1" "CRESCENT_CITY_902_20150507_Q.T@@RATS@@J9A3.1@@R2P2.2.2")) ("CRESCENT_CITY_902_20150507_Q.X1586902Y327151L36LRATS" (terms "CRESCENT_CITY_902_20150507_Q.T@@RATS@@R2P2.1@@R2R12.1.1" "CRESCENT_CITY_902_20150507_Q.T@@RATS@@U7C1.F5@@R2P2.1.2" "CRESCENT_CITY_902_20150507_Q.@@R2P2.2.1.2")) ("CRESCENT_CITY_902_20150507_Q.X1587500Y162500L36LRATS" (terms "CRESCENT_CITY_902_20150507_Q.T@@RATS@@R2P2.1@@R2R12.1.2" "CRESCENT_CITY_902_20150507_Q.@@R2R12.2.1.2" "CRESCENT_CITY_902_20150507_Q.T@@RATS@@R2R12.1@@R2R11.1.1")) ("CRESCENT_CITY_902_20150507_Q.X1591500Y162500L36LRATS" (terms "CRESCENT_CITY_902_20150507_Q.@@R2R11.2.1.2" "CRESCENT_CITY_902_20150507_Q.T@@RATS@@R2R12.1@@R2R11.1.2")) ("CRESCENT_CITY_902_20150507_Q.X1587500Y159000L36LRATS" (terms "CRESCENT_CITY_902_20150507_Q.@@R2R12.2.1.1" "CRESCENT_CITY_902_20150507_Q.T@@RATS@@R2R12.2@@U2T1.2.1")) ("CRESCENT_CITY_902_20150507_Q.X1579500Y158000L36LRATS" (terms "CRESCENT_CITY_902_20150507_Q.T@@RATS@@R2R12.2@@U2T1.2.2" "CRESCENT_CITY_902_20150507_Q.@@U2T1.2.1")) ("CRESCENT_CITY_902_20150507_Q.X1591500Y159000L36RATS" (terms "CRESCENT_CITY_902_20150507_Q.@@R2R11.2.1.1" "CRESCENT_CITY_902_20150507_Q.@@R2R11.2_SOURCE.1"))) (Ports) (Stimuli ("local96" (scope local) (stimType periodic) (Props (periodicFreq "5e+007") (periodicJitter "0") (periodicPattern "1"))) ("local99" (scope local) (stimType periodic) (Props (periodicFreq "5e+007") (periodicJitter "0") (periodicPattern "1"))) ("local97" (scope local) (stimType periodic) (Props (periodicFreq "5e+007") (periodicJitter "0") (periodicPattern "1"))) ("local98" (scope local) (stimType periodic) (Props (periodicFreq "5e+007") (periodicJitter "0") (periodicPattern "1")))) (Notes) (Constraints ("RATSNEST_SCHEDULE" "MIN_TREE") ("RELATIVE_PROPAGATION_DELAY" ("SPI_PCH-MUX" "CRESCENT_CITY_902_20150507_Q U7C1.F5" "CRESCENT_CITY_902_20150507_Q U2T1.2" "GLOBAL" "LENGTH" "0.00635" "LENGTH" "0"))) (MeasurementSets ("EMI" ("EMIStatus" status("on")) ("PeakEmission" status("on")) ("PeakFrequency" status("on")) ("PulseFreq" status("on")) ("RiseTime" status("on")) ("VoltageSwing" status("on"))) ("Reflection" ("BufferDelayFall" status("off")) ("BufferDelayRise" status("off")) ("EyeHeight" status("off")) ("EyeJitter" status("off")) ("EyeWidth" status("off")) ("FirstIncidentFall" status("off")) ("FirstIncidentRise" status("off")) ("Glitch" status("on")) ("GlitchFall" status("off")) ("GlitchRise" status("off")) ("Monotonic" status("on")) ("MonotonicFall" status("off")) ("MonotonicRise" status("off")) ("NoiseMargin" status("on")) ("NoiseMarginHigh" status("off")) ("NoiseMarginLow" status("off")) ("OvershootHigh" status("on")) ("OvershootLow" status("on")) ("PropDelay" status("on")) ("SettleDelay" status("on")) ("SettleDelayFall" status("off")) ("SettleDelayRise" status("off")) ("SwitchDelay" status("on")) ("SwitchDelayFall" status("off")) ("SwitchDelayRise" status("off"))) ("Crosstalk" ("Crosstalk" status("on"))) ("Custom")) (VectorSets) (Props (XnetName "SPI_PCH_IO2") (allDrivers "active") (customSimType "Reflection") (ftsMode ("Typ")) (rcvrSelect "all") (tlineDelayMode "time") (userRevision "1.0")))) (Subckts) (CrossSections ("CRESCENT_CITY_902_20150507_Q" (Props (SXDesignName "CRESCENT_CITY_902_20150507_Q")) (Layers ("" (layerType "SURFACE") (material "AIR") (thickness "0 mil") (dielectricConstant "1.000000") (lossTangent "0") (etchFactor "0.000000") (elecCondVal "0 mho/cm") (thermCondVal "0 w/cm-degC")) ("" (layerType "DIELECTRIC") (material "CONFORMAL_COAT") (thickness "0.5 mil") (dielectricConstant "3.800000") (lossTangent "0.035") (etchFactor "0.000000") (elecCondVal "0 mho/cm") (thermCondVal "0.012 w/cm-degC")) ("TOP" (layerType "CONDUCTOR") (material "COPPER") (thickness "  2.100000 mil") (width "4.00 MIL") (dielectricConstant "4.500000") (lossTangent "0") (etchFactor "70.000000") (elecCondVal "595900.000000 mho/cm") (thermCondVal "0 w/cm-degC") (signalDieConstant "3.800000") (signalLossTangent "0.035")) ("" (layerType "DIELECTRIC") (material "FR-4") (thickness "  2.670000 mil") (dielectricConstant "4.000000") (lossTangent "0.035") (etchFactor "0.000000") (elecCondVal "0 mho/cm") (thermCondVal "0.012 w/cm-degC")) ("L2_GND1" (layerType "PLANE") (material "COPPER") (isShield t) (thickness "  1.250000 mil") (dielectricConstant "4.500000") (lossTangent "0.035") (etchFactor "90.000000") (elecCondVal "595900.000000 mho/cm") (thermCondVal "0.012 w/cm-degC")) ("" (layerType "DIELECTRIC") (material "FR-4") (thickness "  9.000000 mil") (dielectricConstant "4.100000") (lossTangent "0.035") (etchFactor "0.000000") (elecCondVal "0 mho/cm") (thermCondVal "0.012 w/cm-degC")) ("L3_SIG1" (layerType "CONDUCTOR") (material "COPPER") (thickness "  1.250000 mil") (width "4.00 MIL") (dielectricConstant "4.500000") (lossTangent "0.035") (etchFactor "90.000000") (elecCondVal "595900.000000 mho/cm") (thermCondVal "0.012 w/cm-degC") (signalDieConstant "4.100000") (signalLossTangent "0.035")) ("" (layerType "DIELECTRIC") (material "FR-4") (thickness "  3.000000 mil") (dielectricConstant "4.500000") (lossTangent "0.035") (etchFactor "0.000000") (elecCondVal "0 mho/cm") (thermCondVal "0 w/cm-degC")) ("L4_GND2" (layerType "PLANE") (material "COPPER") (isShield t) (thickness "  1.250000 mil") (dielectricConstant "4.500000") (lossTangent "0.035") (etchFactor "90.000000") (elecCondVal "595900.000000 mho/cm") (thermCondVal "0 w/cm-degC")) ("" (layerType "DIELECTRIC") (material "FR-4") (thickness "  9.000000 mil") (dielectricConstant "4.000000") (lossTangent "0.035") (etchFactor "0.000000") (elecCondVal "0 mho/cm") (thermCondVal "0.012 w/cm-degC")) ("L5_SIG2" (layerType "CONDUCTOR") (material "COPPER") (thickness "  1.250000 mil") (width "4.00 MIL") (dielectricConstant "4.500000") (lossTangent "0.035") (etchFactor "90.000000") (elecCondVal "595900.000000 mho/cm") (thermCondVal "0.012 w/cm-degC") (signalDieConstant "4.000000") (signalLossTangent "0.035")) ("" (layerType "DIELECTRIC") (material "FR-4") (thickness "  3.000000 mil") (dielectricConstant "4.500000") (lossTangent "0.035") (etchFactor "0.000000") (elecCondVal "0 mho/cm") (thermCondVal "0 w/cm-degC")) ("L6_GND3" (layerType "PLANE") (material "COPPER") (isShield t) (thickness "  1.250000 mil") (dielectricConstant "4.500000") (lossTangent "0.035") (etchFactor "90.000000") (elecCondVal "595900.000000 mho/cm") (thermCondVal "0 w/cm-degC")) ("" (layerType "DIELECTRIC") (material "FR-4") (thickness "  4.500000 mil") (dielectricConstant "4.100000") (lossTangent "0.035") (etchFactor "0.000000") (elecCondVal "0 mho/cm") (thermCondVal "0.012 w/cm-degC")) ("L7_PWR1-SIG" (layerType "PLANE") (material "COPPER") (isShield t) (thickness "  2.610000 mil") (dielectricConstant "4.500000") (lossTangent "0.035") (etchFactor "90.000000") (elecCondVal "595900.000000 mho/cm") (thermCondVal "0.012 w/cm-degC")) ("" (layerType "DIELECTRIC") (material "FR-4") (thickness "  3.100000 mil") (dielectricConstant "4.500000") (lossTangent "0.035") (etchFactor "0.000000") (elecCondVal "0 mho/cm") (thermCondVal "0 w/cm-degC")) ("L8_GND_TEMP" (layerType "PLANE") (material "COPPER") (isShield t) (thickness "  1.250000 mil") (dielectricConstant "4.500000") (lossTangent "0.035") (etchFactor "90.000000") (elecCondVal "595900.000000 mho/cm") (thermCondVal "0 w/cm-degC")) ("" (layerType "DIELECTRIC") (material "FR-4") (thickness "  3.030000 mil") (dielectricConstant "4.500000") (lossTangent "0.035") (etchFactor "0.000000") (elecCondVal "0 mho/cm") (thermCondVal "0 w/cm-degC")) ("L9_SIG_TEMP" (layerType "CONDUCTOR") (material "COPPER") (thickness "  1.250000 mil") (width "3.52 MIL") (dielectricConstant "4.500000") (lossTangent "0.035") (etchFactor "90.000000") (elecCondVal "595900.000000 mho/cm") (thermCondVal "0 w/cm-degC") (signalDieConstant "4.500000") (signalLossTangent "0.035")) ("" (layerType "DIELECTRIC") (material "FR-4") (thickness "  5.000000 mil") (dielectricConstant "4.500000") (lossTangent "0.035") (etchFactor "0.000000") (elecCondVal "0 mho/cm") (thermCondVal "0 w/cm-degC")) ("L10_SIG_TEMP" (layerType "CONDUCTOR") (material "COPPER") (thickness "  1.250000 mil") (width "3.52 MIL") (dielectricConstant "4.500000") (lossTangent "0.035") (etchFactor "90.000000") (elecCondVal "595900.000000 mho/cm") (thermCondVal "0 w/cm-degC") (signalDieConstant "4.500000") (signalLossTangent "0.035")) ("" (layerType "DIELECTRIC") (material "FR-4") (thickness "  3.030000 mil") (dielectricConstant "4.500000") (lossTangent "0.035") (etchFactor "0.000000") (elecCondVal "0 mho/cm") (thermCondVal "0 w/cm-degC")) ("L11_GND_TEMP" (layerType "PLANE") (material "COPPER") (isShield t) (thickness "  1.250000 mil") (dielectricConstant "4.500000") (lossTangent "0.035") (etchFactor "90.000000") (elecCondVal "595900.000000 mho/cm") (thermCondVal "0 w/cm-degC")) ("" (layerType "DIELECTRIC") (material "FR-4") (thickness "  3.100000 mil") (dielectricConstant "4.000000") (lossTangent "0.035") (etchFactor "0.000000") (elecCondVal "0 mho/cm") (thermCondVal "0.012 w/cm-degC")) ("L12_PWR2-SIG" (layerType "PLANE") (material "COPPER") (isShield t) (thickness "  2.610000 mil") (dielectricConstant "4.500000") (lossTangent "0.035") (etchFactor "90.000000") (elecCondVal "595900.000000 mho/cm") (thermCondVal "0.012 w/cm-degC")) ("" (layerType "DIELECTRIC") (material "FR-4") (thickness "  4.500000 mil") (dielectricConstant "4.500000") (lossTangent "0.035") (etchFactor "0.000000") (elecCondVal "0 mho/cm") (thermCondVal "0 w/cm-degC")) ("L13_GND4" (layerType "PLANE") (material "COPPER") (isShield t) (thickness "  1.250000 mil") (dielectricConstant "4.500000") (lossTangent "0.035") (etchFactor "90.000000") (elecCondVal "595900.000000 mho/cm") (thermCondVal "0 w/cm-degC")) ("" (layerType "DIELECTRIC") (material "FR-4") (thickness "  3.000000 mil") (dielectricConstant "4.100000") (lossTangent "0.035") (etchFactor "0.000000") (elecCondVal "0 mho/cm") (thermCondVal "0.012 w/cm-degC")) ("L14_SIG3" (layerType "CONDUCTOR") (material "COPPER") (thickness "  1.250000 mil") (width "4.00 MIL") (dielectricConstant "4.500000") (lossTangent "0.035") (etchFactor "90.000000") (elecCondVal "595900.000000 mho/cm") (thermCondVal "0.012 w/cm-degC") (signalDieConstant "4.100000") (signalLossTangent "0.035")) ("" (layerType "DIELECTRIC") (material "FR-4") (thickness "  9.000000 mil") (dielectricConstant "4.500000") (lossTangent "0.035") (etchFactor "0.000000") (elecCondVal "0 mho/cm") (thermCondVal "0 w/cm-degC")) ("L15_GND5" (layerType "PLANE") (material "COPPER") (isShield t) (thickness "  1.250000 mil") (dielectricConstant "4.500000") (lossTangent "0.035") (etchFactor "90.000000") (elecCondVal "595900.000000 mho/cm") (thermCondVal "0 w/cm-degC")) ("" (layerType "DIELECTRIC") (material "FR-4") (thickness "  3.000000 mil") (dielectricConstant "4.500000") (lossTangent "0.035") (etchFactor "0.000000") (elecCondVal "0 mho/cm") (thermCondVal "0.012 w/cm-degC")) ("L16_SIG4" (layerType "CONDUCTOR") (material "COPPER") (thickness "  1.250000 mil") (width "4.00 MIL") (dielectricConstant "4.500000") (lossTangent "0.035") (etchFactor "90.000000") (elecCondVal "595900.000000 mho/cm") (thermCondVal "0.012 w/cm-degC") (signalDieConstant "4.500000") (signalLossTangent "0.035")) ("" (layerType "DIELECTRIC") (material "FR-4") (thickness "  9.000000 mil") (dielectricConstant "4.500000") (lossTangent "0.035") (etchFactor "0.000000") (elecCondVal "0 mho/cm") (thermCondVal "0 w/cm-degC")) ("L17_GND6" (layerType "PLANE") (material "COPPER") (isShield t) (thickness "  1.250000 mil") (dielectricConstant "4.500000") (lossTangent "0.035") (etchFactor "90.000000") (elecCondVal "595900.000000 mho/cm") (thermCondVal "0.012 w/cm-degC")) ("" (layerType "DIELECTRIC") (material "FR-4") (thickness "  2.670000 mil") (dielectricConstant "4.500000") (lossTangent "0.035") (etchFactor "0.000000") (elecCondVal "0 mho/cm") (thermCondVal "0.012 w/cm-degC")) ("BOTTOM" (layerType "CONDUCTOR") (material "COPPER") (thickness "  2.100000 mil") (width "4.00 MIL") (dielectricConstant "4.500000") (lossTangent "0") (etchFactor "70.000000") (elecCondVal "595900.000000 mho/cm") (thermCondVal "0 w/cm-degC") (signalDieConstant "3.800000") (signalLossTangent "0.035")) ("" (layerType "DIELECTRIC") (material "CONFORMAL_COAT") (thickness "0.5 mil") (dielectricConstant "3.800000") (lossTangent "0.035") (etchFactor "0.000000") (elecCondVal "0 mho/cm") (thermCondVal "0.012 w/cm-degC")) ("" (layerType "SURFACE") (material "AIR") (thickness "0 mil") (dielectricConstant "1.000000") (lossTangent "0") (etchFactor "0.000000") (elecCondVal "0 mho/cm") (thermCondVal "0 w/cm-degC"))))) (Props (DesUnits "mils 2") (LayerStack ("DIELECTRIC" "DIELECTRIC" "BOTTOM" "DIELECTRIC" "L17_GND6" "DIELECTRIC" "L16_SIG4" "DIELECTRIC" "L15_GND5" "DIELECTRIC" "L14_SIG3" "DIELECTRIC" "L13_GND4" "DIELECTRIC" "L12_PWR2-SIG" "DIELECTRIC" "L11_GND_TEMP" "DIELECTRIC" "L10_SIG_TEMP" "DIELECTRIC" "L9_SIG_TEMP" "DIELECTRIC" "L8_GND_TEMP" "DIELECTRIC" "L7_PWR1-SIG" "DIELECTRIC" "L6_GND3" "DIELECTRIC" "L5_SIG2" "DIELECTRIC" "L4_GND2" "DIELECTRIC" "L3_SIG1" "DIELECTRIC" "L2_GND1" "DIELECTRIC" "TOP" "DIELECTRIC" "DIELECTRIC")) (Revision "16.600")) (Params (DiffInputPkg ((temperature "27") (bufferModelNonInverting "CDSDefaultInput_2p5v") (bufferModelInverting "CDSDefaultInput_2p5v") (threshInputHighMin "1.7 V") (threshInputHighTyp "1.7  V") (threshInputHighMax "1.7  V") (threshInputLowMin "0.7  V") (threshInputLowTyp "0.7  V") (threshInputLowMax "0.7  V") (mappingTagNonInverting nil) (mappingTagInverting nil) (cycle "1"))) (IbisOutputPkg ((temperature "27") (bufferModel "CDSDefaultOutput_2p5v") (stimuli nil) (offsets nil) (state "tristate") (cycle "1") (termMap nil) (setup "2.0e-09") (hold "1.0e-09") (rise nil) (fall nil) (macroType nil) (voltage nil) (spice nil) (LEFDEFPinName nil) (LEFDEFPinType nil) (mappingTag nil))) (IbisIOPkg ((temperature "27") (bufferModel "CDSDefaultIO_2p5v") (stimuli nil) (offsets nil) (state "tristate") (cycle "1") (termMap nil) (setup "2.0e-09") (hold "1.0e-09") (rise nil) (fall nil) (macroType nil) (voltage nil) (spice nil) (LEFDEFPinName nil) (LEFDEFPinType nil) (mappingTag nil))) (IbisIOMacro ((temperature "27") (bufferModel "CDSDefaultIO_2p5v") (stimuli nil) (offsets nil) (state "tristate") (cycle "1") (termMap nil) (setup "2.0e-09") (hold "1.0e-09") (rise nil) (fall nil) (macroType nil) (voltage nil) (spice nil) (LEFDEFPinName nil) (LEFDEFPinType nil) (mappingTag nil))) (ESpiceDevice nil) (IbisInput ((temperature "27") (bufferModel "CDSDefaultInput_2p5v") (cycle "1") (LEFDEFPinName nil) (LEFDEFPinType nil) (mappingTag nil))) (ShuntTerm ((resistance "50 ohm") (voltage "5 V") (maxDelay "0.1 ns"))) (SeriesTerm ((resistance "22 ohm") (maxDelay "0.1 ns"))) (CurrentProbe nil) (idlCircuit ((allDrivers "active") (ftsMode '("Typ")) (rcvrSelect "all") (simMode "Reflection") (tlineDelayMode "time") (userRevision "1.0") (autoSolve "On"))) (TheveninTerm ((resistanceUp "180 ohm") (resistanceDown "270 ohm") (voltageUp "5 V") (voltageDown "0 V") (maxDelay "0.1 ns"))) (RCTerm ((resistance "50 ohm") (capacitance "20 pF") (voltage "5 V") (maxDelay "0.1 ns"))) (LowClampTerm ((cutoffVoltage "0.7 V") (voltage "0 V") (maxDelay "0.1 ns"))) (Cable (length("1 m"))) (HiClampTerm ((cutoffVoltage "0.7 V") (voltage "5 V") (maxDelay "0.1 ns"))) (DualClampTerm ((cutoffVoltageUp "0.7 V") (cutoffVoltageDown "0.7 V") (voltageUp "5 V") (voltageDown "0 V") (maxDelay "0.1 ns"))) (IbisInputPkg ((temperature "27") (bufferModel "CDSDefaultInput_2p5v") (cycle "1") (LEFDEFPinName nil) (LEFDEFPinType nil) (mappingTag nil))) (async ((asyncTimePoints "") (asyncInitState "1"))) (clocked ((clockRise "1e-09") (clockFall "1e-09") (clockFreq "100e6") (clockInitState "0") (clockDutyCycle "0.5") (clockJitter "0"))) (Diode ((cutoffVoltage "0.7 V"))) (IbisOutput ((temperature "27") (bufferModel "CDSDefaultOutput_2p5v") (stimuli nil) (offsets nil) (state "tristate") (cycle "1") (termMap nil) (setup "2.0e-09") (hold "1.0e-09") (rise nil) (fall nil) (macroType nil) (voltage nil) (spice nil) (LEFDEFPinName nil) (LEFDEFPinType nil) (mappingTag nil))) (periodic ((periodicFreq "100e6") (periodicPattern "10") (periodicJitter "0"))) (IbisIO ((temperature "27") (bufferModel "CDSDefaultIO_2p5v") (stimuli nil) (offsets nil) (state "tristate") (cycle "1") (termMap nil) (setup "2.0e-09") (hold "1.0e-09") (rise nil) (fall nil) (macroType nil) (voltage nil) (spice nil) (LEFDEFPinName nil) (LEFDEFPinType nil) (mappingTag nil))) (Via ((model "Unknown") (viaOutputFormat "Unknown") (viaPadstack nil) (viaTopLayer nil) (viaBottomLayer nil) (viaIsPower nil) (viaIsGround nil))) (CPWMS ((d1Thickness "10 mil") (d1Constant "4.5") (d1LossTangent "0.035") (d2Thickness "0.72 mil") (d2Constant "4.5") (d2LossTangent "0.035") (d3Thickness "0.0") (d3Constant "1") (d3LossTangent "0") length("1000 mil") (spacing "5 mil") (spacing2 "5 mil") (spacing3 "5 mil") (spacing4 "5 mil") (spacing5 "5 mil") (traceConductivity "595900 mho/cm") (traceGeometry "cpwms") (traceLayerName "") (traceThickness "0.72 mil") (traceType "single") (traceWidth "5.0 mil") (traceWidth2 "5.0 mil") (traceWidth3 "5.0 mil") (traceWidth4 "5.0 mil") (traceWidth5 "5.0 mil") (traceWidth6 "5.0 mil") (offset "0 mil") (traceCount "1") (impedance nil))) (Trace ((d1Thickness "10 mil") (d1Constant "4.5") (d1LossTangent "0.035") (d2Thickness "10 mil") (d2Constant "4.5") (d2LossTangent "0.035") (d3Thickness "0.0") (d3Constant "1.0") (d3LossTangent "0") length("1000 mil") (spacing "5 mil") (spacing2 "5 mil") (spacing3 "5 mil") (spacing4 "5 mil") (spacing5 "5 mil") (traceConductivity "595900 mho/cm") (traceGeometry "microstrip") (traceLayerName "") (traceThickness "0.72 mil") (traceType "single") (traceWidth "5.0 mil") (traceWidth2 "5.0 mil") (traceWidth3 "5.0 mil") (traceWidth4 "5.0 mil") (traceWidth5 "5.0 mil") (traceWidth6 "5.0 mil") (offset "0 mil") (traceCount "1") (impedance nil))) (Source ((voltage "5 V"))) (CPWSL ((d1Thickness "10 mil") (d1Constant "4.5") (d1LossTangent "0.035") (d2Thickness "0.72 mil") (d2Constant "4.5") (d2LossTangent "0.035") (d3Thickness "10 mil") (d3Constant "4.5") (d3LossTangent "0.035") length("1000 mil") (spacing "5 mil") (spacing2 "5 mil") (spacing3 "5 mil") (spacing4 "5 mil") (spacing5 "5 mil") (traceConductivity "595900 mho/cm") (traceGeometry "cpwms") (traceLayerName "") (traceThickness "0.72 mil") (traceType "single") (traceWidth "5.0 mil") (traceWidth2 "5.0 mil") (traceWidth3 "5.0 mil") (traceWidth4 "5.0 mil") (traceWidth5 "5.0 mil") (traceWidth6 "5.0 mil") (offset "0 mil") (traceCount "1") (impedance nil))) (RLGC (length("1000 mil"))) (Capacitor ((capacitance "10 pF") (orientation "0"))) (DiffIOPkg ((temperature "27") (bufferModelNonInverting "CDSDefaultIO_2p5v") (bufferModelInverting "CDSDefaultIO_2p5v") (stimuli nil) (offsets nil) (state "tristate") (cycle "1") (termMap nil) (setup "0.9e-09") (hold "0.4e-09") (rise nil) (fall nil) (threshInputHighMin "1.7 V") (threshInputHighTyp "1.7  V") (threshInputHighMax "1.7  V") (threshInputLowMin "0.7  V") (threshInputLowTyp "0.7  V") (threshInputLowMax "0.7 ") (threshOutputHighMin "2.365  V") (threshOutputHighTyp "2.5  V") (threshOutputHighMax "2.625  V") (threshOutputLowMin "1.275  V") (threshOutputLowTyp "1.7  V") (threshOutputLowMax "1.985  V") (mappingTagNonInverting nil) (mappingTagInverting nil) (spice nil))) (Inductor ((inductance "5 nH") (orientation "0"))) (DiffIO ((temperature "27") (bufferModelNonInverting "CDSDefaultIO_2p5v") (bufferModelInverting "CDSDefaultIO_2p5v") (stimuli nil) (offsets nil) (state "tristate") (cycle "1") (termMap nil) (setup "0.9e-09") (hold "0.4e-09") (rise nil) (fall nil) (threshInputHighMin "1.7 V") (threshInputHighTyp "1.7  V") (threshInputHighMax "1.7  V") (threshInputLowMin "0.7  V") (threshInputLowTyp "0.7  V") (threshInputLowMax "0.7 ") (threshOutputHighMin "2.365  V") (threshOutputHighTyp "2.5  V") (threshOutputHighMax "2.625  V") (threshOutputLowMin "1.275  V") (threshOutputLowTyp "1.7  V") (threshOutputLowMax "1.985  V") (mappingTagNonInverting nil) (mappingTagInverting nil) (spice nil))) (CPW ((d1Thickness "10 mil") (d1Constant "4.5") (d1LossTangent "0.035") (d2Thickness "0.72 mil") (d2Constant "1") (d2LossTangent "0") (d3Thickness "0.0") (d3Constant "1") (d3LossTangent "0") length("1000 mil") (spacing "5 mil") (spacing2 "5 mil") (spacing3 "5 mil") (spacing4 "5 mil") (spacing5 "5 mil") (traceConductivity "595900 mho/cm") (traceGeometry "cpwms") (traceLayerName "") (traceThickness "0.72 mil") (traceType "single") (traceWidth "5.0 mil") (traceWidth2 "5.0 mil") (traceWidth3 "5.0 mil") (traceWidth4 "5.0 mil") (traceWidth5 "5.0 mil") (traceWidth6 "5.0 mil") (offset "0 mil") (traceCount "1") (impedance nil))) (Connector nil) (TLine ((diffImpedance "100ohm") (diffVelocity "1.4142e+08M/s") (impedance "60ohm") length("2800 mil") (propDelay "0.5 ns") (velocity "5600 mil/ns") (traceCount "1") (traceGeometry "Microstrip") (impedanceMin nil) (impedanceMax nil) (lengthMin nil) (lengthMax nil) (propDelayMin nil) (propDelayMax nil) (impedanceSweepCount nil) (propDelaySweepCount nil) (velocitySweepCount nil) (lengthSweepCount nil) (matchSetName nil))) (sync ((syncFreq "100e6") (syncInitState "1") (syncPattern "10") (syncEdgeSwitch "rise"))) (IbisIO_OpenPullDown ((temperature "27") (bufferModel "CDSDefaultIO_2p5v") (stimuli nil) (offsets nil) (state "tristate") (cycle "1") (termMap nil) (setup "2.0e-09") (hold "1.0e-09") (rise nil) (fall nil) (macroType nil) (voltage nil) (spice nil) (LEFDEFPinName nil) (LEFDEFPinType nil) (mappingTag nil))) (DiffOutputPkg ((temperature "27") (bufferModelNonInverting "CDSDefaultOutput_2p5v") (bufferModelInverting "CDSDefaultOutput_2p5v") (stimuli nil) (offsets nil) (state "tristate") (cycle "1") (termMap nil) (setup "0.9e-09") (hold "0.4e-09") (rise nil) (fall nil) (threshOutputHighMin "2.375  V") (threshOutputHighTyp "2.5  V") (threshOutputHighMax "2.625  V") (threshOutputLowMin "1.275  V") (threshOutputLowTyp "1.7  V") (threshOutputLowMax "1.985  V") (mappingTagNonInverting nil) (mappingTagInverting nil) (spice nil))) (DiffInput ((temperature "27") (bufferModelNonInverting "CDSDefaultInput_2p5v") (bufferModelInverting "CDSDefaultInput_2p5v") (threshInputHighMin "1.7 V") (threshInputHighTyp "1.7  V") (threshInputHighMax "1.7  V") (threshInputLowMin "0.7  V") (threshInputLowTyp "0.7  V") (threshInputLowMax "0.7  V") (mappingTagNonInverting nil) (mappingTagInverting nil) (cycle "1"))) (Resistor ((resistance "50 ohm") (orientation "0"))) (DiffOutput ((temperature "27") (bufferModelNonInverting "CDSDefaultOutput_2p5v") (bufferModelInverting "CDSDefaultOutput_2p5v") (stimuli nil) (offsets nil) (state "tristate") (cycle "1") (termMap nil) (setup "0.9e-09") (hold "0.4e-09") (rise nil) (fall nil) (threshOutputHighMin "2.375  V") (threshOutputHighTyp "2.5  V") (threshOutputHighMax "2.625  V") (threshOutputLowMin "1.275  V") (threshOutputLowTyp "1.7  V") (threshOutputLowMax "1.985  V") (mappingTagNonInverting nil) (mappingTagInverting nil) (spice nil))) (IbisOutput_OpenPullUp ((temperature "27") (bufferModel "CDSDefaultOutput_2p5v") (stimuli nil) (offsets nil) (state "tristate") (cycle "1") (termMap nil) (setup "2.0e-09") (hold "1.0e-09") (rise nil) (fall nil) (macroType nil) (voltage nil) (spice nil) (LEFDEFPinName nil) (LEFDEFPinType nil) (mappingTag nil))) (IbisIO_OpenPullUp ((temperature "27") (bufferModel "CDSDefaultIO_2p5v") (stimuli nil) (offsets nil) (state "tristate") (cycle "1") (termMap nil) (setup "2.0e-09") (hold "1.0e-09") (rise nil) (fall nil) (macroType nil) (voltage nil) (spice nil) (LEFDEFPinName nil) (LEFDEFPinType nil) (mappingTag nil)))))
				)
				( objectStatus "SPI_PCH_IO2" )
			)
			( electricalCSet "@crescent_city_bb_fab1_lib.crescent_city_bb_fab1(sch_1):\SPI_PCH_MOSI_R\"
				( groupRef "SPI_PCH_MOSI_R:SPI_PCH-MUX" )
				( groupRef "SPI_PCH_MOSI_R:SPI_PCH-TPM" )
				( pinPairRef "SPI_PCH_MOSI_R:U7C1.H4:U8F1.5" )
				( pinPairRef "SPI_PCH_MOSI_R:U7C1.H4:J8E1.3" )
				( attribute "TOPOLOGY_TEMPLATE_REVISION" "1.0"
					( Origin gBackEnd )
				)
				( topologyData 32427
(SKIDL (Circuits ("MAIN" (Parts ("CRESCENT_CITY_902_20150507_Q.@@J8E1.3" IbisIOPkg (xy (5534 4221)) (refDes "J8E1") (model "Unknown") (Props (_SXDesignName "CRESCENT_CITY_902_20150507_Q") (brdx "16320 MIL") (brdy "2501.74 MIL") (bufferModel "CDSDefaultIO_2p5v") (cycle "1") (hold "1.0e-09") (mappingTag "") (offsets ("4" "0") ("5" "0")) (setup "2.0e-09") (state "tristate") (stimuli ("5" "local91") ("4" "local90")) (temperature "27") (termMap ("4" "Data") ("5" "Enable"))) (Terms ("CRESCENT_CITY_902_20150507_Q.X1632000Y250174L2LRATS" "3"))) ("CRESCENT_CITY_902_20150507_Q.@@U7C1.H4" IbisIOPkg (xy (5502 4240)) (refDes "U7C1") (model "Unknown") (Props (_SXDesignName "CRESCENT_CITY_902_20150507_Q") (brdx "14861.61 MIL") (brdy "3731.89 MIL") (bufferModel "CDSDefaultIO_2p5v") (cycle "1") (hold "1.0e-09") (mappingTag "") (offsets ("4" "0") ("5" "0")) (setup "2.0e-09") (state "tristate") (stimuli ("5" "local93") ("4" "local92")) (temperature "27") (termMap ("4" "Data") ("5" "Enable"))) (Terms ("CRESCENT_CITY_902_20150507_Q.X1486161Y373189L2LRATS" "H4"))) ("CRESCENT_CITY_902_20150507_Q.@@U8F1.5" IbisIOPkg (xy (5519 4227)) (refDes "U8F1") (model "Unknown") (Props (_SXDesignName "CRESCENT_CITY_902_20150507_Q") (brdx "15580 MIL") (brdy "1520 MIL") (bufferModel "CDSDefaultIO_2p5v") (cycle "1") (hold "1.0e-09") (mappingTag "") (offsets ("4" "0") ("5" "0")) (setup "2.0e-09") (state "tristate") (stimuli ("5" "local95") ("4" "local94")) (temperature "27") (termMap ("4" "Data") ("5" "Enable"))) (Terms ("CRESCENT_CITY_902_20150507_Q.X1558000Y152000L2LRATS" "5"))) ("CRESCENT_CITY_902_20150507_Q.@@J9A3.6" Connector (xy (5435 4232)) (refDes "J9A3") (Props (_SXDesignName "CRESCENT_CITY_902_20150507_Q") (brdx "17997.25 MIL") (brdy "5382.83 MIL") (pin_use "1")) (Terms ("CRESCENT_CITY_902_20150507_Q.X1799725Y538283L2LRATS" "6"))) ("CRESCENT_CITY_902_20150507_Q.T@@RATS@@U7C1.H4@@R7C15.1" TLine (xy (5503 4229)) (mirror x) (refDes "TL63") (Props (_SXDesignName "CRESCENT_CITY_902_20150507_Q") (impedance "52.449 ohm") length("245.07 MIL") (propDelay "0.04402 ns") (traceCount "1") (traceGeometry "Microstrip") (velocity "5567.24 mil/ns")) (Terms ("CRESCENT_CITY_902_20150507_Q.X1486161Y373189L2LRATS" "1") ("CRESCENT_CITY_902_20150507_Q.X1480723Y354120L2LRATS" "2"))) ("CRESCENT_CITY_902_20150507_Q.@@R8E2.2.1" Resistor (xy (5464 4229)) (mirror x) (refDes "R8E2") (value "1000 Ohm") (Props (_SXDesignName "CRESCENT_CITY_902_20150507_Q")) (Terms ("CRESCENT_CITY_902_20150507_Q.X1645000Y253345L2LRATS" "2") ("CRESCENT_CITY_902_20150507_Q.X1641500Y253345L2LRATS" "1"))) ("CRESCENT_CITY_902_20150507_Q.@@R8E4.2.1" Resistor (xy (5479 4216)) (refDes "R8E4") (value "10000 Ohm") (Props (_SXDesignName "CRESCENT_CITY_902_20150507_Q")) (Terms ("CRESCENT_CITY_902_20150507_Q.X1641500Y246000L2RATS" "2") ("CRESCENT_CITY_902_20150507_Q.X1645000Y246000L2LRATS" "1"))) ("CRESCENT_CITY_902_20150507_Q.@@R8E6.1.2" Resistor (xy (5495 4216)) (refDes "R8E6") (value "10000 Ohm") (Props (_SXDesignName "CRESCENT_CITY_902_20150507_Q")) (Terms ("CRESCENT_CITY_902_20150507_Q.X1641500Y242500L2RATS" "1") ("CRESCENT_CITY_902_20150507_Q.X1645000Y242500L2LRATS" "2"))) ("CRESCENT_CITY_902_20150507_Q.T@@RATS@@R8E10.2@@J8E1.3" TLine (xy (5525 4216)) (refDes "TL64") (Props (_SXDesignName "CRESCENT_CITY_902_20150507_Q") (impedance "48.412 ohm") length("345.68 MIL") (propDelay "0.06209 ns") (traceCount "1") (traceGeometry "Microstrip") (velocity "5567.4 mil/ns")) (Terms ("CRESCENT_CITY_902_20150507_Q.X1623551Y224055L2LRATS" "1") ("CRESCENT_CITY_902_20150507_Q.X1632000Y250174L2LRATS" "2"))) ("CRESCENT_CITY_902_20150507_Q.T@@RATS@@R8E2.2@@R8E4.1" TLine (xy (5479 4222)) (refDes "TL65") (Props (_SXDesignName "CRESCENT_CITY_902_20150507_Q") (impedance "48.412 ohm") length("73.45 MIL") (propDelay "0.01319 ns") (traceCount "1") (traceGeometry "Microstrip") (velocity "5568.62 mil/ns")) (Terms ("CRESCENT_CITY_902_20150507_Q.X1645000Y253345L2LRATS" "1") ("CRESCENT_CITY_902_20150507_Q.X1645000Y246000L2LRATS" "2"))) ("CRESCENT_CITY_902_20150507_Q.T@@RATS@@R8E10.1@@U8F1.5" TLine (xy (5510 4222)) (refDes "TL66") (Props (_SXDesignName "CRESCENT_CITY_902_20150507_Q") (impedance "48.412 ohm") length("1411.06 MIL") (propDelay "0.25344 ns") (traceCount "1") (traceGeometry "Microstrip") (velocity "5567.64 mil/ns")) (Terms ("CRESCENT_CITY_902_20150507_Q.X1623551Y227555L2LRATS" "1") ("CRESCENT_CITY_902_20150507_Q.X1558000Y152000L2LRATS" "2"))) ("CRESCENT_CITY_902_20150507_Q.T@@RATS@@R7C15.2@@R8E2.2" TLine (xy (5479 4229)) (mirror x) (refDes "TL67") (Props (_SXDesignName "CRESCENT_CITY_902_20150507_Q") (impedance "48.412 ohm") length("2615.52 MIL") (propDelay "0.46977 ns") (traceCount "1") (traceGeometry "Microstrip") (velocity "5567.68 mil/ns")) (Terms ("CRESCENT_CITY_902_20150507_Q.X1484223Y354120L2LRATS" "1") ("CRESCENT_CITY_902_20150507_Q.X1645000Y253345L2LRATS" "2"))) ("CRESCENT_CITY_902_20150507_Q.T@@RATS@@R8E6.2@@R8E10.1" TLine (xy (5501 4222)) (refDes "TL68") (Props (_SXDesignName "CRESCENT_CITY_902_20150507_Q") (impedance "48.412 ohm") length("363.94 MIL") (propDelay "0.06537 ns") (traceCount "1") (traceGeometry "Microstrip") (velocity "5567.4 mil/ns")) (Terms ("CRESCENT_CITY_902_20150507_Q.X1645000Y242500L2LRATS" "1") ("CRESCENT_CITY_902_20150507_Q.X1623551Y227555L2LRATS" "2"))) ("CRESCENT_CITY_902_20150507_Q.@@R7C15.2.1" Resistor (xy (5488 4229)) (refDes "R7C15") (value "33.2 Ohm") (Props (_SXDesignName "CRESCENT_CITY_902_20150507_Q")) (Terms ("CRESCENT_CITY_902_20150507_Q.X1484223Y354120L2LRATS" "2") ("CRESCENT_CITY_902_20150507_Q.X1480723Y354120L2LRATS" "1"))) ("CRESCENT_CITY_902_20150507_Q.T@@RATS@@R8E2.1@@J9A3.6" TLine (xy (5449 4229)) (mirror x) (refDes "TL69") (Props (_SXDesignName "CRESCENT_CITY_902_20150507_Q") (impedance "48.412 ohm") length("4431.61 MIL") (propDelay "0.79595 ns") (traceCount "1") (traceGeometry "Microstrip") (velocity "5567.72 mil/ns")) (Terms ("CRESCENT_CITY_902_20150507_Q.X1641500Y253345L2LRATS" "1") ("CRESCENT_CITY_902_20150507_Q.X1799725Y538283L2LRATS" "2"))) ("CRESCENT_CITY_902_20150507_Q.@@R8E10.2.1" Resistor (xy (5510 4216)) (mirror x) (refDes "R8E10") (value "33.2 Ohm") (Props (_SXDesignName "CRESCENT_CITY_902_20150507_Q")) (Terms ("CRESCENT_CITY_902_20150507_Q.X1623551Y224055L2LRATS" "2") ("CRESCENT_CITY_902_20150507_Q.X1623551Y227555L2LRATS" "1"))) ("CRESCENT_CITY_902_20150507_Q.@@R8E4.2_SOURCE" Source (xy (5472 4216)) (refDes "GND") (value "0 V") (Props (_SXDesignName "CRESCENT_CITY_902_20150507_Q")) (Terms ("CRESCENT_CITY_902_20150507_Q.X1641500Y246000L2RATS" "1"))) ("CRESCENT_CITY_902_20150507_Q.@@R8E6.1_SOURCE" Source (xy (5488 4216)) (refDes "P3V3_STBY") (value "3.3 V") (Props (_SXDesignName "CRESCENT_CITY_902_20150507_Q")) (Terms ("CRESCENT_CITY_902_20150507_Q.X1641500Y242500L2RATS" "1"))) ("CRESCENT_CITY_902_20150507_Q.T@@RATS@@R8E4.1@@R8E6.2" TLine (xy (5488 4222)) (refDes "TL70") (Props (_SXDesignName "CRESCENT_CITY_902_20150507_Q") (impedance "48.412 ohm") length("35.00 MIL") (propDelay "0.00629 ns") (traceCount "1") (traceGeometry "Microstrip") (velocity "5564.37 mil/ns")) (Terms ("CRESCENT_CITY_902_20150507_Q.X1645000Y246000L2LRATS" "1") ("CRESCENT_CITY_902_20150507_Q.X1645000Y242500L2LRATS" "2")))) (Nodes ("CRESCENT_CITY_902_20150507_Q.X1632000Y250174L2LRATS" (terms "CRESCENT_CITY_902_20150507_Q.T@@RATS@@R8E10.2@@J8E1.3.2" "CRESCENT_CITY_902_20150507_Q.@@J8E1.3.1")) ("CRESCENT_CITY_902_20150507_Q.X1558000Y152000L2LRATS" (terms "CRESCENT_CITY_902_20150507_Q.T@@RATS@@R8E10.1@@U8F1.5.2" "CRESCENT_CITY_902_20150507_Q.@@U8F1.5.1")) ("CRESCENT_CITY_902_20150507_Q.X1645000Y246000L2LRATS" (terms "CRESCENT_CITY_902_20150507_Q.T@@RATS@@R8E4.1@@R8E6.2.1" "CRESCENT_CITY_902_20150507_Q.T@@RATS@@R8E2.2@@R8E4.1.2" "CRESCENT_CITY_902_20150507_Q.@@R8E4.2.1.2")) ("CRESCENT_CITY_902_20150507_Q.X1484223Y354120L2LRATS" (terms "CRESCENT_CITY_902_20150507_Q.@@R7C15.2.1.1" "CRESCENT_CITY_902_20150507_Q.T@@RATS@@R7C15.2@@R8E2.2.1")) ("CRESCENT_CITY_902_20150507_Q.X1641500Y246000L2RATS" (terms "CRESCENT_CITY_902_20150507_Q.@@R8E4.2_SOURCE.1" "CRESCENT_CITY_902_20150507_Q.@@R8E4.2.1.1")) ("CRESCENT_CITY_902_20150507_Q.X1641500Y242500L2RATS" (terms "CRESCENT_CITY_902_20150507_Q.@@R8E6.1_SOURCE.1" "CRESCENT_CITY_902_20150507_Q.@@R8E6.1.2.1")) ("CRESCENT_CITY_902_20150507_Q.X1645000Y242500L2LRATS" (terms "CRESCENT_CITY_902_20150507_Q.T@@RATS@@R8E4.1@@R8E6.2.2" "CRESCENT_CITY_902_20150507_Q.T@@RATS@@R8E6.2@@R8E10.1.1" "CRESCENT_CITY_902_20150507_Q.@@R8E6.1.2.2")) ("CRESCENT_CITY_902_20150507_Q.X1799725Y538283L2LRATS" (terms "CRESCENT_CITY_902_20150507_Q.T@@RATS@@R8E2.1@@J9A3.6.2" "CRESCENT_CITY_902_20150507_Q.@@J9A3.6.1")) ("CRESCENT_CITY_902_20150507_Q.X1645000Y253345L2LRATS" (terms "CRESCENT_CITY_902_20150507_Q.T@@RATS@@R7C15.2@@R8E2.2.2" "CRESCENT_CITY_902_20150507_Q.T@@RATS@@R8E2.2@@R8E4.1.1" "CRESCENT_CITY_902_20150507_Q.@@R8E2.2.1.1")) ("CRESCENT_CITY_902_20150507_Q.X1641500Y253345L2LRATS" (terms "CRESCENT_CITY_902_20150507_Q.T@@RATS@@R8E2.1@@J9A3.6.1" "CRESCENT_CITY_902_20150507_Q.@@R8E2.2.1.2")) ("CRESCENT_CITY_902_20150507_Q.X1623551Y227555L2LRATS" (terms "CRESCENT_CITY_902_20150507_Q.@@R8E10.2.1.2" "CRESCENT_CITY_902_20150507_Q.T@@RATS@@R8E6.2@@R8E10.1.2" "CRESCENT_CITY_902_20150507_Q.T@@RATS@@R8E10.1@@U8F1.5.1")) ("CRESCENT_CITY_902_20150507_Q.X1486161Y373189L2LRATS" (terms "CRESCENT_CITY_902_20150507_Q.T@@RATS@@U7C1.H4@@R7C15.1.1" "CRESCENT_CITY_902_20150507_Q.@@U7C1.H4.1")) ("CRESCENT_CITY_902_20150507_Q.X1480723Y354120L2LRATS" (terms "CRESCENT_CITY_902_20150507_Q.@@R7C15.2.1.2" "CRESCENT_CITY_902_20150507_Q.T@@RATS@@U7C1.H4@@R7C15.1.2")) ("CRESCENT_CITY_902_20150507_Q.X1623551Y224055L2LRATS" (terms "CRESCENT_CITY_902_20150507_Q.@@R8E10.2.1.1" "CRESCENT_CITY_902_20150507_Q.T@@RATS@@R8E10.2@@J8E1.3.1"))) (Ports) (Stimuli ("local92" (scope local) (stimType periodic) (Props (periodicFreq "5e+007") (periodicJitter "0") (periodicPattern "1"))) ("local95" (scope local) (stimType periodic) (Props (periodicFreq "5e+007") (periodicJitter "0") (periodicPattern "1"))) ("local90" (scope local) (stimType periodic) (Props (periodicFreq "5e+007") (periodicJitter "0") (periodicPattern "1"))) ("local94" (scope local) (stimType periodic) (Props (periodicFreq "5e+007") (periodicJitter "0") (periodicPattern "1"))) ("local91" (scope local) (stimType periodic) (Props (periodicFreq "5e+007") (periodicJitter "0") (periodicPattern "1"))) ("local93" (scope local) (stimType periodic) (Props (periodicFreq "5e+007") (periodicJitter "0") (periodicPattern "1")))) (Notes) (Constraints ("RELATIVE_PROPAGATION_DELAY" ("SPI_PCH-MUX" "CRESCENT_CITY_902_20150507_Q U7C1.H4" "CRESCENT_CITY_902_20150507_Q U8F1.5" "GLOBAL" "LENGTH" "0.00635" "LENGTH" "0") ("SPI_PCH-TPM" "CRESCENT_CITY_902_20150507_Q U7C1.H4" "CRESCENT_CITY_902_20150507_Q J8E1.3" "GLOBAL" "LENGTH" "0.00635" "LENGTH" "0"))) (MeasurementSets ("EMI" ("EMIStatus" status("on")) ("PeakEmission" status("on")) ("PeakFrequency" status("on")) ("PulseFreq" status("on")) ("RiseTime" status("on")) ("VoltageSwing" status("on"))) ("Reflection" ("BufferDelayFall" status("off")) ("BufferDelayRise" status("off")) ("EyeHeight" status("off")) ("EyeJitter" status("off")) ("EyeWidth" status("off")) ("FirstIncidentFall" status("off")) ("FirstIncidentRise" status("off")) ("Glitch" status("on")) ("GlitchFall" status("off")) ("GlitchRise" status("off")) ("Monotonic" status("on")) ("MonotonicFall" status("off")) ("MonotonicRise" status("off")) ("NoiseMargin" status("on")) ("NoiseMarginHigh" status("off")) ("NoiseMarginLow" status("off")) ("OvershootHigh" status("on")) ("OvershootLow" status("on")) ("PropDelay" status("on")) ("SettleDelay" status("on")) ("SettleDelayFall" status("off")) ("SettleDelayRise" status("off")) ("SwitchDelay" status("on")) ("SwitchDelayFall" status("off")) ("SwitchDelayRise" status("off"))) ("Crosstalk" ("Crosstalk" status("on"))) ("Custom")) (VectorSets) (Props (XnetName "SPI_PCH_MOSI_R") (allDrivers "active") (customSimType "Reflection") (ftsMode ("Typ")) (rcvrSelect "all") (tlineDelayMode "time") (userRevision "1.0")))) (Subckts) (CrossSections ("CRESCENT_CITY_902_20150507_Q" (Props (SXDesignName "CRESCENT_CITY_902_20150507_Q")) (Layers ("" (layerType "SURFACE") (material "AIR") (thickness "0 mil") (dielectricConstant "1.000000") (lossTangent "0") (etchFactor "0.000000") (elecCondVal "0 mho/cm") (thermCondVal "0 w/cm-degC")) ("" (layerType "DIELECTRIC") (material "CONFORMAL_COAT") (thickness "0.5 mil") (dielectricConstant "3.800000") (lossTangent "0.035") (etchFactor "0.000000") (elecCondVal "0 mho/cm") (thermCondVal "0.012 w/cm-degC")) ("TOP" (layerType "CONDUCTOR") (material "COPPER") (thickness "  2.100000 mil") (width "4.00 MIL") (dielectricConstant "4.500000") (lossTangent "0") (etchFactor "70.000000") (elecCondVal "595900.000000 mho/cm") (thermCondVal "0 w/cm-degC") (signalDieConstant "3.800000") (signalLossTangent "0.035")) ("" (layerType "DIELECTRIC") (material "FR-4") (thickness "  2.670000 mil") (dielectricConstant "4.000000") (lossTangent "0.035") (etchFactor "0.000000") (elecCondVal "0 mho/cm") (thermCondVal "0.012 w/cm-degC")) ("L2_GND1" (layerType "PLANE") (material "COPPER") (isShield t) (thickness "  1.250000 mil") (dielectricConstant "4.500000") (lossTangent "0.035") (etchFactor "90.000000") (elecCondVal "595900.000000 mho/cm") (thermCondVal "0.012 w/cm-degC")) ("" (layerType "DIELECTRIC") (material "FR-4") (thickness "  9.000000 mil") (dielectricConstant "4.100000") (lossTangent "0.035") (etchFactor "0.000000") (elecCondVal "0 mho/cm") (thermCondVal "0.012 w/cm-degC")) ("L3_SIG1" (layerType "CONDUCTOR") (material "COPPER") (thickness "  1.250000 mil") (width "4.00 MIL") (dielectricConstant "4.500000") (lossTangent "0.035") (etchFactor "90.000000") (elecCondVal "595900.000000 mho/cm") (thermCondVal "0.012 w/cm-degC") (signalDieConstant "4.100000") (signalLossTangent "0.035")) ("" (layerType "DIELECTRIC") (material "FR-4") (thickness "  3.000000 mil") (dielectricConstant "4.500000") (lossTangent "0.035") (etchFactor "0.000000") (elecCondVal "0 mho/cm") (thermCondVal "0 w/cm-degC")) ("L4_GND2" (layerType "PLANE") (material "COPPER") (isShield t) (thickness "  1.250000 mil") (dielectricConstant "4.500000") (lossTangent "0.035") (etchFactor "90.000000") (elecCondVal "595900.000000 mho/cm") (thermCondVal "0 w/cm-degC")) ("" (layerType "DIELECTRIC") (material "FR-4") (thickness "  9.000000 mil") (dielectricConstant "4.000000") (lossTangent "0.035") (etchFactor "0.000000") (elecCondVal "0 mho/cm") (thermCondVal "0.012 w/cm-degC")) ("L5_SIG2" (layerType "CONDUCTOR") (material "COPPER") (thickness "  1.250000 mil") (width "4.00 MIL") (dielectricConstant "4.500000") (lossTangent "0.035") (etchFactor "90.000000") (elecCondVal "595900.000000 mho/cm") (thermCondVal "0.012 w/cm-degC") (signalDieConstant "4.000000") (signalLossTangent "0.035")) ("" (layerType "DIELECTRIC") (material "FR-4") (thickness "  3.000000 mil") (dielectricConstant "4.500000") (lossTangent "0.035") (etchFactor "0.000000") (elecCondVal "0 mho/cm") (thermCondVal "0 w/cm-degC")) ("L6_GND3" (layerType "PLANE") (material "COPPER") (isShield t) (thickness "  1.250000 mil") (dielectricConstant "4.500000") (lossTangent "0.035") (etchFactor "90.000000") (elecCondVal "595900.000000 mho/cm") (thermCondVal "0 w/cm-degC")) ("" (layerType "DIELECTRIC") (material "FR-4") (thickness "  4.500000 mil") (dielectricConstant "4.100000") (lossTangent "0.035") (etchFactor "0.000000") (elecCondVal "0 mho/cm") (thermCondVal "0.012 w/cm-degC")) ("L7_PWR1-SIG" (layerType "PLANE") (material "COPPER") (isShield t) (thickness "  2.610000 mil") (dielectricConstant "4.500000") (lossTangent "0.035") (etchFactor "90.000000") (elecCondVal "595900.000000 mho/cm") (thermCondVal "0.012 w/cm-degC")) ("" (layerType "DIELECTRIC") (material "FR-4") (thickness "  3.100000 mil") (dielectricConstant "4.500000") (lossTangent "0.035") (etchFactor "0.000000") (elecCondVal "0 mho/cm") (thermCondVal "0 w/cm-degC")) ("L8_GND_TEMP" (layerType "PLANE") (material "COPPER") (isShield t) (thickness "  1.250000 mil") (dielectricConstant "4.500000") (lossTangent "0.035") (etchFactor "90.000000") (elecCondVal "595900.000000 mho/cm") (thermCondVal "0 w/cm-degC")) ("" (layerType "DIELECTRIC") (material "FR-4") (thickness "  3.030000 mil") (dielectricConstant "4.500000") (lossTangent "0.035") (etchFactor "0.000000") (elecCondVal "0 mho/cm") (thermCondVal "0 w/cm-degC")) ("L9_SIG_TEMP" (layerType "CONDUCTOR") (material "COPPER") (thickness "  1.250000 mil") (width "3.52 MIL") (dielectricConstant "4.500000") (lossTangent "0.035") (etchFactor "90.000000") (elecCondVal "595900.000000 mho/cm") (thermCondVal "0 w/cm-degC") (signalDieConstant "4.500000") (signalLossTangent "0.035")) ("" (layerType "DIELECTRIC") (material "FR-4") (thickness "  5.000000 mil") (dielectricConstant "4.500000") (lossTangent "0.035") (etchFactor "0.000000") (elecCondVal "0 mho/cm") (thermCondVal "0 w/cm-degC")) ("L10_SIG_TEMP" (layerType "CONDUCTOR") (material "COPPER") (thickness "  1.250000 mil") (width "3.52 MIL") (dielectricConstant "4.500000") (lossTangent "0.035") (etchFactor "90.000000") (elecCondVal "595900.000000 mho/cm") (thermCondVal "0 w/cm-degC") (signalDieConstant "4.500000") (signalLossTangent "0.035")) ("" (layerType "DIELECTRIC") (material "FR-4") (thickness "  3.030000 mil") (dielectricConstant "4.500000") (lossTangent "0.035") (etchFactor "0.000000") (elecCondVal "0 mho/cm") (thermCondVal "0 w/cm-degC")) ("L11_GND_TEMP" (layerType "PLANE") (material "COPPER") (isShield t) (thickness "  1.250000 mil") (dielectricConstant "4.500000") (lossTangent "0.035") (etchFactor "90.000000") (elecCondVal "595900.000000 mho/cm") (thermCondVal "0 w/cm-degC")) ("" (layerType "DIELECTRIC") (material "FR-4") (thickness "  3.100000 mil") (dielectricConstant "4.000000") (lossTangent "0.035") (etchFactor "0.000000") (elecCondVal "0 mho/cm") (thermCondVal "0.012 w/cm-degC")) ("L12_PWR2-SIG" (layerType "PLANE") (material "COPPER") (isShield t) (thickness "  2.610000 mil") (dielectricConstant "4.500000") (lossTangent "0.035") (etchFactor "90.000000") (elecCondVal "595900.000000 mho/cm") (thermCondVal "0.012 w/cm-degC")) ("" (layerType "DIELECTRIC") (material "FR-4") (thickness "  4.500000 mil") (dielectricConstant "4.500000") (lossTangent "0.035") (etchFactor "0.000000") (elecCondVal "0 mho/cm") (thermCondVal "0 w/cm-degC")) ("L13_GND4" (layerType "PLANE") (material "COPPER") (isShield t) (thickness "  1.250000 mil") (dielectricConstant "4.500000") (lossTangent "0.035") (etchFactor "90.000000") (elecCondVal "595900.000000 mho/cm") (thermCondVal "0 w/cm-degC")) ("" (layerType "DIELECTRIC") (material "FR-4") (thickness "  3.000000 mil") (dielectricConstant "4.100000") (lossTangent "0.035") (etchFactor "0.000000") (elecCondVal "0 mho/cm") (thermCondVal "0.012 w/cm-degC")) ("L14_SIG3" (layerType "CONDUCTOR") (material "COPPER") (thickness "  1.250000 mil") (width "4.00 MIL") (dielectricConstant "4.500000") (lossTangent "0.035") (etchFactor "90.000000") (elecCondVal "595900.000000 mho/cm") (thermCondVal "0.012 w/cm-degC") (signalDieConstant "4.100000") (signalLossTangent "0.035")) ("" (layerType "DIELECTRIC") (material "FR-4") (thickness "  9.000000 mil") (dielectricConstant "4.500000") (lossTangent "0.035") (etchFactor "0.000000") (elecCondVal "0 mho/cm") (thermCondVal "0 w/cm-degC")) ("L15_GND5" (layerType "PLANE") (material "COPPER") (isShield t) (thickness "  1.250000 mil") (dielectricConstant "4.500000") (lossTangent "0.035") (etchFactor "90.000000") (elecCondVal "595900.000000 mho/cm") (thermCondVal "0 w/cm-degC")) ("" (layerType "DIELECTRIC") (material "FR-4") (thickness "  3.000000 mil") (dielectricConstant "4.500000") (lossTangent "0.035") (etchFactor "0.000000") (elecCondVal "0 mho/cm") (thermCondVal "0.012 w/cm-degC")) ("L16_SIG4" (layerType "CONDUCTOR") (material "COPPER") (thickness "  1.250000 mil") (width "4.00 MIL") (dielectricConstant "4.500000") (lossTangent "0.035") (etchFactor "90.000000") (elecCondVal "595900.000000 mho/cm") (thermCondVal "0.012 w/cm-degC") (signalDieConstant "4.500000") (signalLossTangent "0.035")) ("" (layerType "DIELECTRIC") (material "FR-4") (thickness "  9.000000 mil") (dielectricConstant "4.500000") (lossTangent "0.035") (etchFactor "0.000000") (elecCondVal "0 mho/cm") (thermCondVal "0 w/cm-degC")) ("L17_GND6" (layerType "PLANE") (material "COPPER") (isShield t) (thickness "  1.250000 mil") (dielectricConstant "4.500000") (lossTangent "0.035") (etchFactor "90.000000") (elecCondVal "595900.000000 mho/cm") (thermCondVal "0.012 w/cm-degC")) ("" (layerType "DIELECTRIC") (material "FR-4") (thickness "  2.670000 mil") (dielectricConstant "4.500000") (lossTangent "0.035") (etchFactor "0.000000") (elecCondVal "0 mho/cm") (thermCondVal "0.012 w/cm-degC")) ("BOTTOM" (layerType "CONDUCTOR") (material "COPPER") (thickness "  2.100000 mil") (width "4.00 MIL") (dielectricConstant "4.500000") (lossTangent "0") (etchFactor "70.000000") (elecCondVal "595900.000000 mho/cm") (thermCondVal "0 w/cm-degC") (signalDieConstant "3.800000") (signalLossTangent "0.035")) ("" (layerType "DIELECTRIC") (material "CONFORMAL_COAT") (thickness "0.5 mil") (dielectricConstant "3.800000") (lossTangent "0.035") (etchFactor "0.000000") (elecCondVal "0 mho/cm") (thermCondVal "0.012 w/cm-degC")) ("" (layerType "SURFACE") (material "AIR") (thickness "0 mil") (dielectricConstant "1.000000") (lossTangent "0") (etchFactor "0.000000") (elecCondVal "0 mho/cm") (thermCondVal "0 w/cm-degC"))))) (Props (DesUnits "mils 2") (LayerStack ("DIELECTRIC" "DIELECTRIC" "BOTTOM" "DIELECTRIC" "L17_GND6" "DIELECTRIC" "L16_SIG4" "DIELECTRIC" "L15_GND5" "DIELECTRIC" "L14_SIG3" "DIELECTRIC" "L13_GND4" "DIELECTRIC" "L12_PWR2-SIG" "DIELECTRIC" "L11_GND_TEMP" "DIELECTRIC" "L10_SIG_TEMP" "DIELECTRIC" "L9_SIG_TEMP" "DIELECTRIC" "L8_GND_TEMP" "DIELECTRIC" "L7_PWR1-SIG" "DIELECTRIC" "L6_GND3" "DIELECTRIC" "L5_SIG2" "DIELECTRIC" "L4_GND2" "DIELECTRIC" "L3_SIG1" "DIELECTRIC" "L2_GND1" "DIELECTRIC" "TOP" "DIELECTRIC" "DIELECTRIC")) (Revision "16.600")) (Params (DiffInputPkg ((temperature "27") (bufferModelNonInverting "CDSDefaultInput_2p5v") (bufferModelInverting "CDSDefaultInput_2p5v") (threshInputHighMin "1.7 V") (threshInputHighTyp "1.7  V") (threshInputHighMax "1.7  V") (threshInputLowMin "0.7  V") (threshInputLowTyp "0.7  V") (threshInputLowMax "0.7  V") (mappingTagNonInverting nil) (mappingTagInverting nil) (cycle "1"))) (IbisOutputPkg ((temperature "27") (bufferModel "CDSDefaultOutput_2p5v") (stimuli nil) (offsets nil) (state "tristate") (cycle "1") (termMap nil) (setup "2.0e-09") (hold "1.0e-09") (rise nil) (fall nil) (macroType nil) (voltage nil) (spice nil) (LEFDEFPinName nil) (LEFDEFPinType nil) (mappingTag nil))) (IbisIOPkg ((temperature "27") (bufferModel "CDSDefaultIO_2p5v") (stimuli nil) (offsets nil) (state "tristate") (cycle "1") (termMap nil) (setup "2.0e-09") (hold "1.0e-09") (rise nil) (fall nil) (macroType nil) (voltage nil) (spice nil) (LEFDEFPinName nil) (LEFDEFPinType nil) (mappingTag nil))) (IbisIOMacro ((temperature "27") (bufferModel "CDSDefaultIO_2p5v") (stimuli nil) (offsets nil) (state "tristate") (cycle "1") (termMap nil) (setup "2.0e-09") (hold "1.0e-09") (rise nil) (fall nil) (macroType nil) (voltage nil) (spice nil) (LEFDEFPinName nil) (LEFDEFPinType nil) (mappingTag nil))) (ESpiceDevice nil) (IbisInput ((temperature "27") (bufferModel "CDSDefaultInput_2p5v") (cycle "1") (LEFDEFPinName nil) (LEFDEFPinType nil) (mappingTag nil))) (ShuntTerm ((resistance "50 ohm") (voltage "5 V") (maxDelay "0.1 ns"))) (SeriesTerm ((resistance "22 ohm") (maxDelay "0.1 ns"))) (CurrentProbe nil) (idlCircuit ((allDrivers "active") (ftsMode '("Typ")) (rcvrSelect "all") (simMode "Reflection") (tlineDelayMode "time") (userRevision "1.0") (autoSolve "On"))) (TheveninTerm ((resistanceUp "180 ohm") (resistanceDown "270 ohm") (voltageUp "5 V") (voltageDown "0 V") (maxDelay "0.1 ns"))) (RCTerm ((resistance "50 ohm") (capacitance "20 pF") (voltage "5 V") (maxDelay "0.1 ns"))) (LowClampTerm ((cutoffVoltage "0.7 V") (voltage "0 V") (maxDelay "0.1 ns"))) (Cable (length("1 m"))) (HiClampTerm ((cutoffVoltage "0.7 V") (voltage "5 V") (maxDelay "0.1 ns"))) (DualClampTerm ((cutoffVoltageUp "0.7 V") (cutoffVoltageDown "0.7 V") (voltageUp "5 V") (voltageDown "0 V") (maxDelay "0.1 ns"))) (IbisInputPkg ((temperature "27") (bufferModel "CDSDefaultInput_2p5v") (cycle "1") (LEFDEFPinName nil) (LEFDEFPinType nil) (mappingTag nil))) (async ((asyncTimePoints "") (asyncInitState "1"))) (clocked ((clockRise "1e-09") (clockFall "1e-09") (clockFreq "100e6") (clockInitState "0") (clockDutyCycle "0.5") (clockJitter "0"))) (Diode ((cutoffVoltage "0.7 V"))) (IbisOutput ((temperature "27") (bufferModel "CDSDefaultOutput_2p5v") (stimuli nil) (offsets nil) (state "tristate") (cycle "1") (termMap nil) (setup "2.0e-09") (hold "1.0e-09") (rise nil) (fall nil) (macroType nil) (voltage nil) (spice nil) (LEFDEFPinName nil) (LEFDEFPinType nil) (mappingTag nil))) (periodic ((periodicFreq "100e6") (periodicPattern "10") (periodicJitter "0"))) (IbisIO ((temperature "27") (bufferModel "CDSDefaultIO_2p5v") (stimuli nil) (offsets nil) (state "tristate") (cycle "1") (termMap nil) (setup "2.0e-09") (hold "1.0e-09") (rise nil) (fall nil) (macroType nil) (voltage nil) (spice nil) (LEFDEFPinName nil) (LEFDEFPinType nil) (mappingTag nil))) (Via ((model "Unknown") (viaOutputFormat "Unknown") (viaPadstack nil) (viaTopLayer nil) (viaBottomLayer nil) (viaIsPower nil) (viaIsGround nil))) (CPWMS ((d1Thickness "10 mil") (d1Constant "4.5") (d1LossTangent "0.035") (d2Thickness "0.72 mil") (d2Constant "4.5") (d2LossTangent "0.035") (d3Thickness "0.0") (d3Constant "1") (d3LossTangent "0") length("1000 mil") (spacing "5 mil") (spacing2 "5 mil") (spacing3 "5 mil") (spacing4 "5 mil") (spacing5 "5 mil") (traceConductivity "595900 mho/cm") (traceGeometry "cpwms") (traceLayerName "") (traceThickness "0.72 mil") (traceType "single") (traceWidth "5.0 mil") (traceWidth2 "5.0 mil") (traceWidth3 "5.0 mil") (traceWidth4 "5.0 mil") (traceWidth5 "5.0 mil") (traceWidth6 "5.0 mil") (offset "0 mil") (traceCount "1") (impedance nil))) (Trace ((d1Thickness "10 mil") (d1Constant "4.5") (d1LossTangent "0.035") (d2Thickness "10 mil") (d2Constant "4.5") (d2LossTangent "0.035") (d3Thickness "0.0") (d3Constant "1.0") (d3LossTangent "0") length("1000 mil") (spacing "5 mil") (spacing2 "5 mil") (spacing3 "5 mil") (spacing4 "5 mil") (spacing5 "5 mil") (traceConductivity "595900 mho/cm") (traceGeometry "microstrip") (traceLayerName "") (traceThickness "0.72 mil") (traceType "single") (traceWidth "5.0 mil") (traceWidth2 "5.0 mil") (traceWidth3 "5.0 mil") (traceWidth4 "5.0 mil") (traceWidth5 "5.0 mil") (traceWidth6 "5.0 mil") (offset "0 mil") (traceCount "1") (impedance nil))) (Source ((voltage "5 V"))) (CPWSL ((d1Thickness "10 mil") (d1Constant "4.5") (d1LossTangent "0.035") (d2Thickness "0.72 mil") (d2Constant "4.5") (d2LossTangent "0.035") (d3Thickness "10 mil") (d3Constant "4.5") (d3LossTangent "0.035") length("1000 mil") (spacing "5 mil") (spacing2 "5 mil") (spacing3 "5 mil") (spacing4 "5 mil") (spacing5 "5 mil") (traceConductivity "595900 mho/cm") (traceGeometry "cpwms") (traceLayerName "") (traceThickness "0.72 mil") (traceType "single") (traceWidth "5.0 mil") (traceWidth2 "5.0 mil") (traceWidth3 "5.0 mil") (traceWidth4 "5.0 mil") (traceWidth5 "5.0 mil") (traceWidth6 "5.0 mil") (offset "0 mil") (traceCount "1") (impedance nil))) (RLGC (length("1000 mil"))) (Capacitor ((capacitance "10 pF") (orientation "0"))) (DiffIOPkg ((temperature "27") (bufferModelNonInverting "CDSDefaultIO_2p5v") (bufferModelInverting "CDSDefaultIO_2p5v") (stimuli nil) (offsets nil) (state "tristate") (cycle "1") (termMap nil) (setup "0.9e-09") (hold "0.4e-09") (rise nil) (fall nil) (threshInputHighMin "1.7 V") (threshInputHighTyp "1.7  V") (threshInputHighMax "1.7  V") (threshInputLowMin "0.7  V") (threshInputLowTyp "0.7  V") (threshInputLowMax "0.7 ") (threshOutputHighMin "2.365  V") (threshOutputHighTyp "2.5  V") (threshOutputHighMax "2.625  V") (threshOutputLowMin "1.275  V") (threshOutputLowTyp "1.7  V") (threshOutputLowMax "1.985  V") (mappingTagNonInverting nil) (mappingTagInverting nil) (spice nil))) (Inductor ((inductance "5 nH") (orientation "0"))) (DiffIO ((temperature "27") (bufferModelNonInverting "CDSDefaultIO_2p5v") (bufferModelInverting "CDSDefaultIO_2p5v") (stimuli nil) (offsets nil) (state "tristate") (cycle "1") (termMap nil) (setup "0.9e-09") (hold "0.4e-09") (rise nil) (fall nil) (threshInputHighMin "1.7 V") (threshInputHighTyp "1.7  V") (threshInputHighMax "1.7  V") (threshInputLowMin "0.7  V") (threshInputLowTyp "0.7  V") (threshInputLowMax "0.7 ") (threshOutputHighMin "2.365  V") (threshOutputHighTyp "2.5  V") (threshOutputHighMax "2.625  V") (threshOutputLowMin "1.275  V") (threshOutputLowTyp "1.7  V") (threshOutputLowMax "1.985  V") (mappingTagNonInverting nil) (mappingTagInverting nil) (spice nil))) (CPW ((d1Thickness "10 mil") (d1Constant "4.5") (d1LossTangent "0.035") (d2Thickness "0.72 mil") (d2Constant "1") (d2LossTangent "0") (d3Thickness "0.0") (d3Constant "1") (d3LossTangent "0") length("1000 mil") (spacing "5 mil") (spacing2 "5 mil") (spacing3 "5 mil") (spacing4 "5 mil") (spacing5 "5 mil") (traceConductivity "595900 mho/cm") (traceGeometry "cpwms") (traceLayerName "") (traceThickness "0.72 mil") (traceType "single") (traceWidth "5.0 mil") (traceWidth2 "5.0 mil") (traceWidth3 "5.0 mil") (traceWidth4 "5.0 mil") (traceWidth5 "5.0 mil") (traceWidth6 "5.0 mil") (offset "0 mil") (traceCount "1") (impedance nil))) (Connector nil) (TLine ((diffImpedance "100ohm") (diffVelocity "1.4142e+08M/s") (impedance "60ohm") length("2800 mil") (propDelay "0.5 ns") (velocity "5600 mil/ns") (traceCount "1") (traceGeometry "Microstrip") (impedanceMin nil) (impedanceMax nil) (lengthMin nil) (lengthMax nil) (propDelayMin nil) (propDelayMax nil) (impedanceSweepCount nil) (propDelaySweepCount nil) (velocitySweepCount nil) (lengthSweepCount nil) (matchSetName nil))) (sync ((syncFreq "100e6") (syncInitState "1") (syncPattern "10") (syncEdgeSwitch "rise"))) (IbisIO_OpenPullDown ((temperature "27") (bufferModel "CDSDefaultIO_2p5v") (stimuli nil) (offsets nil) (state "tristate") (cycle "1") (termMap nil) (setup "2.0e-09") (hold "1.0e-09") (rise nil) (fall nil) (macroType nil) (voltage nil) (spice nil) (LEFDEFPinName nil) (LEFDEFPinType nil) (mappingTag nil))) (DiffOutputPkg ((temperature "27") (bufferModelNonInverting "CDSDefaultOutput_2p5v") (bufferModelInverting "CDSDefaultOutput_2p5v") (stimuli nil) (offsets nil) (state "tristate") (cycle "1") (termMap nil) (setup "0.9e-09") (hold "0.4e-09") (rise nil) (fall nil) (threshOutputHighMin "2.375  V") (threshOutputHighTyp "2.5  V") (threshOutputHighMax "2.625  V") (threshOutputLowMin "1.275  V") (threshOutputLowTyp "1.7  V") (threshOutputLowMax "1.985  V") (mappingTagNonInverting nil) (mappingTagInverting nil) (spice nil))) (DiffInput ((temperature "27") (bufferModelNonInverting "CDSDefaultInput_2p5v") (bufferModelInverting "CDSDefaultInput_2p5v") (threshInputHighMin "1.7 V") (threshInputHighTyp "1.7  V") (threshInputHighMax "1.7  V") (threshInputLowMin "0.7  V") (threshInputLowTyp "0.7  V") (threshInputLowMax "0.7  V") (mappingTagNonInverting nil) (mappingTagInverting nil) (cycle "1"))) (Resistor ((resistance "50 ohm") (orientation "0"))) (DiffOutput ((temperature "27") (bufferModelNonInverting "CDSDefaultOutput_2p5v") (bufferModelInverting "CDSDefaultOutput_2p5v") (stimuli nil) (offsets nil) (state "tristate") (cycle "1") (termMap nil) (setup "0.9e-09") (hold "0.4e-09") (rise nil) (fall nil) (threshOutputHighMin "2.375  V") (threshOutputHighTyp "2.5  V") (threshOutputHighMax "2.625  V") (threshOutputLowMin "1.275  V") (threshOutputLowTyp "1.7  V") (threshOutputLowMax "1.985  V") (mappingTagNonInverting nil) (mappingTagInverting nil) (spice nil))) (IbisOutput_OpenPullUp ((temperature "27") (bufferModel "CDSDefaultOutput_2p5v") (stimuli nil) (offsets nil) (state "tristate") (cycle "1") (termMap nil) (setup "2.0e-09") (hold "1.0e-09") (rise nil) (fall nil) (macroType nil) (voltage nil) (spice nil) (LEFDEFPinName nil) (LEFDEFPinType nil) (mappingTag nil))) (IbisIO_OpenPullUp ((temperature "27") (bufferModel "CDSDefaultIO_2p5v") (stimuli nil) (offsets nil) (state "tristate") (cycle "1") (termMap nil) (setup "2.0e-09") (hold "1.0e-09") (rise nil) (fall nil) (macroType nil) (voltage nil) (spice nil) (LEFDEFPinName nil) (LEFDEFPinType nil) (mappingTag nil)))))
				)
				( objectStatus "SPI_PCH_MOSI_R" )
			)
			( electricalCSet "@crescent_city_bb_fab1_lib.crescent_city_bb_fab1(sch_1):\SPI_PCH_MISO_R\"
				( groupRef "SPI_PCH_MISO_R:SPI_PCH-TPM" )
				( groupRef "SPI_PCH_MISO_R:SPI_PCH-MUX" )
				( pinPairRef "SPI_PCH_MISO_R:U7C1.L3:J8E1.4" )
				( pinPairRef "SPI_PCH_MISO_R:U7C1.L3:U8F1.14" )
				( attribute "TOPOLOGY_TEMPLATE_REVISION" "1.0"
					( Origin gBackEnd )
				)
				( topologyData 27816
(SKIDL (Circuits ("MAIN" (Parts ("CRESCENT_CITY_902_20150507_Q.@@U7C1.L3" IbisIOPkg (xy (5506 4227)) (refDes "U7C1") (model "Unknown") (Props (_SXDesignName "CRESCENT_CITY_902_20150507_Q") (brdx "14920.67 MIL") (brdy "3715.55 MIL") (bufferModel "CDSDefaultIO_2p5v") (cycle "1") (hold "1.0e-09") (mappingTag "") (offsets ("4" "0") ("5" "0")) (setup "2.0e-09") (state "tristate") (stimuli ("4" "local84") ("5" "local85")) (temperature "27") (termMap ("4" "Data") ("5" "Enable"))) (Terms ("CRESCENT_CITY_902_20150507_Q.X1492067Y371555L2LRATS" "L3"))) ("CRESCENT_CITY_902_20150507_Q.@@J8E1.4" IbisIOPkg (xy (5521 4221)) (refDes "J8E1") (model "Unknown") (Props (_SXDesignName "CRESCENT_CITY_902_20150507_Q") (brdx "16320 MIL") (brdy "2541.11 MIL") (bufferModel "CDSDefaultIO_2p5v") (cycle "1") (hold "1.0e-09") (mappingTag "") (offsets ("4" "0") ("5" "0")) (setup "2.0e-09") (state "tristate") (stimuli ("4" "local86") ("5" "local87")) (temperature "27") (termMap ("4" "Data") ("5" "Enable"))) (Terms ("CRESCENT_CITY_902_20150507_Q.X1632000Y254111L2LRATS" "4"))) ("CRESCENT_CITY_902_20150507_Q.@@U8F1.14" IbisIOPkg (xy (5502 4240)) (refDes "U8F1") (model "Unknown") (Props (_SXDesignName "CRESCENT_CITY_902_20150507_Q") (brdx "15795 MIL") (brdy "1570 MIL") (bufferModel "CDSDefaultIO_2p5v") (cycle "1") (hold "1.0e-09") (mappingTag "") (offsets ("4" "0") ("5" "0")) (setup "2.0e-09") (state "tristate") (stimuli ("4" "local88") ("5" "local89")) (temperature "27") (termMap ("4" "Data") ("5" "Enable"))) (Terms ("CRESCENT_CITY_902_20150507_Q.X1579500Y157000L2LRATS" "14"))) ("CRESCENT_CITY_902_20150507_Q.@@R8E13.2.1" Resistor (xy (5497 4216)) (mirror x) (refDes "R8E13") (value "33.2 Ohm") (Props (_SXDesignName "CRESCENT_CITY_902_20150507_Q")) (Terms ("CRESCENT_CITY_902_20150507_Q.X1623900Y221100L2LRATS" "2") ("CRESCENT_CITY_902_20150507_Q.X1620400Y221100L2LRATS" "1"))) ("CRESCENT_CITY_902_20150507_Q.T@@RATS@@R8E13.2@@J8E1.4" TLine (xy (5512 4216)) (refDes "TL59") (Props (_SXDesignName "CRESCENT_CITY_902_20150507_Q") (impedance "48.412 ohm") length("411.11 MIL") (propDelay "0.07384 ns") (traceCount "1") (traceGeometry "Microstrip") (velocity "5567.56 mil/ns")) (Terms ("CRESCENT_CITY_902_20150507_Q.X1623900Y221100L2LRATS" "1") ("CRESCENT_CITY_902_20150507_Q.X1632000Y254111L2LRATS" "2"))) ("CRESCENT_CITY_902_20150507_Q.T@@RATS@@R8F6.2@@U8F1.14" TLine (xy (5497 4229)) (refDes "TL60") (Props (_SXDesignName "CRESCENT_CITY_902_20150507_Q") (impedance "48.412 ohm") length("95.00 MIL") (propDelay "0.01706 ns") (traceCount "1") (traceGeometry "Microstrip") (velocity "5568.58 mil/ns")) (Terms ("CRESCENT_CITY_902_20150507_Q.X1587500Y155500L2LRATS" "1") ("CRESCENT_CITY_902_20150507_Q.X1579500Y157000L2LRATS" "2"))) ("CRESCENT_CITY_902_20150507_Q.@@R8F6.2.1" Resistor (xy (5488 4229)) (mirror x) (refDes "R8F6") (value "33.2 Ohm") (Props (_SXDesignName "CRESCENT_CITY_902_20150507_Q")) (Terms ("CRESCENT_CITY_902_20150507_Q.X1587500Y155500L2LRATS" "2") ("CRESCENT_CITY_902_20150507_Q.X1587500Y152000L2LRATS" "1"))) ("CRESCENT_CITY_902_20150507_Q.T@@RATS@@R8E13.1@@R8F6.1" TLine (xy (5482 4222)) (mirror x) (refDes "TL61") (Props (_SXDesignName "CRESCENT_CITY_902_20150507_Q") (impedance "48.412 ohm") length("1020.00 MIL") (propDelay "0.1832 ns") (traceCount "1") (traceGeometry "Microstrip") (velocity "5567.68 mil/ns")) (Terms ("CRESCENT_CITY_902_20150507_Q.X1620400Y221100L2LRATS" "1") ("CRESCENT_CITY_902_20150507_Q.X1587500Y152000L2LRATS" "2"))) ("CRESCENT_CITY_902_20150507_Q.T@@RATS@@R8E13.1@@U7C1.L3" TLine (xy (5497 4222)) (refDes "TL62") (Props (_SXDesignName "CRESCENT_CITY_902_20150507_Q") (impedance "49.728 ohm") length("2787.88 MIL") (propDelay "0.50072 ns") (traceCount "1") (traceGeometry "Microstrip") (velocity "5567.76 mil/ns")) (Terms ("CRESCENT_CITY_902_20150507_Q.X1620400Y221100L2LRATS" "1") ("CRESCENT_CITY_902_20150507_Q.X1492067Y371555L2LRATS" "2")))) (Nodes ("CRESCENT_CITY_902_20150507_Q.X1620400Y221100L2LRATS" (terms "CRESCENT_CITY_902_20150507_Q.T@@RATS@@R8E13.1@@U7C1.L3.1" "CRESCENT_CITY_902_20150507_Q.T@@RATS@@R8E13.1@@R8F6.1.1" "CRESCENT_CITY_902_20150507_Q.@@R8E13.2.1.2")) ("CRESCENT_CITY_902_20150507_Q.X1587500Y152000L2LRATS" (terms "CRESCENT_CITY_902_20150507_Q.T@@RATS@@R8E13.1@@R8F6.1.2" "CRESCENT_CITY_902_20150507_Q.@@R8F6.2.1.2")) ("CRESCENT_CITY_902_20150507_Q.X1492067Y371555L2LRATS" (terms "CRESCENT_CITY_902_20150507_Q.T@@RATS@@R8E13.1@@U7C1.L3.2" "CRESCENT_CITY_902_20150507_Q.@@U7C1.L3.1")) ("CRESCENT_CITY_902_20150507_Q.X1632000Y254111L2LRATS" (terms "CRESCENT_CITY_902_20150507_Q.T@@RATS@@R8E13.2@@J8E1.4.2" "CRESCENT_CITY_902_20150507_Q.@@J8E1.4.1")) ("CRESCENT_CITY_902_20150507_Q.X1623900Y221100L2LRATS" (terms "CRESCENT_CITY_902_20150507_Q.T@@RATS@@R8E13.2@@J8E1.4.1" "CRESCENT_CITY_902_20150507_Q.@@R8E13.2.1.1")) ("CRESCENT_CITY_902_20150507_Q.X1587500Y155500L2LRATS" (terms "CRESCENT_CITY_902_20150507_Q.@@R8F6.2.1.1" "CRESCENT_CITY_902_20150507_Q.T@@RATS@@R8F6.2@@U8F1.14.1")) ("CRESCENT_CITY_902_20150507_Q.X1579500Y157000L2LRATS" (terms "CRESCENT_CITY_902_20150507_Q.T@@RATS@@R8F6.2@@U8F1.14.2" "CRESCENT_CITY_902_20150507_Q.@@U8F1.14.1"))) (Ports) (Stimuli ("local88" (scope local) (stimType periodic) (Props (periodicFreq "5e+007") (periodicJitter "0") (periodicPattern "1"))) ("local86" (scope local) (stimType periodic) (Props (periodicFreq "5e+007") (periodicJitter "0") (periodicPattern "1"))) ("local84" (scope local) (stimType periodic) (Props (periodicFreq "5e+007") (periodicJitter "0") (periodicPattern "1"))) ("local89" (scope local) (stimType periodic) (Props (periodicFreq "5e+007") (periodicJitter "0") (periodicPattern "1"))) ("local85" (scope local) (stimType periodic) (Props (periodicFreq "5e+007") (periodicJitter "0") (periodicPattern "1"))) ("local87" (scope local) (stimType periodic) (Props (periodicFreq "5e+007") (periodicJitter "0") (periodicPattern "1")))) (Notes) (Constraints ("RELATIVE_PROPAGATION_DELAY" ("SPI_PCH_TPM" "CRESCENT_CITY_902_20150507_Q U7C1.L3" "CRESCENT_CITY_902_20150507_Q J8E1.4" "GLOBAL" "LENGTH" "0.00635" "LENGTH" "0") ("SPI_PCH-MUX" "CRESCENT_CITY_902_20150507_Q U7C1.L3" "CRESCENT_CITY_902_20150507_Q U8F1.14" "GLOBAL" "LENGTH" "0.00635" "LENGTH" "0"))) (MeasurementSets ("EMI" ("EMIStatus" status("on")) ("PeakEmission" status("on")) ("PeakFrequency" status("on")) ("PulseFreq" status("on")) ("RiseTime" status("on")) ("VoltageSwing" status("on"))) ("Reflection" ("BufferDelayFall" status("off")) ("BufferDelayRise" status("off")) ("EyeHeight" status("off")) ("EyeJitter" status("off")) ("EyeWidth" status("off")) ("FirstIncidentFall" status("off")) ("FirstIncidentRise" status("off")) ("Glitch" status("on")) ("GlitchFall" status("off")) ("GlitchRise" status("off")) ("Monotonic" status("on")) ("MonotonicFall" status("off")) ("MonotonicRise" status("off")) ("NoiseMargin" status("on")) ("NoiseMarginHigh" status("off")) ("NoiseMarginLow" status("off")) ("OvershootHigh" status("on")) ("OvershootLow" status("on")) ("PropDelay" status("on")) ("SettleDelay" status("on")) ("SettleDelayFall" status("off")) ("SettleDelayRise" status("off")) ("SwitchDelay" status("on")) ("SwitchDelayFall" status("off")) ("SwitchDelayRise" status("off"))) ("Crosstalk" ("Crosstalk" status("on"))) ("Custom")) (VectorSets) (Props (XnetName "SPI_PCH_MISO_R") (allDrivers "active") (customSimType "Reflection") (ftsMode ("Typ")) (rcvrSelect "all") (tlineDelayMode "time") (userRevision "1.0")))) (Subckts) (CrossSections ("CRESCENT_CITY_902_20150507_Q" (Props (SXDesignName "CRESCENT_CITY_902_20150507_Q")) (Layers ("" (layerType "SURFACE") (material "AIR") (thickness "0 mil") (dielectricConstant "1.000000") (lossTangent "0") (etchFactor "0.000000") (elecCondVal "0 mho/cm") (thermCondVal "0 w/cm-degC")) ("" (layerType "DIELECTRIC") (material "CONFORMAL_COAT") (thickness "0.5 mil") (dielectricConstant "3.800000") (lossTangent "0.035") (etchFactor "0.000000") (elecCondVal "0 mho/cm") (thermCondVal "0.012 w/cm-degC")) ("TOP" (layerType "CONDUCTOR") (material "COPPER") (thickness "  2.100000 mil") (width "4.00 MIL") (dielectricConstant "4.500000") (lossTangent "0") (etchFactor "70.000000") (elecCondVal "595900.000000 mho/cm") (thermCondVal "0 w/cm-degC") (signalDieConstant "3.800000") (signalLossTangent "0.035")) ("" (layerType "DIELECTRIC") (material "FR-4") (thickness "  2.670000 mil") (dielectricConstant "4.000000") (lossTangent "0.035") (etchFactor "0.000000") (elecCondVal "0 mho/cm") (thermCondVal "0.012 w/cm-degC")) ("L2_GND1" (layerType "PLANE") (material "COPPER") (isShield t) (thickness "  1.250000 mil") (dielectricConstant "4.500000") (lossTangent "0.035") (etchFactor "90.000000") (elecCondVal "595900.000000 mho/cm") (thermCondVal "0.012 w/cm-degC")) ("" (layerType "DIELECTRIC") (material "FR-4") (thickness "  9.000000 mil") (dielectricConstant "4.100000") (lossTangent "0.035") (etchFactor "0.000000") (elecCondVal "0 mho/cm") (thermCondVal "0.012 w/cm-degC")) ("L3_SIG1" (layerType "CONDUCTOR") (material "COPPER") (thickness "  1.250000 mil") (width "4.00 MIL") (dielectricConstant "4.500000") (lossTangent "0.035") (etchFactor "90.000000") (elecCondVal "595900.000000 mho/cm") (thermCondVal "0.012 w/cm-degC") (signalDieConstant "4.100000") (signalLossTangent "0.035")) ("" (layerType "DIELECTRIC") (material "FR-4") (thickness "  3.000000 mil") (dielectricConstant "4.500000") (lossTangent "0.035") (etchFactor "0.000000") (elecCondVal "0 mho/cm") (thermCondVal "0 w/cm-degC")) ("L4_GND2" (layerType "PLANE") (material "COPPER") (isShield t) (thickness "  1.250000 mil") (dielectricConstant "4.500000") (lossTangent "0.035") (etchFactor "90.000000") (elecCondVal "595900.000000 mho/cm") (thermCondVal "0 w/cm-degC")) ("" (layerType "DIELECTRIC") (material "FR-4") (thickness "  9.000000 mil") (dielectricConstant "4.000000") (lossTangent "0.035") (etchFactor "0.000000") (elecCondVal "0 mho/cm") (thermCondVal "0.012 w/cm-degC")) ("L5_SIG2" (layerType "CONDUCTOR") (material "COPPER") (thickness "  1.250000 mil") (width "4.00 MIL") (dielectricConstant "4.500000") (lossTangent "0.035") (etchFactor "90.000000") (elecCondVal "595900.000000 mho/cm") (thermCondVal "0.012 w/cm-degC") (signalDieConstant "4.000000") (signalLossTangent "0.035")) ("" (layerType "DIELECTRIC") (material "FR-4") (thickness "  3.000000 mil") (dielectricConstant "4.500000") (lossTangent "0.035") (etchFactor "0.000000") (elecCondVal "0 mho/cm") (thermCondVal "0 w/cm-degC")) ("L6_GND3" (layerType "PLANE") (material "COPPER") (isShield t) (thickness "  1.250000 mil") (dielectricConstant "4.500000") (lossTangent "0.035") (etchFactor "90.000000") (elecCondVal "595900.000000 mho/cm") (thermCondVal "0 w/cm-degC")) ("" (layerType "DIELECTRIC") (material "FR-4") (thickness "  4.500000 mil") (dielectricConstant "4.100000") (lossTangent "0.035") (etchFactor "0.000000") (elecCondVal "0 mho/cm") (thermCondVal "0.012 w/cm-degC")) ("L7_PWR1-SIG" (layerType "PLANE") (material "COPPER") (isShield t) (thickness "  2.610000 mil") (dielectricConstant "4.500000") (lossTangent "0.035") (etchFactor "90.000000") (elecCondVal "595900.000000 mho/cm") (thermCondVal "0.012 w/cm-degC")) ("" (layerType "DIELECTRIC") (material "FR-4") (thickness "  3.100000 mil") (dielectricConstant "4.500000") (lossTangent "0.035") (etchFactor "0.000000") (elecCondVal "0 mho/cm") (thermCondVal "0 w/cm-degC")) ("L8_GND_TEMP" (layerType "PLANE") (material "COPPER") (isShield t) (thickness "  1.250000 mil") (dielectricConstant "4.500000") (lossTangent "0.035") (etchFactor "90.000000") (elecCondVal "595900.000000 mho/cm") (thermCondVal "0 w/cm-degC")) ("" (layerType "DIELECTRIC") (material "FR-4") (thickness "  3.030000 mil") (dielectricConstant "4.500000") (lossTangent "0.035") (etchFactor "0.000000") (elecCondVal "0 mho/cm") (thermCondVal "0 w/cm-degC")) ("L9_SIG_TEMP" (layerType "CONDUCTOR") (material "COPPER") (thickness "  1.250000 mil") (width "3.52 MIL") (dielectricConstant "4.500000") (lossTangent "0.035") (etchFactor "90.000000") (elecCondVal "595900.000000 mho/cm") (thermCondVal "0 w/cm-degC") (signalDieConstant "4.500000") (signalLossTangent "0.035")) ("" (layerType "DIELECTRIC") (material "FR-4") (thickness "  5.000000 mil") (dielectricConstant "4.500000") (lossTangent "0.035") (etchFactor "0.000000") (elecCondVal "0 mho/cm") (thermCondVal "0 w/cm-degC")) ("L10_SIG_TEMP" (layerType "CONDUCTOR") (material "COPPER") (thickness "  1.250000 mil") (width "3.52 MIL") (dielectricConstant "4.500000") (lossTangent "0.035") (etchFactor "90.000000") (elecCondVal "595900.000000 mho/cm") (thermCondVal "0 w/cm-degC") (signalDieConstant "4.500000") (signalLossTangent "0.035")) ("" (layerType "DIELECTRIC") (material "FR-4") (thickness "  3.030000 mil") (dielectricConstant "4.500000") (lossTangent "0.035") (etchFactor "0.000000") (elecCondVal "0 mho/cm") (thermCondVal "0 w/cm-degC")) ("L11_GND_TEMP" (layerType "PLANE") (material "COPPER") (isShield t) (thickness "  1.250000 mil") (dielectricConstant "4.500000") (lossTangent "0.035") (etchFactor "90.000000") (elecCondVal "595900.000000 mho/cm") (thermCondVal "0 w/cm-degC")) ("" (layerType "DIELECTRIC") (material "FR-4") (thickness "  3.100000 mil") (dielectricConstant "4.000000") (lossTangent "0.035") (etchFactor "0.000000") (elecCondVal "0 mho/cm") (thermCondVal "0.012 w/cm-degC")) ("L12_PWR2-SIG" (layerType "PLANE") (material "COPPER") (isShield t) (thickness "  2.610000 mil") (dielectricConstant "4.500000") (lossTangent "0.035") (etchFactor "90.000000") (elecCondVal "595900.000000 mho/cm") (thermCondVal "0.012 w/cm-degC")) ("" (layerType "DIELECTRIC") (material "FR-4") (thickness "  4.500000 mil") (dielectricConstant "4.500000") (lossTangent "0.035") (etchFactor "0.000000") (elecCondVal "0 mho/cm") (thermCondVal "0 w/cm-degC")) ("L13_GND4" (layerType "PLANE") (material "COPPER") (isShield t) (thickness "  1.250000 mil") (dielectricConstant "4.500000") (lossTangent "0.035") (etchFactor "90.000000") (elecCondVal "595900.000000 mho/cm") (thermCondVal "0 w/cm-degC")) ("" (layerType "DIELECTRIC") (material "FR-4") (thickness "  3.000000 mil") (dielectricConstant "4.100000") (lossTangent "0.035") (etchFactor "0.000000") (elecCondVal "0 mho/cm") (thermCondVal "0.012 w/cm-degC")) ("L14_SIG3" (layerType "CONDUCTOR") (material "COPPER") (thickness "  1.250000 mil") (width "4.00 MIL") (dielectricConstant "4.500000") (lossTangent "0.035") (etchFactor "90.000000") (elecCondVal "595900.000000 mho/cm") (thermCondVal "0.012 w/cm-degC") (signalDieConstant "4.100000") (signalLossTangent "0.035")) ("" (layerType "DIELECTRIC") (material "FR-4") (thickness "  9.000000 mil") (dielectricConstant "4.500000") (lossTangent "0.035") (etchFactor "0.000000") (elecCondVal "0 mho/cm") (thermCondVal "0 w/cm-degC")) ("L15_GND5" (layerType "PLANE") (material "COPPER") (isShield t) (thickness "  1.250000 mil") (dielectricConstant "4.500000") (lossTangent "0.035") (etchFactor "90.000000") (elecCondVal "595900.000000 mho/cm") (thermCondVal "0 w/cm-degC")) ("" (layerType "DIELECTRIC") (material "FR-4") (thickness "  3.000000 mil") (dielectricConstant "4.500000") (lossTangent "0.035") (etchFactor "0.000000") (elecCondVal "0 mho/cm") (thermCondVal "0.012 w/cm-degC")) ("L16_SIG4" (layerType "CONDUCTOR") (material "COPPER") (thickness "  1.250000 mil") (width "4.00 MIL") (dielectricConstant "4.500000") (lossTangent "0.035") (etchFactor "90.000000") (elecCondVal "595900.000000 mho/cm") (thermCondVal "0.012 w/cm-degC") (signalDieConstant "4.500000") (signalLossTangent "0.035")) ("" (layerType "DIELECTRIC") (material "FR-4") (thickness "  9.000000 mil") (dielectricConstant "4.500000") (lossTangent "0.035") (etchFactor "0.000000") (elecCondVal "0 mho/cm") (thermCondVal "0 w/cm-degC")) ("L17_GND6" (layerType "PLANE") (material "COPPER") (isShield t) (thickness "  1.250000 mil") (dielectricConstant "4.500000") (lossTangent "0.035") (etchFactor "90.000000") (elecCondVal "595900.000000 mho/cm") (thermCondVal "0.012 w/cm-degC")) ("" (layerType "DIELECTRIC") (material "FR-4") (thickness "  2.670000 mil") (dielectricConstant "4.500000") (lossTangent "0.035") (etchFactor "0.000000") (elecCondVal "0 mho/cm") (thermCondVal "0.012 w/cm-degC")) ("BOTTOM" (layerType "CONDUCTOR") (material "COPPER") (thickness "  2.100000 mil") (width "4.00 MIL") (dielectricConstant "4.500000") (lossTangent "0") (etchFactor "70.000000") (elecCondVal "595900.000000 mho/cm") (thermCondVal "0 w/cm-degC") (signalDieConstant "3.800000") (signalLossTangent "0.035")) ("" (layerType "DIELECTRIC") (material "CONFORMAL_COAT") (thickness "0.5 mil") (dielectricConstant "3.800000") (lossTangent "0.035") (etchFactor "0.000000") (elecCondVal "0 mho/cm") (thermCondVal "0.012 w/cm-degC")) ("" (layerType "SURFACE") (material "AIR") (thickness "0 mil") (dielectricConstant "1.000000") (lossTangent "0") (etchFactor "0.000000") (elecCondVal "0 mho/cm") (thermCondVal "0 w/cm-degC"))))) (Props (DesUnits "mils 2") (LayerStack ("DIELECTRIC" "DIELECTRIC" "BOTTOM" "DIELECTRIC" "L17_GND6" "DIELECTRIC" "L16_SIG4" "DIELECTRIC" "L15_GND5" "DIELECTRIC" "L14_SIG3" "DIELECTRIC" "L13_GND4" "DIELECTRIC" "L12_PWR2-SIG" "DIELECTRIC" "L11_GND_TEMP" "DIELECTRIC" "L10_SIG_TEMP" "DIELECTRIC" "L9_SIG_TEMP" "DIELECTRIC" "L8_GND_TEMP" "DIELECTRIC" "L7_PWR1-SIG" "DIELECTRIC" "L6_GND3" "DIELECTRIC" "L5_SIG2" "DIELECTRIC" "L4_GND2" "DIELECTRIC" "L3_SIG1" "DIELECTRIC" "L2_GND1" "DIELECTRIC" "TOP" "DIELECTRIC" "DIELECTRIC")) (Revision "16.600")) (Params (DiffInputPkg ((temperature "27") (bufferModelNonInverting "CDSDefaultInput_2p5v") (bufferModelInverting "CDSDefaultInput_2p5v") (threshInputHighMin "1.7 V") (threshInputHighTyp "1.7  V") (threshInputHighMax "1.7  V") (threshInputLowMin "0.7  V") (threshInputLowTyp "0.7  V") (threshInputLowMax "0.7  V") (mappingTagNonInverting nil) (mappingTagInverting nil) (cycle "1"))) (IbisOutputPkg ((temperature "27") (bufferModel "CDSDefaultOutput_2p5v") (stimuli nil) (offsets nil) (state "tristate") (cycle "1") (termMap nil) (setup "2.0e-09") (hold "1.0e-09") (rise nil) (fall nil) (macroType nil) (voltage nil) (spice nil) (LEFDEFPinName nil) (LEFDEFPinType nil) (mappingTag nil))) (IbisIOPkg ((temperature "27") (bufferModel "CDSDefaultIO_2p5v") (stimuli nil) (offsets nil) (state "tristate") (cycle "1") (termMap nil) (setup "2.0e-09") (hold "1.0e-09") (rise nil) (fall nil) (macroType nil) (voltage nil) (spice nil) (LEFDEFPinName nil) (LEFDEFPinType nil) (mappingTag nil))) (IbisIOMacro ((temperature "27") (bufferModel "CDSDefaultIO_2p5v") (stimuli nil) (offsets nil) (state "tristate") (cycle "1") (termMap nil) (setup "2.0e-09") (hold "1.0e-09") (rise nil) (fall nil) (macroType nil) (voltage nil) (spice nil) (LEFDEFPinName nil) (LEFDEFPinType nil) (mappingTag nil))) (ESpiceDevice nil) (IbisInput ((temperature "27") (bufferModel "CDSDefaultInput_2p5v") (cycle "1") (LEFDEFPinName nil) (LEFDEFPinType nil) (mappingTag nil))) (ShuntTerm ((resistance "50 ohm") (voltage "5 V") (maxDelay "0.1 ns"))) (SeriesTerm ((resistance "22 ohm") (maxDelay "0.1 ns"))) (CurrentProbe nil) (idlCircuit ((allDrivers "active") (ftsMode '("Typ")) (rcvrSelect "all") (simMode "Reflection") (tlineDelayMode "time") (userRevision "1.0") (autoSolve "On"))) (TheveninTerm ((resistanceUp "180 ohm") (resistanceDown "270 ohm") (voltageUp "5 V") (voltageDown "0 V") (maxDelay "0.1 ns"))) (RCTerm ((resistance "50 ohm") (capacitance "20 pF") (voltage "5 V") (maxDelay "0.1 ns"))) (LowClampTerm ((cutoffVoltage "0.7 V") (voltage "0 V") (maxDelay "0.1 ns"))) (Cable (length("1 m"))) (HiClampTerm ((cutoffVoltage "0.7 V") (voltage "5 V") (maxDelay "0.1 ns"))) (DualClampTerm ((cutoffVoltageUp "0.7 V") (cutoffVoltageDown "0.7 V") (voltageUp "5 V") (voltageDown "0 V") (maxDelay "0.1 ns"))) (IbisInputPkg ((temperature "27") (bufferModel "CDSDefaultInput_2p5v") (cycle "1") (LEFDEFPinName nil) (LEFDEFPinType nil) (mappingTag nil))) (async ((asyncTimePoints "") (asyncInitState "1"))) (clocked ((clockRise "1e-09") (clockFall "1e-09") (clockFreq "100e6") (clockInitState "0") (clockDutyCycle "0.5") (clockJitter "0"))) (Diode ((cutoffVoltage "0.7 V"))) (IbisOutput ((temperature "27") (bufferModel "CDSDefaultOutput_2p5v") (stimuli nil) (offsets nil) (state "tristate") (cycle "1") (termMap nil) (setup "2.0e-09") (hold "1.0e-09") (rise nil) (fall nil) (macroType nil) (voltage nil) (spice nil) (LEFDEFPinName nil) (LEFDEFPinType nil) (mappingTag nil))) (periodic ((periodicFreq "100e6") (periodicPattern "10") (periodicJitter "0"))) (IbisIO ((temperature "27") (bufferModel "CDSDefaultIO_2p5v") (stimuli nil) (offsets nil) (state "tristate") (cycle "1") (termMap nil) (setup "2.0e-09") (hold "1.0e-09") (rise nil) (fall nil) (macroType nil) (voltage nil) (spice nil) (LEFDEFPinName nil) (LEFDEFPinType nil) (mappingTag nil))) (Via ((model "Unknown") (viaOutputFormat "Unknown") (viaPadstack nil) (viaTopLayer nil) (viaBottomLayer nil) (viaIsPower nil) (viaIsGround nil))) (CPWMS ((d1Thickness "10 mil") (d1Constant "4.5") (d1LossTangent "0.035") (d2Thickness "0.72 mil") (d2Constant "4.5") (d2LossTangent "0.035") (d3Thickness "0.0") (d3Constant "1") (d3LossTangent "0") length("1000 mil") (spacing "5 mil") (spacing2 "5 mil") (spacing3 "5 mil") (spacing4 "5 mil") (spacing5 "5 mil") (traceConductivity "595900 mho/cm") (traceGeometry "cpwms") (traceLayerName "") (traceThickness "0.72 mil") (traceType "single") (traceWidth "5.0 mil") (traceWidth2 "5.0 mil") (traceWidth3 "5.0 mil") (traceWidth4 "5.0 mil") (traceWidth5 "5.0 mil") (traceWidth6 "5.0 mil") (offset "0 mil") (traceCount "1") (impedance nil))) (Trace ((d1Thickness "10 mil") (d1Constant "4.5") (d1LossTangent "0.035") (d2Thickness "10 mil") (d2Constant "4.5") (d2LossTangent "0.035") (d3Thickness "0.0") (d3Constant "1.0") (d3LossTangent "0") length("1000 mil") (spacing "5 mil") (spacing2 "5 mil") (spacing3 "5 mil") (spacing4 "5 mil") (spacing5 "5 mil") (traceConductivity "595900 mho/cm") (traceGeometry "microstrip") (traceLayerName "") (traceThickness "0.72 mil") (traceType "single") (traceWidth "5.0 mil") (traceWidth2 "5.0 mil") (traceWidth3 "5.0 mil") (traceWidth4 "5.0 mil") (traceWidth5 "5.0 mil") (traceWidth6 "5.0 mil") (offset "0 mil") (traceCount "1") (impedance nil))) (Source ((voltage "5 V"))) (CPWSL ((d1Thickness "10 mil") (d1Constant "4.5") (d1LossTangent "0.035") (d2Thickness "0.72 mil") (d2Constant "4.5") (d2LossTangent "0.035") (d3Thickness "10 mil") (d3Constant "4.5") (d3LossTangent "0.035") length("1000 mil") (spacing "5 mil") (spacing2 "5 mil") (spacing3 "5 mil") (spacing4 "5 mil") (spacing5 "5 mil") (traceConductivity "595900 mho/cm") (traceGeometry "cpwms") (traceLayerName "") (traceThickness "0.72 mil") (traceType "single") (traceWidth "5.0 mil") (traceWidth2 "5.0 mil") (traceWidth3 "5.0 mil") (traceWidth4 "5.0 mil") (traceWidth5 "5.0 mil") (traceWidth6 "5.0 mil") (offset "0 mil") (traceCount "1") (impedance nil))) (RLGC (length("1000 mil"))) (Capacitor ((capacitance "10 pF") (orientation "0"))) (DiffIOPkg ((temperature "27") (bufferModelNonInverting "CDSDefaultIO_2p5v") (bufferModelInverting "CDSDefaultIO_2p5v") (stimuli nil) (offsets nil) (state "tristate") (cycle "1") (termMap nil) (setup "0.9e-09") (hold "0.4e-09") (rise nil) (fall nil) (threshInputHighMin "1.7 V") (threshInputHighTyp "1.7  V") (threshInputHighMax "1.7  V") (threshInputLowMin "0.7  V") (threshInputLowTyp "0.7  V") (threshInputLowMax "0.7 ") (threshOutputHighMin "2.365  V") (threshOutputHighTyp "2.5  V") (threshOutputHighMax "2.625  V") (threshOutputLowMin "1.275  V") (threshOutputLowTyp "1.7  V") (threshOutputLowMax "1.985  V") (mappingTagNonInverting nil) (mappingTagInverting nil) (spice nil))) (Inductor ((inductance "5 nH") (orientation "0"))) (DiffIO ((temperature "27") (bufferModelNonInverting "CDSDefaultIO_2p5v") (bufferModelInverting "CDSDefaultIO_2p5v") (stimuli nil) (offsets nil) (state "tristate") (cycle "1") (termMap nil) (setup "0.9e-09") (hold "0.4e-09") (rise nil) (fall nil) (threshInputHighMin "1.7 V") (threshInputHighTyp "1.7  V") (threshInputHighMax "1.7  V") (threshInputLowMin "0.7  V") (threshInputLowTyp "0.7  V") (threshInputLowMax "0.7 ") (threshOutputHighMin "2.365  V") (threshOutputHighTyp "2.5  V") (threshOutputHighMax "2.625  V") (threshOutputLowMin "1.275  V") (threshOutputLowTyp "1.7  V") (threshOutputLowMax "1.985  V") (mappingTagNonInverting nil) (mappingTagInverting nil) (spice nil))) (CPW ((d1Thickness "10 mil") (d1Constant "4.5") (d1LossTangent "0.035") (d2Thickness "0.72 mil") (d2Constant "1") (d2LossTangent "0") (d3Thickness "0.0") (d3Constant "1") (d3LossTangent "0") length("1000 mil") (spacing "5 mil") (spacing2 "5 mil") (spacing3 "5 mil") (spacing4 "5 mil") (spacing5 "5 mil") (traceConductivity "595900 mho/cm") (traceGeometry "cpwms") (traceLayerName "") (traceThickness "0.72 mil") (traceType "single") (traceWidth "5.0 mil") (traceWidth2 "5.0 mil") (traceWidth3 "5.0 mil") (traceWidth4 "5.0 mil") (traceWidth5 "5.0 mil") (traceWidth6 "5.0 mil") (offset "0 mil") (traceCount "1") (impedance nil))) (Connector nil) (TLine ((diffImpedance "100ohm") (diffVelocity "1.4142e+08M/s") (impedance "60ohm") length("2800 mil") (propDelay "0.5 ns") (velocity "5600 mil/ns") (traceCount "1") (traceGeometry "Microstrip") (impedanceMin nil) (impedanceMax nil) (lengthMin nil) (lengthMax nil) (propDelayMin nil) (propDelayMax nil) (impedanceSweepCount nil) (propDelaySweepCount nil) (velocitySweepCount nil) (lengthSweepCount nil) (matchSetName nil))) (sync ((syncFreq "100e6") (syncInitState "1") (syncPattern "10") (syncEdgeSwitch "rise"))) (IbisIO_OpenPullDown ((temperature "27") (bufferModel "CDSDefaultIO_2p5v") (stimuli nil) (offsets nil) (state "tristate") (cycle "1") (termMap nil) (setup "2.0e-09") (hold "1.0e-09") (rise nil) (fall nil) (macroType nil) (voltage nil) (spice nil) (LEFDEFPinName nil) (LEFDEFPinType nil) (mappingTag nil))) (DiffOutputPkg ((temperature "27") (bufferModelNonInverting "CDSDefaultOutput_2p5v") (bufferModelInverting "CDSDefaultOutput_2p5v") (stimuli nil) (offsets nil) (state "tristate") (cycle "1") (termMap nil) (setup "0.9e-09") (hold "0.4e-09") (rise nil) (fall nil) (threshOutputHighMin "2.375  V") (threshOutputHighTyp "2.5  V") (threshOutputHighMax "2.625  V") (threshOutputLowMin "1.275  V") (threshOutputLowTyp "1.7  V") (threshOutputLowMax "1.985  V") (mappingTagNonInverting nil) (mappingTagInverting nil) (spice nil))) (DiffInput ((temperature "27") (bufferModelNonInverting "CDSDefaultInput_2p5v") (bufferModelInverting "CDSDefaultInput_2p5v") (threshInputHighMin "1.7 V") (threshInputHighTyp "1.7  V") (threshInputHighMax "1.7  V") (threshInputLowMin "0.7  V") (threshInputLowTyp "0.7  V") (threshInputLowMax "0.7  V") (mappingTagNonInverting nil) (mappingTagInverting nil) (cycle "1"))) (Resistor ((resistance "50 ohm") (orientation "0"))) (DiffOutput ((temperature "27") (bufferModelNonInverting "CDSDefaultOutput_2p5v") (bufferModelInverting "CDSDefaultOutput_2p5v") (stimuli nil) (offsets nil) (state "tristate") (cycle "1") (termMap nil) (setup "0.9e-09") (hold "0.4e-09") (rise nil) (fall nil) (threshOutputHighMin "2.375  V") (threshOutputHighTyp "2.5  V") (threshOutputHighMax "2.625  V") (threshOutputLowMin "1.275  V") (threshOutputLowTyp "1.7  V") (threshOutputLowMax "1.985  V") (mappingTagNonInverting nil) (mappingTagInverting nil) (spice nil))) (IbisOutput_OpenPullUp ((temperature "27") (bufferModel "CDSDefaultOutput_2p5v") (stimuli nil) (offsets nil) (state "tristate") (cycle "1") (termMap nil) (setup "2.0e-09") (hold "1.0e-09") (rise nil) (fall nil) (macroType nil) (voltage nil) (spice nil) (LEFDEFPinName nil) (LEFDEFPinType nil) (mappingTag nil))) (IbisIO_OpenPullUp ((temperature "27") (bufferModel "CDSDefaultIO_2p5v") (stimuli nil) (offsets nil) (state "tristate") (cycle "1") (termMap nil) (setup "2.0e-09") (hold "1.0e-09") (rise nil) (fall nil) (macroType nil) (voltage nil) (spice nil) (LEFDEFPinName nil) (LEFDEFPinType nil) (mappingTag nil)))))
				)
				( objectStatus "SPI_PCH_MISO_R" )
			)
			( electricalCSet "@crescent_city_bb_fab1_lib.crescent_city_bb_fab1(sch_1):\SPI_PCH_IO3_1\"
				( groupRef "SPI_PCH_IO3:SPI_PCH-MUX" )
				( pinPairRef "SPI_PCH_IO3:U7C1.L1:U2T1.5" )
				( attribute "RATSNEST_SCHEDULE" "MIN_TREE"
					( Status sLocked )
					( Origin gBackEnd )
				)
				( attribute "TOPOLOGY_TEMPLATE_REVISION" "1.0"
					( Origin gBackEnd )
				)
				( topologyData 28647
(SKIDL (Circuits ("MAIN" (Parts ("CRESCENT_CITY_902_20150507_Q.@@U2T1.5" IbisIOPkg (xy (5505 4220)) (refDes "U2T1") (model "Unknown") (Props (_SXDesignName "CRESCENT_CITY_902_20150507_Q") (brdx "15795 MIL") (brdy "1505 MIL") (bufferModel "CDSDefaultIO_2p5v") (cycle "1") (hold "1.0e-09") (mappingTag "") (offsets ("4" "0") ("5" "0")) (setup "2.0e-09") (state "tristate") (stimuli ("4" "local80") ("5" "local81")) (temperature "27") (termMap ("4" "Data") ("5" "Enable"))) (Terms ("CRESCENT_CITY_902_20150507_Q.X1579500Y150500L36LRATS" "5"))) ("CRESCENT_CITY_902_20150507_Q.@@U7C1.L1" IbisIOPkg (xy (5502 4240)) (refDes "U7C1") (model "Unknown") (Props (_SXDesignName "CRESCENT_CITY_902_20150507_Q") (brdx "14920.67 MIL") (brdy "3682.87 MIL") (bufferModel "CDSDefaultIO_2p5v") (cycle "1") (hold "1.0e-09") (mappingTag "") (offsets ("4" "0") ("5" "0")) (setup "2.0e-09") (state "tristate") (stimuli ("4" "local82") ("5" "local83")) (temperature "27") (termMap ("4" "Data") ("5" "Enable"))) (Terms ("CRESCENT_CITY_902_20150507_Q.X1492067Y368287L2LRATS" "L1"))) ("CRESCENT_CITY_902_20150507_Q.@@R2T1.2_SOURCE" Source (xy (5459 4229)) (refDes "GND") (value "0 V") (Props (_SXDesignName "CRESCENT_CITY_902_20150507_Q")) (Terms ("CRESCENT_CITY_902_20150507_Q.X1591500Y155500L36RATS" "1"))) ("CRESCENT_CITY_902_20150507_Q.@@R2T1.2.1" Resistor (xy (5466 4229)) (refDes "R2T1") (value "1000 Ohm") (Props (_SXDesignName "CRESCENT_CITY_902_20150507_Q")) (Terms ("CRESCENT_CITY_902_20150507_Q.X1591500Y155500L36RATS" "2") ("CRESCENT_CITY_902_20150507_Q.X1591500Y152000L36LRATS" "1"))) ("CRESCENT_CITY_902_20150507_Q.T@@RATS@@U2T1.5@@R2T2.2" TLine (xy (5490 4215)) (mirror x) (refDes "TL55") (Props (_SXDesignName "CRESCENT_CITY_902_20150507_Q") (impedance "46.577 ohm") length("130.00 MIL") (propDelay "0.02335 ns") (traceCount "1") (traceGeometry "Microstrip") (velocity "5567.44 mil/ns")) (Terms ("CRESCENT_CITY_902_20150507_Q.X1579500Y150500L36LRATS" "1") ("CRESCENT_CITY_902_20150507_Q.X1587500Y155500L36LRATS" "2"))) ("CRESCENT_CITY_902_20150507_Q.T@@RATS@@R2T1.1@@R2T2.1" TLine (xy (5475 4229)) (refDes "TL56") (Props (_SXDesignName "CRESCENT_CITY_902_20150507_Q") (impedance "46.577 ohm") length("40.00 MIL") (propDelay "0.00718 ns") (traceCount "1") (traceGeometry "Microstrip") (velocity "5571.02 mil/ns")) (Terms ("CRESCENT_CITY_902_20150507_Q.X1591500Y152000L36LRATS" "1") ("CRESCENT_CITY_902_20150507_Q.X1587500Y152000L36LRATS" "2"))) ("CRESCENT_CITY_902_20150507_Q.T@@RATS@@U7C1.L1@@R3N17.2" TLine (xy (5503 4209)) (mirror x) (refDes "TL57") (Props (_SXDesignName "CRESCENT_CITY_902_20150507_Q") (impedance "48.412 ohm") length("43.63 MIL") (propDelay "0.00784 ns") (traceCount "1") (traceGeometry "Microstrip") (velocity "5565.04 mil/ns")) (Terms ("CRESCENT_CITY_902_20150507_Q.X1492067Y368287L2LRATS" "1") ("CRESCENT_CITY_902_20150507_Q.X1487770Y368353L36LRATS" "2"))) ("CRESCENT_CITY_902_20150507_Q.@@R2T2.2.1" Resistor (xy (5475 4215)) (mirror x) (refDes "R2T2") (value "33.2 Ohm") (Props (_SXDesignName "CRESCENT_CITY_902_20150507_Q")) (Terms ("CRESCENT_CITY_902_20150507_Q.X1587500Y155500L36LRATS" "2") ("CRESCENT_CITY_902_20150507_Q.X1587500Y152000L36LRATS" "1"))) ("CRESCENT_CITY_902_20150507_Q.T@@RATS@@R2T2.1@@U7C1.L1" TLine (xy (5497 4229)) (refDes "TL58") (Props (_SXDesignName "CRESCENT_CITY_902_20150507_Q") (impedance "48.412 ohm") length("3117.20 MIL") (propDelay "0.55987 ns") (traceCount "1") (traceGeometry "Microstrip") (velocity "5567.72 mil/ns")) (Terms ("CRESCENT_CITY_902_20150507_Q.X1587500Y152000L36LRATS" "1") ("CRESCENT_CITY_902_20150507_Q.X1492067Y368287L2LRATS" "2"))) ("CRESCENT_CITY_902_20150507_Q.@@R3N17.1_SOURCE" Source (xy (5481 4209)) (refDes "P3V3_STBY") (value "3.3 V") (Props (_SXDesignName "CRESCENT_CITY_902_20150507_Q")) (Terms ("CRESCENT_CITY_902_20150507_Q.X1491270Y368353L36RATS" "1"))) ("CRESCENT_CITY_902_20150507_Q.@@R3N17.1.2" Resistor (xy (5488 4209)) (refDes "R3N17") (value "10000 Ohm") (Props (_SXDesignName "CRESCENT_CITY_902_20150507_Q")) (Terms ("CRESCENT_CITY_902_20150507_Q.X1491270Y368353L36RATS" "1") ("CRESCENT_CITY_902_20150507_Q.X1487770Y368353L36LRATS" "2")))) (Nodes ("CRESCENT_CITY_902_20150507_Q.X1491270Y368353L36RATS" (terms "CRESCENT_CITY_902_20150507_Q.@@R3N17.1.2.1" "CRESCENT_CITY_902_20150507_Q.@@R3N17.1_SOURCE.1")) ("CRESCENT_CITY_902_20150507_Q.X1591500Y152000L36LRATS" (terms "CRESCENT_CITY_902_20150507_Q.T@@RATS@@R2T1.1@@R2T2.1.1" "CRESCENT_CITY_902_20150507_Q.@@R2T1.2.1.2")) ("CRESCENT_CITY_902_20150507_Q.X1492067Y368287L2LRATS" (terms "CRESCENT_CITY_902_20150507_Q.T@@RATS@@R2T2.1@@U7C1.L1.2" "CRESCENT_CITY_902_20150507_Q.T@@RATS@@U7C1.L1@@R3N17.2.1" "CRESCENT_CITY_902_20150507_Q.@@U7C1.L1.1")) ("CRESCENT_CITY_902_20150507_Q.X1579500Y150500L36LRATS" (terms "CRESCENT_CITY_902_20150507_Q.T@@RATS@@U2T1.5@@R2T2.2.1" "CRESCENT_CITY_902_20150507_Q.@@U2T1.5.1")) ("CRESCENT_CITY_902_20150507_Q.X1587500Y152000L36LRATS" (terms "CRESCENT_CITY_902_20150507_Q.T@@RATS@@R2T2.1@@U7C1.L1.1" "CRESCENT_CITY_902_20150507_Q.@@R2T2.2.1.2" "CRESCENT_CITY_902_20150507_Q.T@@RATS@@R2T1.1@@R2T2.1.2")) ("CRESCENT_CITY_902_20150507_Q.X1487770Y368353L36LRATS" (terms "CRESCENT_CITY_902_20150507_Q.@@R3N17.1.2.2" "CRESCENT_CITY_902_20150507_Q.T@@RATS@@U7C1.L1@@R3N17.2.2")) ("CRESCENT_CITY_902_20150507_Q.X1587500Y155500L36LRATS" (terms "CRESCENT_CITY_902_20150507_Q.@@R2T2.2.1.1" "CRESCENT_CITY_902_20150507_Q.T@@RATS@@U2T1.5@@R2T2.2.2")) ("CRESCENT_CITY_902_20150507_Q.X1591500Y155500L36RATS" (terms "CRESCENT_CITY_902_20150507_Q.@@R2T1.2.1.1" "CRESCENT_CITY_902_20150507_Q.@@R2T1.2_SOURCE.1"))) (Ports) (Stimuli ("local71" (scope local) (stimType periodic) (Props (periodicFreq "5e+007") (periodicJitter "0") (periodicPattern "1"))) ("local73" (scope local) (stimType periodic) (Props (periodicFreq "5e+007") (periodicJitter "0") (periodicPattern "1"))) ("local72" (scope local) (stimType periodic) (Props (periodicFreq "5e+007") (periodicJitter "0") (periodicPattern "1"))) ("local81" (scope local) (stimType periodic) (Props (periodicFreq "5e+007") (periodicJitter "0") (periodicPattern "1"))) ("local83" (scope local) (stimType periodic) (Props (periodicFreq "5e+007") (periodicJitter "0") (periodicPattern "1"))) ("local74" (scope local) (stimType periodic) (Props (periodicFreq "5e+007") (periodicJitter "0") (periodicPattern "1"))) ("local82" (scope local) (stimType periodic) (Props (periodicFreq "5e+007") (periodicJitter "0") (periodicPattern "1"))) ("local69" (scope local) (stimType periodic) (Props (periodicFreq "5e+007") (periodicJitter "0") (periodicPattern "1"))) ("local70" (scope local) (stimType periodic) (Props (periodicFreq "5e+007") (periodicJitter "0") (periodicPattern "1"))) ("local80" (scope local) (stimType periodic) (Props (periodicFreq "5e+007") (periodicJitter "0") (periodicPattern "1")))) (Notes) (Constraints ("RATSNEST_SCHEDULE" "MIN_TREE") ("RELATIVE_PROPAGATION_DELAY" ("SPI_PCH-MUX" "CRESCENT_CITY_902_20150507_Q U7C1.L1" "CRESCENT_CITY_902_20150507_Q U2T1.5" "GLOBAL" "LENGTH" "0.00635" "LENGTH" "0"))) (MeasurementSets ("EMI" ("EMIStatus" status("on")) ("PeakEmission" status("on")) ("PeakFrequency" status("on")) ("PulseFreq" status("on")) ("RiseTime" status("on")) ("VoltageSwing" status("on"))) ("Reflection" ("BufferDelayFall" status("off")) ("BufferDelayRise" status("off")) ("EyeHeight" status("off")) ("EyeJitter" status("off")) ("EyeWidth" status("off")) ("FirstIncidentFall" status("off")) ("FirstIncidentRise" status("off")) ("Glitch" status("on")) ("GlitchFall" status("off")) ("GlitchRise" status("off")) ("Monotonic" status("on")) ("MonotonicFall" status("off")) ("MonotonicRise" status("off")) ("NoiseMargin" status("on")) ("NoiseMarginHigh" status("off")) ("NoiseMarginLow" status("off")) ("OvershootHigh" status("on")) ("OvershootLow" status("on")) ("PropDelay" status("on")) ("SettleDelay" status("on")) ("SettleDelayFall" status("off")) ("SettleDelayRise" status("off")) ("SwitchDelay" status("on")) ("SwitchDelayFall" status("off")) ("SwitchDelayRise" status("off"))) ("Crosstalk" ("Crosstalk" status("on"))) ("Custom")) (VectorSets) (Props (XnetName "SPI_PCH_IO3") (allDrivers "active") (customSimType "Reflection") (ftsMode ("Typ")) (rcvrSelect "all") (tlineDelayMode "time") (userRevision "1.0")))) (Subckts) (CrossSections ("CRESCENT_CITY_902_20150507_Q" (Props (SXDesignName "CRESCENT_CITY_902_20150507_Q")) (Layers ("" (layerType "SURFACE") (material "AIR") (thickness "0 mil") (dielectricConstant "1.000000") (lossTangent "0") (etchFactor "0.000000") (elecCondVal "0 mho/cm") (thermCondVal "0 w/cm-degC")) ("" (layerType "DIELECTRIC") (material "CONFORMAL_COAT") (thickness "0.5 mil") (dielectricConstant "3.800000") (lossTangent "0.035") (etchFactor "0.000000") (elecCondVal "0 mho/cm") (thermCondVal "0.012 w/cm-degC")) ("TOP" (layerType "CONDUCTOR") (material "COPPER") (thickness "  2.100000 mil") (width "4.00 MIL") (dielectricConstant "4.500000") (lossTangent "0") (etchFactor "70.000000") (elecCondVal "595900.000000 mho/cm") (thermCondVal "0 w/cm-degC") (signalDieConstant "3.800000") (signalLossTangent "0.035")) ("" (layerType "DIELECTRIC") (material "FR-4") (thickness "  2.670000 mil") (dielectricConstant "4.000000") (lossTangent "0.035") (etchFactor "0.000000") (elecCondVal "0 mho/cm") (thermCondVal "0.012 w/cm-degC")) ("L2_GND1" (layerType "PLANE") (material "COPPER") (isShield t) (thickness "  1.250000 mil") (dielectricConstant "4.500000") (lossTangent "0.035") (etchFactor "90.000000") (elecCondVal "595900.000000 mho/cm") (thermCondVal "0.012 w/cm-degC")) ("" (layerType "DIELECTRIC") (material "FR-4") (thickness "  9.000000 mil") (dielectricConstant "4.100000") (lossTangent "0.035") (etchFactor "0.000000") (elecCondVal "0 mho/cm") (thermCondVal "0.012 w/cm-degC")) ("L3_SIG1" (layerType "CONDUCTOR") (material "COPPER") (thickness "  1.250000 mil") (width "4.00 MIL") (dielectricConstant "4.500000") (lossTangent "0.035") (etchFactor "90.000000") (elecCondVal "595900.000000 mho/cm") (thermCondVal "0.012 w/cm-degC") (signalDieConstant "4.100000") (signalLossTangent "0.035")) ("" (layerType "DIELECTRIC") (material "FR-4") (thickness "  3.000000 mil") (dielectricConstant "4.500000") (lossTangent "0.035") (etchFactor "0.000000") (elecCondVal "0 mho/cm") (thermCondVal "0 w/cm-degC")) ("L4_GND2" (layerType "PLANE") (material "COPPER") (isShield t) (thickness "  1.250000 mil") (dielectricConstant "4.500000") (lossTangent "0.035") (etchFactor "90.000000") (elecCondVal "595900.000000 mho/cm") (thermCondVal "0 w/cm-degC")) ("" (layerType "DIELECTRIC") (material "FR-4") (thickness "  9.000000 mil") (dielectricConstant "4.000000") (lossTangent "0.035") (etchFactor "0.000000") (elecCondVal "0 mho/cm") (thermCondVal "0.012 w/cm-degC")) ("L5_SIG2" (layerType "CONDUCTOR") (material "COPPER") (thickness "  1.250000 mil") (width "4.00 MIL") (dielectricConstant "4.500000") (lossTangent "0.035") (etchFactor "90.000000") (elecCondVal "595900.000000 mho/cm") (thermCondVal "0.012 w/cm-degC") (signalDieConstant "4.000000") (signalLossTangent "0.035")) ("" (layerType "DIELECTRIC") (material "FR-4") (thickness "  3.000000 mil") (dielectricConstant "4.500000") (lossTangent "0.035") (etchFactor "0.000000") (elecCondVal "0 mho/cm") (thermCondVal "0 w/cm-degC")) ("L6_GND3" (layerType "PLANE") (material "COPPER") (isShield t) (thickness "  1.250000 mil") (dielectricConstant "4.500000") (lossTangent "0.035") (etchFactor "90.000000") (elecCondVal "595900.000000 mho/cm") (thermCondVal "0 w/cm-degC")) ("" (layerType "DIELECTRIC") (material "FR-4") (thickness "  4.500000 mil") (dielectricConstant "4.100000") (lossTangent "0.035") (etchFactor "0.000000") (elecCondVal "0 mho/cm") (thermCondVal "0.012 w/cm-degC")) ("L7_PWR1-SIG" (layerType "PLANE") (material "COPPER") (isShield t) (thickness "  2.610000 mil") (dielectricConstant "4.500000") (lossTangent "0.035") (etchFactor "90.000000") (elecCondVal "595900.000000 mho/cm") (thermCondVal "0.012 w/cm-degC")) ("" (layerType "DIELECTRIC") (material "FR-4") (thickness "  3.100000 mil") (dielectricConstant "4.500000") (lossTangent "0.035") (etchFactor "0.000000") (elecCondVal "0 mho/cm") (thermCondVal "0 w/cm-degC")) ("L8_GND_TEMP" (layerType "PLANE") (material "COPPER") (isShield t) (thickness "  1.250000 mil") (dielectricConstant "4.500000") (lossTangent "0.035") (etchFactor "90.000000") (elecCondVal "595900.000000 mho/cm") (thermCondVal "0 w/cm-degC")) ("" (layerType "DIELECTRIC") (material "FR-4") (thickness "  3.030000 mil") (dielectricConstant "4.500000") (lossTangent "0.035") (etchFactor "0.000000") (elecCondVal "0 mho/cm") (thermCondVal "0 w/cm-degC")) ("L9_SIG_TEMP" (layerType "CONDUCTOR") (material "COPPER") (thickness "  1.250000 mil") (width "3.52 MIL") (dielectricConstant "4.500000") (lossTangent "0.035") (etchFactor "90.000000") (elecCondVal "595900.000000 mho/cm") (thermCondVal "0 w/cm-degC") (signalDieConstant "4.500000") (signalLossTangent "0.035")) ("" (layerType "DIELECTRIC") (material "FR-4") (thickness "  5.000000 mil") (dielectricConstant "4.500000") (lossTangent "0.035") (etchFactor "0.000000") (elecCondVal "0 mho/cm") (thermCondVal "0 w/cm-degC")) ("L10_SIG_TEMP" (layerType "CONDUCTOR") (material "COPPER") (thickness "  1.250000 mil") (width "3.52 MIL") (dielectricConstant "4.500000") (lossTangent "0.035") (etchFactor "90.000000") (elecCondVal "595900.000000 mho/cm") (thermCondVal "0 w/cm-degC") (signalDieConstant "4.500000") (signalLossTangent "0.035")) ("" (layerType "DIELECTRIC") (material "FR-4") (thickness "  3.030000 mil") (dielectricConstant "4.500000") (lossTangent "0.035") (etchFactor "0.000000") (elecCondVal "0 mho/cm") (thermCondVal "0 w/cm-degC")) ("L11_GND_TEMP" (layerType "PLANE") (material "COPPER") (isShield t) (thickness "  1.250000 mil") (dielectricConstant "4.500000") (lossTangent "0.035") (etchFactor "90.000000") (elecCondVal "595900.000000 mho/cm") (thermCondVal "0 w/cm-degC")) ("" (layerType "DIELECTRIC") (material "FR-4") (thickness "  3.100000 mil") (dielectricConstant "4.000000") (lossTangent "0.035") (etchFactor "0.000000") (elecCondVal "0 mho/cm") (thermCondVal "0.012 w/cm-degC")) ("L12_PWR2-SIG" (layerType "PLANE") (material "COPPER") (isShield t) (thickness "  2.610000 mil") (dielectricConstant "4.500000") (lossTangent "0.035") (etchFactor "90.000000") (elecCondVal "595900.000000 mho/cm") (thermCondVal "0.012 w/cm-degC")) ("" (layerType "DIELECTRIC") (material "FR-4") (thickness "  4.500000 mil") (dielectricConstant "4.500000") (lossTangent "0.035") (etchFactor "0.000000") (elecCondVal "0 mho/cm") (thermCondVal "0 w/cm-degC")) ("L13_GND4" (layerType "PLANE") (material "COPPER") (isShield t) (thickness "  1.250000 mil") (dielectricConstant "4.500000") (lossTangent "0.035") (etchFactor "90.000000") (elecCondVal "595900.000000 mho/cm") (thermCondVal "0 w/cm-degC")) ("" (layerType "DIELECTRIC") (material "FR-4") (thickness "  3.000000 mil") (dielectricConstant "4.100000") (lossTangent "0.035") (etchFactor "0.000000") (elecCondVal "0 mho/cm") (thermCondVal "0.012 w/cm-degC")) ("L14_SIG3" (layerType "CONDUCTOR") (material "COPPER") (thickness "  1.250000 mil") (width "4.00 MIL") (dielectricConstant "4.500000") (lossTangent "0.035") (etchFactor "90.000000") (elecCondVal "595900.000000 mho/cm") (thermCondVal "0.012 w/cm-degC") (signalDieConstant "4.100000") (signalLossTangent "0.035")) ("" (layerType "DIELECTRIC") (material "FR-4") (thickness "  9.000000 mil") (dielectricConstant "4.500000") (lossTangent "0.035") (etchFactor "0.000000") (elecCondVal "0 mho/cm") (thermCondVal "0 w/cm-degC")) ("L15_GND5" (layerType "PLANE") (material "COPPER") (isShield t) (thickness "  1.250000 mil") (dielectricConstant "4.500000") (lossTangent "0.035") (etchFactor "90.000000") (elecCondVal "595900.000000 mho/cm") (thermCondVal "0 w/cm-degC")) ("" (layerType "DIELECTRIC") (material "FR-4") (thickness "  3.000000 mil") (dielectricConstant "4.500000") (lossTangent "0.035") (etchFactor "0.000000") (elecCondVal "0 mho/cm") (thermCondVal "0.012 w/cm-degC")) ("L16_SIG4" (layerType "CONDUCTOR") (material "COPPER") (thickness "  1.250000 mil") (width "4.00 MIL") (dielectricConstant "4.500000") (lossTangent "0.035") (etchFactor "90.000000") (elecCondVal "595900.000000 mho/cm") (thermCondVal "0.012 w/cm-degC") (signalDieConstant "4.500000") (signalLossTangent "0.035")) ("" (layerType "DIELECTRIC") (material "FR-4") (thickness "  9.000000 mil") (dielectricConstant "4.500000") (lossTangent "0.035") (etchFactor "0.000000") (elecCondVal "0 mho/cm") (thermCondVal "0 w/cm-degC")) ("L17_GND6" (layerType "PLANE") (material "COPPER") (isShield t) (thickness "  1.250000 mil") (dielectricConstant "4.500000") (lossTangent "0.035") (etchFactor "90.000000") (elecCondVal "595900.000000 mho/cm") (thermCondVal "0.012 w/cm-degC")) ("" (layerType "DIELECTRIC") (material "FR-4") (thickness "  2.670000 mil") (dielectricConstant "4.500000") (lossTangent "0.035") (etchFactor "0.000000") (elecCondVal "0 mho/cm") (thermCondVal "0.012 w/cm-degC")) ("BOTTOM" (layerType "CONDUCTOR") (material "COPPER") (thickness "  2.100000 mil") (width "4.00 MIL") (dielectricConstant "4.500000") (lossTangent "0") (etchFactor "70.000000") (elecCondVal "595900.000000 mho/cm") (thermCondVal "0 w/cm-degC") (signalDieConstant "3.800000") (signalLossTangent "0.035")) ("" (layerType "DIELECTRIC") (material "CONFORMAL_COAT") (thickness "0.5 mil") (dielectricConstant "3.800000") (lossTangent "0.035") (etchFactor "0.000000") (elecCondVal "0 mho/cm") (thermCondVal "0.012 w/cm-degC")) ("" (layerType "SURFACE") (material "AIR") (thickness "0 mil") (dielectricConstant "1.000000") (lossTangent "0") (etchFactor "0.000000") (elecCondVal "0 mho/cm") (thermCondVal "0 w/cm-degC"))))) (Props (DesUnits "mils 2") (LayerStack ("DIELECTRIC" "DIELECTRIC" "BOTTOM" "DIELECTRIC" "L17_GND6" "DIELECTRIC" "L16_SIG4" "DIELECTRIC" "L15_GND5" "DIELECTRIC" "L14_SIG3" "DIELECTRIC" "L13_GND4" "DIELECTRIC" "L12_PWR2-SIG" "DIELECTRIC" "L11_GND_TEMP" "DIELECTRIC" "L10_SIG_TEMP" "DIELECTRIC" "L9_SIG_TEMP" "DIELECTRIC" "L8_GND_TEMP" "DIELECTRIC" "L7_PWR1-SIG" "DIELECTRIC" "L6_GND3" "DIELECTRIC" "L5_SIG2" "DIELECTRIC" "L4_GND2" "DIELECTRIC" "L3_SIG1" "DIELECTRIC" "L2_GND1" "DIELECTRIC" "TOP" "DIELECTRIC" "DIELECTRIC")) (Revision "16.600")) (Params (DiffInputPkg ((temperature "27") (bufferModelNonInverting "CDSDefaultInput_2p5v") (bufferModelInverting "CDSDefaultInput_2p5v") (threshInputHighMin "1.7 V") (threshInputHighTyp "1.7  V") (threshInputHighMax "1.7  V") (threshInputLowMin "0.7  V") (threshInputLowTyp "0.7  V") (threshInputLowMax "0.7  V") (mappingTagNonInverting nil) (mappingTagInverting nil) (cycle "1"))) (IbisOutputPkg ((temperature "27") (bufferModel "CDSDefaultOutput_2p5v") (stimuli nil) (offsets nil) (state "tristate") (cycle "1") (termMap nil) (setup "2.0e-09") (hold "1.0e-09") (rise nil) (fall nil) (macroType nil) (voltage nil) (spice nil) (LEFDEFPinName nil) (LEFDEFPinType nil) (mappingTag nil))) (IbisIOPkg ((temperature "27") (bufferModel "CDSDefaultIO_2p5v") (stimuli nil) (offsets nil) (state "tristate") (cycle "1") (termMap nil) (setup "2.0e-09") (hold "1.0e-09") (rise nil) (fall nil) (macroType nil) (voltage nil) (spice nil) (LEFDEFPinName nil) (LEFDEFPinType nil) (mappingTag nil))) (IbisIOMacro ((temperature "27") (bufferModel "CDSDefaultIO_2p5v") (stimuli nil) (offsets nil) (state "tristate") (cycle "1") (termMap nil) (setup "2.0e-09") (hold "1.0e-09") (rise nil) (fall nil) (macroType nil) (voltage nil) (spice nil) (LEFDEFPinName nil) (LEFDEFPinType nil) (mappingTag nil))) (ESpiceDevice nil) (IbisInput ((temperature "27") (bufferModel "CDSDefaultInput_2p5v") (cycle "1") (LEFDEFPinName nil) (LEFDEFPinType nil) (mappingTag nil))) (ShuntTerm ((resistance "50 ohm") (voltage "5 V") (maxDelay "0.1 ns"))) (SeriesTerm ((resistance "22 ohm") (maxDelay "0.1 ns"))) (CurrentProbe nil) (idlCircuit ((allDrivers "active") (ftsMode '("Typ")) (rcvrSelect "all") (simMode "Reflection") (tlineDelayMode "time") (userRevision "1.0") (autoSolve "On"))) (TheveninTerm ((resistanceUp "180 ohm") (resistanceDown "270 ohm") (voltageUp "5 V") (voltageDown "0 V") (maxDelay "0.1 ns"))) (RCTerm ((resistance "50 ohm") (capacitance "20 pF") (voltage "5 V") (maxDelay "0.1 ns"))) (LowClampTerm ((cutoffVoltage "0.7 V") (voltage "0 V") (maxDelay "0.1 ns"))) (Cable (length("1 m"))) (HiClampTerm ((cutoffVoltage "0.7 V") (voltage "5 V") (maxDelay "0.1 ns"))) (DualClampTerm ((cutoffVoltageUp "0.7 V") (cutoffVoltageDown "0.7 V") (voltageUp "5 V") (voltageDown "0 V") (maxDelay "0.1 ns"))) (IbisInputPkg ((temperature "27") (bufferModel "CDSDefaultInput_2p5v") (cycle "1") (LEFDEFPinName nil) (LEFDEFPinType nil) (mappingTag nil))) (async ((asyncTimePoints "") (asyncInitState "1"))) (clocked ((clockRise "1e-09") (clockFall "1e-09") (clockFreq "100e6") (clockInitState "0") (clockDutyCycle "0.5") (clockJitter "0"))) (Diode ((cutoffVoltage "0.7 V"))) (IbisOutput ((temperature "27") (bufferModel "CDSDefaultOutput_2p5v") (stimuli nil) (offsets nil) (state "tristate") (cycle "1") (termMap nil) (setup "2.0e-09") (hold "1.0e-09") (rise nil) (fall nil) (macroType nil) (voltage nil) (spice nil) (LEFDEFPinName nil) (LEFDEFPinType nil) (mappingTag nil))) (periodic ((periodicFreq "100e6") (periodicPattern "10") (periodicJitter "0"))) (IbisIO ((temperature "27") (bufferModel "CDSDefaultIO_2p5v") (stimuli nil) (offsets nil) (state "tristate") (cycle "1") (termMap nil) (setup "2.0e-09") (hold "1.0e-09") (rise nil) (fall nil) (macroType nil) (voltage nil) (spice nil) (LEFDEFPinName nil) (LEFDEFPinType nil) (mappingTag nil))) (Via ((model "Unknown") (viaOutputFormat "Unknown") (viaPadstack nil) (viaTopLayer nil) (viaBottomLayer nil) (viaIsPower nil) (viaIsGround nil))) (CPWMS ((d1Thickness "10 mil") (d1Constant "4.5") (d1LossTangent "0.035") (d2Thickness "0.72 mil") (d2Constant "4.5") (d2LossTangent "0.035") (d3Thickness "0.0") (d3Constant "1") (d3LossTangent "0") length("1000 mil") (spacing "5 mil") (spacing2 "5 mil") (spacing3 "5 mil") (spacing4 "5 mil") (spacing5 "5 mil") (traceConductivity "595900 mho/cm") (traceGeometry "cpwms") (traceLayerName "") (traceThickness "0.72 mil") (traceType "single") (traceWidth "5.0 mil") (traceWidth2 "5.0 mil") (traceWidth3 "5.0 mil") (traceWidth4 "5.0 mil") (traceWidth5 "5.0 mil") (traceWidth6 "5.0 mil") (offset "0 mil") (traceCount "1") (impedance nil))) (Trace ((d1Thickness "10 mil") (d1Constant "4.5") (d1LossTangent "0.035") (d2Thickness "10 mil") (d2Constant "4.5") (d2LossTangent "0.035") (d3Thickness "0.0") (d3Constant "1.0") (d3LossTangent "0") length("1000 mil") (spacing "5 mil") (spacing2 "5 mil") (spacing3 "5 mil") (spacing4 "5 mil") (spacing5 "5 mil") (traceConductivity "595900 mho/cm") (traceGeometry "microstrip") (traceLayerName "") (traceThickness "0.72 mil") (traceType "single") (traceWidth "5.0 mil") (traceWidth2 "5.0 mil") (traceWidth3 "5.0 mil") (traceWidth4 "5.0 mil") (traceWidth5 "5.0 mil") (traceWidth6 "5.0 mil") (offset "0 mil") (traceCount "1") (impedance nil))) (Source ((voltage "5 V"))) (CPWSL ((d1Thickness "10 mil") (d1Constant "4.5") (d1LossTangent "0.035") (d2Thickness "0.72 mil") (d2Constant "4.5") (d2LossTangent "0.035") (d3Thickness "10 mil") (d3Constant "4.5") (d3LossTangent "0.035") length("1000 mil") (spacing "5 mil") (spacing2 "5 mil") (spacing3 "5 mil") (spacing4 "5 mil") (spacing5 "5 mil") (traceConductivity "595900 mho/cm") (traceGeometry "cpwms") (traceLayerName "") (traceThickness "0.72 mil") (traceType "single") (traceWidth "5.0 mil") (traceWidth2 "5.0 mil") (traceWidth3 "5.0 mil") (traceWidth4 "5.0 mil") (traceWidth5 "5.0 mil") (traceWidth6 "5.0 mil") (offset "0 mil") (traceCount "1") (impedance nil))) (RLGC (length("1000 mil"))) (Capacitor ((capacitance "10 pF") (orientation "0"))) (DiffIOPkg ((temperature "27") (bufferModelNonInverting "CDSDefaultIO_2p5v") (bufferModelInverting "CDSDefaultIO_2p5v") (stimuli nil) (offsets nil) (state "tristate") (cycle "1") (termMap nil) (setup "0.9e-09") (hold "0.4e-09") (rise nil) (fall nil) (threshInputHighMin "1.7 V") (threshInputHighTyp "1.7  V") (threshInputHighMax "1.7  V") (threshInputLowMin "0.7  V") (threshInputLowTyp "0.7  V") (threshInputLowMax "0.7 ") (threshOutputHighMin "2.365  V") (threshOutputHighTyp "2.5  V") (threshOutputHighMax "2.625  V") (threshOutputLowMin "1.275  V") (threshOutputLowTyp "1.7  V") (threshOutputLowMax "1.985  V") (mappingTagNonInverting nil) (mappingTagInverting nil) (spice nil))) (Inductor ((inductance "5 nH") (orientation "0"))) (DiffIO ((temperature "27") (bufferModelNonInverting "CDSDefaultIO_2p5v") (bufferModelInverting "CDSDefaultIO_2p5v") (stimuli nil) (offsets nil) (state "tristate") (cycle "1") (termMap nil) (setup "0.9e-09") (hold "0.4e-09") (rise nil) (fall nil) (threshInputHighMin "1.7 V") (threshInputHighTyp "1.7  V") (threshInputHighMax "1.7  V") (threshInputLowMin "0.7  V") (threshInputLowTyp "0.7  V") (threshInputLowMax "0.7 ") (threshOutputHighMin "2.365  V") (threshOutputHighTyp "2.5  V") (threshOutputHighMax "2.625  V") (threshOutputLowMin "1.275  V") (threshOutputLowTyp "1.7  V") (threshOutputLowMax "1.985  V") (mappingTagNonInverting nil) (mappingTagInverting nil) (spice nil))) (CPW ((d1Thickness "10 mil") (d1Constant "4.5") (d1LossTangent "0.035") (d2Thickness "0.72 mil") (d2Constant "1") (d2LossTangent "0") (d3Thickness "0.0") (d3Constant "1") (d3LossTangent "0") length("1000 mil") (spacing "5 mil") (spacing2 "5 mil") (spacing3 "5 mil") (spacing4 "5 mil") (spacing5 "5 mil") (traceConductivity "595900 mho/cm") (traceGeometry "cpwms") (traceLayerName "") (traceThickness "0.72 mil") (traceType "single") (traceWidth "5.0 mil") (traceWidth2 "5.0 mil") (traceWidth3 "5.0 mil") (traceWidth4 "5.0 mil") (traceWidth5 "5.0 mil") (traceWidth6 "5.0 mil") (offset "0 mil") (traceCount "1") (impedance nil))) (Connector nil) (TLine ((diffImpedance "100ohm") (diffVelocity "1.4142e+08M/s") (impedance "60ohm") length("2800 mil") (propDelay "0.5 ns") (velocity "5600 mil/ns") (traceCount "1") (traceGeometry "Microstrip") (impedanceMin nil) (impedanceMax nil) (lengthMin nil) (lengthMax nil) (propDelayMin nil) (propDelayMax nil) (impedanceSweepCount nil) (propDelaySweepCount nil) (velocitySweepCount nil) (lengthSweepCount nil) (matchSetName nil))) (sync ((syncFreq "100e6") (syncInitState "1") (syncPattern "10") (syncEdgeSwitch "rise"))) (IbisIO_OpenPullDown ((temperature "27") (bufferModel "CDSDefaultIO_2p5v") (stimuli nil) (offsets nil) (state "tristate") (cycle "1") (termMap nil) (setup "2.0e-09") (hold "1.0e-09") (rise nil) (fall nil) (macroType nil) (voltage nil) (spice nil) (LEFDEFPinName nil) (LEFDEFPinType nil) (mappingTag nil))) (DiffOutputPkg ((temperature "27") (bufferModelNonInverting "CDSDefaultOutput_2p5v") (bufferModelInverting "CDSDefaultOutput_2p5v") (stimuli nil) (offsets nil) (state "tristate") (cycle "1") (termMap nil) (setup "0.9e-09") (hold "0.4e-09") (rise nil) (fall nil) (threshOutputHighMin "2.375  V") (threshOutputHighTyp "2.5  V") (threshOutputHighMax "2.625  V") (threshOutputLowMin "1.275  V") (threshOutputLowTyp "1.7  V") (threshOutputLowMax "1.985  V") (mappingTagNonInverting nil) (mappingTagInverting nil) (spice nil))) (DiffInput ((temperature "27") (bufferModelNonInverting "CDSDefaultInput_2p5v") (bufferModelInverting "CDSDefaultInput_2p5v") (threshInputHighMin "1.7 V") (threshInputHighTyp "1.7  V") (threshInputHighMax "1.7  V") (threshInputLowMin "0.7  V") (threshInputLowTyp "0.7  V") (threshInputLowMax "0.7  V") (mappingTagNonInverting nil) (mappingTagInverting nil) (cycle "1"))) (Resistor ((resistance "50 ohm") (orientation "0"))) (DiffOutput ((temperature "27") (bufferModelNonInverting "CDSDefaultOutput_2p5v") (bufferModelInverting "CDSDefaultOutput_2p5v") (stimuli nil) (offsets nil) (state "tristate") (cycle "1") (termMap nil) (setup "0.9e-09") (hold "0.4e-09") (rise nil) (fall nil) (threshOutputHighMin "2.375  V") (threshOutputHighTyp "2.5  V") (threshOutputHighMax "2.625  V") (threshOutputLowMin "1.275  V") (threshOutputLowTyp "1.7  V") (threshOutputLowMax "1.985  V") (mappingTagNonInverting nil) (mappingTagInverting nil) (spice nil))) (IbisOutput_OpenPullUp ((temperature "27") (bufferModel "CDSDefaultOutput_2p5v") (stimuli nil) (offsets nil) (state "tristate") (cycle "1") (termMap nil) (setup "2.0e-09") (hold "1.0e-09") (rise nil) (fall nil) (macroType nil) (voltage nil) (spice nil) (LEFDEFPinName nil) (LEFDEFPinType nil) (mappingTag nil))) (IbisIO_OpenPullUp ((temperature "27") (bufferModel "CDSDefaultIO_2p5v") (stimuli nil) (offsets nil) (state "tristate") (cycle "1") (termMap nil) (setup "2.0e-09") (hold "1.0e-09") (rise nil) (fall nil) (macroType nil) (voltage nil) (spice nil) (LEFDEFPinName nil) (LEFDEFPinType nil) (mappingTag nil)))))
				)
				( objectStatus "SPI_PCH_IO3" )
			)
			( electricalCSet "@crescent_city_bb_fab1_lib.crescent_city_bb_fab1(sch_1):\SPI_PCH_TPM_CS_N\"
				( groupRef "SPI_PCH_TPM_CS_N:SPI_PCH-TPM" )
				( pinPairRef "SPI_PCH_TPM_CS_N:U7C1.K4:J8E1.5" )
				( attribute "TOPOLOGY_TEMPLATE_REVISION" "1.0"
					( Origin gBackEnd )
				)
				( topologyData 25235
(SKIDL (Circuits ("MAIN" (Parts ("CRESCENT_CITY_902_20150507_Q.@@J8E1.5" IbisIOPkg (xy (5527 4228)) (refDes "J8E1") (model "Unknown") (Props (_SXDesignName "CRESCENT_CITY_902_20150507_Q") (brdx "16320 MIL") (brdy "2580.48 MIL") (bufferModel "CDSDefaultIO_2p5v") (cycle "1") (hold "1.0e-09") (mappingTag "") (offsets ("4" "0") ("5" "0")) (setup "2.0e-09") (state "tristate") (stimuli ("4" "local59") ("5" "local60")) (temperature "27") (termMap ("4" "Data") ("5" "Enable"))) (Terms ("CRESCENT_CITY_902_20150507_Q.X1632000Y258048L2LRATS" "5"))) ("CRESCENT_CITY_902_20150507_Q.@@U7C1.K4" IbisIOPkg (xy (5502 4240)) (refDes "U7C1") (model "Unknown") (Props (_SXDesignName "CRESCENT_CITY_902_20150507_Q") (brdx "14900.98 MIL") (brdy "3731.89 MIL") (bufferModel "CDSDefaultIO_2p5v") (cycle "1") (hold "1.0e-09") (mappingTag "") (offsets ("4" "0") ("5" "0")) (setup "2.0e-09") (state "tristate") (stimuli ("4" "local61") ("5" "local62")) (temperature "27") (termMap ("4" "Data") ("5" "Enable"))) (Terms ("CRESCENT_CITY_902_20150507_Q.X1490098Y373189L2LRATS" "K4"))) ("CRESCENT_CITY_902_20150507_Q.T@@RATS@@U7C1.K4@@R8D35.1" TLine (xy (5503 4229)) (mirror x) (refDes "TL45") (Props (_SXDesignName "CRESCENT_CITY_902_20150507_Q") (impedance "52.449 ohm") length("2660.91 MIL") (propDelay "0.47792 ns") (traceCount "1") (traceGeometry "Microstrip") (velocity "5567.68 mil/ns")) (Terms ("CRESCENT_CITY_902_20150507_Q.X1490098Y373189L2LRATS" "1") ("CRESCENT_CITY_902_20150507_Q.X1645000Y262000L2LRATS" "2"))) ("CRESCENT_CITY_902_20150507_Q.T@@RATS@@J8E1.5@@R8D35.2" TLine (xy (5512 4223)) (mirror x) (refDes "TL46") (Props (_SXDesignName "CRESCENT_CITY_902_20150507_Q") (impedance "48.412 ohm") length("134.52 MIL") (propDelay "0.02416 ns") (traceCount "1") (traceGeometry "Microstrip") (velocity "5567.87 mil/ns")) (Terms ("CRESCENT_CITY_902_20150507_Q.X1632000Y258048L2LRATS" "1") ("CRESCENT_CITY_902_20150507_Q.X1641500Y262000L2LRATS" "2"))) ("CRESCENT_CITY_902_20150507_Q.@@R8D35.2.1" Resistor (xy (5497 4223)) (mirror x) (refDes "R8D35") (value "1 Ohm") (Props (_SXDesignName "CRESCENT_CITY_902_20150507_Q")) (Terms ("CRESCENT_CITY_902_20150507_Q.X1641500Y262000L2LRATS" "2") ("CRESCENT_CITY_902_20150507_Q.X1645000Y262000L2LRATS" "1")))) (Nodes ("CRESCENT_CITY_902_20150507_Q.X1490098Y373189L2LRATS" (terms "CRESCENT_CITY_902_20150507_Q.T@@RATS@@U7C1.K4@@R8D35.1.1" "CRESCENT_CITY_902_20150507_Q.@@U7C1.K4.1")) ("CRESCENT_CITY_902_20150507_Q.X1641500Y262000L2LRATS" (terms "CRESCENT_CITY_902_20150507_Q.@@R8D35.2.1.1" "CRESCENT_CITY_902_20150507_Q.T@@RATS@@J8E1.5@@R8D35.2.2")) ("CRESCENT_CITY_902_20150507_Q.X1632000Y258048L2LRATS" (terms "CRESCENT_CITY_902_20150507_Q.T@@RATS@@J8E1.5@@R8D35.2.1" "CRESCENT_CITY_902_20150507_Q.@@J8E1.5.1")) ("CRESCENT_CITY_902_20150507_Q.X1645000Y262000L2LRATS" (terms "CRESCENT_CITY_902_20150507_Q.@@R8D35.2.1.2" "CRESCENT_CITY_902_20150507_Q.T@@RATS@@U7C1.K4@@R8D35.1.2"))) (Ports) (Stimuli ("local62" (scope local) (stimType periodic) (Props (periodicFreq "5e+007") (periodicJitter "0") (periodicPattern "1"))) ("local59" (scope local) (stimType periodic) (Props (periodicFreq "5e+007") (periodicJitter "0") (periodicPattern "1"))) ("local60" (scope local) (stimType periodic) (Props (periodicFreq "5e+007") (periodicJitter "0") (periodicPattern "1"))) ("local61" (scope local) (stimType periodic) (Props (periodicFreq "5e+007") (periodicJitter "0") (periodicPattern "1")))) (Notes) (Constraints ("RELATIVE_PROPAGATION_DELAY" ("SPI_PCH-TPM" "CRESCENT_CITY_902_20150507_Q U7C1.K4" "CRESCENT_CITY_902_20150507_Q J8E1.5" "LOCAL" "LENGTH" "0.00635" "LENGTH" "0"))) (MeasurementSets ("EMI" ("EMIStatus" status("on")) ("PeakEmission" status("on")) ("PeakFrequency" status("on")) ("PulseFreq" status("on")) ("RiseTime" status("on")) ("VoltageSwing" status("on"))) ("Reflection" ("BufferDelayFall" status("off")) ("BufferDelayRise" status("off")) ("EyeHeight" status("off")) ("EyeJitter" status("off")) ("EyeWidth" status("off")) ("FirstIncidentFall" status("off")) ("FirstIncidentRise" status("off")) ("Glitch" status("on")) ("GlitchFall" status("off")) ("GlitchRise" status("off")) ("Monotonic" status("on")) ("MonotonicFall" status("off")) ("MonotonicRise" status("off")) ("NoiseMargin" status("on")) ("NoiseMarginHigh" status("off")) ("NoiseMarginLow" status("off")) ("OvershootHigh" status("on")) ("OvershootLow" status("on")) ("PropDelay" status("on")) ("SettleDelay" status("on")) ("SettleDelayFall" status("off")) ("SettleDelayRise" status("off")) ("SwitchDelay" status("on")) ("SwitchDelayFall" status("off")) ("SwitchDelayRise" status("off"))) ("Crosstalk" ("Crosstalk" status("on"))) ("Custom")) (VectorSets) (Props (XnetName "SPI_PCH_TPM_CS_N") (allDrivers "active") (customSimType "Reflection") (ftsMode ("Typ")) (rcvrSelect "all") (tlineDelayMode "time") (userRevision "1.0")))) (Subckts) (CrossSections ("CRESCENT_CITY_902_20150507_Q" (Props (SXDesignName "CRESCENT_CITY_902_20150507_Q")) (Layers ("" (layerType "SURFACE") (material "AIR") (thickness "0 mil") (dielectricConstant "1.000000") (lossTangent "0") (etchFactor "0.000000") (elecCondVal "0 mho/cm") (thermCondVal "0 w/cm-degC")) ("" (layerType "DIELECTRIC") (material "CONFORMAL_COAT") (thickness "0.5 mil") (dielectricConstant "3.800000") (lossTangent "0.035") (etchFactor "0.000000") (elecCondVal "0 mho/cm") (thermCondVal "0.012 w/cm-degC")) ("TOP" (layerType "CONDUCTOR") (material "COPPER") (thickness "  2.100000 mil") (width "4.00 MIL") (dielectricConstant "4.500000") (lossTangent "0") (etchFactor "70.000000") (elecCondVal "595900.000000 mho/cm") (thermCondVal "0 w/cm-degC") (signalDieConstant "3.800000") (signalLossTangent "0.035")) ("" (layerType "DIELECTRIC") (material "FR-4") (thickness "  2.670000 mil") (dielectricConstant "4.000000") (lossTangent "0.035") (etchFactor "0.000000") (elecCondVal "0 mho/cm") (thermCondVal "0.012 w/cm-degC")) ("L2_GND1" (layerType "PLANE") (material "COPPER") (isShield t) (thickness "  1.250000 mil") (dielectricConstant "4.500000") (lossTangent "0.035") (etchFactor "90.000000") (elecCondVal "595900.000000 mho/cm") (thermCondVal "0.012 w/cm-degC")) ("" (layerType "DIELECTRIC") (material "FR-4") (thickness "  9.000000 mil") (dielectricConstant "4.100000") (lossTangent "0.035") (etchFactor "0.000000") (elecCondVal "0 mho/cm") (thermCondVal "0.012 w/cm-degC")) ("L3_SIG1" (layerType "CONDUCTOR") (material "COPPER") (thickness "  1.250000 mil") (width "4.00 MIL") (dielectricConstant "4.500000") (lossTangent "0.035") (etchFactor "90.000000") (elecCondVal "595900.000000 mho/cm") (thermCondVal "0.012 w/cm-degC") (signalDieConstant "4.100000") (signalLossTangent "0.035")) ("" (layerType "DIELECTRIC") (material "FR-4") (thickness "  3.000000 mil") (dielectricConstant "4.500000") (lossTangent "0.035") (etchFactor "0.000000") (elecCondVal "0 mho/cm") (thermCondVal "0 w/cm-degC")) ("L4_GND2" (layerType "PLANE") (material "COPPER") (isShield t) (thickness "  1.250000 mil") (dielectricConstant "4.500000") (lossTangent "0.035") (etchFactor "90.000000") (elecCondVal "595900.000000 mho/cm") (thermCondVal "0 w/cm-degC")) ("" (layerType "DIELECTRIC") (material "FR-4") (thickness "  9.000000 mil") (dielectricConstant "4.000000") (lossTangent "0.035") (etchFactor "0.000000") (elecCondVal "0 mho/cm") (thermCondVal "0.012 w/cm-degC")) ("L5_SIG2" (layerType "CONDUCTOR") (material "COPPER") (thickness "  1.250000 mil") (width "4.00 MIL") (dielectricConstant "4.500000") (lossTangent "0.035") (etchFactor "90.000000") (elecCondVal "595900.000000 mho/cm") (thermCondVal "0.012 w/cm-degC") (signalDieConstant "4.000000") (signalLossTangent "0.035")) ("" (layerType "DIELECTRIC") (material "FR-4") (thickness "  3.000000 mil") (dielectricConstant "4.500000") (lossTangent "0.035") (etchFactor "0.000000") (elecCondVal "0 mho/cm") (thermCondVal "0 w/cm-degC")) ("L6_GND3" (layerType "PLANE") (material "COPPER") (isShield t) (thickness "  1.250000 mil") (dielectricConstant "4.500000") (lossTangent "0.035") (etchFactor "90.000000") (elecCondVal "595900.000000 mho/cm") (thermCondVal "0 w/cm-degC")) ("" (layerType "DIELECTRIC") (material "FR-4") (thickness "  4.500000 mil") (dielectricConstant "4.100000") (lossTangent "0.035") (etchFactor "0.000000") (elecCondVal "0 mho/cm") (thermCondVal "0.012 w/cm-degC")) ("L7_PWR1-SIG" (layerType "PLANE") (material "COPPER") (isShield t) (thickness "  2.610000 mil") (dielectricConstant "4.500000") (lossTangent "0.035") (etchFactor "90.000000") (elecCondVal "595900.000000 mho/cm") (thermCondVal "0.012 w/cm-degC")) ("" (layerType "DIELECTRIC") (material "FR-4") (thickness "  3.100000 mil") (dielectricConstant "4.500000") (lossTangent "0.035") (etchFactor "0.000000") (elecCondVal "0 mho/cm") (thermCondVal "0 w/cm-degC")) ("L8_GND_TEMP" (layerType "PLANE") (material "COPPER") (isShield t) (thickness "  1.250000 mil") (dielectricConstant "4.500000") (lossTangent "0.035") (etchFactor "90.000000") (elecCondVal "595900.000000 mho/cm") (thermCondVal "0 w/cm-degC")) ("" (layerType "DIELECTRIC") (material "FR-4") (thickness "  3.030000 mil") (dielectricConstant "4.500000") (lossTangent "0.035") (etchFactor "0.000000") (elecCondVal "0 mho/cm") (thermCondVal "0 w/cm-degC")) ("L9_SIG_TEMP" (layerType "CONDUCTOR") (material "COPPER") (thickness "  1.250000 mil") (width "3.52 MIL") (dielectricConstant "4.500000") (lossTangent "0.035") (etchFactor "90.000000") (elecCondVal "595900.000000 mho/cm") (thermCondVal "0 w/cm-degC") (signalDieConstant "4.500000") (signalLossTangent "0.035")) ("" (layerType "DIELECTRIC") (material "FR-4") (thickness "  5.000000 mil") (dielectricConstant "4.500000") (lossTangent "0.035") (etchFactor "0.000000") (elecCondVal "0 mho/cm") (thermCondVal "0 w/cm-degC")) ("L10_SIG_TEMP" (layerType "CONDUCTOR") (material "COPPER") (thickness "  1.250000 mil") (width "3.52 MIL") (dielectricConstant "4.500000") (lossTangent "0.035") (etchFactor "90.000000") (elecCondVal "595900.000000 mho/cm") (thermCondVal "0 w/cm-degC") (signalDieConstant "4.500000") (signalLossTangent "0.035")) ("" (layerType "DIELECTRIC") (material "FR-4") (thickness "  3.030000 mil") (dielectricConstant "4.500000") (lossTangent "0.035") (etchFactor "0.000000") (elecCondVal "0 mho/cm") (thermCondVal "0 w/cm-degC")) ("L11_GND_TEMP" (layerType "PLANE") (material "COPPER") (isShield t) (thickness "  1.250000 mil") (dielectricConstant "4.500000") (lossTangent "0.035") (etchFactor "90.000000") (elecCondVal "595900.000000 mho/cm") (thermCondVal "0 w/cm-degC")) ("" (layerType "DIELECTRIC") (material "FR-4") (thickness "  3.100000 mil") (dielectricConstant "4.000000") (lossTangent "0.035") (etchFactor "0.000000") (elecCondVal "0 mho/cm") (thermCondVal "0.012 w/cm-degC")) ("L12_PWR2-SIG" (layerType "PLANE") (material "COPPER") (isShield t) (thickness "  2.610000 mil") (dielectricConstant "4.500000") (lossTangent "0.035") (etchFactor "90.000000") (elecCondVal "595900.000000 mho/cm") (thermCondVal "0.012 w/cm-degC")) ("" (layerType "DIELECTRIC") (material "FR-4") (thickness "  4.500000 mil") (dielectricConstant "4.500000") (lossTangent "0.035") (etchFactor "0.000000") (elecCondVal "0 mho/cm") (thermCondVal "0 w/cm-degC")) ("L13_GND4" (layerType "PLANE") (material "COPPER") (isShield t) (thickness "  1.250000 mil") (dielectricConstant "4.500000") (lossTangent "0.035") (etchFactor "90.000000") (elecCondVal "595900.000000 mho/cm") (thermCondVal "0 w/cm-degC")) ("" (layerType "DIELECTRIC") (material "FR-4") (thickness "  3.000000 mil") (dielectricConstant "4.100000") (lossTangent "0.035") (etchFactor "0.000000") (elecCondVal "0 mho/cm") (thermCondVal "0.012 w/cm-degC")) ("L14_SIG3" (layerType "CONDUCTOR") (material "COPPER") (thickness "  1.250000 mil") (width "4.00 MIL") (dielectricConstant "4.500000") (lossTangent "0.035") (etchFactor "90.000000") (elecCondVal "595900.000000 mho/cm") (thermCondVal "0.012 w/cm-degC") (signalDieConstant "4.100000") (signalLossTangent "0.035")) ("" (layerType "DIELECTRIC") (material "FR-4") (thickness "  9.000000 mil") (dielectricConstant "4.500000") (lossTangent "0.035") (etchFactor "0.000000") (elecCondVal "0 mho/cm") (thermCondVal "0 w/cm-degC")) ("L15_GND5" (layerType "PLANE") (material "COPPER") (isShield t) (thickness "  1.250000 mil") (dielectricConstant "4.500000") (lossTangent "0.035") (etchFactor "90.000000") (elecCondVal "595900.000000 mho/cm") (thermCondVal "0 w/cm-degC")) ("" (layerType "DIELECTRIC") (material "FR-4") (thickness "  3.000000 mil") (dielectricConstant "4.500000") (lossTangent "0.035") (etchFactor "0.000000") (elecCondVal "0 mho/cm") (thermCondVal "0.012 w/cm-degC")) ("L16_SIG4" (layerType "CONDUCTOR") (material "COPPER") (thickness "  1.250000 mil") (width "4.00 MIL") (dielectricConstant "4.500000") (lossTangent "0.035") (etchFactor "90.000000") (elecCondVal "595900.000000 mho/cm") (thermCondVal "0.012 w/cm-degC") (signalDieConstant "4.500000") (signalLossTangent "0.035")) ("" (layerType "DIELECTRIC") (material "FR-4") (thickness "  9.000000 mil") (dielectricConstant "4.500000") (lossTangent "0.035") (etchFactor "0.000000") (elecCondVal "0 mho/cm") (thermCondVal "0 w/cm-degC")) ("L17_GND6" (layerType "PLANE") (material "COPPER") (isShield t) (thickness "  1.250000 mil") (dielectricConstant "4.500000") (lossTangent "0.035") (etchFactor "90.000000") (elecCondVal "595900.000000 mho/cm") (thermCondVal "0.012 w/cm-degC")) ("" (layerType "DIELECTRIC") (material "FR-4") (thickness "  2.670000 mil") (dielectricConstant "4.500000") (lossTangent "0.035") (etchFactor "0.000000") (elecCondVal "0 mho/cm") (thermCondVal "0.012 w/cm-degC")) ("BOTTOM" (layerType "CONDUCTOR") (material "COPPER") (thickness "  2.100000 mil") (width "4.00 MIL") (dielectricConstant "4.500000") (lossTangent "0") (etchFactor "70.000000") (elecCondVal "595900.000000 mho/cm") (thermCondVal "0 w/cm-degC") (signalDieConstant "3.800000") (signalLossTangent "0.035")) ("" (layerType "DIELECTRIC") (material "CONFORMAL_COAT") (thickness "0.5 mil") (dielectricConstant "3.800000") (lossTangent "0.035") (etchFactor "0.000000") (elecCondVal "0 mho/cm") (thermCondVal "0.012 w/cm-degC")) ("" (layerType "SURFACE") (material "AIR") (thickness "0 mil") (dielectricConstant "1.000000") (lossTangent "0") (etchFactor "0.000000") (elecCondVal "0 mho/cm") (thermCondVal "0 w/cm-degC"))))) (Props (DesUnits "mils 2") (LayerStack ("DIELECTRIC" "DIELECTRIC" "BOTTOM" "DIELECTRIC" "L17_GND6" "DIELECTRIC" "L16_SIG4" "DIELECTRIC" "L15_GND5" "DIELECTRIC" "L14_SIG3" "DIELECTRIC" "L13_GND4" "DIELECTRIC" "L12_PWR2-SIG" "DIELECTRIC" "L11_GND_TEMP" "DIELECTRIC" "L10_SIG_TEMP" "DIELECTRIC" "L9_SIG_TEMP" "DIELECTRIC" "L8_GND_TEMP" "DIELECTRIC" "L7_PWR1-SIG" "DIELECTRIC" "L6_GND3" "DIELECTRIC" "L5_SIG2" "DIELECTRIC" "L4_GND2" "DIELECTRIC" "L3_SIG1" "DIELECTRIC" "L2_GND1" "DIELECTRIC" "TOP" "DIELECTRIC" "DIELECTRIC")) (Revision "16.600")) (Params (DiffInputPkg ((temperature "27") (bufferModelNonInverting "CDSDefaultInput_2p5v") (bufferModelInverting "CDSDefaultInput_2p5v") (threshInputHighMin "1.7 V") (threshInputHighTyp "1.7  V") (threshInputHighMax "1.7  V") (threshInputLowMin "0.7  V") (threshInputLowTyp "0.7  V") (threshInputLowMax "0.7  V") (mappingTagNonInverting nil) (mappingTagInverting nil) (cycle "1"))) (IbisOutputPkg ((temperature "27") (bufferModel "CDSDefaultOutput_2p5v") (stimuli nil) (offsets nil) (state "tristate") (cycle "1") (termMap nil) (setup "2.0e-09") (hold "1.0e-09") (rise nil) (fall nil) (macroType nil) (voltage nil) (spice nil) (LEFDEFPinName nil) (LEFDEFPinType nil) (mappingTag nil))) (IbisIOPkg ((temperature "27") (bufferModel "CDSDefaultIO_2p5v") (stimuli nil) (offsets nil) (state "tristate") (cycle "1") (termMap nil) (setup "2.0e-09") (hold "1.0e-09") (rise nil) (fall nil) (macroType nil) (voltage nil) (spice nil) (LEFDEFPinName nil) (LEFDEFPinType nil) (mappingTag nil))) (IbisIOMacro ((temperature "27") (bufferModel "CDSDefaultIO_2p5v") (stimuli nil) (offsets nil) (state "tristate") (cycle "1") (termMap nil) (setup "2.0e-09") (hold "1.0e-09") (rise nil) (fall nil) (macroType nil) (voltage nil) (spice nil) (LEFDEFPinName nil) (LEFDEFPinType nil) (mappingTag nil))) (ESpiceDevice nil) (IbisInput ((temperature "27") (bufferModel "CDSDefaultInput_2p5v") (cycle "1") (LEFDEFPinName nil) (LEFDEFPinType nil) (mappingTag nil))) (ShuntTerm ((resistance "50 ohm") (voltage "5 V") (maxDelay "0.1 ns"))) (SeriesTerm ((resistance "22 ohm") (maxDelay "0.1 ns"))) (CurrentProbe nil) (idlCircuit ((allDrivers "active") (ftsMode '("Typ")) (rcvrSelect "all") (simMode "Reflection") (tlineDelayMode "time") (userRevision "1.0") (autoSolve "On"))) (TheveninTerm ((resistanceUp "180 ohm") (resistanceDown "270 ohm") (voltageUp "5 V") (voltageDown "0 V") (maxDelay "0.1 ns"))) (RCTerm ((resistance "50 ohm") (capacitance "20 pF") (voltage "5 V") (maxDelay "0.1 ns"))) (LowClampTerm ((cutoffVoltage "0.7 V") (voltage "0 V") (maxDelay "0.1 ns"))) (Cable (length("1 m"))) (HiClampTerm ((cutoffVoltage "0.7 V") (voltage "5 V") (maxDelay "0.1 ns"))) (DualClampTerm ((cutoffVoltageUp "0.7 V") (cutoffVoltageDown "0.7 V") (voltageUp "5 V") (voltageDown "0 V") (maxDelay "0.1 ns"))) (IbisInputPkg ((temperature "27") (bufferModel "CDSDefaultInput_2p5v") (cycle "1") (LEFDEFPinName nil) (LEFDEFPinType nil) (mappingTag nil))) (async ((asyncTimePoints "") (asyncInitState "1"))) (clocked ((clockRise "1e-09") (clockFall "1e-09") (clockFreq "100e6") (clockInitState "0") (clockDutyCycle "0.5") (clockJitter "0"))) (Diode ((cutoffVoltage "0.7 V"))) (IbisOutput ((temperature "27") (bufferModel "CDSDefaultOutput_2p5v") (stimuli nil) (offsets nil) (state "tristate") (cycle "1") (termMap nil) (setup "2.0e-09") (hold "1.0e-09") (rise nil) (fall nil) (macroType nil) (voltage nil) (spice nil) (LEFDEFPinName nil) (LEFDEFPinType nil) (mappingTag nil))) (periodic ((periodicFreq "100e6") (periodicPattern "10") (periodicJitter "0"))) (IbisIO ((temperature "27") (bufferModel "CDSDefaultIO_2p5v") (stimuli nil) (offsets nil) (state "tristate") (cycle "1") (termMap nil) (setup "2.0e-09") (hold "1.0e-09") (rise nil) (fall nil) (macroType nil) (voltage nil) (spice nil) (LEFDEFPinName nil) (LEFDEFPinType nil) (mappingTag nil))) (Via ((model "Unknown") (viaOutputFormat "Unknown") (viaPadstack nil) (viaTopLayer nil) (viaBottomLayer nil) (viaIsPower nil) (viaIsGround nil))) (CPWMS ((d1Thickness "10 mil") (d1Constant "4.5") (d1LossTangent "0.035") (d2Thickness "0.72 mil") (d2Constant "4.5") (d2LossTangent "0.035") (d3Thickness "0.0") (d3Constant "1") (d3LossTangent "0") length("1000 mil") (spacing "5 mil") (spacing2 "5 mil") (spacing3 "5 mil") (spacing4 "5 mil") (spacing5 "5 mil") (traceConductivity "595900 mho/cm") (traceGeometry "cpwms") (traceLayerName "") (traceThickness "0.72 mil") (traceType "single") (traceWidth "5.0 mil") (traceWidth2 "5.0 mil") (traceWidth3 "5.0 mil") (traceWidth4 "5.0 mil") (traceWidth5 "5.0 mil") (traceWidth6 "5.0 mil") (offset "0 mil") (traceCount "1") (impedance nil))) (Trace ((d1Thickness "10 mil") (d1Constant "4.5") (d1LossTangent "0.035") (d2Thickness "10 mil") (d2Constant "4.5") (d2LossTangent "0.035") (d3Thickness "0.0") (d3Constant "1.0") (d3LossTangent "0") length("1000 mil") (spacing "5 mil") (spacing2 "5 mil") (spacing3 "5 mil") (spacing4 "5 mil") (spacing5 "5 mil") (traceConductivity "595900 mho/cm") (traceGeometry "microstrip") (traceLayerName "") (traceThickness "0.72 mil") (traceType "single") (traceWidth "5.0 mil") (traceWidth2 "5.0 mil") (traceWidth3 "5.0 mil") (traceWidth4 "5.0 mil") (traceWidth5 "5.0 mil") (traceWidth6 "5.0 mil") (offset "0 mil") (traceCount "1") (impedance nil))) (Source ((voltage "5 V"))) (CPWSL ((d1Thickness "10 mil") (d1Constant "4.5") (d1LossTangent "0.035") (d2Thickness "0.72 mil") (d2Constant "4.5") (d2LossTangent "0.035") (d3Thickness "10 mil") (d3Constant "4.5") (d3LossTangent "0.035") length("1000 mil") (spacing "5 mil") (spacing2 "5 mil") (spacing3 "5 mil") (spacing4 "5 mil") (spacing5 "5 mil") (traceConductivity "595900 mho/cm") (traceGeometry "cpwms") (traceLayerName "") (traceThickness "0.72 mil") (traceType "single") (traceWidth "5.0 mil") (traceWidth2 "5.0 mil") (traceWidth3 "5.0 mil") (traceWidth4 "5.0 mil") (traceWidth5 "5.0 mil") (traceWidth6 "5.0 mil") (offset "0 mil") (traceCount "1") (impedance nil))) (RLGC (length("1000 mil"))) (Capacitor ((capacitance "10 pF") (orientation "0"))) (DiffIOPkg ((temperature "27") (bufferModelNonInverting "CDSDefaultIO_2p5v") (bufferModelInverting "CDSDefaultIO_2p5v") (stimuli nil) (offsets nil) (state "tristate") (cycle "1") (termMap nil) (setup "0.9e-09") (hold "0.4e-09") (rise nil) (fall nil) (threshInputHighMin "1.7 V") (threshInputHighTyp "1.7  V") (threshInputHighMax "1.7  V") (threshInputLowMin "0.7  V") (threshInputLowTyp "0.7  V") (threshInputLowMax "0.7 ") (threshOutputHighMin "2.365  V") (threshOutputHighTyp "2.5  V") (threshOutputHighMax "2.625  V") (threshOutputLowMin "1.275  V") (threshOutputLowTyp "1.7  V") (threshOutputLowMax "1.985  V") (mappingTagNonInverting nil) (mappingTagInverting nil) (spice nil))) (Inductor ((inductance "5 nH") (orientation "0"))) (DiffIO ((temperature "27") (bufferModelNonInverting "CDSDefaultIO_2p5v") (bufferModelInverting "CDSDefaultIO_2p5v") (stimuli nil) (offsets nil) (state "tristate") (cycle "1") (termMap nil) (setup "0.9e-09") (hold "0.4e-09") (rise nil) (fall nil) (threshInputHighMin "1.7 V") (threshInputHighTyp "1.7  V") (threshInputHighMax "1.7  V") (threshInputLowMin "0.7  V") (threshInputLowTyp "0.7  V") (threshInputLowMax "0.7 ") (threshOutputHighMin "2.365  V") (threshOutputHighTyp "2.5  V") (threshOutputHighMax "2.625  V") (threshOutputLowMin "1.275  V") (threshOutputLowTyp "1.7  V") (threshOutputLowMax "1.985  V") (mappingTagNonInverting nil) (mappingTagInverting nil) (spice nil))) (CPW ((d1Thickness "10 mil") (d1Constant "4.5") (d1LossTangent "0.035") (d2Thickness "0.72 mil") (d2Constant "1") (d2LossTangent "0") (d3Thickness "0.0") (d3Constant "1") (d3LossTangent "0") length("1000 mil") (spacing "5 mil") (spacing2 "5 mil") (spacing3 "5 mil") (spacing4 "5 mil") (spacing5 "5 mil") (traceConductivity "595900 mho/cm") (traceGeometry "cpwms") (traceLayerName "") (traceThickness "0.72 mil") (traceType "single") (traceWidth "5.0 mil") (traceWidth2 "5.0 mil") (traceWidth3 "5.0 mil") (traceWidth4 "5.0 mil") (traceWidth5 "5.0 mil") (traceWidth6 "5.0 mil") (offset "0 mil") (traceCount "1") (impedance nil))) (Connector nil) (TLine ((diffImpedance "100ohm") (diffVelocity "1.4142e+08M/s") (impedance "60ohm") length("2800 mil") (propDelay "0.5 ns") (velocity "5600 mil/ns") (traceCount "1") (traceGeometry "Microstrip") (impedanceMin nil) (impedanceMax nil) (lengthMin nil) (lengthMax nil) (propDelayMin nil) (propDelayMax nil) (impedanceSweepCount nil) (propDelaySweepCount nil) (velocitySweepCount nil) (lengthSweepCount nil) (matchSetName nil))) (sync ((syncFreq "100e6") (syncInitState "1") (syncPattern "10") (syncEdgeSwitch "rise"))) (IbisIO_OpenPullDown ((temperature "27") (bufferModel "CDSDefaultIO_2p5v") (stimuli nil) (offsets nil) (state "tristate") (cycle "1") (termMap nil) (setup "2.0e-09") (hold "1.0e-09") (rise nil) (fall nil) (macroType nil) (voltage nil) (spice nil) (LEFDEFPinName nil) (LEFDEFPinType nil) (mappingTag nil))) (DiffOutputPkg ((temperature "27") (bufferModelNonInverting "CDSDefaultOutput_2p5v") (bufferModelInverting "CDSDefaultOutput_2p5v") (stimuli nil) (offsets nil) (state "tristate") (cycle "1") (termMap nil) (setup "0.9e-09") (hold "0.4e-09") (rise nil) (fall nil) (threshOutputHighMin "2.375  V") (threshOutputHighTyp "2.5  V") (threshOutputHighMax "2.625  V") (threshOutputLowMin "1.275  V") (threshOutputLowTyp "1.7  V") (threshOutputLowMax "1.985  V") (mappingTagNonInverting nil) (mappingTagInverting nil) (spice nil))) (DiffInput ((temperature "27") (bufferModelNonInverting "CDSDefaultInput_2p5v") (bufferModelInverting "CDSDefaultInput_2p5v") (threshInputHighMin "1.7 V") (threshInputHighTyp "1.7  V") (threshInputHighMax "1.7  V") (threshInputLowMin "0.7  V") (threshInputLowTyp "0.7  V") (threshInputLowMax "0.7  V") (mappingTagNonInverting nil) (mappingTagInverting nil) (cycle "1"))) (Resistor ((resistance "50 ohm") (orientation "0"))) (DiffOutput ((temperature "27") (bufferModelNonInverting "CDSDefaultOutput_2p5v") (bufferModelInverting "CDSDefaultOutput_2p5v") (stimuli nil) (offsets nil) (state "tristate") (cycle "1") (termMap nil) (setup "0.9e-09") (hold "0.4e-09") (rise nil) (fall nil) (threshOutputHighMin "2.375  V") (threshOutputHighTyp "2.5  V") (threshOutputHighMax "2.625  V") (threshOutputLowMin "1.275  V") (threshOutputLowTyp "1.7  V") (threshOutputLowMax "1.985  V") (mappingTagNonInverting nil) (mappingTagInverting nil) (spice nil))) (IbisOutput_OpenPullUp ((temperature "27") (bufferModel "CDSDefaultOutput_2p5v") (stimuli nil) (offsets nil) (state "tristate") (cycle "1") (termMap nil) (setup "2.0e-09") (hold "1.0e-09") (rise nil) (fall nil) (macroType nil) (voltage nil) (spice nil) (LEFDEFPinName nil) (LEFDEFPinType nil) (mappingTag nil))) (IbisIO_OpenPullUp ((temperature "27") (bufferModel "CDSDefaultIO_2p5v") (stimuli nil) (offsets nil) (state "tristate") (cycle "1") (termMap nil) (setup "2.0e-09") (hold "1.0e-09") (rise nil) (fall nil) (macroType nil) (voltage nil) (spice nil) (LEFDEFPinName nil) (LEFDEFPinType nil) (mappingTag nil)))))
				)
				( objectStatus "SPI_PCH_TPM_CS_N" )
			)
			( electricalCSet "@crescent_city_bb_fab1_lib.crescent_city_bb_fab1(sch_1):\SPI_PCH_CS0_R1_N\"
				( groupRef "SPI_PCH_CS0_R1_N:SPI_PCH-MUX" )
				( pinPairRef "SPI_PCH_CS0_R1_N:U7C1.J3:U8F1.11" )
				( attribute "TOPOLOGY_TEMPLATE_REVISION" "1.0"
					( Origin gBackEnd )
				)
				( topologyData 25231
(SKIDL (Circuits ("MAIN" (Parts ("CRESCENT_CITY_902_20150507_Q.@@U7C1.J3" IbisIOPkg (xy (5527 4228)) (refDes "U7C1") (model "Unknown") (Props (_SXDesignName "CRESCENT_CITY_902_20150507_Q") (brdx "14881.3 MIL") (brdy "3715.55 MIL") (bufferModel "CDSDefaultIO_2p5v") (cycle "1") (hold "1.0e-09") (mappingTag "") (offsets ("4" "0") ("5" "0")) (setup "2.0e-09") (state "tristate") (stimuli ("4" "local55") ("5" "local56")) (temperature "27") (termMap ("4" "Data") ("5" "Enable"))) (Terms ("CRESCENT_CITY_902_20150507_Q.X1488130Y371555L2LRATS" "J3"))) ("CRESCENT_CITY_902_20150507_Q.@@U8F1.11" IbisIOPkg (xy (5502 4240)) (refDes "U8F1") (model "Unknown") (Props (_SXDesignName "CRESCENT_CITY_902_20150507_Q") (brdx "15795 MIL") (brdy "1495 MIL") (bufferModel "CDSDefaultIO_2p5v") (cycle "1") (hold "1.0e-09") (mappingTag "") (offsets ("4" "0") ("5" "0")) (setup "2.0e-09") (state "tristate") (stimuli ("4" "local57") ("5" "local58")) (temperature "27") (termMap ("4" "Data") ("5" "Enable"))) (Terms ("CRESCENT_CITY_902_20150507_Q.X1579500Y149500L2LRATS" "11"))) ("CRESCENT_CITY_902_20150507_Q.T@@RATS@@U8F1.11@@R7C16.2" TLine (xy (5503 4229)) (mirror x) (refDes "TL43") (Props (_SXDesignName "CRESCENT_CITY_902_20150507_Q") (impedance "48.412 ohm") length("2922.97 MIL") (propDelay "0.52499 ns") (traceCount "1") (traceGeometry "Microstrip") (velocity "5567.68 mil/ns")) (Terms ("CRESCENT_CITY_902_20150507_Q.X1579500Y149500L2LRATS" "1") ("CRESCENT_CITY_902_20150507_Q.X1491823Y354120L2LRATS" "2"))) ("CRESCENT_CITY_902_20150507_Q.T@@RATS@@U7C1.J3@@R7C16.1" TLine (xy (5512 4223)) (mirror x) (refDes "TL44") (Props (_SXDesignName "CRESCENT_CITY_902_20150507_Q") (impedance "52.449 ohm") length("176.28 MIL") (propDelay "0.03166 ns") (traceCount "1") (traceGeometry "Microstrip") (velocity "5567.91 mil/ns")) (Terms ("CRESCENT_CITY_902_20150507_Q.X1488130Y371555L2LRATS" "1") ("CRESCENT_CITY_902_20150507_Q.X1488323Y354120L2LRATS" "2"))) ("CRESCENT_CITY_902_20150507_Q.@@R7C16.2.1" Resistor (xy (5503 4223)) (refDes "R7C16") (value "33.2 Ohm") (Props (_SXDesignName "CRESCENT_CITY_902_20150507_Q")) (Terms ("CRESCENT_CITY_902_20150507_Q.X1491823Y354120L2LRATS" "2") ("CRESCENT_CITY_902_20150507_Q.X1488323Y354120L2LRATS" "1")))) (Nodes ("CRESCENT_CITY_902_20150507_Q.X1488130Y371555L2LRATS" (terms "CRESCENT_CITY_902_20150507_Q.T@@RATS@@U7C1.J3@@R7C16.1.1" "CRESCENT_CITY_902_20150507_Q.@@U7C1.J3.1")) ("CRESCENT_CITY_902_20150507_Q.X1488323Y354120L2LRATS" (terms "CRESCENT_CITY_902_20150507_Q.@@R7C16.2.1.2" "CRESCENT_CITY_902_20150507_Q.T@@RATS@@U7C1.J3@@R7C16.1.2")) ("CRESCENT_CITY_902_20150507_Q.X1579500Y149500L2LRATS" (terms "CRESCENT_CITY_902_20150507_Q.T@@RATS@@U8F1.11@@R7C16.2.1" "CRESCENT_CITY_902_20150507_Q.@@U8F1.11.1")) ("CRESCENT_CITY_902_20150507_Q.X1491823Y354120L2LRATS" (terms "CRESCENT_CITY_902_20150507_Q.@@R7C16.2.1.1" "CRESCENT_CITY_902_20150507_Q.T@@RATS@@U8F1.11@@R7C16.2.2"))) (Ports) (Stimuli ("local55" (scope local) (stimType periodic) (Props (periodicFreq "5e+007") (periodicJitter "0") (periodicPattern "1"))) ("local57" (scope local) (stimType periodic) (Props (periodicFreq "5e+007") (periodicJitter "0") (periodicPattern "1"))) ("local56" (scope local) (stimType periodic) (Props (periodicFreq "5e+007") (periodicJitter "0") (periodicPattern "1"))) ("local58" (scope local) (stimType periodic) (Props (periodicFreq "5e+007") (periodicJitter "0") (periodicPattern "1")))) (Notes) (Constraints ("RELATIVE_PROPAGATION_DELAY" ("SPI_PCH-MUX" "CRESCENT_CITY_902_20150507_Q U7C1.J3" "CRESCENT_CITY_902_20150507_Q U8F1.11" "GLOBAL" "LENGTH" "0.00635" "LENGTH" "0"))) (MeasurementSets ("EMI" ("EMIStatus" status("on")) ("PeakEmission" status("on")) ("PeakFrequency" status("on")) ("PulseFreq" status("on")) ("RiseTime" status("on")) ("VoltageSwing" status("on"))) ("Reflection" ("BufferDelayFall" status("off")) ("BufferDelayRise" status("off")) ("EyeHeight" status("off")) ("EyeJitter" status("off")) ("EyeWidth" status("off")) ("FirstIncidentFall" status("off")) ("FirstIncidentRise" status("off")) ("Glitch" status("on")) ("GlitchFall" status("off")) ("GlitchRise" status("off")) ("Monotonic" status("on")) ("MonotonicFall" status("off")) ("MonotonicRise" status("off")) ("NoiseMargin" status("on")) ("NoiseMarginHigh" status("off")) ("NoiseMarginLow" status("off")) ("OvershootHigh" status("on")) ("OvershootLow" status("on")) ("PropDelay" status("on")) ("SettleDelay" status("on")) ("SettleDelayFall" status("off")) ("SettleDelayRise" status("off")) ("SwitchDelay" status("on")) ("SwitchDelayFall" status("off")) ("SwitchDelayRise" status("off"))) ("Crosstalk" ("Crosstalk" status("on"))) ("Custom")) (VectorSets) (Props (XnetName "SPI_PCH_CS0_R1_N") (allDrivers "active") (customSimType "Reflection") (ftsMode ("Typ")) (rcvrSelect "all") (tlineDelayMode "time") (userRevision "1.0")))) (Subckts) (CrossSections ("CRESCENT_CITY_902_20150507_Q" (Props (SXDesignName "CRESCENT_CITY_902_20150507_Q")) (Layers ("" (layerType "SURFACE") (material "AIR") (thickness "0 mil") (dielectricConstant "1.000000") (lossTangent "0") (etchFactor "0.000000") (elecCondVal "0 mho/cm") (thermCondVal "0 w/cm-degC")) ("" (layerType "DIELECTRIC") (material "CONFORMAL_COAT") (thickness "0.5 mil") (dielectricConstant "3.800000") (lossTangent "0.035") (etchFactor "0.000000") (elecCondVal "0 mho/cm") (thermCondVal "0.012 w/cm-degC")) ("TOP" (layerType "CONDUCTOR") (material "COPPER") (thickness "  2.100000 mil") (width "4.00 MIL") (dielectricConstant "4.500000") (lossTangent "0") (etchFactor "70.000000") (elecCondVal "595900.000000 mho/cm") (thermCondVal "0 w/cm-degC") (signalDieConstant "3.800000") (signalLossTangent "0.035")) ("" (layerType "DIELECTRIC") (material "FR-4") (thickness "  2.670000 mil") (dielectricConstant "4.000000") (lossTangent "0.035") (etchFactor "0.000000") (elecCondVal "0 mho/cm") (thermCondVal "0.012 w/cm-degC")) ("L2_GND1" (layerType "PLANE") (material "COPPER") (isShield t) (thickness "  1.250000 mil") (dielectricConstant "4.500000") (lossTangent "0.035") (etchFactor "90.000000") (elecCondVal "595900.000000 mho/cm") (thermCondVal "0.012 w/cm-degC")) ("" (layerType "DIELECTRIC") (material "FR-4") (thickness "  9.000000 mil") (dielectricConstant "4.100000") (lossTangent "0.035") (etchFactor "0.000000") (elecCondVal "0 mho/cm") (thermCondVal "0.012 w/cm-degC")) ("L3_SIG1" (layerType "CONDUCTOR") (material "COPPER") (thickness "  1.250000 mil") (width "4.00 MIL") (dielectricConstant "4.500000") (lossTangent "0.035") (etchFactor "90.000000") (elecCondVal "595900.000000 mho/cm") (thermCondVal "0.012 w/cm-degC") (signalDieConstant "4.100000") (signalLossTangent "0.035")) ("" (layerType "DIELECTRIC") (material "FR-4") (thickness "  3.000000 mil") (dielectricConstant "4.500000") (lossTangent "0.035") (etchFactor "0.000000") (elecCondVal "0 mho/cm") (thermCondVal "0 w/cm-degC")) ("L4_GND2" (layerType "PLANE") (material "COPPER") (isShield t) (thickness "  1.250000 mil") (dielectricConstant "4.500000") (lossTangent "0.035") (etchFactor "90.000000") (elecCondVal "595900.000000 mho/cm") (thermCondVal "0 w/cm-degC")) ("" (layerType "DIELECTRIC") (material "FR-4") (thickness "  9.000000 mil") (dielectricConstant "4.000000") (lossTangent "0.035") (etchFactor "0.000000") (elecCondVal "0 mho/cm") (thermCondVal "0.012 w/cm-degC")) ("L5_SIG2" (layerType "CONDUCTOR") (material "COPPER") (thickness "  1.250000 mil") (width "4.00 MIL") (dielectricConstant "4.500000") (lossTangent "0.035") (etchFactor "90.000000") (elecCondVal "595900.000000 mho/cm") (thermCondVal "0.012 w/cm-degC") (signalDieConstant "4.000000") (signalLossTangent "0.035")) ("" (layerType "DIELECTRIC") (material "FR-4") (thickness "  3.000000 mil") (dielectricConstant "4.500000") (lossTangent "0.035") (etchFactor "0.000000") (elecCondVal "0 mho/cm") (thermCondVal "0 w/cm-degC")) ("L6_GND3" (layerType "PLANE") (material "COPPER") (isShield t) (thickness "  1.250000 mil") (dielectricConstant "4.500000") (lossTangent "0.035") (etchFactor "90.000000") (elecCondVal "595900.000000 mho/cm") (thermCondVal "0 w/cm-degC")) ("" (layerType "DIELECTRIC") (material "FR-4") (thickness "  4.500000 mil") (dielectricConstant "4.100000") (lossTangent "0.035") (etchFactor "0.000000") (elecCondVal "0 mho/cm") (thermCondVal "0.012 w/cm-degC")) ("L7_PWR1-SIG" (layerType "PLANE") (material "COPPER") (isShield t) (thickness "  2.610000 mil") (dielectricConstant "4.500000") (lossTangent "0.035") (etchFactor "90.000000") (elecCondVal "595900.000000 mho/cm") (thermCondVal "0.012 w/cm-degC")) ("" (layerType "DIELECTRIC") (material "FR-4") (thickness "  3.100000 mil") (dielectricConstant "4.500000") (lossTangent "0.035") (etchFactor "0.000000") (elecCondVal "0 mho/cm") (thermCondVal "0 w/cm-degC")) ("L8_GND_TEMP" (layerType "PLANE") (material "COPPER") (isShield t) (thickness "  1.250000 mil") (dielectricConstant "4.500000") (lossTangent "0.035") (etchFactor "90.000000") (elecCondVal "595900.000000 mho/cm") (thermCondVal "0 w/cm-degC")) ("" (layerType "DIELECTRIC") (material "FR-4") (thickness "  3.030000 mil") (dielectricConstant "4.500000") (lossTangent "0.035") (etchFactor "0.000000") (elecCondVal "0 mho/cm") (thermCondVal "0 w/cm-degC")) ("L9_SIG_TEMP" (layerType "CONDUCTOR") (material "COPPER") (thickness "  1.250000 mil") (width "3.52 MIL") (dielectricConstant "4.500000") (lossTangent "0.035") (etchFactor "90.000000") (elecCondVal "595900.000000 mho/cm") (thermCondVal "0 w/cm-degC") (signalDieConstant "4.500000") (signalLossTangent "0.035")) ("" (layerType "DIELECTRIC") (material "FR-4") (thickness "  5.000000 mil") (dielectricConstant "4.500000") (lossTangent "0.035") (etchFactor "0.000000") (elecCondVal "0 mho/cm") (thermCondVal "0 w/cm-degC")) ("L10_SIG_TEMP" (layerType "CONDUCTOR") (material "COPPER") (thickness "  1.250000 mil") (width "3.52 MIL") (dielectricConstant "4.500000") (lossTangent "0.035") (etchFactor "90.000000") (elecCondVal "595900.000000 mho/cm") (thermCondVal "0 w/cm-degC") (signalDieConstant "4.500000") (signalLossTangent "0.035")) ("" (layerType "DIELECTRIC") (material "FR-4") (thickness "  3.030000 mil") (dielectricConstant "4.500000") (lossTangent "0.035") (etchFactor "0.000000") (elecCondVal "0 mho/cm") (thermCondVal "0 w/cm-degC")) ("L11_GND_TEMP" (layerType "PLANE") (material "COPPER") (isShield t) (thickness "  1.250000 mil") (dielectricConstant "4.500000") (lossTangent "0.035") (etchFactor "90.000000") (elecCondVal "595900.000000 mho/cm") (thermCondVal "0 w/cm-degC")) ("" (layerType "DIELECTRIC") (material "FR-4") (thickness "  3.100000 mil") (dielectricConstant "4.000000") (lossTangent "0.035") (etchFactor "0.000000") (elecCondVal "0 mho/cm") (thermCondVal "0.012 w/cm-degC")) ("L12_PWR2-SIG" (layerType "PLANE") (material "COPPER") (isShield t) (thickness "  2.610000 mil") (dielectricConstant "4.500000") (lossTangent "0.035") (etchFactor "90.000000") (elecCondVal "595900.000000 mho/cm") (thermCondVal "0.012 w/cm-degC")) ("" (layerType "DIELECTRIC") (material "FR-4") (thickness "  4.500000 mil") (dielectricConstant "4.500000") (lossTangent "0.035") (etchFactor "0.000000") (elecCondVal "0 mho/cm") (thermCondVal "0 w/cm-degC")) ("L13_GND4" (layerType "PLANE") (material "COPPER") (isShield t) (thickness "  1.250000 mil") (dielectricConstant "4.500000") (lossTangent "0.035") (etchFactor "90.000000") (elecCondVal "595900.000000 mho/cm") (thermCondVal "0 w/cm-degC")) ("" (layerType "DIELECTRIC") (material "FR-4") (thickness "  3.000000 mil") (dielectricConstant "4.100000") (lossTangent "0.035") (etchFactor "0.000000") (elecCondVal "0 mho/cm") (thermCondVal "0.012 w/cm-degC")) ("L14_SIG3" (layerType "CONDUCTOR") (material "COPPER") (thickness "  1.250000 mil") (width "4.00 MIL") (dielectricConstant "4.500000") (lossTangent "0.035") (etchFactor "90.000000") (elecCondVal "595900.000000 mho/cm") (thermCondVal "0.012 w/cm-degC") (signalDieConstant "4.100000") (signalLossTangent "0.035")) ("" (layerType "DIELECTRIC") (material "FR-4") (thickness "  9.000000 mil") (dielectricConstant "4.500000") (lossTangent "0.035") (etchFactor "0.000000") (elecCondVal "0 mho/cm") (thermCondVal "0 w/cm-degC")) ("L15_GND5" (layerType "PLANE") (material "COPPER") (isShield t) (thickness "  1.250000 mil") (dielectricConstant "4.500000") (lossTangent "0.035") (etchFactor "90.000000") (elecCondVal "595900.000000 mho/cm") (thermCondVal "0 w/cm-degC")) ("" (layerType "DIELECTRIC") (material "FR-4") (thickness "  3.000000 mil") (dielectricConstant "4.500000") (lossTangent "0.035") (etchFactor "0.000000") (elecCondVal "0 mho/cm") (thermCondVal "0.012 w/cm-degC")) ("L16_SIG4" (layerType "CONDUCTOR") (material "COPPER") (thickness "  1.250000 mil") (width "4.00 MIL") (dielectricConstant "4.500000") (lossTangent "0.035") (etchFactor "90.000000") (elecCondVal "595900.000000 mho/cm") (thermCondVal "0.012 w/cm-degC") (signalDieConstant "4.500000") (signalLossTangent "0.035")) ("" (layerType "DIELECTRIC") (material "FR-4") (thickness "  9.000000 mil") (dielectricConstant "4.500000") (lossTangent "0.035") (etchFactor "0.000000") (elecCondVal "0 mho/cm") (thermCondVal "0 w/cm-degC")) ("L17_GND6" (layerType "PLANE") (material "COPPER") (isShield t) (thickness "  1.250000 mil") (dielectricConstant "4.500000") (lossTangent "0.035") (etchFactor "90.000000") (elecCondVal "595900.000000 mho/cm") (thermCondVal "0.012 w/cm-degC")) ("" (layerType "DIELECTRIC") (material "FR-4") (thickness "  2.670000 mil") (dielectricConstant "4.500000") (lossTangent "0.035") (etchFactor "0.000000") (elecCondVal "0 mho/cm") (thermCondVal "0.012 w/cm-degC")) ("BOTTOM" (layerType "CONDUCTOR") (material "COPPER") (thickness "  2.100000 mil") (width "4.00 MIL") (dielectricConstant "4.500000") (lossTangent "0") (etchFactor "70.000000") (elecCondVal "595900.000000 mho/cm") (thermCondVal "0 w/cm-degC") (signalDieConstant "3.800000") (signalLossTangent "0.035")) ("" (layerType "DIELECTRIC") (material "CONFORMAL_COAT") (thickness "0.5 mil") (dielectricConstant "3.800000") (lossTangent "0.035") (etchFactor "0.000000") (elecCondVal "0 mho/cm") (thermCondVal "0.012 w/cm-degC")) ("" (layerType "SURFACE") (material "AIR") (thickness "0 mil") (dielectricConstant "1.000000") (lossTangent "0") (etchFactor "0.000000") (elecCondVal "0 mho/cm") (thermCondVal "0 w/cm-degC"))))) (Props (DesUnits "mils 2") (LayerStack ("DIELECTRIC" "DIELECTRIC" "BOTTOM" "DIELECTRIC" "L17_GND6" "DIELECTRIC" "L16_SIG4" "DIELECTRIC" "L15_GND5" "DIELECTRIC" "L14_SIG3" "DIELECTRIC" "L13_GND4" "DIELECTRIC" "L12_PWR2-SIG" "DIELECTRIC" "L11_GND_TEMP" "DIELECTRIC" "L10_SIG_TEMP" "DIELECTRIC" "L9_SIG_TEMP" "DIELECTRIC" "L8_GND_TEMP" "DIELECTRIC" "L7_PWR1-SIG" "DIELECTRIC" "L6_GND3" "DIELECTRIC" "L5_SIG2" "DIELECTRIC" "L4_GND2" "DIELECTRIC" "L3_SIG1" "DIELECTRIC" "L2_GND1" "DIELECTRIC" "TOP" "DIELECTRIC" "DIELECTRIC")) (Revision "16.600")) (Params (DiffInputPkg ((temperature "27") (bufferModelNonInverting "CDSDefaultInput_2p5v") (bufferModelInverting "CDSDefaultInput_2p5v") (threshInputHighMin "1.7 V") (threshInputHighTyp "1.7  V") (threshInputHighMax "1.7  V") (threshInputLowMin "0.7  V") (threshInputLowTyp "0.7  V") (threshInputLowMax "0.7  V") (mappingTagNonInverting nil) (mappingTagInverting nil) (cycle "1"))) (IbisOutputPkg ((temperature "27") (bufferModel "CDSDefaultOutput_2p5v") (stimuli nil) (offsets nil) (state "tristate") (cycle "1") (termMap nil) (setup "2.0e-09") (hold "1.0e-09") (rise nil) (fall nil) (macroType nil) (voltage nil) (spice nil) (LEFDEFPinName nil) (LEFDEFPinType nil) (mappingTag nil))) (IbisIOPkg ((temperature "27") (bufferModel "CDSDefaultIO_2p5v") (stimuli nil) (offsets nil) (state "tristate") (cycle "1") (termMap nil) (setup "2.0e-09") (hold "1.0e-09") (rise nil) (fall nil) (macroType nil) (voltage nil) (spice nil) (LEFDEFPinName nil) (LEFDEFPinType nil) (mappingTag nil))) (IbisIOMacro ((temperature "27") (bufferModel "CDSDefaultIO_2p5v") (stimuli nil) (offsets nil) (state "tristate") (cycle "1") (termMap nil) (setup "2.0e-09") (hold "1.0e-09") (rise nil) (fall nil) (macroType nil) (voltage nil) (spice nil) (LEFDEFPinName nil) (LEFDEFPinType nil) (mappingTag nil))) (ESpiceDevice nil) (IbisInput ((temperature "27") (bufferModel "CDSDefaultInput_2p5v") (cycle "1") (LEFDEFPinName nil) (LEFDEFPinType nil) (mappingTag nil))) (ShuntTerm ((resistance "50 ohm") (voltage "5 V") (maxDelay "0.1 ns"))) (SeriesTerm ((resistance "22 ohm") (maxDelay "0.1 ns"))) (CurrentProbe nil) (idlCircuit ((allDrivers "active") (ftsMode '("Typ")) (rcvrSelect "all") (simMode "Reflection") (tlineDelayMode "time") (userRevision "1.0") (autoSolve "On"))) (TheveninTerm ((resistanceUp "180 ohm") (resistanceDown "270 ohm") (voltageUp "5 V") (voltageDown "0 V") (maxDelay "0.1 ns"))) (RCTerm ((resistance "50 ohm") (capacitance "20 pF") (voltage "5 V") (maxDelay "0.1 ns"))) (LowClampTerm ((cutoffVoltage "0.7 V") (voltage "0 V") (maxDelay "0.1 ns"))) (Cable (length("1 m"))) (HiClampTerm ((cutoffVoltage "0.7 V") (voltage "5 V") (maxDelay "0.1 ns"))) (DualClampTerm ((cutoffVoltageUp "0.7 V") (cutoffVoltageDown "0.7 V") (voltageUp "5 V") (voltageDown "0 V") (maxDelay "0.1 ns"))) (IbisInputPkg ((temperature "27") (bufferModel "CDSDefaultInput_2p5v") (cycle "1") (LEFDEFPinName nil) (LEFDEFPinType nil) (mappingTag nil))) (async ((asyncTimePoints "") (asyncInitState "1"))) (clocked ((clockRise "1e-09") (clockFall "1e-09") (clockFreq "100e6") (clockInitState "0") (clockDutyCycle "0.5") (clockJitter "0"))) (Diode ((cutoffVoltage "0.7 V"))) (IbisOutput ((temperature "27") (bufferModel "CDSDefaultOutput_2p5v") (stimuli nil) (offsets nil) (state "tristate") (cycle "1") (termMap nil) (setup "2.0e-09") (hold "1.0e-09") (rise nil) (fall nil) (macroType nil) (voltage nil) (spice nil) (LEFDEFPinName nil) (LEFDEFPinType nil) (mappingTag nil))) (periodic ((periodicFreq "100e6") (periodicPattern "10") (periodicJitter "0"))) (IbisIO ((temperature "27") (bufferModel "CDSDefaultIO_2p5v") (stimuli nil) (offsets nil) (state "tristate") (cycle "1") (termMap nil) (setup "2.0e-09") (hold "1.0e-09") (rise nil) (fall nil) (macroType nil) (voltage nil) (spice nil) (LEFDEFPinName nil) (LEFDEFPinType nil) (mappingTag nil))) (Via ((model "Unknown") (viaOutputFormat "Unknown") (viaPadstack nil) (viaTopLayer nil) (viaBottomLayer nil) (viaIsPower nil) (viaIsGround nil))) (CPWMS ((d1Thickness "10 mil") (d1Constant "4.5") (d1LossTangent "0.035") (d2Thickness "0.72 mil") (d2Constant "4.5") (d2LossTangent "0.035") (d3Thickness "0.0") (d3Constant "1") (d3LossTangent "0") length("1000 mil") (spacing "5 mil") (spacing2 "5 mil") (spacing3 "5 mil") (spacing4 "5 mil") (spacing5 "5 mil") (traceConductivity "595900 mho/cm") (traceGeometry "cpwms") (traceLayerName "") (traceThickness "0.72 mil") (traceType "single") (traceWidth "5.0 mil") (traceWidth2 "5.0 mil") (traceWidth3 "5.0 mil") (traceWidth4 "5.0 mil") (traceWidth5 "5.0 mil") (traceWidth6 "5.0 mil") (offset "0 mil") (traceCount "1") (impedance nil))) (Trace ((d1Thickness "10 mil") (d1Constant "4.5") (d1LossTangent "0.035") (d2Thickness "10 mil") (d2Constant "4.5") (d2LossTangent "0.035") (d3Thickness "0.0") (d3Constant "1.0") (d3LossTangent "0") length("1000 mil") (spacing "5 mil") (spacing2 "5 mil") (spacing3 "5 mil") (spacing4 "5 mil") (spacing5 "5 mil") (traceConductivity "595900 mho/cm") (traceGeometry "microstrip") (traceLayerName "") (traceThickness "0.72 mil") (traceType "single") (traceWidth "5.0 mil") (traceWidth2 "5.0 mil") (traceWidth3 "5.0 mil") (traceWidth4 "5.0 mil") (traceWidth5 "5.0 mil") (traceWidth6 "5.0 mil") (offset "0 mil") (traceCount "1") (impedance nil))) (Source ((voltage "5 V"))) (CPWSL ((d1Thickness "10 mil") (d1Constant "4.5") (d1LossTangent "0.035") (d2Thickness "0.72 mil") (d2Constant "4.5") (d2LossTangent "0.035") (d3Thickness "10 mil") (d3Constant "4.5") (d3LossTangent "0.035") length("1000 mil") (spacing "5 mil") (spacing2 "5 mil") (spacing3 "5 mil") (spacing4 "5 mil") (spacing5 "5 mil") (traceConductivity "595900 mho/cm") (traceGeometry "cpwms") (traceLayerName "") (traceThickness "0.72 mil") (traceType "single") (traceWidth "5.0 mil") (traceWidth2 "5.0 mil") (traceWidth3 "5.0 mil") (traceWidth4 "5.0 mil") (traceWidth5 "5.0 mil") (traceWidth6 "5.0 mil") (offset "0 mil") (traceCount "1") (impedance nil))) (RLGC (length("1000 mil"))) (Capacitor ((capacitance "10 pF") (orientation "0"))) (DiffIOPkg ((temperature "27") (bufferModelNonInverting "CDSDefaultIO_2p5v") (bufferModelInverting "CDSDefaultIO_2p5v") (stimuli nil) (offsets nil) (state "tristate") (cycle "1") (termMap nil) (setup "0.9e-09") (hold "0.4e-09") (rise nil) (fall nil) (threshInputHighMin "1.7 V") (threshInputHighTyp "1.7  V") (threshInputHighMax "1.7  V") (threshInputLowMin "0.7  V") (threshInputLowTyp "0.7  V") (threshInputLowMax "0.7 ") (threshOutputHighMin "2.365  V") (threshOutputHighTyp "2.5  V") (threshOutputHighMax "2.625  V") (threshOutputLowMin "1.275  V") (threshOutputLowTyp "1.7  V") (threshOutputLowMax "1.985  V") (mappingTagNonInverting nil) (mappingTagInverting nil) (spice nil))) (Inductor ((inductance "5 nH") (orientation "0"))) (DiffIO ((temperature "27") (bufferModelNonInverting "CDSDefaultIO_2p5v") (bufferModelInverting "CDSDefaultIO_2p5v") (stimuli nil) (offsets nil) (state "tristate") (cycle "1") (termMap nil) (setup "0.9e-09") (hold "0.4e-09") (rise nil) (fall nil) (threshInputHighMin "1.7 V") (threshInputHighTyp "1.7  V") (threshInputHighMax "1.7  V") (threshInputLowMin "0.7  V") (threshInputLowTyp "0.7  V") (threshInputLowMax "0.7 ") (threshOutputHighMin "2.365  V") (threshOutputHighTyp "2.5  V") (threshOutputHighMax "2.625  V") (threshOutputLowMin "1.275  V") (threshOutputLowTyp "1.7  V") (threshOutputLowMax "1.985  V") (mappingTagNonInverting nil) (mappingTagInverting nil) (spice nil))) (CPW ((d1Thickness "10 mil") (d1Constant "4.5") (d1LossTangent "0.035") (d2Thickness "0.72 mil") (d2Constant "1") (d2LossTangent "0") (d3Thickness "0.0") (d3Constant "1") (d3LossTangent "0") length("1000 mil") (spacing "5 mil") (spacing2 "5 mil") (spacing3 "5 mil") (spacing4 "5 mil") (spacing5 "5 mil") (traceConductivity "595900 mho/cm") (traceGeometry "cpwms") (traceLayerName "") (traceThickness "0.72 mil") (traceType "single") (traceWidth "5.0 mil") (traceWidth2 "5.0 mil") (traceWidth3 "5.0 mil") (traceWidth4 "5.0 mil") (traceWidth5 "5.0 mil") (traceWidth6 "5.0 mil") (offset "0 mil") (traceCount "1") (impedance nil))) (Connector nil) (TLine ((diffImpedance "100ohm") (diffVelocity "1.4142e+08M/s") (impedance "60ohm") length("2800 mil") (propDelay "0.5 ns") (velocity "5600 mil/ns") (traceCount "1") (traceGeometry "Microstrip") (impedanceMin nil) (impedanceMax nil) (lengthMin nil) (lengthMax nil) (propDelayMin nil) (propDelayMax nil) (impedanceSweepCount nil) (propDelaySweepCount nil) (velocitySweepCount nil) (lengthSweepCount nil) (matchSetName nil))) (sync ((syncFreq "100e6") (syncInitState "1") (syncPattern "10") (syncEdgeSwitch "rise"))) (IbisIO_OpenPullDown ((temperature "27") (bufferModel "CDSDefaultIO_2p5v") (stimuli nil) (offsets nil) (state "tristate") (cycle "1") (termMap nil) (setup "2.0e-09") (hold "1.0e-09") (rise nil) (fall nil) (macroType nil) (voltage nil) (spice nil) (LEFDEFPinName nil) (LEFDEFPinType nil) (mappingTag nil))) (DiffOutputPkg ((temperature "27") (bufferModelNonInverting "CDSDefaultOutput_2p5v") (bufferModelInverting "CDSDefaultOutput_2p5v") (stimuli nil) (offsets nil) (state "tristate") (cycle "1") (termMap nil) (setup "0.9e-09") (hold "0.4e-09") (rise nil) (fall nil) (threshOutputHighMin "2.375  V") (threshOutputHighTyp "2.5  V") (threshOutputHighMax "2.625  V") (threshOutputLowMin "1.275  V") (threshOutputLowTyp "1.7  V") (threshOutputLowMax "1.985  V") (mappingTagNonInverting nil) (mappingTagInverting nil) (spice nil))) (DiffInput ((temperature "27") (bufferModelNonInverting "CDSDefaultInput_2p5v") (bufferModelInverting "CDSDefaultInput_2p5v") (threshInputHighMin "1.7 V") (threshInputHighTyp "1.7  V") (threshInputHighMax "1.7  V") (threshInputLowMin "0.7  V") (threshInputLowTyp "0.7  V") (threshInputLowMax "0.7  V") (mappingTagNonInverting nil) (mappingTagInverting nil) (cycle "1"))) (Resistor ((resistance "50 ohm") (orientation "0"))) (DiffOutput ((temperature "27") (bufferModelNonInverting "CDSDefaultOutput_2p5v") (bufferModelInverting "CDSDefaultOutput_2p5v") (stimuli nil) (offsets nil) (state "tristate") (cycle "1") (termMap nil) (setup "0.9e-09") (hold "0.4e-09") (rise nil) (fall nil) (threshOutputHighMin "2.375  V") (threshOutputHighTyp "2.5  V") (threshOutputHighMax "2.625  V") (threshOutputLowMin "1.275  V") (threshOutputLowTyp "1.7  V") (threshOutputLowMax "1.985  V") (mappingTagNonInverting nil) (mappingTagInverting nil) (spice nil))) (IbisOutput_OpenPullUp ((temperature "27") (bufferModel "CDSDefaultOutput_2p5v") (stimuli nil) (offsets nil) (state "tristate") (cycle "1") (termMap nil) (setup "2.0e-09") (hold "1.0e-09") (rise nil) (fall nil) (macroType nil) (voltage nil) (spice nil) (LEFDEFPinName nil) (LEFDEFPinType nil) (mappingTag nil))) (IbisIO_OpenPullUp ((temperature "27") (bufferModel "CDSDefaultIO_2p5v") (stimuli nil) (offsets nil) (state "tristate") (cycle "1") (termMap nil) (setup "2.0e-09") (hold "1.0e-09") (rise nil) (fall nil) (macroType nil) (voltage nil) (spice nil) (LEFDEFPinName nil) (LEFDEFPinType nil) (mappingTag nil)))))
				)
				( objectStatus "SPI_PCH_CS0_R1_N" )
			)
			( electricalCSet "@crescent_city_bb_fab1_lib.crescent_city_bb_fab1(sch_1):\SPI_PCH_CLK\"
				( groupRef "SPI_PCH_CLK:SPI_PCH-TPM" )
				( groupRef "SPI_PCH_CLK:SPI_PCH-MUX" )
				( pinPairRef "SPI_PCH_CLK:U7C1.K2:J8E1.1" )
				( pinPairRef "SPI_PCH_CLK:U8F1.2:U7C1.K2" )
				( pinPairRef "SPI_PCH_CLK:R8E9.1:NET.T.1" )
				( pinPairRef "SPI_PCH_CLK:R8E9.2:J8E1.1" )
				( attribute "RATSNEST_SCHEDULE" "TEMPLATE"
					( Status sLocked )
					( Origin gBackEnd )
				)
				( attribute "TOPOLOGY_TEMPLATE_REVISION" "1.0"
					( Origin gBackEnd )
				)
				( topologyData 27785
(SKIDL (Circuits ("MAIN" (Parts ("CRESCENT_CITY_902_20150507_Q.@@J8E1.1" IbisIOPkg (xy (5490 4220)) (refDes "J8E1") (model "Unknown") (Props (_SXDesignName "CRESCENT_CITY_902_20150507_Q") (brdx "16320 MIL") (brdy "2423 MIL") (bufferModel "CDSDefaultIO_2p5v") (cycle "1") (hold "1.0e-09") (mappingTag "") (offsets ("5" "0") ("4" "0")) (setup "2.0e-09") (state "tristate") (stimuli ("5" "local38") ("4" "local37")) (temperature "27") (termMap ("4" "Data") ("5" "Enable"))) (Terms ("CRESCENT_CITY_902_20150507_Q.X1632000Y242300L2LRATS" "1"))) ("CRESCENT_CITY_902_20150507_Q.@@U8F1.2" IbisIOPkg (xy (5506 4214)) (refDes "U8F1") (model "Unknown") (Props (_SXDesignName "CRESCENT_CITY_902_20150507_Q") (brdx "15580 MIL") (brdy "1595 MIL") (bufferModel "CDSDefaultIO_2p5v") (cycle "1") (hold "1.0e-09") (mappingTag "") (offsets ("5" "0") ("4" "0")) (setup "2.0e-09") (state "tristate") (stimuli ("5" "local36") ("4" "local35")) (temperature "27") (termMap ("4" "Data") ("5" "Enable"))) (Terms ("CRESCENT_CITY_902_20150507_Q.X1558000Y159500L2LRATS" "2"))) ("CRESCENT_CITY_902_20150507_Q.@@U7C1.K2" IbisIOPkg (xy (5502 4240)) (refDes "U7C1") (model "Unknown") (Props (_SXDesignName "CRESCENT_CITY_902_20150507_Q") (brdx "14900.98 MIL") (brdy "3699.21 MIL") (bufferModel "CDSDefaultIO_2p5v") (cycle "1") (hold "1.0e-09") (mappingTag "") (offsets ("5" "0") ("4" "0")) (setup "2.0e-09") (state "tristate") (stimuli ("5" "local34") ("4" "local33")) (temperature "27") (termMap ("4" "Data") ("5" "Enable"))) (Terms ("CRESCENT_CITY_902_20150507_Q.X1490098Y369921L2LRATS" "K2"))) ("CRESCENT_CITY_902_20150507_Q.T@@RATSX1614067Y230957NetSPI_PCH_CLKT.1@@U8F1.2" TLine (xy (5497 4209)) (refDes "TL39") (Props (_SXDesignName "CRESCENT_CITY_902_20150507_Q") (impedance "48.412 ohm") length("1431.34 MIL") (propDelay "0.25254 ns") (traceCount "1") (traceGeometry "Microstrip") (velocity "5667.76 mil/ns")) (Terms ("CRESCENT_CITY_902_20150507_Q.X1614067Y230957NetSPI_PCH_CLKT.1" "1") ("CRESCENT_CITY_902_20150507_Q.X1558000Y159500L2LRATS" "2"))) ("CRESCENT_CITY_902_20150507_Q.T@@RATSX1614067Y230957NetSPI_PCH_CLKT.1@@U7C1.K2" TLine (xy (5497 4229)) (refDes "TL40") (Props (_SXDesignName "CRESCENT_CITY_902_20150507_Q") (impedance "52.449 ohm") length("2559.48 MIL") (propDelay "0.45411 ns") (traceCount "1") (traceGeometry "Microstrip") (velocity "5636.26 mil/ns")) (Terms ("CRESCENT_CITY_902_20150507_Q.X1614067Y230957NetSPI_PCH_CLKT.1" "1") ("CRESCENT_CITY_902_20150507_Q.X1490098Y369921L2LRATS" "2"))) ("CRESCENT_CITY_902_20150507_Q.T@@RATSX1614067Y230957NetSPI_PCH_CLKT.1@@R8E9.1" TLine (xy (5488 4229)) (mirror x) (refDes "TL41") (Props (_SXDesignName "CRESCENT_CITY_902_20150507_Q") (impedance "48.412 ohm") length("110.55 MIL") (propDelay "0.01763 ns") (traceCount "1") (traceGeometry "Microstrip") (velocity "6270.55 mil/ns")) (Terms ("CRESCENT_CITY_902_20150507_Q.X1614067Y230957NetSPI_PCH_CLKT.1" "1") ("CRESCENT_CITY_902_20150507_Q.X1628540Y225530L2LRATS" "2"))) ("CRESCENT_CITY_902_20150507_Q.@@R8E9.2.1" Resistor (xy (5460 4215)) (mirror x) (refDes "R8E9") (value "33.2 Ohm") (Props (_SXDesignName "CRESCENT_CITY_902_20150507_Q")) (Terms ("CRESCENT_CITY_902_20150507_Q.X1632040Y225530L2LRATS" "2") ("CRESCENT_CITY_902_20150507_Q.X1628540Y225530L2LRATS" "1"))) ("CRESCENT_CITY_902_20150507_Q.T@@RATS@@J8E1.1@@R8E9.2" TLine (xy (5475 4215)) (mirror x) (refDes "TL42") (Props (_SXDesignName "CRESCENT_CITY_902_20150507_Q") (impedance "48.412 ohm") length("168.10 MIL") (propDelay "0.03019 ns") (traceCount "1") (traceGeometry "Microstrip") (velocity "5568.07 mil/ns")) (Terms ("CRESCENT_CITY_902_20150507_Q.X1632000Y242300L2LRATS" "1") ("CRESCENT_CITY_902_20150507_Q.X1632040Y225530L2LRATS" "2")))) (Nodes ("CRESCENT_CITY_902_20150507_Q.X1614067Y230957NetSPI_PCH_CLKT.1" (terms "CRESCENT_CITY_902_20150507_Q.T@@RATSX1614067Y230957NetSPI_PCH_CLKT.1@@R8E9.1.1" "CRESCENT_CITY_902_20150507_Q.T@@RATSX1614067Y230957NetSPI_PCH_CLKT.1@@U7C1.K2.1" "CRESCENT_CITY_902_20150507_Q.T@@RATSX1614067Y230957NetSPI_PCH_CLKT.1@@U8F1.2.1") (tee "CRESCENT_CITY_902_20150507_Q NET.T.1")) ("CRESCENT_CITY_902_20150507_Q.X1628540Y225530L2LRATS" (terms "CRESCENT_CITY_902_20150507_Q.@@R8E9.2.1.2" "CRESCENT_CITY_902_20150507_Q.T@@RATSX1614067Y230957NetSPI_PCH_CLKT.1@@R8E9.1.2")) ("CRESCENT_CITY_902_20150507_Q.X1632040Y225530L2LRATS" (terms "CRESCENT_CITY_902_20150507_Q.T@@RATS@@J8E1.1@@R8E9.2.2" "CRESCENT_CITY_902_20150507_Q.@@R8E9.2.1.1")) ("CRESCENT_CITY_902_20150507_Q.X1558000Y159500L2LRATS" (terms "CRESCENT_CITY_902_20150507_Q.T@@RATSX1614067Y230957NetSPI_PCH_CLKT.1@@U8F1.2.2" "CRESCENT_CITY_902_20150507_Q.@@U8F1.2.1")) ("CRESCENT_CITY_902_20150507_Q.X1632000Y242300L2LRATS" (terms "CRESCENT_CITY_902_20150507_Q.T@@RATS@@J8E1.1@@R8E9.2.1" "CRESCENT_CITY_902_20150507_Q.@@J8E1.1.1")) ("CRESCENT_CITY_902_20150507_Q.X1490098Y369921L2LRATS" (terms "CRESCENT_CITY_902_20150507_Q.T@@RATSX1614067Y230957NetSPI_PCH_CLKT.1@@U7C1.K2.2" "CRESCENT_CITY_902_20150507_Q.@@U7C1.K2.1"))) (Ports) (Stimuli ("local36" (scope local) (stimType periodic) (Props (periodicFreq "5e+007") (periodicJitter "0") (periodicPattern "1"))) ("local34" (scope local) (stimType periodic) (Props (periodicFreq "5e+007") (periodicJitter "0") (periodicPattern "1"))) ("local35" (scope local) (stimType periodic) (Props (periodicFreq "5e+007") (periodicJitter "0") (periodicPattern "1"))) ("local37" (scope local) (stimType periodic) (Props (periodicFreq "5e+007") (periodicJitter "0") (periodicPattern "1"))) ("local33" (scope local) (stimType periodic) (Props (periodicFreq "5e+007") (periodicJitter "0") (periodicPattern "1"))) ("local38" (scope local) (stimType periodic) (Props (periodicFreq "5e+007") (periodicJitter "0") (periodicPattern "1")))) (Notes) (Constraints ("DELAY_RULE" ("CRESCENT_CITY_902_20150507_Q J8E1.1" "CRESCENT_CITY_902_20150507_Q R8E9.2" "LENGTH" "" "LENGTH" "0.1016") ("CRESCENT_CITY_902_20150507_Q R8E9.1" "CRESCENT_CITY_902_20150507_Q NET.T.1" "LENGTH" "" "LENGTH" "0.00508")) ("RATSNEST_SCHEDULE" "TEMPLATE") ("RELATIVE_PROPAGATION_DELAY" ("SPI_PCH-TPM" "CRESCENT_CITY_902_20150507_Q U7C1.K2" "CRESCENT_CITY_902_20150507_Q J8E1.1" "GLOBAL" "LENGTH" "0.00635" "LENGTH" "0"))) (MeasurementSets ("EMI" ("EMIStatus" status("on")) ("PeakEmission" status("on")) ("PeakFrequency" status("on")) ("PulseFreq" status("on")) ("RiseTime" status("on")) ("VoltageSwing" status("on"))) ("Reflection" ("BufferDelayFall" status("off")) ("BufferDelayRise" status("off")) ("EyeHeight" status("off")) ("EyeJitter" status("off")) ("EyeWidth" status("off")) ("FirstIncidentFall" status("off")) ("FirstIncidentRise" status("off")) ("Glitch" status("on")) ("GlitchFall" status("off")) ("GlitchRise" status("off")) ("Monotonic" status("on")) ("MonotonicFall" status("off")) ("MonotonicRise" status("off")) ("NoiseMargin" status("on")) ("NoiseMarginHigh" status("off")) ("NoiseMarginLow" status("off")) ("OvershootHigh" status("on")) ("OvershootLow" status("on")) ("PropDelay" status("on")) ("SettleDelay" status("on")) ("SettleDelayFall" status("off")) ("SettleDelayRise" status("off")) ("SwitchDelay" status("on")) ("SwitchDelayFall" status("off")) ("SwitchDelayRise" status("off"))) ("Crosstalk" ("Crosstalk" status("on"))) ("Custom")) (VectorSets) (Props (XnetName "SPI_PCH_CLK") (allDrivers "active") (customSimType "Reflection") (ftsMode ("Typ")) (rcvrSelect "all") (tlineDelayMode "time") (userRevision "1.0")))) (Subckts) (CrossSections ("CRESCENT_CITY_902_20150507_Q" (Props (SXDesignName "CRESCENT_CITY_902_20150507_Q")) (Layers ("" (layerType "SURFACE") (material "AIR") (thickness "0 mil") (dielectricConstant "1.000000") (lossTangent "0") (etchFactor "0.000000") (elecCondVal "0 mho/cm") (thermCondVal "0 w/cm-degC")) ("" (layerType "DIELECTRIC") (material "CONFORMAL_COAT") (thickness "0.5 mil") (dielectricConstant "3.800000") (lossTangent "0.035") (etchFactor "0.000000") (elecCondVal "0 mho/cm") (thermCondVal "0.012 w/cm-degC")) ("TOP" (layerType "CONDUCTOR") (material "COPPER") (thickness "  2.100000 mil") (width "4.00 MIL") (dielectricConstant "4.500000") (lossTangent "0") (etchFactor "70.000000") (elecCondVal "595900.000000 mho/cm") (thermCondVal "0 w/cm-degC") (signalDieConstant "3.800000") (signalLossTangent "0.035")) ("" (layerType "DIELECTRIC") (material "FR-4") (thickness "  2.670000 mil") (dielectricConstant "4.000000") (lossTangent "0.035") (etchFactor "0.000000") (elecCondVal "0 mho/cm") (thermCondVal "0.012 w/cm-degC")) ("L2_GND1" (layerType "PLANE") (material "COPPER") (isShield t) (thickness "  1.250000 mil") (dielectricConstant "4.500000") (lossTangent "0.035") (etchFactor "90.000000") (elecCondVal "595900.000000 mho/cm") (thermCondVal "0.012 w/cm-degC")) ("" (layerType "DIELECTRIC") (material "FR-4") (thickness "  9.000000 mil") (dielectricConstant "4.100000") (lossTangent "0.035") (etchFactor "0.000000") (elecCondVal "0 mho/cm") (thermCondVal "0.012 w/cm-degC")) ("L3_SIG1" (layerType "CONDUCTOR") (material "COPPER") (thickness "  1.250000 mil") (width "4.00 MIL") (dielectricConstant "4.500000") (lossTangent "0.035") (etchFactor "90.000000") (elecCondVal "595900.000000 mho/cm") (thermCondVal "0.012 w/cm-degC") (signalDieConstant "4.100000") (signalLossTangent "0.035")) ("" (layerType "DIELECTRIC") (material "FR-4") (thickness "  3.000000 mil") (dielectricConstant "4.500000") (lossTangent "0.035") (etchFactor "0.000000") (elecCondVal "0 mho/cm") (thermCondVal "0 w/cm-degC")) ("L4_GND2" (layerType "PLANE") (material "COPPER") (isShield t) (thickness "  1.250000 mil") (dielectricConstant "4.500000") (lossTangent "0.035") (etchFactor "90.000000") (elecCondVal "595900.000000 mho/cm") (thermCondVal "0 w/cm-degC")) ("" (layerType "DIELECTRIC") (material "FR-4") (thickness "  9.000000 mil") (dielectricConstant "4.000000") (lossTangent "0.035") (etchFactor "0.000000") (elecCondVal "0 mho/cm") (thermCondVal "0.012 w/cm-degC")) ("L5_SIG2" (layerType "CONDUCTOR") (material "COPPER") (thickness "  1.250000 mil") (width "4.00 MIL") (dielectricConstant "4.500000") (lossTangent "0.035") (etchFactor "90.000000") (elecCondVal "595900.000000 mho/cm") (thermCondVal "0.012 w/cm-degC") (signalDieConstant "4.000000") (signalLossTangent "0.035")) ("" (layerType "DIELECTRIC") (material "FR-4") (thickness "  3.000000 mil") (dielectricConstant "4.500000") (lossTangent "0.035") (etchFactor "0.000000") (elecCondVal "0 mho/cm") (thermCondVal "0 w/cm-degC")) ("L6_GND3" (layerType "PLANE") (material "COPPER") (isShield t) (thickness "  1.250000 mil") (dielectricConstant "4.500000") (lossTangent "0.035") (etchFactor "90.000000") (elecCondVal "595900.000000 mho/cm") (thermCondVal "0 w/cm-degC")) ("" (layerType "DIELECTRIC") (material "FR-4") (thickness "  4.500000 mil") (dielectricConstant "4.100000") (lossTangent "0.035") (etchFactor "0.000000") (elecCondVal "0 mho/cm") (thermCondVal "0.012 w/cm-degC")) ("L7_PWR1-SIG" (layerType "PLANE") (material "COPPER") (isShield t) (thickness "  2.610000 mil") (dielectricConstant "4.500000") (lossTangent "0.035") (etchFactor "90.000000") (elecCondVal "595900.000000 mho/cm") (thermCondVal "0.012 w/cm-degC")) ("" (layerType "DIELECTRIC") (material "FR-4") (thickness "  3.100000 mil") (dielectricConstant "4.500000") (lossTangent "0.035") (etchFactor "0.000000") (elecCondVal "0 mho/cm") (thermCondVal "0 w/cm-degC")) ("L8_GND_TEMP" (layerType "PLANE") (material "COPPER") (isShield t) (thickness "  1.250000 mil") (dielectricConstant "4.500000") (lossTangent "0.035") (etchFactor "90.000000") (elecCondVal "595900.000000 mho/cm") (thermCondVal "0 w/cm-degC")) ("" (layerType "DIELECTRIC") (material "FR-4") (thickness "  3.030000 mil") (dielectricConstant "4.500000") (lossTangent "0.035") (etchFactor "0.000000") (elecCondVal "0 mho/cm") (thermCondVal "0 w/cm-degC")) ("L9_SIG_TEMP" (layerType "CONDUCTOR") (material "COPPER") (thickness "  1.250000 mil") (width "3.52 MIL") (dielectricConstant "4.500000") (lossTangent "0.035") (etchFactor "90.000000") (elecCondVal "595900.000000 mho/cm") (thermCondVal "0 w/cm-degC") (signalDieConstant "4.500000") (signalLossTangent "0.035")) ("" (layerType "DIELECTRIC") (material "FR-4") (thickness "  5.000000 mil") (dielectricConstant "4.500000") (lossTangent "0.035") (etchFactor "0.000000") (elecCondVal "0 mho/cm") (thermCondVal "0 w/cm-degC")) ("L10_SIG_TEMP" (layerType "CONDUCTOR") (material "COPPER") (thickness "  1.250000 mil") (width "3.52 MIL") (dielectricConstant "4.500000") (lossTangent "0.035") (etchFactor "90.000000") (elecCondVal "595900.000000 mho/cm") (thermCondVal "0 w/cm-degC") (signalDieConstant "4.500000") (signalLossTangent "0.035")) ("" (layerType "DIELECTRIC") (material "FR-4") (thickness "  3.030000 mil") (dielectricConstant "4.500000") (lossTangent "0.035") (etchFactor "0.000000") (elecCondVal "0 mho/cm") (thermCondVal "0 w/cm-degC")) ("L11_GND_TEMP" (layerType "PLANE") (material "COPPER") (isShield t) (thickness "  1.250000 mil") (dielectricConstant "4.500000") (lossTangent "0.035") (etchFactor "90.000000") (elecCondVal "595900.000000 mho/cm") (thermCondVal "0 w/cm-degC")) ("" (layerType "DIELECTRIC") (material "FR-4") (thickness "  3.100000 mil") (dielectricConstant "4.000000") (lossTangent "0.035") (etchFactor "0.000000") (elecCondVal "0 mho/cm") (thermCondVal "0.012 w/cm-degC")) ("L12_PWR2-SIG" (layerType "PLANE") (material "COPPER") (isShield t) (thickness "  2.610000 mil") (dielectricConstant "4.500000") (lossTangent "0.035") (etchFactor "90.000000") (elecCondVal "595900.000000 mho/cm") (thermCondVal "0.012 w/cm-degC")) ("" (layerType "DIELECTRIC") (material "FR-4") (thickness "  4.500000 mil") (dielectricConstant "4.500000") (lossTangent "0.035") (etchFactor "0.000000") (elecCondVal "0 mho/cm") (thermCondVal "0 w/cm-degC")) ("L13_GND4" (layerType "PLANE") (material "COPPER") (isShield t) (thickness "  1.250000 mil") (dielectricConstant "4.500000") (lossTangent "0.035") (etchFactor "90.000000") (elecCondVal "595900.000000 mho/cm") (thermCondVal "0 w/cm-degC")) ("" (layerType "DIELECTRIC") (material "FR-4") (thickness "  3.000000 mil") (dielectricConstant "4.100000") (lossTangent "0.035") (etchFactor "0.000000") (elecCondVal "0 mho/cm") (thermCondVal "0.012 w/cm-degC")) ("L14_SIG3" (layerType "CONDUCTOR") (material "COPPER") (thickness "  1.250000 mil") (width "4.00 MIL") (dielectricConstant "4.500000") (lossTangent "0.035") (etchFactor "90.000000") (elecCondVal "595900.000000 mho/cm") (thermCondVal "0.012 w/cm-degC") (signalDieConstant "4.100000") (signalLossTangent "0.035")) ("" (layerType "DIELECTRIC") (material "FR-4") (thickness "  9.000000 mil") (dielectricConstant "4.500000") (lossTangent "0.035") (etchFactor "0.000000") (elecCondVal "0 mho/cm") (thermCondVal "0 w/cm-degC")) ("L15_GND5" (layerType "PLANE") (material "COPPER") (isShield t) (thickness "  1.250000 mil") (dielectricConstant "4.500000") (lossTangent "0.035") (etchFactor "90.000000") (elecCondVal "595900.000000 mho/cm") (thermCondVal "0 w/cm-degC")) ("" (layerType "DIELECTRIC") (material "FR-4") (thickness "  3.000000 mil") (dielectricConstant "4.500000") (lossTangent "0.035") (etchFactor "0.000000") (elecCondVal "0 mho/cm") (thermCondVal "0.012 w/cm-degC")) ("L16_SIG4" (layerType "CONDUCTOR") (material "COPPER") (thickness "  1.250000 mil") (width "4.00 MIL") (dielectricConstant "4.500000") (lossTangent "0.035") (etchFactor "90.000000") (elecCondVal "595900.000000 mho/cm") (thermCondVal "0.012 w/cm-degC") (signalDieConstant "4.500000") (signalLossTangent "0.035")) ("" (layerType "DIELECTRIC") (material "FR-4") (thickness "  9.000000 mil") (dielectricConstant "4.500000") (lossTangent "0.035") (etchFactor "0.000000") (elecCondVal "0 mho/cm") (thermCondVal "0 w/cm-degC")) ("L17_GND6" (layerType "PLANE") (material "COPPER") (isShield t) (thickness "  1.250000 mil") (dielectricConstant "4.500000") (lossTangent "0.035") (etchFactor "90.000000") (elecCondVal "595900.000000 mho/cm") (thermCondVal "0.012 w/cm-degC")) ("" (layerType "DIELECTRIC") (material "FR-4") (thickness "  2.670000 mil") (dielectricConstant "4.500000") (lossTangent "0.035") (etchFactor "0.000000") (elecCondVal "0 mho/cm") (thermCondVal "0.012 w/cm-degC")) ("BOTTOM" (layerType "CONDUCTOR") (material "COPPER") (thickness "  2.100000 mil") (width "4.00 MIL") (dielectricConstant "4.500000") (lossTangent "0") (etchFactor "70.000000") (elecCondVal "595900.000000 mho/cm") (thermCondVal "0 w/cm-degC") (signalDieConstant "3.800000") (signalLossTangent "0.035")) ("" (layerType "DIELECTRIC") (material "CONFORMAL_COAT") (thickness "0.5 mil") (dielectricConstant "3.800000") (lossTangent "0.035") (etchFactor "0.000000") (elecCondVal "0 mho/cm") (thermCondVal "0.012 w/cm-degC")) ("" (layerType "SURFACE") (material "AIR") (thickness "0 mil") (dielectricConstant "1.000000") (lossTangent "0") (etchFactor "0.000000") (elecCondVal "0 mho/cm") (thermCondVal "0 w/cm-degC"))))) (Props (DesUnits "mils 2") (LayerStack ("DIELECTRIC" "DIELECTRIC" "BOTTOM" "DIELECTRIC" "L17_GND6" "DIELECTRIC" "L16_SIG4" "DIELECTRIC" "L15_GND5" "DIELECTRIC" "L14_SIG3" "DIELECTRIC" "L13_GND4" "DIELECTRIC" "L12_PWR2-SIG" "DIELECTRIC" "L11_GND_TEMP" "DIELECTRIC" "L10_SIG_TEMP" "DIELECTRIC" "L9_SIG_TEMP" "DIELECTRIC" "L8_GND_TEMP" "DIELECTRIC" "L7_PWR1-SIG" "DIELECTRIC" "L6_GND3" "DIELECTRIC" "L5_SIG2" "DIELECTRIC" "L4_GND2" "DIELECTRIC" "L3_SIG1" "DIELECTRIC" "L2_GND1" "DIELECTRIC" "TOP" "DIELECTRIC" "DIELECTRIC")) (Revision "16.600")) (Params (DiffInputPkg ((temperature "27") (bufferModelNonInverting "CDSDefaultInput_2p5v") (bufferModelInverting "CDSDefaultInput_2p5v") (threshInputHighMin "1.7 V") (threshInputHighTyp "1.7  V") (threshInputHighMax "1.7  V") (threshInputLowMin "0.7  V") (threshInputLowTyp "0.7  V") (threshInputLowMax "0.7  V") (mappingTagNonInverting nil) (mappingTagInverting nil) (cycle "1"))) (IbisOutputPkg ((temperature "27") (bufferModel "CDSDefaultOutput_2p5v") (stimuli nil) (offsets nil) (state "tristate") (cycle "1") (termMap nil) (setup "2.0e-09") (hold "1.0e-09") (rise nil) (fall nil) (macroType nil) (voltage nil) (spice nil) (LEFDEFPinName nil) (LEFDEFPinType nil) (mappingTag nil))) (IbisIOPkg ((temperature "27") (bufferModel "CDSDefaultIO_2p5v") (stimuli nil) (offsets nil) (state "tristate") (cycle "1") (termMap nil) (setup "2.0e-09") (hold "1.0e-09") (rise nil) (fall nil) (macroType nil) (voltage nil) (spice nil) (LEFDEFPinName nil) (LEFDEFPinType nil) (mappingTag nil))) (IbisIOMacro ((temperature "27") (bufferModel "CDSDefaultIO_2p5v") (stimuli nil) (offsets nil) (state "tristate") (cycle "1") (termMap nil) (setup "2.0e-09") (hold "1.0e-09") (rise nil) (fall nil) (macroType nil) (voltage nil) (spice nil) (LEFDEFPinName nil) (LEFDEFPinType nil) (mappingTag nil))) (ESpiceDevice nil) (IbisInput ((temperature "27") (bufferModel "CDSDefaultInput_2p5v") (cycle "1") (LEFDEFPinName nil) (LEFDEFPinType nil) (mappingTag nil))) (ShuntTerm ((resistance "50 ohm") (voltage "5 V") (maxDelay "0.1 ns"))) (SeriesTerm ((resistance "22 ohm") (maxDelay "0.1 ns"))) (CurrentProbe nil) (idlCircuit ((allDrivers "active") (ftsMode '("Typ")) (rcvrSelect "all") (simMode "Reflection") (tlineDelayMode "time") (userRevision "1.0") (autoSolve "On"))) (TheveninTerm ((resistanceUp "180 ohm") (resistanceDown "270 ohm") (voltageUp "5 V") (voltageDown "0 V") (maxDelay "0.1 ns"))) (RCTerm ((resistance "50 ohm") (capacitance "20 pF") (voltage "5 V") (maxDelay "0.1 ns"))) (LowClampTerm ((cutoffVoltage "0.7 V") (voltage "0 V") (maxDelay "0.1 ns"))) (Cable (length("1 m"))) (HiClampTerm ((cutoffVoltage "0.7 V") (voltage "5 V") (maxDelay "0.1 ns"))) (DualClampTerm ((cutoffVoltageUp "0.7 V") (cutoffVoltageDown "0.7 V") (voltageUp "5 V") (voltageDown "0 V") (maxDelay "0.1 ns"))) (IbisInputPkg ((temperature "27") (bufferModel "CDSDefaultInput_2p5v") (cycle "1") (LEFDEFPinName nil) (LEFDEFPinType nil) (mappingTag nil))) (async ((asyncTimePoints "") (asyncInitState "1"))) (clocked ((clockRise "1e-09") (clockFall "1e-09") (clockFreq "100e6") (clockInitState "0") (clockDutyCycle "0.5") (clockJitter "0"))) (Diode ((cutoffVoltage "0.7 V"))) (IbisOutput ((temperature "27") (bufferModel "CDSDefaultOutput_2p5v") (stimuli nil) (offsets nil) (state "tristate") (cycle "1") (termMap nil) (setup "2.0e-09") (hold "1.0e-09") (rise nil) (fall nil) (macroType nil) (voltage nil) (spice nil) (LEFDEFPinName nil) (LEFDEFPinType nil) (mappingTag nil))) (periodic ((periodicFreq "100e6") (periodicPattern "10") (periodicJitter "0"))) (IbisIO ((temperature "27") (bufferModel "CDSDefaultIO_2p5v") (stimuli nil) (offsets nil) (state "tristate") (cycle "1") (termMap nil) (setup "2.0e-09") (hold "1.0e-09") (rise nil) (fall nil) (macroType nil) (voltage nil) (spice nil) (LEFDEFPinName nil) (LEFDEFPinType nil) (mappingTag nil))) (Via ((model "Unknown") (viaOutputFormat "Unknown") (viaPadstack nil) (viaTopLayer nil) (viaBottomLayer nil) (viaIsPower nil) (viaIsGround nil))) (CPWMS ((d1Thickness "10 mil") (d1Constant "4.5") (d1LossTangent "0.035") (d2Thickness "0.72 mil") (d2Constant "4.5") (d2LossTangent "0.035") (d3Thickness "0.0") (d3Constant "1") (d3LossTangent "0") length("1000 mil") (spacing "5 mil") (spacing2 "5 mil") (spacing3 "5 mil") (spacing4 "5 mil") (spacing5 "5 mil") (traceConductivity "595900 mho/cm") (traceGeometry "cpwms") (traceLayerName "") (traceThickness "0.72 mil") (traceType "single") (traceWidth "5.0 mil") (traceWidth2 "5.0 mil") (traceWidth3 "5.0 mil") (traceWidth4 "5.0 mil") (traceWidth5 "5.0 mil") (traceWidth6 "5.0 mil") (offset "0 mil") (traceCount "1") (impedance nil))) (Trace ((d1Thickness "10 mil") (d1Constant "4.5") (d1LossTangent "0.035") (d2Thickness "10 mil") (d2Constant "4.5") (d2LossTangent "0.035") (d3Thickness "0.0") (d3Constant "1.0") (d3LossTangent "0") length("1000 mil") (spacing "5 mil") (spacing2 "5 mil") (spacing3 "5 mil") (spacing4 "5 mil") (spacing5 "5 mil") (traceConductivity "595900 mho/cm") (traceGeometry "microstrip") (traceLayerName "") (traceThickness "0.72 mil") (traceType "single") (traceWidth "5.0 mil") (traceWidth2 "5.0 mil") (traceWidth3 "5.0 mil") (traceWidth4 "5.0 mil") (traceWidth5 "5.0 mil") (traceWidth6 "5.0 mil") (offset "0 mil") (traceCount "1") (impedance nil))) (Source ((voltage "5 V"))) (CPWSL ((d1Thickness "10 mil") (d1Constant "4.5") (d1LossTangent "0.035") (d2Thickness "0.72 mil") (d2Constant "4.5") (d2LossTangent "0.035") (d3Thickness "10 mil") (d3Constant "4.5") (d3LossTangent "0.035") length("1000 mil") (spacing "5 mil") (spacing2 "5 mil") (spacing3 "5 mil") (spacing4 "5 mil") (spacing5 "5 mil") (traceConductivity "595900 mho/cm") (traceGeometry "cpwms") (traceLayerName "") (traceThickness "0.72 mil") (traceType "single") (traceWidth "5.0 mil") (traceWidth2 "5.0 mil") (traceWidth3 "5.0 mil") (traceWidth4 "5.0 mil") (traceWidth5 "5.0 mil") (traceWidth6 "5.0 mil") (offset "0 mil") (traceCount "1") (impedance nil))) (RLGC (length("1000 mil"))) (Capacitor ((capacitance "10 pF") (orientation "0"))) (DiffIOPkg ((temperature "27") (bufferModelNonInverting "CDSDefaultIO_2p5v") (bufferModelInverting "CDSDefaultIO_2p5v") (stimuli nil) (offsets nil) (state "tristate") (cycle "1") (termMap nil) (setup "0.9e-09") (hold "0.4e-09") (rise nil) (fall nil) (threshInputHighMin "1.7 V") (threshInputHighTyp "1.7  V") (threshInputHighMax "1.7  V") (threshInputLowMin "0.7  V") (threshInputLowTyp "0.7  V") (threshInputLowMax "0.7 ") (threshOutputHighMin "2.365  V") (threshOutputHighTyp "2.5  V") (threshOutputHighMax "2.625  V") (threshOutputLowMin "1.275  V") (threshOutputLowTyp "1.7  V") (threshOutputLowMax "1.985  V") (mappingTagNonInverting nil) (mappingTagInverting nil) (spice nil))) (Inductor ((inductance "5 nH") (orientation "0"))) (DiffIO ((temperature "27") (bufferModelNonInverting "CDSDefaultIO_2p5v") (bufferModelInverting "CDSDefaultIO_2p5v") (stimuli nil) (offsets nil) (state "tristate") (cycle "1") (termMap nil) (setup "0.9e-09") (hold "0.4e-09") (rise nil) (fall nil) (threshInputHighMin "1.7 V") (threshInputHighTyp "1.7  V") (threshInputHighMax "1.7  V") (threshInputLowMin "0.7  V") (threshInputLowTyp "0.7  V") (threshInputLowMax "0.7 ") (threshOutputHighMin "2.365  V") (threshOutputHighTyp "2.5  V") (threshOutputHighMax "2.625  V") (threshOutputLowMin "1.275  V") (threshOutputLowTyp "1.7  V") (threshOutputLowMax "1.985  V") (mappingTagNonInverting nil) (mappingTagInverting nil) (spice nil))) (CPW ((d1Thickness "10 mil") (d1Constant "4.5") (d1LossTangent "0.035") (d2Thickness "0.72 mil") (d2Constant "1") (d2LossTangent "0") (d3Thickness "0.0") (d3Constant "1") (d3LossTangent "0") length("1000 mil") (spacing "5 mil") (spacing2 "5 mil") (spacing3 "5 mil") (spacing4 "5 mil") (spacing5 "5 mil") (traceConductivity "595900 mho/cm") (traceGeometry "cpwms") (traceLayerName "") (traceThickness "0.72 mil") (traceType "single") (traceWidth "5.0 mil") (traceWidth2 "5.0 mil") (traceWidth3 "5.0 mil") (traceWidth4 "5.0 mil") (traceWidth5 "5.0 mil") (traceWidth6 "5.0 mil") (offset "0 mil") (traceCount "1") (impedance nil))) (Connector nil) (TLine ((diffImpedance "100ohm") (diffVelocity "1.4142e+08M/s") (impedance "60ohm") length("2800 mil") (propDelay "0.5 ns") (velocity "5600 mil/ns") (traceCount "1") (traceGeometry "Microstrip") (impedanceMin nil) (impedanceMax nil) (lengthMin nil) (lengthMax nil) (propDelayMin nil) (propDelayMax nil) (impedanceSweepCount nil) (propDelaySweepCount nil) (velocitySweepCount nil) (lengthSweepCount nil) (matchSetName nil))) (sync ((syncFreq "100e6") (syncInitState "1") (syncPattern "10") (syncEdgeSwitch "rise"))) (IbisIO_OpenPullDown ((temperature "27") (bufferModel "CDSDefaultIO_2p5v") (stimuli nil) (offsets nil) (state "tristate") (cycle "1") (termMap nil) (setup "2.0e-09") (hold "1.0e-09") (rise nil) (fall nil) (macroType nil) (voltage nil) (spice nil) (LEFDEFPinName nil) (LEFDEFPinType nil) (mappingTag nil))) (DiffOutputPkg ((temperature "27") (bufferModelNonInverting "CDSDefaultOutput_2p5v") (bufferModelInverting "CDSDefaultOutput_2p5v") (stimuli nil) (offsets nil) (state "tristate") (cycle "1") (termMap nil) (setup "0.9e-09") (hold "0.4e-09") (rise nil) (fall nil) (threshOutputHighMin "2.375  V") (threshOutputHighTyp "2.5  V") (threshOutputHighMax "2.625  V") (threshOutputLowMin "1.275  V") (threshOutputLowTyp "1.7  V") (threshOutputLowMax "1.985  V") (mappingTagNonInverting nil) (mappingTagInverting nil) (spice nil))) (DiffInput ((temperature "27") (bufferModelNonInverting "CDSDefaultInput_2p5v") (bufferModelInverting "CDSDefaultInput_2p5v") (threshInputHighMin "1.7 V") (threshInputHighTyp "1.7  V") (threshInputHighMax "1.7  V") (threshInputLowMin "0.7  V") (threshInputLowTyp "0.7  V") (threshInputLowMax "0.7  V") (mappingTagNonInverting nil) (mappingTagInverting nil) (cycle "1"))) (Resistor ((resistance "50 ohm") (orientation "0"))) (DiffOutput ((temperature "27") (bufferModelNonInverting "CDSDefaultOutput_2p5v") (bufferModelInverting "CDSDefaultOutput_2p5v") (stimuli nil) (offsets nil) (state "tristate") (cycle "1") (termMap nil) (setup "0.9e-09") (hold "0.4e-09") (rise nil) (fall nil) (threshOutputHighMin "2.375  V") (threshOutputHighTyp "2.5  V") (threshOutputHighMax "2.625  V") (threshOutputLowMin "1.275  V") (threshOutputLowTyp "1.7  V") (threshOutputLowMax "1.985  V") (mappingTagNonInverting nil) (mappingTagInverting nil) (spice nil))) (IbisOutput_OpenPullUp ((temperature "27") (bufferModel "CDSDefaultOutput_2p5v") (stimuli nil) (offsets nil) (state "tristate") (cycle "1") (termMap nil) (setup "2.0e-09") (hold "1.0e-09") (rise nil) (fall nil) (macroType nil) (voltage nil) (spice nil) (LEFDEFPinName nil) (LEFDEFPinType nil) (mappingTag nil))) (IbisIO_OpenPullUp ((temperature "27") (bufferModel "CDSDefaultIO_2p5v") (stimuli nil) (offsets nil) (state "tristate") (cycle "1") (termMap nil) (setup "2.0e-09") (hold "1.0e-09") (rise nil) (fall nil) (macroType nil) (voltage nil) (spice nil) (LEFDEFPinName nil) (LEFDEFPinType nil) (mappingTag nil)))))
				)
				( objectStatus "SPI_PCH_CLK" )
			)
			( electricalCSet "@crescent_city_bb_fab1_lib.crescent_city_bb_fab1(sch_1):\SPI_SWITCH_MOSI\"
				( groupRef "SPI_SWITCH_MOSI:SPI_MUX-U7F1" )
				( groupRef "SPI_SWITCH_MOSI:SPI_MUX-U3T1" )
				( pinPairRef "SPI_SWITCH_MOSI:U8F1.7:U7F1.15" )
				( pinPairRef "SPI_SWITCH_MOSI:U8F1.7:U3T1.15" )
				( attribute "TOPOLOGY_TEMPLATE_REVISION" "1.0"
					( Origin gBackEnd )
				)
				( topologyData 27814
(SKIDL (Circuits ("MAIN" (Parts ("CRESCENT_CITY_902_20150507_Q.@@U3T1.15" IbisIOPkg (xy (5521 4214)) (refDes "U3T1") (model "Unknown") (Props (_SXDesignName "CRESCENT_CITY_902_20150507_Q") (brdx "14975 MIL") (brdy "834 MIL") (bufferModel "CDSDefaultIO_2p5v") (cycle "1") (hold "1.0e-09") (mappingTag "") (offsets ("4" "0") ("5" "0")) (setup "2.0e-09") (state "tristate") (stimuli ("4" "local49") ("5" "local50")) (temperature "27") (termMap ("4" "Data") ("5" "Enable"))) (Terms ("CRESCENT_CITY_902_20150507_Q.X1497500Y83400L36LRATS" "15"))) ("CRESCENT_CITY_902_20150507_Q.@@U8F1.7" IbisIOPkg (xy (5512 4227)) (refDes "U8F1") (model "Unknown") (Props (_SXDesignName "CRESCENT_CITY_902_20150507_Q") (brdx "15580 MIL") (brdy "1470 MIL") (bufferModel "CDSDefaultIO_2p5v") (cycle "1") (hold "1.0e-09") (mappingTag "") (offsets ("4" "0") ("5" "0")) (setup "2.0e-09") (state "tristate") (stimuli ("4" "local51") ("5" "local52")) (temperature "27") (termMap ("4" "Data") ("5" "Enable"))) (Terms ("CRESCENT_CITY_902_20150507_Q.X1558000Y147000L2LRATS" "7"))) ("CRESCENT_CITY_902_20150507_Q.@@U7F1.15" IbisIOPkg (xy (5502 4240)) (refDes "U7F1") (model "Unknown") (Props (_SXDesignName "CRESCENT_CITY_902_20150507_Q") (brdx "15220.2 MIL") (brdy "841.5 MIL") (bufferModel "CDSDefaultIO_2p5v") (cycle "1") (hold "1.0e-09") (mappingTag "") (offsets ("4" "0") ("5" "0")) (setup "2.0e-09") (state "tristate") (stimuli ("4" "local53") ("5" "local54")) (temperature "27") (termMap ("4" "Data") ("5" "Enable"))) (Terms ("CRESCENT_CITY_902_20150507_Q.X1522020Y84150L2LRATS" "15"))) ("CRESCENT_CITY_902_20150507_Q.T@@RATS@@R7F29.2@@U7F1.15" TLine (xy (5497 4229)) (refDes "TL35") (Props (_SXDesignName "CRESCENT_CITY_902_20150507_Q") (impedance "48.412 ohm") length("181.70 MIL") (propDelay "0.03263 ns") (traceCount "1") (traceGeometry "Microstrip") (velocity "5568.5 mil/ns")) (Terms ("CRESCENT_CITY_902_20150507_Q.X1515500Y72500L2LRATS" "1") ("CRESCENT_CITY_902_20150507_Q.X1522020Y84150L2LRATS" "2"))) ("CRESCENT_CITY_902_20150507_Q.@@R3T10.1.2" Resistor (xy (5497 4209)) (refDes "R3T10") (value "33.2 Ohm") (Props (_SXDesignName "CRESCENT_CITY_902_20150507_Q")) (Terms ("CRESCENT_CITY_902_20150507_Q.X1515500Y72500L36LRATS" "1") ("CRESCENT_CITY_902_20150507_Q.X1512000Y72500L36LRATS" "2"))) ("CRESCENT_CITY_902_20150507_Q.@@R7F29.2.1" Resistor (xy (5488 4229)) (mirror x) (refDes "R7F29") (value "33.2 Ohm") (Props (_SXDesignName "CRESCENT_CITY_902_20150507_Q")) (Terms ("CRESCENT_CITY_902_20150507_Q.X1515500Y72500L2LRATS" "2") ("CRESCENT_CITY_902_20150507_Q.X1512000Y72500L2LRATS" "1"))) ("CRESCENT_CITY_902_20150507_Q.T@@RATS@@R3T10.1@@R7F29.1" TLine (xy (5482 4222)) (mirror x) (refDes "TL36") (Props (_SXDesignName "CRESCENT_CITY_902_20150507_Q") (impedance "48.412 ohm") length("35.00 MIL") (propDelay "0.00629 ns") (traceCount "1") (traceGeometry "Microstrip") (velocity "5564.37 mil/ns")) (Terms ("CRESCENT_CITY_902_20150507_Q.X1515500Y72500L36LRATS" "1") ("CRESCENT_CITY_902_20150507_Q.X1512000Y72500L2LRATS" "2"))) ("CRESCENT_CITY_902_20150507_Q.T@@RATS@@U8F1.7@@R3T10.1" TLine (xy (5497 4222)) (mirror x) (refDes "TL37") (Props (_SXDesignName "CRESCENT_CITY_902_20150507_Q") (impedance "48.412 ohm") length("1170.00 MIL") (propDelay "0.21014 ns") (traceCount "1") (traceGeometry "Microstrip") (velocity "5567.72 mil/ns")) (Terms ("CRESCENT_CITY_902_20150507_Q.X1558000Y147000L2LRATS" "1") ("CRESCENT_CITY_902_20150507_Q.X1515500Y72500L36LRATS" "2"))) ("CRESCENT_CITY_902_20150507_Q.T@@RATS@@U3T1.15@@R3T10.2" TLine (xy (5506 4209)) (mirror x) (refDes "TL38") (Props (_SXDesignName "CRESCENT_CITY_902_20150507_Q") (impedance "46.577 ohm") length("254.00 MIL") (propDelay "0.04562 ns") (traceCount "1") (traceGeometry "Microstrip") (velocity "5567.72 mil/ns")) (Terms ("CRESCENT_CITY_902_20150507_Q.X1497500Y83400L36LRATS" "1") ("CRESCENT_CITY_902_20150507_Q.X1512000Y72500L36LRATS" "2")))) (Nodes ("CRESCENT_CITY_902_20150507_Q.X1515500Y72500L2LRATS" (terms "CRESCENT_CITY_902_20150507_Q.@@R7F29.2.1.1" "CRESCENT_CITY_902_20150507_Q.T@@RATS@@R7F29.2@@U7F1.15.1")) ("CRESCENT_CITY_902_20150507_Q.X1497500Y83400L36LRATS" (terms "CRESCENT_CITY_902_20150507_Q.T@@RATS@@U3T1.15@@R3T10.2.1" "CRESCENT_CITY_902_20150507_Q.@@U3T1.15.1")) ("CRESCENT_CITY_902_20150507_Q.X1558000Y147000L2LRATS" (terms "CRESCENT_CITY_902_20150507_Q.T@@RATS@@U8F1.7@@R3T10.1.1" "CRESCENT_CITY_902_20150507_Q.@@U8F1.7.1")) ("CRESCENT_CITY_902_20150507_Q.X1512000Y72500L2LRATS" (terms "CRESCENT_CITY_902_20150507_Q.T@@RATS@@R3T10.1@@R7F29.1.2" "CRESCENT_CITY_902_20150507_Q.@@R7F29.2.1.2")) ("CRESCENT_CITY_902_20150507_Q.X1515500Y72500L36LRATS" (terms "CRESCENT_CITY_902_20150507_Q.T@@RATS@@U8F1.7@@R3T10.1.2" "CRESCENT_CITY_902_20150507_Q.T@@RATS@@R3T10.1@@R7F29.1.1" "CRESCENT_CITY_902_20150507_Q.@@R3T10.1.2.1")) ("CRESCENT_CITY_902_20150507_Q.X1512000Y72500L36LRATS" (terms "CRESCENT_CITY_902_20150507_Q.T@@RATS@@U3T1.15@@R3T10.2.2" "CRESCENT_CITY_902_20150507_Q.@@R3T10.1.2.2")) ("CRESCENT_CITY_902_20150507_Q.X1522020Y84150L2LRATS" (terms "CRESCENT_CITY_902_20150507_Q.T@@RATS@@R7F29.2@@U7F1.15.2" "CRESCENT_CITY_902_20150507_Q.@@U7F1.15.1"))) (Ports) (Stimuli ("local51" (scope local) (stimType periodic) (Props (periodicFreq "5e+007") (periodicJitter "0") (periodicPattern "1"))) ("local54" (scope local) (stimType periodic) (Props (periodicFreq "5e+007") (periodicJitter "0") (periodicPattern "1"))) ("local49" (scope local) (stimType periodic) (Props (periodicFreq "5e+007") (periodicJitter "0") (periodicPattern "1"))) ("local50" (scope local) (stimType periodic) (Props (periodicFreq "5e+007") (periodicJitter "0") (periodicPattern "1"))) ("local53" (scope local) (stimType periodic) (Props (periodicFreq "5e+007") (periodicJitter "0") (periodicPattern "1"))) ("local52" (scope local) (stimType periodic) (Props (periodicFreq "5e+007") (periodicJitter "0") (periodicPattern "1")))) (Notes) (Constraints ("RELATIVE_PROPAGATION_DELAY" ("SPI_U7F1" "CRESCENT_CITY_902_20150507_Q U8F1.7" "CRESCENT_CITY_902_20150507_Q U7F1.15" "GLOBAL" "LENGTH" "0.00635" "LENGTH" "0") ("SPI_U3T1" "CRESCENT_CITY_902_20150507_Q U8F1.7" "CRESCENT_CITY_902_20150507_Q U3T1.15" "GLOBAL" "LENGTH" "0.00635" "LENGTH" "0"))) (MeasurementSets ("EMI" ("EMIStatus" status("on")) ("PeakEmission" status("on")) ("PeakFrequency" status("on")) ("PulseFreq" status("on")) ("RiseTime" status("on")) ("VoltageSwing" status("on"))) ("Reflection" ("BufferDelayFall" status("off")) ("BufferDelayRise" status("off")) ("EyeHeight" status("off")) ("EyeJitter" status("off")) ("EyeWidth" status("off")) ("FirstIncidentFall" status("off")) ("FirstIncidentRise" status("off")) ("Glitch" status("on")) ("GlitchFall" status("off")) ("GlitchRise" status("off")) ("Monotonic" status("on")) ("MonotonicFall" status("off")) ("MonotonicRise" status("off")) ("NoiseMargin" status("on")) ("NoiseMarginHigh" status("off")) ("NoiseMarginLow" status("off")) ("OvershootHigh" status("on")) ("OvershootLow" status("on")) ("PropDelay" status("on")) ("SettleDelay" status("on")) ("SettleDelayFall" status("off")) ("SettleDelayRise" status("off")) ("SwitchDelay" status("on")) ("SwitchDelayFall" status("off")) ("SwitchDelayRise" status("off"))) ("Crosstalk" ("Crosstalk" status("on"))) ("Custom")) (VectorSets) (Props (XnetName "SPI_SWITCH_MOSI") (allDrivers "active") (customSimType "Reflection") (ftsMode ("Typ")) (rcvrSelect "all") (tlineDelayMode "time") (userRevision "1.0")))) (Subckts) (CrossSections ("CRESCENT_CITY_902_20150507_Q" (Props (SXDesignName "CRESCENT_CITY_902_20150507_Q")) (Layers ("" (layerType "SURFACE") (material "AIR") (thickness "0 mil") (dielectricConstant "1.000000") (lossTangent "0") (etchFactor "0.000000") (elecCondVal "0 mho/cm") (thermCondVal "0 w/cm-degC")) ("" (layerType "DIELECTRIC") (material "CONFORMAL_COAT") (thickness "0.5 mil") (dielectricConstant "3.800000") (lossTangent "0.035") (etchFactor "0.000000") (elecCondVal "0 mho/cm") (thermCondVal "0.012 w/cm-degC")) ("TOP" (layerType "CONDUCTOR") (material "COPPER") (thickness "  2.100000 mil") (width "4.00 MIL") (dielectricConstant "4.500000") (lossTangent "0") (etchFactor "70.000000") (elecCondVal "595900.000000 mho/cm") (thermCondVal "0 w/cm-degC") (signalDieConstant "3.800000") (signalLossTangent "0.035")) ("" (layerType "DIELECTRIC") (material "FR-4") (thickness "  2.670000 mil") (dielectricConstant "4.000000") (lossTangent "0.035") (etchFactor "0.000000") (elecCondVal "0 mho/cm") (thermCondVal "0.012 w/cm-degC")) ("L2_GND1" (layerType "PLANE") (material "COPPER") (isShield t) (thickness "  1.250000 mil") (dielectricConstant "4.500000") (lossTangent "0.035") (etchFactor "90.000000") (elecCondVal "595900.000000 mho/cm") (thermCondVal "0.012 w/cm-degC")) ("" (layerType "DIELECTRIC") (material "FR-4") (thickness "  9.000000 mil") (dielectricConstant "4.100000") (lossTangent "0.035") (etchFactor "0.000000") (elecCondVal "0 mho/cm") (thermCondVal "0.012 w/cm-degC")) ("L3_SIG1" (layerType "CONDUCTOR") (material "COPPER") (thickness "  1.250000 mil") (width "4.00 MIL") (dielectricConstant "4.500000") (lossTangent "0.035") (etchFactor "90.000000") (elecCondVal "595900.000000 mho/cm") (thermCondVal "0.012 w/cm-degC") (signalDieConstant "4.100000") (signalLossTangent "0.035")) ("" (layerType "DIELECTRIC") (material "FR-4") (thickness "  3.000000 mil") (dielectricConstant "4.500000") (lossTangent "0.035") (etchFactor "0.000000") (elecCondVal "0 mho/cm") (thermCondVal "0 w/cm-degC")) ("L4_GND2" (layerType "PLANE") (material "COPPER") (isShield t) (thickness "  1.250000 mil") (dielectricConstant "4.500000") (lossTangent "0.035") (etchFactor "90.000000") (elecCondVal "595900.000000 mho/cm") (thermCondVal "0 w/cm-degC")) ("" (layerType "DIELECTRIC") (material "FR-4") (thickness "  9.000000 mil") (dielectricConstant "4.000000") (lossTangent "0.035") (etchFactor "0.000000") (elecCondVal "0 mho/cm") (thermCondVal "0.012 w/cm-degC")) ("L5_SIG2" (layerType "CONDUCTOR") (material "COPPER") (thickness "  1.250000 mil") (width "4.00 MIL") (dielectricConstant "4.500000") (lossTangent "0.035") (etchFactor "90.000000") (elecCondVal "595900.000000 mho/cm") (thermCondVal "0.012 w/cm-degC") (signalDieConstant "4.000000") (signalLossTangent "0.035")) ("" (layerType "DIELECTRIC") (material "FR-4") (thickness "  3.000000 mil") (dielectricConstant "4.500000") (lossTangent "0.035") (etchFactor "0.000000") (elecCondVal "0 mho/cm") (thermCondVal "0 w/cm-degC")) ("L6_GND3" (layerType "PLANE") (material "COPPER") (isShield t) (thickness "  1.250000 mil") (dielectricConstant "4.500000") (lossTangent "0.035") (etchFactor "90.000000") (elecCondVal "595900.000000 mho/cm") (thermCondVal "0 w/cm-degC")) ("" (layerType "DIELECTRIC") (material "FR-4") (thickness "  4.500000 mil") (dielectricConstant "4.100000") (lossTangent "0.035") (etchFactor "0.000000") (elecCondVal "0 mho/cm") (thermCondVal "0.012 w/cm-degC")) ("L7_PWR1-SIG" (layerType "PLANE") (material "COPPER") (isShield t) (thickness "  2.610000 mil") (dielectricConstant "4.500000") (lossTangent "0.035") (etchFactor "90.000000") (elecCondVal "595900.000000 mho/cm") (thermCondVal "0.012 w/cm-degC")) ("" (layerType "DIELECTRIC") (material "FR-4") (thickness "  3.100000 mil") (dielectricConstant "4.500000") (lossTangent "0.035") (etchFactor "0.000000") (elecCondVal "0 mho/cm") (thermCondVal "0 w/cm-degC")) ("L8_GND_TEMP" (layerType "PLANE") (material "COPPER") (isShield t) (thickness "  1.250000 mil") (dielectricConstant "4.500000") (lossTangent "0.035") (etchFactor "90.000000") (elecCondVal "595900.000000 mho/cm") (thermCondVal "0 w/cm-degC")) ("" (layerType "DIELECTRIC") (material "FR-4") (thickness "  3.030000 mil") (dielectricConstant "4.500000") (lossTangent "0.035") (etchFactor "0.000000") (elecCondVal "0 mho/cm") (thermCondVal "0 w/cm-degC")) ("L9_SIG_TEMP" (layerType "CONDUCTOR") (material "COPPER") (thickness "  1.250000 mil") (width "3.52 MIL") (dielectricConstant "4.500000") (lossTangent "0.035") (etchFactor "90.000000") (elecCondVal "595900.000000 mho/cm") (thermCondVal "0 w/cm-degC") (signalDieConstant "4.500000") (signalLossTangent "0.035")) ("" (layerType "DIELECTRIC") (material "FR-4") (thickness "  5.000000 mil") (dielectricConstant "4.500000") (lossTangent "0.035") (etchFactor "0.000000") (elecCondVal "0 mho/cm") (thermCondVal "0 w/cm-degC")) ("L10_SIG_TEMP" (layerType "CONDUCTOR") (material "COPPER") (thickness "  1.250000 mil") (width "3.52 MIL") (dielectricConstant "4.500000") (lossTangent "0.035") (etchFactor "90.000000") (elecCondVal "595900.000000 mho/cm") (thermCondVal "0 w/cm-degC") (signalDieConstant "4.500000") (signalLossTangent "0.035")) ("" (layerType "DIELECTRIC") (material "FR-4") (thickness "  3.030000 mil") (dielectricConstant "4.500000") (lossTangent "0.035") (etchFactor "0.000000") (elecCondVal "0 mho/cm") (thermCondVal "0 w/cm-degC")) ("L11_GND_TEMP" (layerType "PLANE") (material "COPPER") (isShield t) (thickness "  1.250000 mil") (dielectricConstant "4.500000") (lossTangent "0.035") (etchFactor "90.000000") (elecCondVal "595900.000000 mho/cm") (thermCondVal "0 w/cm-degC")) ("" (layerType "DIELECTRIC") (material "FR-4") (thickness "  3.100000 mil") (dielectricConstant "4.000000") (lossTangent "0.035") (etchFactor "0.000000") (elecCondVal "0 mho/cm") (thermCondVal "0.012 w/cm-degC")) ("L12_PWR2-SIG" (layerType "PLANE") (material "COPPER") (isShield t) (thickness "  2.610000 mil") (dielectricConstant "4.500000") (lossTangent "0.035") (etchFactor "90.000000") (elecCondVal "595900.000000 mho/cm") (thermCondVal "0.012 w/cm-degC")) ("" (layerType "DIELECTRIC") (material "FR-4") (thickness "  4.500000 mil") (dielectricConstant "4.500000") (lossTangent "0.035") (etchFactor "0.000000") (elecCondVal "0 mho/cm") (thermCondVal "0 w/cm-degC")) ("L13_GND4" (layerType "PLANE") (material "COPPER") (isShield t) (thickness "  1.250000 mil") (dielectricConstant "4.500000") (lossTangent "0.035") (etchFactor "90.000000") (elecCondVal "595900.000000 mho/cm") (thermCondVal "0 w/cm-degC")) ("" (layerType "DIELECTRIC") (material "FR-4") (thickness "  3.000000 mil") (dielectricConstant "4.100000") (lossTangent "0.035") (etchFactor "0.000000") (elecCondVal "0 mho/cm") (thermCondVal "0.012 w/cm-degC")) ("L14_SIG3" (layerType "CONDUCTOR") (material "COPPER") (thickness "  1.250000 mil") (width "4.00 MIL") (dielectricConstant "4.500000") (lossTangent "0.035") (etchFactor "90.000000") (elecCondVal "595900.000000 mho/cm") (thermCondVal "0.012 w/cm-degC") (signalDieConstant "4.100000") (signalLossTangent "0.035")) ("" (layerType "DIELECTRIC") (material "FR-4") (thickness "  9.000000 mil") (dielectricConstant "4.500000") (lossTangent "0.035") (etchFactor "0.000000") (elecCondVal "0 mho/cm") (thermCondVal "0 w/cm-degC")) ("L15_GND5" (layerType "PLANE") (material "COPPER") (isShield t) (thickness "  1.250000 mil") (dielectricConstant "4.500000") (lossTangent "0.035") (etchFactor "90.000000") (elecCondVal "595900.000000 mho/cm") (thermCondVal "0 w/cm-degC")) ("" (layerType "DIELECTRIC") (material "FR-4") (thickness "  3.000000 mil") (dielectricConstant "4.500000") (lossTangent "0.035") (etchFactor "0.000000") (elecCondVal "0 mho/cm") (thermCondVal "0.012 w/cm-degC")) ("L16_SIG4" (layerType "CONDUCTOR") (material "COPPER") (thickness "  1.250000 mil") (width "4.00 MIL") (dielectricConstant "4.500000") (lossTangent "0.035") (etchFactor "90.000000") (elecCondVal "595900.000000 mho/cm") (thermCondVal "0.012 w/cm-degC") (signalDieConstant "4.500000") (signalLossTangent "0.035")) ("" (layerType "DIELECTRIC") (material "FR-4") (thickness "  9.000000 mil") (dielectricConstant "4.500000") (lossTangent "0.035") (etchFactor "0.000000") (elecCondVal "0 mho/cm") (thermCondVal "0 w/cm-degC")) ("L17_GND6" (layerType "PLANE") (material "COPPER") (isShield t) (thickness "  1.250000 mil") (dielectricConstant "4.500000") (lossTangent "0.035") (etchFactor "90.000000") (elecCondVal "595900.000000 mho/cm") (thermCondVal "0.012 w/cm-degC")) ("" (layerType "DIELECTRIC") (material "FR-4") (thickness "  2.670000 mil") (dielectricConstant "4.500000") (lossTangent "0.035") (etchFactor "0.000000") (elecCondVal "0 mho/cm") (thermCondVal "0.012 w/cm-degC")) ("BOTTOM" (layerType "CONDUCTOR") (material "COPPER") (thickness "  2.100000 mil") (width "4.00 MIL") (dielectricConstant "4.500000") (lossTangent "0") (etchFactor "70.000000") (elecCondVal "595900.000000 mho/cm") (thermCondVal "0 w/cm-degC") (signalDieConstant "3.800000") (signalLossTangent "0.035")) ("" (layerType "DIELECTRIC") (material "CONFORMAL_COAT") (thickness "0.5 mil") (dielectricConstant "3.800000") (lossTangent "0.035") (etchFactor "0.000000") (elecCondVal "0 mho/cm") (thermCondVal "0.012 w/cm-degC")) ("" (layerType "SURFACE") (material "AIR") (thickness "0 mil") (dielectricConstant "1.000000") (lossTangent "0") (etchFactor "0.000000") (elecCondVal "0 mho/cm") (thermCondVal "0 w/cm-degC"))))) (Props (DesUnits "mils 2") (LayerStack ("DIELECTRIC" "DIELECTRIC" "BOTTOM" "DIELECTRIC" "L17_GND6" "DIELECTRIC" "L16_SIG4" "DIELECTRIC" "L15_GND5" "DIELECTRIC" "L14_SIG3" "DIELECTRIC" "L13_GND4" "DIELECTRIC" "L12_PWR2-SIG" "DIELECTRIC" "L11_GND_TEMP" "DIELECTRIC" "L10_SIG_TEMP" "DIELECTRIC" "L9_SIG_TEMP" "DIELECTRIC" "L8_GND_TEMP" "DIELECTRIC" "L7_PWR1-SIG" "DIELECTRIC" "L6_GND3" "DIELECTRIC" "L5_SIG2" "DIELECTRIC" "L4_GND2" "DIELECTRIC" "L3_SIG1" "DIELECTRIC" "L2_GND1" "DIELECTRIC" "TOP" "DIELECTRIC" "DIELECTRIC")) (Revision "16.600")) (Params (DiffInputPkg ((temperature "27") (bufferModelNonInverting "CDSDefaultInput_2p5v") (bufferModelInverting "CDSDefaultInput_2p5v") (threshInputHighMin "1.7 V") (threshInputHighTyp "1.7  V") (threshInputHighMax "1.7  V") (threshInputLowMin "0.7  V") (threshInputLowTyp "0.7  V") (threshInputLowMax "0.7  V") (mappingTagNonInverting nil) (mappingTagInverting nil) (cycle "1"))) (IbisOutputPkg ((temperature "27") (bufferModel "CDSDefaultOutput_2p5v") (stimuli nil) (offsets nil) (state "tristate") (cycle "1") (termMap nil) (setup "2.0e-09") (hold "1.0e-09") (rise nil) (fall nil) (macroType nil) (voltage nil) (spice nil) (LEFDEFPinName nil) (LEFDEFPinType nil) (mappingTag nil))) (IbisIOPkg ((temperature "27") (bufferModel "CDSDefaultIO_2p5v") (stimuli nil) (offsets nil) (state "tristate") (cycle "1") (termMap nil) (setup "2.0e-09") (hold "1.0e-09") (rise nil) (fall nil) (macroType nil) (voltage nil) (spice nil) (LEFDEFPinName nil) (LEFDEFPinType nil) (mappingTag nil))) (IbisIOMacro ((temperature "27") (bufferModel "CDSDefaultIO_2p5v") (stimuli nil) (offsets nil) (state "tristate") (cycle "1") (termMap nil) (setup "2.0e-09") (hold "1.0e-09") (rise nil) (fall nil) (macroType nil) (voltage nil) (spice nil) (LEFDEFPinName nil) (LEFDEFPinType nil) (mappingTag nil))) (ESpiceDevice nil) (IbisInput ((temperature "27") (bufferModel "CDSDefaultInput_2p5v") (cycle "1") (LEFDEFPinName nil) (LEFDEFPinType nil) (mappingTag nil))) (ShuntTerm ((resistance "50 ohm") (voltage "5 V") (maxDelay "0.1 ns"))) (SeriesTerm ((resistance "22 ohm") (maxDelay "0.1 ns"))) (CurrentProbe nil) (idlCircuit ((allDrivers "active") (ftsMode '("Typ")) (rcvrSelect "all") (simMode "Reflection") (tlineDelayMode "time") (userRevision "1.0") (autoSolve "On"))) (TheveninTerm ((resistanceUp "180 ohm") (resistanceDown "270 ohm") (voltageUp "5 V") (voltageDown "0 V") (maxDelay "0.1 ns"))) (RCTerm ((resistance "50 ohm") (capacitance "20 pF") (voltage "5 V") (maxDelay "0.1 ns"))) (LowClampTerm ((cutoffVoltage "0.7 V") (voltage "0 V") (maxDelay "0.1 ns"))) (Cable (length("1 m"))) (HiClampTerm ((cutoffVoltage "0.7 V") (voltage "5 V") (maxDelay "0.1 ns"))) (DualClampTerm ((cutoffVoltageUp "0.7 V") (cutoffVoltageDown "0.7 V") (voltageUp "5 V") (voltageDown "0 V") (maxDelay "0.1 ns"))) (IbisInputPkg ((temperature "27") (bufferModel "CDSDefaultInput_2p5v") (cycle "1") (LEFDEFPinName nil) (LEFDEFPinType nil) (mappingTag nil))) (async ((asyncTimePoints "") (asyncInitState "1"))) (clocked ((clockRise "1e-09") (clockFall "1e-09") (clockFreq "100e6") (clockInitState "0") (clockDutyCycle "0.5") (clockJitter "0"))) (Diode ((cutoffVoltage "0.7 V"))) (IbisOutput ((temperature "27") (bufferModel "CDSDefaultOutput_2p5v") (stimuli nil) (offsets nil) (state "tristate") (cycle "1") (termMap nil) (setup "2.0e-09") (hold "1.0e-09") (rise nil) (fall nil) (macroType nil) (voltage nil) (spice nil) (LEFDEFPinName nil) (LEFDEFPinType nil) (mappingTag nil))) (periodic ((periodicFreq "100e6") (periodicPattern "10") (periodicJitter "0"))) (IbisIO ((temperature "27") (bufferModel "CDSDefaultIO_2p5v") (stimuli nil) (offsets nil) (state "tristate") (cycle "1") (termMap nil) (setup "2.0e-09") (hold "1.0e-09") (rise nil) (fall nil) (macroType nil) (voltage nil) (spice nil) (LEFDEFPinName nil) (LEFDEFPinType nil) (mappingTag nil))) (Via ((model "Unknown") (viaOutputFormat "Unknown") (viaPadstack nil) (viaTopLayer nil) (viaBottomLayer nil) (viaIsPower nil) (viaIsGround nil))) (CPWMS ((d1Thickness "10 mil") (d1Constant "4.5") (d1LossTangent "0.035") (d2Thickness "0.72 mil") (d2Constant "4.5") (d2LossTangent "0.035") (d3Thickness "0.0") (d3Constant "1") (d3LossTangent "0") length("1000 mil") (spacing "5 mil") (spacing2 "5 mil") (spacing3 "5 mil") (spacing4 "5 mil") (spacing5 "5 mil") (traceConductivity "595900 mho/cm") (traceGeometry "cpwms") (traceLayerName "") (traceThickness "0.72 mil") (traceType "single") (traceWidth "5.0 mil") (traceWidth2 "5.0 mil") (traceWidth3 "5.0 mil") (traceWidth4 "5.0 mil") (traceWidth5 "5.0 mil") (traceWidth6 "5.0 mil") (offset "0 mil") (traceCount "1") (impedance nil))) (Trace ((d1Thickness "10 mil") (d1Constant "4.5") (d1LossTangent "0.035") (d2Thickness "10 mil") (d2Constant "4.5") (d2LossTangent "0.035") (d3Thickness "0.0") (d3Constant "1.0") (d3LossTangent "0") length("1000 mil") (spacing "5 mil") (spacing2 "5 mil") (spacing3 "5 mil") (spacing4 "5 mil") (spacing5 "5 mil") (traceConductivity "595900 mho/cm") (traceGeometry "microstrip") (traceLayerName "") (traceThickness "0.72 mil") (traceType "single") (traceWidth "5.0 mil") (traceWidth2 "5.0 mil") (traceWidth3 "5.0 mil") (traceWidth4 "5.0 mil") (traceWidth5 "5.0 mil") (traceWidth6 "5.0 mil") (offset "0 mil") (traceCount "1") (impedance nil))) (Source ((voltage "5 V"))) (CPWSL ((d1Thickness "10 mil") (d1Constant "4.5") (d1LossTangent "0.035") (d2Thickness "0.72 mil") (d2Constant "4.5") (d2LossTangent "0.035") (d3Thickness "10 mil") (d3Constant "4.5") (d3LossTangent "0.035") length("1000 mil") (spacing "5 mil") (spacing2 "5 mil") (spacing3 "5 mil") (spacing4 "5 mil") (spacing5 "5 mil") (traceConductivity "595900 mho/cm") (traceGeometry "cpwms") (traceLayerName "") (traceThickness "0.72 mil") (traceType "single") (traceWidth "5.0 mil") (traceWidth2 "5.0 mil") (traceWidth3 "5.0 mil") (traceWidth4 "5.0 mil") (traceWidth5 "5.0 mil") (traceWidth6 "5.0 mil") (offset "0 mil") (traceCount "1") (impedance nil))) (RLGC (length("1000 mil"))) (Capacitor ((capacitance "10 pF") (orientation "0"))) (DiffIOPkg ((temperature "27") (bufferModelNonInverting "CDSDefaultIO_2p5v") (bufferModelInverting "CDSDefaultIO_2p5v") (stimuli nil) (offsets nil) (state "tristate") (cycle "1") (termMap nil) (setup "0.9e-09") (hold "0.4e-09") (rise nil) (fall nil) (threshInputHighMin "1.7 V") (threshInputHighTyp "1.7  V") (threshInputHighMax "1.7  V") (threshInputLowMin "0.7  V") (threshInputLowTyp "0.7  V") (threshInputLowMax "0.7 ") (threshOutputHighMin "2.365  V") (threshOutputHighTyp "2.5  V") (threshOutputHighMax "2.625  V") (threshOutputLowMin "1.275  V") (threshOutputLowTyp "1.7  V") (threshOutputLowMax "1.985  V") (mappingTagNonInverting nil) (mappingTagInverting nil) (spice nil))) (Inductor ((inductance "5 nH") (orientation "0"))) (DiffIO ((temperature "27") (bufferModelNonInverting "CDSDefaultIO_2p5v") (bufferModelInverting "CDSDefaultIO_2p5v") (stimuli nil) (offsets nil) (state "tristate") (cycle "1") (termMap nil) (setup "0.9e-09") (hold "0.4e-09") (rise nil) (fall nil) (threshInputHighMin "1.7 V") (threshInputHighTyp "1.7  V") (threshInputHighMax "1.7  V") (threshInputLowMin "0.7  V") (threshInputLowTyp "0.7  V") (threshInputLowMax "0.7 ") (threshOutputHighMin "2.365  V") (threshOutputHighTyp "2.5  V") (threshOutputHighMax "2.625  V") (threshOutputLowMin "1.275  V") (threshOutputLowTyp "1.7  V") (threshOutputLowMax "1.985  V") (mappingTagNonInverting nil) (mappingTagInverting nil) (spice nil))) (CPW ((d1Thickness "10 mil") (d1Constant "4.5") (d1LossTangent "0.035") (d2Thickness "0.72 mil") (d2Constant "1") (d2LossTangent "0") (d3Thickness "0.0") (d3Constant "1") (d3LossTangent "0") length("1000 mil") (spacing "5 mil") (spacing2 "5 mil") (spacing3 "5 mil") (spacing4 "5 mil") (spacing5 "5 mil") (traceConductivity "595900 mho/cm") (traceGeometry "cpwms") (traceLayerName "") (traceThickness "0.72 mil") (traceType "single") (traceWidth "5.0 mil") (traceWidth2 "5.0 mil") (traceWidth3 "5.0 mil") (traceWidth4 "5.0 mil") (traceWidth5 "5.0 mil") (traceWidth6 "5.0 mil") (offset "0 mil") (traceCount "1") (impedance nil))) (Connector nil) (TLine ((diffImpedance "100ohm") (diffVelocity "1.4142e+08M/s") (impedance "60ohm") length("2800 mil") (propDelay "0.5 ns") (velocity "5600 mil/ns") (traceCount "1") (traceGeometry "Microstrip") (impedanceMin nil) (impedanceMax nil) (lengthMin nil) (lengthMax nil) (propDelayMin nil) (propDelayMax nil) (impedanceSweepCount nil) (propDelaySweepCount nil) (velocitySweepCount nil) (lengthSweepCount nil) (matchSetName nil))) (sync ((syncFreq "100e6") (syncInitState "1") (syncPattern "10") (syncEdgeSwitch "rise"))) (IbisIO_OpenPullDown ((temperature "27") (bufferModel "CDSDefaultIO_2p5v") (stimuli nil) (offsets nil) (state "tristate") (cycle "1") (termMap nil) (setup "2.0e-09") (hold "1.0e-09") (rise nil) (fall nil) (macroType nil) (voltage nil) (spice nil) (LEFDEFPinName nil) (LEFDEFPinType nil) (mappingTag nil))) (DiffOutputPkg ((temperature "27") (bufferModelNonInverting "CDSDefaultOutput_2p5v") (bufferModelInverting "CDSDefaultOutput_2p5v") (stimuli nil) (offsets nil) (state "tristate") (cycle "1") (termMap nil) (setup "0.9e-09") (hold "0.4e-09") (rise nil) (fall nil) (threshOutputHighMin "2.375  V") (threshOutputHighTyp "2.5  V") (threshOutputHighMax "2.625  V") (threshOutputLowMin "1.275  V") (threshOutputLowTyp "1.7  V") (threshOutputLowMax "1.985  V") (mappingTagNonInverting nil) (mappingTagInverting nil) (spice nil))) (DiffInput ((temperature "27") (bufferModelNonInverting "CDSDefaultInput_2p5v") (bufferModelInverting "CDSDefaultInput_2p5v") (threshInputHighMin "1.7 V") (threshInputHighTyp "1.7  V") (threshInputHighMax "1.7  V") (threshInputLowMin "0.7  V") (threshInputLowTyp "0.7  V") (threshInputLowMax "0.7  V") (mappingTagNonInverting nil) (mappingTagInverting nil) (cycle "1"))) (Resistor ((resistance "50 ohm") (orientation "0"))) (DiffOutput ((temperature "27") (bufferModelNonInverting "CDSDefaultOutput_2p5v") (bufferModelInverting "CDSDefaultOutput_2p5v") (stimuli nil) (offsets nil) (state "tristate") (cycle "1") (termMap nil) (setup "0.9e-09") (hold "0.4e-09") (rise nil) (fall nil) (threshOutputHighMin "2.375  V") (threshOutputHighTyp "2.5  V") (threshOutputHighMax "2.625  V") (threshOutputLowMin "1.275  V") (threshOutputLowTyp "1.7  V") (threshOutputLowMax "1.985  V") (mappingTagNonInverting nil) (mappingTagInverting nil) (spice nil))) (IbisOutput_OpenPullUp ((temperature "27") (bufferModel "CDSDefaultOutput_2p5v") (stimuli nil) (offsets nil) (state "tristate") (cycle "1") (termMap nil) (setup "2.0e-09") (hold "1.0e-09") (rise nil) (fall nil) (macroType nil) (voltage nil) (spice nil) (LEFDEFPinName nil) (LEFDEFPinType nil) (mappingTag nil))) (IbisIO_OpenPullUp ((temperature "27") (bufferModel "CDSDefaultIO_2p5v") (stimuli nil) (offsets nil) (state "tristate") (cycle "1") (termMap nil) (setup "2.0e-09") (hold "1.0e-09") (rise nil) (fall nil) (macroType nil) (voltage nil) (spice nil) (LEFDEFPinName nil) (LEFDEFPinType nil) (mappingTag nil)))))
				)
				( objectStatus "SPI_SWITCH_MOSI" )
			)
			( electricalCSet "@crescent_city_bb_fab1_lib.crescent_city_bb_fab1(sch_1):\SPI_SWITCH_MISO\"
				( groupRef "SPI_SWITCH_MISO:SPI_MUX-U7F1" )
				( groupRef "SPI_SWITCH_MISO:SPI_MUX-U3T1" )
				( pinPairRef "SPI_SWITCH_MISO:U7F1.8:U8F1.12" )
				( pinPairRef "SPI_SWITCH_MISO:U8F1.12:U3T1.8" )
				( pinPairRef "SPI_SWITCH_MISO:U3T1.8:R3T2.2" )
				( pinPairRef "SPI_SWITCH_MISO:U7F1.8:R7F4.2" )
				( pinPairRef "SPI_SWITCH_MISO:R3T2.1:NET.T.1" )
				( pinPairRef "SPI_SWITCH_MISO:R7F4.1:NET.T.1" )
				( attribute "RATSNEST_SCHEDULE" "TEMPLATE"
					( Status sLocked )
					( Origin gBackEnd )
				)
				( attribute "TOPOLOGY_TEMPLATE_REVISION" "1.0"
					( Origin gBackEnd )
				)
				( topologyData 26628
(SKIDL (Circuits ("MAIN" (Parts ("CRESCENT_CITY_195_20150129_6PIN.@@U101.8" IbisIOPkg (xy (5515 4207)) (refDes "U3T1") (model "Unknown") (Props (_SXDesignName "CRESCENT_CITY_195_20150129_6PIN") (brdx "15275 MIL") (brdy "1210 MIL") (bufferModel "CDSDefaultIO_2p5v") (cycle "1") (hold "1.0e-09") (mappingTag "") (offsets ("4" "0") ("5" "0")) (setup "2.0e-09") (state "tristate") (stimuli ("4" "local41") ("5" "local42")) (temperature "27") (termMap ("4" "Data") ("5" "Enable"))) (Terms ("CRESCENT_CITY_195_20150129_6PIN.X1527500Y121000L28LRATS" "8"))) ("CRESCENT_CITY_195_20150129_6PIN.@@U99.8" IbisIOPkg (xy (5502 4240)) (refDes "U7F1") (model "Unknown") (Props (_SXDesignName "CRESCENT_CITY_195_20150129_6PIN") (brdx "14925.2 MIL") (brdy "1212.5 MIL") (bufferModel "CDSDefaultIO_2p5v") (cycle "1") (hold "1.0e-09") (mappingTag "") (offsets ("4" "0") ("5" "0")) (setup "2.0e-09") (state "tristate") (stimuli ("4" "local45") ("5" "local46")) (temperature "27") (termMap ("4" "Data") ("5" "Enable"))) (Terms ("CRESCENT_CITY_195_20150129_6PIN.X1492520Y121250L2LRATS" "8"))) ("CRESCENT_CITY_195_20150129_6PIN.@@U97.12" IbisIOPkg (xy (5506 4220)) (refDes "U8F1") (model "Unknown") (Props (_SXDesignName "CRESCENT_CITY_195_20150129_6PIN") (brdx "17174 MIL") (brdy "870 MIL") (bufferModel "CDSDefaultIO_2p5v") (cycle "1") (hold "1.0e-09") (mappingTag "") (offsets ("4" "0") ("5" "0")) (setup "2.0e-09") (state "tristate") (stimuli ("4" "local47") ("5" "local48")) (temperature "27") (termMap ("4" "Data") ("5" "Enable"))) (Terms ("CRESCENT_CITY_195_20150129_6PIN.X1717400Y87000L2LRATS" "12"))) ("CRESCENT_CITY_195_20150129_6PIN.T@@RATS@@U99.8@@R776.2" TLine (xy (5503 4229)) (mirror x) (refDes "TL31") (Props (_SXDesignName "CRESCENT_CITY_195_20150129_6PIN") (impedance "48.412 ohm") length("152.70 MIL") (propDelay "0.02743 ns") (traceCount "1") (traceGeometry "Microstrip") (velocity "5566.89 mil/ns")) (Terms ("CRESCENT_CITY_195_20150129_6PIN.X1492520Y121250L2LRATS" "1") ("CRESCENT_CITY_195_20150129_6PIN.X1489500Y133500L2LRATS" "2"))) ("CRESCENT_CITY_195_20150129_6PIN.T@@RATS@@R3169.1@@U97.12" TLine (xy (5497 4215)) (refDes "TL32") (Props (_SXDesignName "CRESCENT_CITY_195_20150129_6PIN") (impedance "60 ohm") length("2389.00 MIL") (propDelay "0.429081 ns") (traceCount "1") (traceGeometry "Microstrip") (velocity "5567.72 mil/ns")) (Terms ("idlNode_11" "1") ("CRESCENT_CITY_195_20150129_6PIN.X1717400Y87000L2LRATS" "2"))) ("CRESCENT_CITY_195_20150129_6PIN.@@R776.2.1" Resistor (xy (5488 4229)) (mirror x) (refDes "R7F4") (value "33.2 Ohm") (Props (_SXDesignName "CRESCENT_CITY_195_20150129_6PIN")) (Terms ("CRESCENT_CITY_195_20150129_6PIN.X1489500Y133500L2LRATS" "2") ("CRESCENT_CITY_195_20150129_6PIN.X1493000Y133500L2LRATS" "1"))) ("CRESCENT_CITY_195_20150129_6PIN.@@R3169.1.2" Resistor (xy (5497 4202)) (refDes "R3T2") (value "33.2 Ohm") (Props (_SXDesignName "CRESCENT_CITY_195_20150129_6PIN")) (Terms ("idlNode_6" "1") ("CRESCENT_CITY_195_20150129_6PIN.X1527500Y132500L28LRATS" "2"))) ("CRESCENT_CITY_195_20150129_6PIN.T@@RATS@@R776.1@@R3169.1" TLine (xy (5488 4215)) (refDes "TL33") (Props (_SXDesignName "CRESCENT_CITY_195_20150129_6PIN") (impedance "48.412 ohm") length("370.00 MIL") (propDelay "0.06645 ns") (traceCount "1") (traceGeometry "Microstrip") (velocity "5568.11 mil/ns")) (Terms ("CRESCENT_CITY_195_20150129_6PIN.X1493000Y133500L2LRATS" "1") ("idlNode_11" "2"))) ("CRESCENT_CITY_195_20150129_6PIN.T@@RATS@@R3169.2@@U101.8" TLine (xy (5506 4202)) (refDes "TL34") (Props (_SXDesignName "CRESCENT_CITY_195_20150129_6PIN") (impedance "46.577 ohm") length("115.00 MIL") (propDelay "0.02065 ns") (traceCount "1") (traceGeometry "Microstrip") (velocity "5569.02 mil/ns")) (Terms ("CRESCENT_CITY_195_20150129_6PIN.X1527500Y132500L28LRATS" "1") ("CRESCENT_CITY_195_20150129_6PIN.X1527500Y121000L28LRATS" "2"))) ("idlPart_8" TLine (xy (5493.0 4208.5)) (refDes "TL35") (Props (_SXDesignName "CRESCENT_CITY_195_20150129_6PIN") (impedance "60 ohm") length("2389.00 MIL") (propDelay "0.429081 ns") (traceCount "1") (traceGeometry "Microstrip") (velocity "5567.72 mil/ns")) (Terms ("idlNode_11" "1") ("idlNode_6" "2")))) (Nodes ("CRESCENT_CITY_195_20150129_6PIN.X1493000Y133500L2LRATS" (terms "CRESCENT_CITY_195_20150129_6PIN.T@@RATS@@R776.1@@R3169.1.1" "CRESCENT_CITY_195_20150129_6PIN.@@R776.2.1.2")) ("CRESCENT_CITY_195_20150129_6PIN.X1492520Y121250L2LRATS" (terms "CRESCENT_CITY_195_20150129_6PIN.T@@RATS@@U99.8@@R776.2.1" "CRESCENT_CITY_195_20150129_6PIN.@@U99.8.1")) ("idlNode_11" (terms "idlPart_8.1" "CRESCENT_CITY_195_20150129_6PIN.T@@RATS@@R776.1@@R3169.1.2" "CRESCENT_CITY_195_20150129_6PIN.T@@RATS@@R3169.1@@U97.12.1") (tee "CRESCENT_CITY_195_20150129_6PIN NET.T.1")) ("CRESCENT_CITY_195_20150129_6PIN.X1527500Y121000L28LRATS" (terms "CRESCENT_CITY_195_20150129_6PIN.T@@RATS@@R3169.2@@U101.8.2" "CRESCENT_CITY_195_20150129_6PIN.@@U101.8.1")) ("idlNode_6" (terms "idlPart_8.2" "CRESCENT_CITY_195_20150129_6PIN.@@R3169.1.2.1")) ("CRESCENT_CITY_195_20150129_6PIN.X1489500Y133500L2LRATS" (terms "CRESCENT_CITY_195_20150129_6PIN.@@R776.2.1.1" "CRESCENT_CITY_195_20150129_6PIN.T@@RATS@@U99.8@@R776.2.2")) ("CRESCENT_CITY_195_20150129_6PIN.X1717400Y87000L2LRATS" (terms "CRESCENT_CITY_195_20150129_6PIN.T@@RATS@@R3169.1@@U97.12.2" "CRESCENT_CITY_195_20150129_6PIN.@@U97.12.1")) ("CRESCENT_CITY_195_20150129_6PIN.X1527500Y132500L28LRATS" (terms "CRESCENT_CITY_195_20150129_6PIN.T@@RATS@@R3169.2@@U101.8.1" "CRESCENT_CITY_195_20150129_6PIN.@@R3169.1.2.2"))) (Ports) (Stimuli ("local42" (scope local) (stimType periodic) (Props (periodicFreq "5e+007") (periodicJitter "0") (periodicPattern "1"))) ("local46" (scope local) (stimType periodic) (Props (periodicFreq "5e+007") (periodicJitter "0") (periodicPattern "1"))) ("local48" (scope local) (stimType periodic) (Props (periodicFreq "5e+007") (periodicJitter "0") (periodicPattern "1"))) ("local45" (scope local) (stimType periodic) (Props (periodicFreq "5e+007") (periodicJitter "0") (periodicPattern "1"))) ("local41" (scope local) (stimType periodic) (Props (periodicFreq "5e+007") (periodicJitter "0") (periodicPattern "1"))) ("local47" (scope local) (stimType periodic) (Props (periodicFreq "5e+007") (periodicJitter "0") (periodicPattern "1")))) (Notes) (Constraints ("DELAY_RULE" ("CRESCENT_CITY_195_20150129_6PIN R7F4.1" "CRESCENT_CITY_195_20150129_6PIN NET.T.1" "LENGTH" "" "LENGTH" "0.00508") ("CRESCENT_CITY_195_20150129_6PIN R3T2.1" "CRESCENT_CITY_195_20150129_6PIN NET.T.1" "LENGTH" "" "LENGTH" "0.00508") ("CRESCENT_CITY_195_20150129_6PIN U7F1.8" "CRESCENT_CITY_195_20150129_6PIN R7F4.2" "LENGTH" "" "LENGTH" "0.1016") ("CRESCENT_CITY_195_20150129_6PIN U3T1.8" "CRESCENT_CITY_195_20150129_6PIN R3T2.2" "LENGTH" "" "LENGTH" "0.1016")) ("RATSNEST_SCHEDULE" "TEMPLATE") ("RELATIVE_PROPAGATION_DELAY" ("SPI_U7F1" "CRESCENT_CITY_195_20150129_6PIN U8F1.12" "CRESCENT_CITY_195_20150129_6PIN U7F1.8" "GLOBAL" "LENGTH" "0.00635" "LENGTH" "0") ("SPI_U3T1" "CRESCENT_CITY_195_20150129_6PIN U8F1.12" "CRESCENT_CITY_195_20150129_6PIN U3T1.8" "GLOBAL" "LENGTH" "0.00635" "DELAY" ""))) (MeasurementSets ("EMI" ("EMIStatus" status("on")) ("PeakEmission" status("on")) ("PeakFrequency" status("on")) ("PulseFreq" status("on")) ("RiseTime" status("on")) ("VoltageSwing" status("on"))) ("Reflection" ("BufferDelayFall" status("off")) ("BufferDelayRise" status("off")) ("EyeHeight" status("off")) ("EyeJitter" status("off")) ("EyeWidth" status("off")) ("FirstIncidentFall" status("off")) ("FirstIncidentRise" status("off")) ("Glitch" status("on")) ("GlitchFall" status("off")) ("GlitchRise" status("off")) ("Monotonic" status("on")) ("MonotonicFall" status("off")) ("MonotonicRise" status("off")) ("NoiseMargin" status("on")) ("NoiseMarginHigh" status("off")) ("NoiseMarginLow" status("off")) ("OvershootHigh" status("on")) ("OvershootLow" status("on")) ("PropDelay" status("on")) ("SettleDelay" status("on")) ("SettleDelayFall" status("off")) ("SettleDelayRise" status("off")) ("SwitchDelay" status("on")) ("SwitchDelayFall" status("off")) ("SwitchDelayRise" status("off"))) ("Crosstalk" ("Crosstalk" status("on"))) ("Custom")) (VectorSets) (Props (XnetName "SPI_SWITCH_MISO") (allDrivers "active") (customSimType "Reflection") (ftsMode ("Typ")) (rcvrSelect "all") (tlineDelayMode "time") (userRevision "1.0")))) (Subckts) (CrossSections ("CRESCENT_CITY_195_20150129_6PIN" (Props (SXDesignName "CRESCENT_CITY_195_20150129_6PIN")) (Layers ("" (layerType "SURFACE") (material "AIR") (thickness "0 mil") (dielectricConstant "1.000000") (lossTangent "0") (etchFactor "0.000000") (elecCondVal "0 mho/cm") (thermCondVal "0 w/cm-degC")) ("" (layerType "DIELECTRIC") (material "CONFORMAL_COAT") (thickness "0.5 mil") (dielectricConstant "3.800000") (lossTangent "0.035") (etchFactor "0.000000") (elecCondVal "0 mho/cm") (thermCondVal "0.012 w/cm-degC")) ("TOP" (layerType "CONDUCTOR") (material "COPPER") (thickness "  2.100000 mil") (width "4.00 MIL") (dielectricConstant "4.500000") (lossTangent "0") (etchFactor "70.000000") (elecCondVal "595900.000000 mho/cm") (thermCondVal "0 w/cm-degC") (signalDieConstant "3.800000") (signalLossTangent "0.035")) ("" (layerType "DIELECTRIC") (material "FR-4") (thickness "  2.670000 mil") (dielectricConstant "4.000000") (lossTangent "0.035") (etchFactor "0.000000") (elecCondVal "0 mho/cm") (thermCondVal "0.012 w/cm-degC")) ("L2_GND1" (layerType "PLANE") (material "COPPER") (isShield t) (thickness "  1.250000 mil") (dielectricConstant "4.500000") (lossTangent "0.035") (etchFactor "90.000000") (elecCondVal "595900.000000 mho/cm") (thermCondVal "0.012 w/cm-degC")) ("" (layerType "DIELECTRIC") (material "FR-4") (thickness "  9.000000 mil") (dielectricConstant "4.100000") (lossTangent "0.035") (etchFactor "0.000000") (elecCondVal "0 mho/cm") (thermCondVal "0.012 w/cm-degC")) ("L3_SIG1" (layerType "CONDUCTOR") (material "COPPER") (thickness "  1.250000 mil") (width "4.00 MIL") (dielectricConstant "4.500000") (lossTangent "0.035") (etchFactor "90.000000") (elecCondVal "595900.000000 mho/cm") (thermCondVal "0.012 w/cm-degC") (signalDieConstant "4.100000") (signalLossTangent "0.035")) ("" (layerType "DIELECTRIC") (material "FR-4") (thickness "  3.000000 mil") (dielectricConstant "4.500000") (lossTangent "0.035") (etchFactor "0.000000") (elecCondVal "0 mho/cm") (thermCondVal "0 w/cm-degC")) ("L4_GND2" (layerType "PLANE") (material "COPPER") (isShield t) (thickness "  1.250000 mil") (dielectricConstant "4.500000") (lossTangent "0.035") (etchFactor "90.000000") (elecCondVal "595900.000000 mho/cm") (thermCondVal "0 w/cm-degC")) ("" (layerType "DIELECTRIC") (material "FR-4") (thickness "  9.000000 mil") (dielectricConstant "4.000000") (lossTangent "0.035") (etchFactor "0.000000") (elecCondVal "0 mho/cm") (thermCondVal "0.012 w/cm-degC")) ("L5_SIG2" (layerType "CONDUCTOR") (material "COPPER") (thickness "  1.250000 mil") (width "4.00 MIL") (dielectricConstant "4.500000") (lossTangent "0.035") (etchFactor "90.000000") (elecCondVal "595900.000000 mho/cm") (thermCondVal "0.012 w/cm-degC") (signalDieConstant "4.000000") (signalLossTangent "0.035")) ("" (layerType "DIELECTRIC") (material "FR-4") (thickness "  3.000000 mil") (dielectricConstant "4.500000") (lossTangent "0.035") (etchFactor "0.000000") (elecCondVal "0 mho/cm") (thermCondVal "0 w/cm-degC")) ("L6_GND3" (layerType "PLANE") (material "COPPER") (isShield t) (thickness "  1.250000 mil") (dielectricConstant "4.500000") (lossTangent "0.035") (etchFactor "90.000000") (elecCondVal "595900.000000 mho/cm") (thermCondVal "0 w/cm-degC")) ("" (layerType "DIELECTRIC") (material "FR-4") (thickness "  4.500000 mil") (dielectricConstant "4.100000") (lossTangent "0.035") (etchFactor "0.000000") (elecCondVal "0 mho/cm") (thermCondVal "0.012 w/cm-degC")) ("L7_PWR1-SIG" (layerType "PLANE") (material "COPPER") (isShield t) (thickness "  2.400000 mil") (dielectricConstant "4.500000") (lossTangent "0.035") (etchFactor "90.000000") (elecCondVal "595900.000000 mho/cm") (thermCondVal "0.012 w/cm-degC")) ("" (layerType "DIELECTRIC") (material "FR-4") (thickness "  4.600000 mil") (dielectricConstant "4.000000") (lossTangent "0.035") (etchFactor "0.000000") (elecCondVal "0 mho/cm") (thermCondVal "0.012 w/cm-degC")) ("L8_PWR2-SIG" (layerType "PLANE") (material "COPPER") (isShield t) (thickness "  2.400000 mil") (dielectricConstant "4.500000") (lossTangent "0.035") (etchFactor "90.000000") (elecCondVal "595900.000000 mho/cm") (thermCondVal "0.012 w/cm-degC")) ("" (layerType "DIELECTRIC") (material "FR-4") (thickness "  4.500000 mil") (dielectricConstant "4.500000") (lossTangent "0.035") (etchFactor "0.000000") (elecCondVal "0 mho/cm") (thermCondVal "0 w/cm-degC")) ("L9_GND4" (layerType "PLANE") (material "COPPER") (isShield t) (thickness "  1.250000 mil") (dielectricConstant "4.500000") (lossTangent "0.035") (etchFactor "90.000000") (elecCondVal "595900.000000 mho/cm") (thermCondVal "0 w/cm-degC")) ("" (layerType "DIELECTRIC") (material "FR-4") (thickness "  3.000000 mil") (dielectricConstant "4.100000") (lossTangent "0.035") (etchFactor "0.000000") (elecCondVal "0 mho/cm") (thermCondVal "0.012 w/cm-degC")) ("L10_SIG3" (layerType "CONDUCTOR") (material "COPPER") (thickness "  1.250000 mil") (width "4.00 MIL") (dielectricConstant "4.500000") (lossTangent "0.035") (etchFactor "90.000000") (elecCondVal "595900.000000 mho/cm") (thermCondVal "0.012 w/cm-degC") (signalDieConstant "4.100000") (signalLossTangent "0.035")) ("" (layerType "DIELECTRIC") (material "FR-4") (thickness "  9.000000 mil") (dielectricConstant "4.500000") (lossTangent "0.035") (etchFactor "0.000000") (elecCondVal "0 mho/cm") (thermCondVal "0 w/cm-degC")) ("L11_GND5" (layerType "PLANE") (material "COPPER") (isShield t) (thickness "  1.250000 mil") (dielectricConstant "4.500000") (lossTangent "0.035") (etchFactor "90.000000") (elecCondVal "595900.000000 mho/cm") (thermCondVal "0 w/cm-degC")) ("" (layerType "DIELECTRIC") (material "FR-4") (thickness "  3.000000 mil") (dielectricConstant "4.500000") (lossTangent "0.035") (etchFactor "0.000000") (elecCondVal "0 mho/cm") (thermCondVal "0.012 w/cm-degC")) ("L12_SIG4" (layerType "CONDUCTOR") (material "COPPER") (thickness "  1.250000 mil") (width "4.00 MIL") (dielectricConstant "4.500000") (lossTangent "0.035") (etchFactor "90.000000") (elecCondVal "595900.000000 mho/cm") (thermCondVal "0.012 w/cm-degC") (signalDieConstant "4.500000") (signalLossTangent "0.035")) ("" (layerType "DIELECTRIC") (material "FR-4") (thickness "  9.000000 mil") (dielectricConstant "4.500000") (lossTangent "0.035") (etchFactor "0.000000") (elecCondVal "0 mho/cm") (thermCondVal "0 w/cm-degC")) ("L13_GND6" (layerType "PLANE") (material "COPPER") (isShield t) (thickness "  1.250000 mil") (dielectricConstant "4.500000") (lossTangent "0.035") (etchFactor "90.000000") (elecCondVal "595900.000000 mho/cm") (thermCondVal "0.012 w/cm-degC")) ("" (layerType "DIELECTRIC") (material "FR-4") (thickness "  2.670000 mil") (dielectricConstant "4.500000") (lossTangent "0.035") (etchFactor "0.000000") (elecCondVal "0 mho/cm") (thermCondVal "0.012 w/cm-degC")) ("BOTTOM" (layerType "CONDUCTOR") (material "COPPER") (thickness "  2.100000 mil") (width "4.00 MIL") (dielectricConstant "4.500000") (lossTangent "0") (etchFactor "70.000000") (elecCondVal "595900.000000 mho/cm") (thermCondVal "0 w/cm-degC") (signalDieConstant "3.800000") (signalLossTangent "0.035")) ("" (layerType "DIELECTRIC") (material "CONFORMAL_COAT") (thickness "0.5 mil") (dielectricConstant "3.800000") (lossTangent "0.035") (etchFactor "0.000000") (elecCondVal "0 mho/cm") (thermCondVal "0.012 w/cm-degC")) ("" (layerType "SURFACE") (material "AIR") (thickness "0 mil") (dielectricConstant "1.000000") (lossTangent "0") (etchFactor "0.000000") (elecCondVal "0 mho/cm") (thermCondVal "0 w/cm-degC"))))) (Props (DesUnits "mils 2") (LayerStack ("DIELECTRIC" "DIELECTRIC" "BOTTOM" "DIELECTRIC" "L13_GND6" "DIELECTRIC" "L12_SIG4" "DIELECTRIC" "L11_GND5" "DIELECTRIC" "L10_SIG3" "DIELECTRIC" "L9_GND4" "DIELECTRIC" "L8_PWR2-SIG" "DIELECTRIC" "L7_PWR1-SIG" "DIELECTRIC" "L6_GND3" "DIELECTRIC" "L5_SIG2" "DIELECTRIC" "L4_GND2" "DIELECTRIC" "L3_SIG1" "DIELECTRIC" "L2_GND1" "DIELECTRIC" "TOP" "DIELECTRIC" "DIELECTRIC")) (Revision "16.600")) (Params (DiffInputPkg ((temperature "27") (bufferModelNonInverting "CDSDefaultInput_2p5v") (bufferModelInverting "CDSDefaultInput_2p5v") (threshInputHighMin "1.7 V") (threshInputHighTyp "1.7  V") (threshInputHighMax "1.7  V") (threshInputLowMin "0.7  V") (threshInputLowTyp "0.7  V") (threshInputLowMax "0.7  V") (mappingTagNonInverting nil) (mappingTagInverting nil) (cycle "1"))) (IbisOutputPkg ((temperature "27") (bufferModel "CDSDefaultOutput_2p5v") (stimuli nil) (offsets nil) (state "tristate") (cycle "1") (termMap nil) (setup "2.0e-09") (hold "1.0e-09") (rise nil) (fall nil) (macroType nil) (voltage nil) (spice nil) (LEFDEFPinName nil) (LEFDEFPinType nil) (mappingTag nil))) (IbisIOPkg ((temperature "27") (bufferModel "CDSDefaultIO_2p5v") (stimuli nil) (offsets nil) (state "tristate") (cycle "1") (termMap nil) (setup "2.0e-09") (hold "1.0e-09") (rise nil) (fall nil) (macroType nil) (voltage nil) (spice nil) (LEFDEFPinName nil) (LEFDEFPinType nil) (mappingTag nil))) (IbisIOMacro ((temperature "27") (bufferModel "CDSDefaultIO_2p5v") (stimuli nil) (offsets nil) (state "tristate") (cycle "1") (termMap nil) (setup "2.0e-09") (hold "1.0e-09") (rise nil) (fall nil) (macroType nil) (voltage nil) (spice nil) (LEFDEFPinName nil) (LEFDEFPinType nil) (mappingTag nil))) (ESpiceDevice nil) (IbisInput ((temperature "27") (bufferModel "CDSDefaultInput_2p5v") (cycle "1") (LEFDEFPinName nil) (LEFDEFPinType nil) (mappingTag nil))) (ShuntTerm ((resistance "50 ohm") (voltage "5 V") (maxDelay "0.1 ns"))) (SeriesTerm ((resistance "22 ohm") (maxDelay "0.1 ns"))) (CurrentProbe nil) (idlCircuit ((allDrivers "active") (ftsMode '("Typ")) (rcvrSelect "all") (simMode "Reflection") (tlineDelayMode "time") (userRevision "1.0") (autoSolve "On"))) (TheveninTerm ((resistanceUp "180 ohm") (resistanceDown "270 ohm") (voltageUp "5 V") (voltageDown "0 V") (maxDelay "0.1 ns"))) (RCTerm ((resistance "50 ohm") (capacitance "20 pF") (voltage "5 V") (maxDelay "0.1 ns"))) (LowClampTerm ((cutoffVoltage "0.7 V") (voltage "0 V") (maxDelay "0.1 ns"))) (Cable (length("1 m"))) (HiClampTerm ((cutoffVoltage "0.7 V") (voltage "5 V") (maxDelay "0.1 ns"))) (DualClampTerm ((cutoffVoltageUp "0.7 V") (cutoffVoltageDown "0.7 V") (voltageUp "5 V") (voltageDown "0 V") (maxDelay "0.1 ns"))) (IbisInputPkg ((temperature "27") (bufferModel "CDSDefaultInput_2p5v") (cycle "1") (LEFDEFPinName nil) (LEFDEFPinType nil) (mappingTag nil))) (async ((asyncTimePoints "") (asyncInitState "1"))) (clocked ((clockRise "1e-09") (clockFall "1e-09") (clockFreq "100e6") (clockInitState "0") (clockDutyCycle "0.5") (clockJitter "0"))) (Diode ((cutoffVoltage "0.7 V"))) (IbisOutput ((temperature "27") (bufferModel "CDSDefaultOutput_2p5v") (stimuli nil) (offsets nil) (state "tristate") (cycle "1") (termMap nil) (setup "2.0e-09") (hold "1.0e-09") (rise nil) (fall nil) (macroType nil) (voltage nil) (spice nil) (LEFDEFPinName nil) (LEFDEFPinType nil) (mappingTag nil))) (periodic ((periodicFreq "100e6") (periodicPattern "10") (periodicJitter "0"))) (IbisIO ((temperature "27") (bufferModel "CDSDefaultIO_2p5v") (stimuli nil) (offsets nil) (state "tristate") (cycle "1") (termMap nil) (setup "2.0e-09") (hold "1.0e-09") (rise nil) (fall nil) (macroType nil) (voltage nil) (spice nil) (LEFDEFPinName nil) (LEFDEFPinType nil) (mappingTag nil))) (Via ((model "Unknown") (viaOutputFormat "Unknown") (viaPadstack nil) (viaTopLayer nil) (viaBottomLayer nil) (viaIsPower nil) (viaIsGround nil))) (CPWMS ((d1Thickness "10 mil") (d1Constant "4.5") (d1LossTangent "0.035") (d2Thickness "0.72 mil") (d2Constant "4.5") (d2LossTangent "0.035") (d3Thickness "0.0") (d3Constant "1") (d3LossTangent "0") length("1000 mil") (spacing "5 mil") (spacing2 "5 mil") (spacing3 "5 mil") (spacing4 "5 mil") (spacing5 "5 mil") (traceConductivity "595900 mho/cm") (traceGeometry "cpwms") (traceLayerName "") (traceThickness "0.72 mil") (traceType "single") (traceWidth "5.0 mil") (traceWidth2 "5.0 mil") (traceWidth3 "5.0 mil") (traceWidth4 "5.0 mil") (traceWidth5 "5.0 mil") (traceWidth6 "5.0 mil") (offset "0 mil") (traceCount "1") (impedance nil))) (Trace ((d1Thickness "10 mil") (d1Constant "4.5") (d1LossTangent "0.035") (d2Thickness "10 mil") (d2Constant "4.5") (d2LossTangent "0.035") (d3Thickness "0.0") (d3Constant "1.0") (d3LossTangent "0") length("1000 mil") (spacing "5 mil") (spacing2 "5 mil") (spacing3 "5 mil") (spacing4 "5 mil") (spacing5 "5 mil") (traceConductivity "595900 mho/cm") (traceGeometry "microstrip") (traceLayerName "") (traceThickness "0.72 mil") (traceType "single") (traceWidth "5.0 mil") (traceWidth2 "5.0 mil") (traceWidth3 "5.0 mil") (traceWidth4 "5.0 mil") (traceWidth5 "5.0 mil") (traceWidth6 "5.0 mil") (offset "0 mil") (traceCount "1") (impedance nil))) (Source ((voltage "5 V"))) (CPWSL ((d1Thickness "10 mil") (d1Constant "4.5") (d1LossTangent "0.035") (d2Thickness "0.72 mil") (d2Constant "4.5") (d2LossTangent "0.035") (d3Thickness "10 mil") (d3Constant "4.5") (d3LossTangent "0.035") length("1000 mil") (spacing "5 mil") (spacing2 "5 mil") (spacing3 "5 mil") (spacing4 "5 mil") (spacing5 "5 mil") (traceConductivity "595900 mho/cm") (traceGeometry "cpwms") (traceLayerName "") (traceThickness "0.72 mil") (traceType "single") (traceWidth "5.0 mil") (traceWidth2 "5.0 mil") (traceWidth3 "5.0 mil") (traceWidth4 "5.0 mil") (traceWidth5 "5.0 mil") (traceWidth6 "5.0 mil") (offset "0 mil") (traceCount "1") (impedance nil))) (RLGC (length("1000 mil"))) (Capacitor ((capacitance "10 pF") (orientation "0"))) (DiffIOPkg ((temperature "27") (bufferModelNonInverting "CDSDefaultIO_2p5v") (bufferModelInverting "CDSDefaultIO_2p5v") (stimuli nil) (offsets nil) (state "tristate") (cycle "1") (termMap nil) (setup "0.9e-09") (hold "0.4e-09") (rise nil) (fall nil) (threshInputHighMin "1.7 V") (threshInputHighTyp "1.7  V") (threshInputHighMax "1.7  V") (threshInputLowMin "0.7  V") (threshInputLowTyp "0.7  V") (threshInputLowMax "0.7 ") (threshOutputHighMin "2.365  V") (threshOutputHighTyp "2.5  V") (threshOutputHighMax "2.625  V") (threshOutputLowMin "1.275  V") (threshOutputLowTyp "1.7  V") (threshOutputLowMax "1.985  V") (mappingTagNonInverting nil) (mappingTagInverting nil) (spice nil))) (Inductor ((inductance "5 nH") (orientation "0"))) (DiffIO ((temperature "27") (bufferModelNonInverting "CDSDefaultIO_2p5v") (bufferModelInverting "CDSDefaultIO_2p5v") (stimuli nil) (offsets nil) (state "tristate") (cycle "1") (termMap nil) (setup "0.9e-09") (hold "0.4e-09") (rise nil) (fall nil) (threshInputHighMin "1.7 V") (threshInputHighTyp "1.7  V") (threshInputHighMax "1.7  V") (threshInputLowMin "0.7  V") (threshInputLowTyp "0.7  V") (threshInputLowMax "0.7 ") (threshOutputHighMin "2.365  V") (threshOutputHighTyp "2.5  V") (threshOutputHighMax "2.625  V") (threshOutputLowMin "1.275  V") (threshOutputLowTyp "1.7  V") (threshOutputLowMax "1.985  V") (mappingTagNonInverting nil) (mappingTagInverting nil) (spice nil))) (CPW ((d1Thickness "10 mil") (d1Constant "4.5") (d1LossTangent "0.035") (d2Thickness "0.72 mil") (d2Constant "1") (d2LossTangent "0") (d3Thickness "0.0") (d3Constant "1") (d3LossTangent "0") length("1000 mil") (spacing "5 mil") (spacing2 "5 mil") (spacing3 "5 mil") (spacing4 "5 mil") (spacing5 "5 mil") (traceConductivity "595900 mho/cm") (traceGeometry "cpwms") (traceLayerName "") (traceThickness "0.72 mil") (traceType "single") (traceWidth "5.0 mil") (traceWidth2 "5.0 mil") (traceWidth3 "5.0 mil") (traceWidth4 "5.0 mil") (traceWidth5 "5.0 mil") (traceWidth6 "5.0 mil") (offset "0 mil") (traceCount "1") (impedance nil))) (Connector nil) (TLine ((diffImpedance "100ohm") (diffVelocity "1.4142e+08M/s") (impedance "60ohm") length("2800 mil") (propDelay "0.5 ns") (velocity "5600 mil/ns") (traceCount "1") (traceGeometry "Microstrip") (impedanceMin nil) (impedanceMax nil) (lengthMin nil) (lengthMax nil) (propDelayMin nil) (propDelayMax nil) (impedanceSweepCount nil) (propDelaySweepCount nil) (velocitySweepCount nil) (lengthSweepCount nil) (matchSetName nil))) (sync ((syncFreq "100e6") (syncInitState "1") (syncPattern "10") (syncEdgeSwitch "rise"))) (IbisIO_OpenPullDown ((temperature "27") (bufferModel "CDSDefaultIO_2p5v") (stimuli nil) (offsets nil) (state "tristate") (cycle "1") (termMap nil) (setup "2.0e-09") (hold "1.0e-09") (rise nil) (fall nil) (macroType nil) (voltage nil) (spice nil) (LEFDEFPinName nil) (LEFDEFPinType nil) (mappingTag nil))) (DiffOutputPkg ((temperature "27") (bufferModelNonInverting "CDSDefaultOutput_2p5v") (bufferModelInverting "CDSDefaultOutput_2p5v") (stimuli nil) (offsets nil) (state "tristate") (cycle "1") (termMap nil) (setup "0.9e-09") (hold "0.4e-09") (rise nil) (fall nil) (threshOutputHighMin "2.375  V") (threshOutputHighTyp "2.5  V") (threshOutputHighMax "2.625  V") (threshOutputLowMin "1.275  V") (threshOutputLowTyp "1.7  V") (threshOutputLowMax "1.985  V") (mappingTagNonInverting nil) (mappingTagInverting nil) (spice nil))) (DiffInput ((temperature "27") (bufferModelNonInverting "CDSDefaultInput_2p5v") (bufferModelInverting "CDSDefaultInput_2p5v") (threshInputHighMin "1.7 V") (threshInputHighTyp "1.7  V") (threshInputHighMax "1.7  V") (threshInputLowMin "0.7  V") (threshInputLowTyp "0.7  V") (threshInputLowMax "0.7  V") (mappingTagNonInverting nil) (mappingTagInverting nil) (cycle "1"))) (Resistor ((resistance "50 ohm") (orientation "0"))) (DiffOutput ((temperature "27") (bufferModelNonInverting "CDSDefaultOutput_2p5v") (bufferModelInverting "CDSDefaultOutput_2p5v") (stimuli nil) (offsets nil) (state "tristate") (cycle "1") (termMap nil) (setup "0.9e-09") (hold "0.4e-09") (rise nil) (fall nil) (threshOutputHighMin "2.375  V") (threshOutputHighTyp "2.5  V") (threshOutputHighMax "2.625  V") (threshOutputLowMin "1.275  V") (threshOutputLowTyp "1.7  V") (threshOutputLowMax "1.985  V") (mappingTagNonInverting nil) (mappingTagInverting nil) (spice nil))) (IbisOutput_OpenPullUp ((temperature "27") (bufferModel "CDSDefaultOutput_2p5v") (stimuli nil) (offsets nil) (state "tristate") (cycle "1") (termMap nil) (setup "2.0e-09") (hold "1.0e-09") (rise nil) (fall nil) (macroType nil) (voltage nil) (spice nil) (LEFDEFPinName nil) (LEFDEFPinType nil) (mappingTag nil))) (IbisIO_OpenPullUp ((temperature "27") (bufferModel "CDSDefaultIO_2p5v") (stimuli nil) (offsets nil) (state "tristate") (cycle "1") (termMap nil) (setup "2.0e-09") (hold "1.0e-09") (rise nil) (fall nil) (macroType nil) (voltage nil) (spice nil) (LEFDEFPinName nil) (LEFDEFPinType nil) (mappingTag nil)))))
				)
				( objectStatus "SPI_SWITCH_MISO" )
			)
			( electricalCSet "@crescent_city_bb_fab1_lib.crescent_city_bb_fab1(sch_1):\SPI_SWITCH_CLK\"
				( groupRef "SPI_SWITCH_CLK:SPI_MUX-U7F1" )
				( groupRef "SPI_SWITCH_CLK:SPI_MUX-U3T1" )
				( pinPairRef "SPI_SWITCH_CLK:U8F1.4:U7F1.16" )
				( pinPairRef "SPI_SWITCH_CLK:U8F1.4:U3T1.16" )
				( pinPairRef "SPI_SWITCH_CLK:R8F7.2:U3T1.16" )
				( pinPairRef "SPI_SWITCH_CLK:R8F7.1:NET.T.1" )
				( pinPairRef "SPI_SWITCH_CLK:R8F8.1:NET.T.1" )
				( pinPairRef "SPI_SWITCH_CLK:U7F1.16:R8F8.2" )
				( attribute "RATSNEST_SCHEDULE" "TEMPLATE"
					( Status sLocked )
					( Origin gBackEnd )
				)
				( attribute "TOPOLOGY_TEMPLATE_REVISION" "1.0"
					( Origin gBackEnd )
				)
				( topologyData 28617
(SKIDL (Circuits ("MAIN" (Parts ("CRESCENT_CITY_902_20150507_Q.@@U7F1.16" IbisInputPkg (xy (5535 4214)) (refDes "U7F1") (model "Unknown") (Props (_SXDesignName "CRESCENT_CITY_902_20150507_Q") (brdx "15270.2 MIL") (brdy "841.5 MIL") (bufferModel "CDSDefaultInput_2p5v") (mappingTag "") (temperature "27")) (Terms ("CRESCENT_CITY_902_20150507_Q.X1527020Y84150L2LRATS" "16"))) ("CRESCENT_CITY_902_20150507_Q.@@U8F1.4" IbisIOPkg (xy (5502 4240)) (refDes "U8F1") (model "Unknown") (Props (_SXDesignName "CRESCENT_CITY_902_20150507_Q") (brdx "15580 MIL") (brdy "1545 MIL") (bufferModel "CDSDefaultIO_2p5v") (cycle "1") (hold "1.0e-09") (mappingTag "") (offsets ("5" "0") ("4" "0")) (setup "2.0e-09") (state "tristate") (stimuli ("5" "local44") ("4" "local43")) (temperature "27") (termMap ("4" "Data") ("5" "Enable"))) (Terms ("CRESCENT_CITY_902_20150507_Q.X1558000Y154500L2LRATS" "4"))) ("CRESCENT_CITY_902_20150507_Q.@@U3T1.16" IbisInputPkg (xy (5523 4222)) (refDes "U3T1") (model "Unknown") (Props (_SXDesignName "CRESCENT_CITY_902_20150507_Q") (brdx "14925 MIL") (brdy "834 MIL") (bufferModel "CDSDefaultInput_2p5v") (mappingTag "") (temperature "27")) (Terms ("CRESCENT_CITY_902_20150507_Q.X1492500Y83400L36LRATS" "16"))) ("CRESCENT_CITY_902_20150507_Q.T@@RATS@@U7F1.16@@R8F8.2" TLine (xy (5521 4214)) (mirror x) (refDes "TL30") (Props (_SXDesignName "CRESCENT_CITY_902_20150507_Q") (impedance "48.412 ohm") length("845.30 MIL") (propDelay "0.15182 ns") (traceCount "1") (traceGeometry "Microstrip") (velocity "5567.8 mil/ns")) (Terms ("CRESCENT_CITY_902_20150507_Q.X1527020Y84150L2LRATS" "1") ("CRESCENT_CITY_902_20150507_Q.X1548700Y147000L2LRATS" "2"))) ("CRESCENT_CITY_902_20150507_Q.@@R8F7.1.2" Resistor (xy (5506 4222)) (refDes "R8F7") (value "33.2 Ohm") (Props (_SXDesignName "CRESCENT_CITY_902_20150507_Q")) (Terms ("CRESCENT_CITY_902_20150507_Q.X1545100Y151800L2LRATS" "1") ("CRESCENT_CITY_902_20150507_Q.X1541600Y151800L2LRATS" "2"))) ("CRESCENT_CITY_902_20150507_Q.T@@RATSX1550600Y152267NetSPI_SWITCH_CLKT.1@@U8F1.4" TLine (xy (5497 4229)) (refDes "TL31") (Props (_SXDesignName "CRESCENT_CITY_902_20150507_Q") (impedance "48.412 ohm") length("96.33 MIL") (propDelay "0.0173 ns") (traceCount "1") (traceGeometry "Microstrip") (velocity "5568.19 mil/ns")) (Terms ("CRESCENT_CITY_902_20150507_Q.X1550600Y152267NetSPI_SWITCH_CLKT.1" "1") ("CRESCENT_CITY_902_20150507_Q.X1558000Y154500L2LRATS" "2"))) ("CRESCENT_CITY_902_20150507_Q.T@@RATS@@R8F7.2@@U3T1.16" TLine (xy (5515 4222)) (refDes "TL32") (Props (_SXDesignName "CRESCENT_CITY_902_20150507_Q") (impedance "48.412 ohm") length("1175.00 MIL") (propDelay "0.21104 ns") (traceCount "1") (traceGeometry "Microstrip") (velocity "5567.68 mil/ns")) (Terms ("CRESCENT_CITY_902_20150507_Q.X1541600Y151800L2LRATS" "1") ("CRESCENT_CITY_902_20150507_Q.X1492500Y83400L36LRATS" "2"))) ("CRESCENT_CITY_902_20150507_Q.@@R8F8.2.1" Resistor (xy (5506 4214)) (mirror x) (refDes "R8F8") (value "33.2 Ohm") (Props (_SXDesignName "CRESCENT_CITY_902_20150507_Q")) (Terms ("CRESCENT_CITY_902_20150507_Q.X1548700Y147000L2LRATS" "2") ("CRESCENT_CITY_902_20150507_Q.X1548700Y150500L2LRATS" "1"))) ("CRESCENT_CITY_902_20150507_Q.T@@RATSX1550600Y152267NetSPI_SWITCH_CLKT.1@@R8F8.1" TLine (xy (5497 4214)) (refDes "TL33") (Props (_SXDesignName "CRESCENT_CITY_902_20150507_Q") (impedance "48.412 ohm") length("36.67 MIL") (propDelay "0.00659 ns") (traceCount "1") (traceGeometry "Microstrip") (velocity "5564.49 mil/ns")) (Terms ("CRESCENT_CITY_902_20150507_Q.X1550600Y152267NetSPI_SWITCH_CLKT.1" "1") ("CRESCENT_CITY_902_20150507_Q.X1548700Y150500L2LRATS" "2"))) ("CRESCENT_CITY_902_20150507_Q.T@@RATSX1550600Y152267NetSPI_SWITCH_CLKT.1@@R8F7.1" TLine (xy (5497 4222)) (refDes "TL34") (Props (_SXDesignName "CRESCENT_CITY_902_20150507_Q") (impedance "48.412 ohm") length("59.67 MIL") (propDelay "0.01072 ns") (traceCount "1") (traceGeometry "Microstrip") (velocity "5566.22 mil/ns")) (Terms ("CRESCENT_CITY_902_20150507_Q.X1550600Y152267NetSPI_SWITCH_CLKT.1" "1") ("CRESCENT_CITY_902_20150507_Q.X1545100Y151800L2LRATS" "2")))) (Nodes ("CRESCENT_CITY_902_20150507_Q.X1527020Y84150L2LRATS" (terms "CRESCENT_CITY_902_20150507_Q.T@@RATS@@U7F1.16@@R8F8.2.1" "CRESCENT_CITY_902_20150507_Q.@@U7F1.16.1")) ("CRESCENT_CITY_902_20150507_Q.X1558000Y154500L2LRATS" (terms "CRESCENT_CITY_902_20150507_Q.T@@RATSX1550600Y152267NetSPI_SWITCH_CLKT.1@@U8F1.4.2" "CRESCENT_CITY_902_20150507_Q.@@U8F1.4.1")) ("CRESCENT_CITY_902_20150507_Q.X1545100Y151800L2LRATS" (terms "CRESCENT_CITY_902_20150507_Q.T@@RATSX1550600Y152267NetSPI_SWITCH_CLKT.1@@R8F7.1.2" "CRESCENT_CITY_902_20150507_Q.@@R8F7.1.2.1")) ("CRESCENT_CITY_902_20150507_Q.X1548700Y147000L2LRATS" (terms "CRESCENT_CITY_902_20150507_Q.@@R8F8.2.1.1" "CRESCENT_CITY_902_20150507_Q.T@@RATS@@U7F1.16@@R8F8.2.2")) ("CRESCENT_CITY_902_20150507_Q.X1541600Y151800L2LRATS" (terms "CRESCENT_CITY_902_20150507_Q.T@@RATS@@R8F7.2@@U3T1.16.1" "CRESCENT_CITY_902_20150507_Q.@@R8F7.1.2.2")) ("CRESCENT_CITY_902_20150507_Q.X1492500Y83400L36LRATS" (terms "CRESCENT_CITY_902_20150507_Q.T@@RATS@@R8F7.2@@U3T1.16.2" "CRESCENT_CITY_902_20150507_Q.@@U3T1.16.1")) ("CRESCENT_CITY_902_20150507_Q.X1548700Y150500L2LRATS" (terms "CRESCENT_CITY_902_20150507_Q.T@@RATSX1550600Y152267NetSPI_SWITCH_CLKT.1@@R8F8.1.2" "CRESCENT_CITY_902_20150507_Q.@@R8F8.2.1.2")) ("CRESCENT_CITY_902_20150507_Q.X1550600Y152267NetSPI_SWITCH_CLKT.1" (terms "CRESCENT_CITY_902_20150507_Q.T@@RATSX1550600Y152267NetSPI_SWITCH_CLKT.1@@R8F7.1.1" "CRESCENT_CITY_902_20150507_Q.T@@RATSX1550600Y152267NetSPI_SWITCH_CLKT.1@@R8F8.1.1" "CRESCENT_CITY_902_20150507_Q.T@@RATSX1550600Y152267NetSPI_SWITCH_CLKT.1@@U8F1.4.1") (tee "CRESCENT_CITY_902_20150507_Q NET.T.1"))) (Ports) (Stimuli ("local40" (scope local) (stimType periodic) (Props (periodicFreq "5e+007") (periodicJitter "0") (periodicPattern "1"))) ("local39" (scope local) (stimType periodic) (Props (periodicFreq "5e+007") (periodicJitter "0") (periodicPattern "1"))) ("local43" (scope local) (stimType periodic) (Props (periodicFreq "5e+007") (periodicJitter "0") (periodicPattern "1"))) ("local44" (scope local) (stimType periodic) (Props (periodicFreq "5e+007") (periodicJitter "0") (periodicPattern "1")))) (Notes) (Constraints ("DELAY_RULE" ("CRESCENT_CITY_902_20150507_Q R8F7.2" "CRESCENT_CITY_902_20150507_Q U3T1.16" "LENGTH" "" "LENGTH" "0.1016") ("CRESCENT_CITY_902_20150507_Q R8F7.1" "CRESCENT_CITY_902_20150507_Q NET.T.1" "LENGTH" "" "LENGTH" "0.00508") ("CRESCENT_CITY_902_20150507_Q R8F8.1" "CRESCENT_CITY_902_20150507_Q NET.T.1" "LENGTH" "" "LENGTH" "0.00508") ("CRESCENT_CITY_902_20150507_Q U7F1.16" "CRESCENT_CITY_902_20150507_Q R8F8.2" "LENGTH" "" "LENGTH" "0.1016")) ("RATSNEST_SCHEDULE" "TEMPLATE") ("RELATIVE_PROPAGATION_DELAY" ("SPI_U7F1" "CRESCENT_CITY_902_20150507_Q U8F1.4" "CRESCENT_CITY_902_20150507_Q U7F1.16" "GLOBAL" "LENGTH" "0.00635" "LENGTH" "0") ("SPI_U3T1" "CRESCENT_CITY_902_20150507_Q U8F1.4" "CRESCENT_CITY_902_20150507_Q U3T1.16" "GLOBAL" "LENGTH" "0.00635" "LENGTH" "0"))) (MeasurementSets ("EMI" ("EMIStatus" status("on")) ("PeakEmission" status("on")) ("PeakFrequency" status("on")) ("PulseFreq" status("on")) ("RiseTime" status("on")) ("VoltageSwing" status("on"))) ("Reflection" ("BufferDelayFall" status("off")) ("BufferDelayRise" status("off")) ("EyeHeight" status("off")) ("EyeJitter" status("off")) ("EyeWidth" status("off")) ("FirstIncidentFall" status("off")) ("FirstIncidentRise" status("off")) ("Glitch" status("on")) ("GlitchFall" status("off")) ("GlitchRise" status("off")) ("Monotonic" status("on")) ("MonotonicFall" status("off")) ("MonotonicRise" status("off")) ("NoiseMargin" status("on")) ("NoiseMarginHigh" status("off")) ("NoiseMarginLow" status("off")) ("OvershootHigh" status("on")) ("OvershootLow" status("on")) ("PropDelay" status("on")) ("SettleDelay" status("on")) ("SettleDelayFall" status("off")) ("SettleDelayRise" status("off")) ("SwitchDelay" status("on")) ("SwitchDelayFall" status("off")) ("SwitchDelayRise" status("off"))) ("Crosstalk" ("Crosstalk" status("on"))) ("Custom")) (VectorSets) (Props (XnetName "SPI_SWITCH_CLK") (allDrivers "active") (customSimType "Reflection") (ftsMode ("Typ")) (rcvrSelect "all") (tlineDelayMode "time") (userRevision "1.0")))) (Subckts) (CrossSections ("CRESCENT_CITY_902_20150507_Q" (Props (SXDesignName "CRESCENT_CITY_902_20150507_Q")) (Layers ("" (layerType "SURFACE") (material "AIR") (thickness "0 mil") (dielectricConstant "1.000000") (lossTangent "0") (etchFactor "0.000000") (elecCondVal "0 mho/cm") (thermCondVal "0 w/cm-degC")) ("" (layerType "DIELECTRIC") (material "CONFORMAL_COAT") (thickness "0.5 mil") (dielectricConstant "3.800000") (lossTangent "0.035") (etchFactor "0.000000") (elecCondVal "0 mho/cm") (thermCondVal "0.012 w/cm-degC")) ("TOP" (layerType "CONDUCTOR") (material "COPPER") (thickness "  2.100000 mil") (width "4.00 MIL") (dielectricConstant "4.500000") (lossTangent "0") (etchFactor "70.000000") (elecCondVal "595900.000000 mho/cm") (thermCondVal "0 w/cm-degC") (signalDieConstant "3.800000") (signalLossTangent "0.035")) ("" (layerType "DIELECTRIC") (material "FR-4") (thickness "  2.670000 mil") (dielectricConstant "4.000000") (lossTangent "0.035") (etchFactor "0.000000") (elecCondVal "0 mho/cm") (thermCondVal "0.012 w/cm-degC")) ("L2_GND1" (layerType "PLANE") (material "COPPER") (isShield t) (thickness "  1.250000 mil") (dielectricConstant "4.500000") (lossTangent "0.035") (etchFactor "90.000000") (elecCondVal "595900.000000 mho/cm") (thermCondVal "0.012 w/cm-degC")) ("" (layerType "DIELECTRIC") (material "FR-4") (thickness "  9.000000 mil") (dielectricConstant "4.100000") (lossTangent "0.035") (etchFactor "0.000000") (elecCondVal "0 mho/cm") (thermCondVal "0.012 w/cm-degC")) ("L3_SIG1" (layerType "CONDUCTOR") (material "COPPER") (thickness "  1.250000 mil") (width "4.00 MIL") (dielectricConstant "4.500000") (lossTangent "0.035") (etchFactor "90.000000") (elecCondVal "595900.000000 mho/cm") (thermCondVal "0.012 w/cm-degC") (signalDieConstant "4.100000") (signalLossTangent "0.035")) ("" (layerType "DIELECTRIC") (material "FR-4") (thickness "  3.000000 mil") (dielectricConstant "4.500000") (lossTangent "0.035") (etchFactor "0.000000") (elecCondVal "0 mho/cm") (thermCondVal "0 w/cm-degC")) ("L4_GND2" (layerType "PLANE") (material "COPPER") (isShield t) (thickness "  1.250000 mil") (dielectricConstant "4.500000") (lossTangent "0.035") (etchFactor "90.000000") (elecCondVal "595900.000000 mho/cm") (thermCondVal "0 w/cm-degC")) ("" (layerType "DIELECTRIC") (material "FR-4") (thickness "  9.000000 mil") (dielectricConstant "4.000000") (lossTangent "0.035") (etchFactor "0.000000") (elecCondVal "0 mho/cm") (thermCondVal "0.012 w/cm-degC")) ("L5_SIG2" (layerType "CONDUCTOR") (material "COPPER") (thickness "  1.250000 mil") (width "4.00 MIL") (dielectricConstant "4.500000") (lossTangent "0.035") (etchFactor "90.000000") (elecCondVal "595900.000000 mho/cm") (thermCondVal "0.012 w/cm-degC") (signalDieConstant "4.000000") (signalLossTangent "0.035")) ("" (layerType "DIELECTRIC") (material "FR-4") (thickness "  3.000000 mil") (dielectricConstant "4.500000") (lossTangent "0.035") (etchFactor "0.000000") (elecCondVal "0 mho/cm") (thermCondVal "0 w/cm-degC")) ("L6_GND3" (layerType "PLANE") (material "COPPER") (isShield t) (thickness "  1.250000 mil") (dielectricConstant "4.500000") (lossTangent "0.035") (etchFactor "90.000000") (elecCondVal "595900.000000 mho/cm") (thermCondVal "0 w/cm-degC")) ("" (layerType "DIELECTRIC") (material "FR-4") (thickness "  4.500000 mil") (dielectricConstant "4.100000") (lossTangent "0.035") (etchFactor "0.000000") (elecCondVal "0 mho/cm") (thermCondVal "0.012 w/cm-degC")) ("L7_PWR1-SIG" (layerType "PLANE") (material "COPPER") (isShield t) (thickness "  2.610000 mil") (dielectricConstant "4.500000") (lossTangent "0.035") (etchFactor "90.000000") (elecCondVal "595900.000000 mho/cm") (thermCondVal "0.012 w/cm-degC")) ("" (layerType "DIELECTRIC") (material "FR-4") (thickness "  3.100000 mil") (dielectricConstant "4.500000") (lossTangent "0.035") (etchFactor "0.000000") (elecCondVal "0 mho/cm") (thermCondVal "0 w/cm-degC")) ("L8_GND_TEMP" (layerType "PLANE") (material "COPPER") (isShield t) (thickness "  1.250000 mil") (dielectricConstant "4.500000") (lossTangent "0.035") (etchFactor "90.000000") (elecCondVal "595900.000000 mho/cm") (thermCondVal "0 w/cm-degC")) ("" (layerType "DIELECTRIC") (material "FR-4") (thickness "  3.030000 mil") (dielectricConstant "4.500000") (lossTangent "0.035") (etchFactor "0.000000") (elecCondVal "0 mho/cm") (thermCondVal "0 w/cm-degC")) ("L9_SIG_TEMP" (layerType "CONDUCTOR") (material "COPPER") (thickness "  1.250000 mil") (width "3.52 MIL") (dielectricConstant "4.500000") (lossTangent "0.035") (etchFactor "90.000000") (elecCondVal "595900.000000 mho/cm") (thermCondVal "0 w/cm-degC") (signalDieConstant "4.500000") (signalLossTangent "0.035")) ("" (layerType "DIELECTRIC") (material "FR-4") (thickness "  5.000000 mil") (dielectricConstant "4.500000") (lossTangent "0.035") (etchFactor "0.000000") (elecCondVal "0 mho/cm") (thermCondVal "0 w/cm-degC")) ("L10_SIG_TEMP" (layerType "CONDUCTOR") (material "COPPER") (thickness "  1.250000 mil") (width "3.52 MIL") (dielectricConstant "4.500000") (lossTangent "0.035") (etchFactor "90.000000") (elecCondVal "595900.000000 mho/cm") (thermCondVal "0 w/cm-degC") (signalDieConstant "4.500000") (signalLossTangent "0.035")) ("" (layerType "DIELECTRIC") (material "FR-4") (thickness "  3.030000 mil") (dielectricConstant "4.500000") (lossTangent "0.035") (etchFactor "0.000000") (elecCondVal "0 mho/cm") (thermCondVal "0 w/cm-degC")) ("L11_GND_TEMP" (layerType "PLANE") (material "COPPER") (isShield t) (thickness "  1.250000 mil") (dielectricConstant "4.500000") (lossTangent "0.035") (etchFactor "90.000000") (elecCondVal "595900.000000 mho/cm") (thermCondVal "0 w/cm-degC")) ("" (layerType "DIELECTRIC") (material "FR-4") (thickness "  3.100000 mil") (dielectricConstant "4.000000") (lossTangent "0.035") (etchFactor "0.000000") (elecCondVal "0 mho/cm") (thermCondVal "0.012 w/cm-degC")) ("L12_PWR2-SIG" (layerType "PLANE") (material "COPPER") (isShield t) (thickness "  2.610000 mil") (dielectricConstant "4.500000") (lossTangent "0.035") (etchFactor "90.000000") (elecCondVal "595900.000000 mho/cm") (thermCondVal "0.012 w/cm-degC")) ("" (layerType "DIELECTRIC") (material "FR-4") (thickness "  4.500000 mil") (dielectricConstant "4.500000") (lossTangent "0.035") (etchFactor "0.000000") (elecCondVal "0 mho/cm") (thermCondVal "0 w/cm-degC")) ("L13_GND4" (layerType "PLANE") (material "COPPER") (isShield t) (thickness "  1.250000 mil") (dielectricConstant "4.500000") (lossTangent "0.035") (etchFactor "90.000000") (elecCondVal "595900.000000 mho/cm") (thermCondVal "0 w/cm-degC")) ("" (layerType "DIELECTRIC") (material "FR-4") (thickness "  3.000000 mil") (dielectricConstant "4.100000") (lossTangent "0.035") (etchFactor "0.000000") (elecCondVal "0 mho/cm") (thermCondVal "0.012 w/cm-degC")) ("L14_SIG3" (layerType "CONDUCTOR") (material "COPPER") (thickness "  1.250000 mil") (width "4.00 MIL") (dielectricConstant "4.500000") (lossTangent "0.035") (etchFactor "90.000000") (elecCondVal "595900.000000 mho/cm") (thermCondVal "0.012 w/cm-degC") (signalDieConstant "4.100000") (signalLossTangent "0.035")) ("" (layerType "DIELECTRIC") (material "FR-4") (thickness "  9.000000 mil") (dielectricConstant "4.500000") (lossTangent "0.035") (etchFactor "0.000000") (elecCondVal "0 mho/cm") (thermCondVal "0 w/cm-degC")) ("L15_GND5" (layerType "PLANE") (material "COPPER") (isShield t) (thickness "  1.250000 mil") (dielectricConstant "4.500000") (lossTangent "0.035") (etchFactor "90.000000") (elecCondVal "595900.000000 mho/cm") (thermCondVal "0 w/cm-degC")) ("" (layerType "DIELECTRIC") (material "FR-4") (thickness "  3.000000 mil") (dielectricConstant "4.500000") (lossTangent "0.035") (etchFactor "0.000000") (elecCondVal "0 mho/cm") (thermCondVal "0.012 w/cm-degC")) ("L16_SIG4" (layerType "CONDUCTOR") (material "COPPER") (thickness "  1.250000 mil") (width "4.00 MIL") (dielectricConstant "4.500000") (lossTangent "0.035") (etchFactor "90.000000") (elecCondVal "595900.000000 mho/cm") (thermCondVal "0.012 w/cm-degC") (signalDieConstant "4.500000") (signalLossTangent "0.035")) ("" (layerType "DIELECTRIC") (material "FR-4") (thickness "  9.000000 mil") (dielectricConstant "4.500000") (lossTangent "0.035") (etchFactor "0.000000") (elecCondVal "0 mho/cm") (thermCondVal "0 w/cm-degC")) ("L17_GND6" (layerType "PLANE") (material "COPPER") (isShield t) (thickness "  1.250000 mil") (dielectricConstant "4.500000") (lossTangent "0.035") (etchFactor "90.000000") (elecCondVal "595900.000000 mho/cm") (thermCondVal "0.012 w/cm-degC")) ("" (layerType "DIELECTRIC") (material "FR-4") (thickness "  2.670000 mil") (dielectricConstant "4.500000") (lossTangent "0.035") (etchFactor "0.000000") (elecCondVal "0 mho/cm") (thermCondVal "0.012 w/cm-degC")) ("BOTTOM" (layerType "CONDUCTOR") (material "COPPER") (thickness "  2.100000 mil") (width "4.00 MIL") (dielectricConstant "4.500000") (lossTangent "0") (etchFactor "70.000000") (elecCondVal "595900.000000 mho/cm") (thermCondVal "0 w/cm-degC") (signalDieConstant "3.800000") (signalLossTangent "0.035")) ("" (layerType "DIELECTRIC") (material "CONFORMAL_COAT") (thickness "0.5 mil") (dielectricConstant "3.800000") (lossTangent "0.035") (etchFactor "0.000000") (elecCondVal "0 mho/cm") (thermCondVal "0.012 w/cm-degC")) ("" (layerType "SURFACE") (material "AIR") (thickness "0 mil") (dielectricConstant "1.000000") (lossTangent "0") (etchFactor "0.000000") (elecCondVal "0 mho/cm") (thermCondVal "0 w/cm-degC"))))) (Props (DesUnits "mils 2") (LayerStack ("DIELECTRIC" "DIELECTRIC" "BOTTOM" "DIELECTRIC" "L17_GND6" "DIELECTRIC" "L16_SIG4" "DIELECTRIC" "L15_GND5" "DIELECTRIC" "L14_SIG3" "DIELECTRIC" "L13_GND4" "DIELECTRIC" "L12_PWR2-SIG" "DIELECTRIC" "L11_GND_TEMP" "DIELECTRIC" "L10_SIG_TEMP" "DIELECTRIC" "L9_SIG_TEMP" "DIELECTRIC" "L8_GND_TEMP" "DIELECTRIC" "L7_PWR1-SIG" "DIELECTRIC" "L6_GND3" "DIELECTRIC" "L5_SIG2" "DIELECTRIC" "L4_GND2" "DIELECTRIC" "L3_SIG1" "DIELECTRIC" "L2_GND1" "DIELECTRIC" "TOP" "DIELECTRIC" "DIELECTRIC")) (Revision "16.600")) (Params (DiffInputPkg ((temperature "27") (bufferModelNonInverting "CDSDefaultInput_2p5v") (bufferModelInverting "CDSDefaultInput_2p5v") (threshInputHighMin "1.7 V") (threshInputHighTyp "1.7  V") (threshInputHighMax "1.7  V") (threshInputLowMin "0.7  V") (threshInputLowTyp "0.7  V") (threshInputLowMax "0.7  V") (mappingTagNonInverting nil) (mappingTagInverting nil) (cycle "1"))) (IbisOutputPkg ((temperature "27") (bufferModel "CDSDefaultOutput_2p5v") (stimuli nil) (offsets nil) (state "tristate") (cycle "1") (termMap nil) (setup "2.0e-09") (hold "1.0e-09") (rise nil) (fall nil) (macroType nil) (voltage nil) (spice nil) (LEFDEFPinName nil) (LEFDEFPinType nil) (mappingTag nil))) (IbisIOPkg ((temperature "27") (bufferModel "CDSDefaultIO_2p5v") (stimuli nil) (offsets nil) (state "tristate") (cycle "1") (termMap nil) (setup "2.0e-09") (hold "1.0e-09") (rise nil) (fall nil) (macroType nil) (voltage nil) (spice nil) (LEFDEFPinName nil) (LEFDEFPinType nil) (mappingTag nil))) (IbisIOMacro ((temperature "27") (bufferModel "CDSDefaultIO_2p5v") (stimuli nil) (offsets nil) (state "tristate") (cycle "1") (termMap nil) (setup "2.0e-09") (hold "1.0e-09") (rise nil) (fall nil) (macroType nil) (voltage nil) (spice nil) (LEFDEFPinName nil) (LEFDEFPinType nil) (mappingTag nil))) (ESpiceDevice nil) (IbisInput ((temperature "27") (bufferModel "CDSDefaultInput_2p5v") (cycle "1") (LEFDEFPinName nil) (LEFDEFPinType nil) (mappingTag nil))) (ShuntTerm ((resistance "50 ohm") (voltage "5 V") (maxDelay "0.1 ns"))) (SeriesTerm ((resistance "22 ohm") (maxDelay "0.1 ns"))) (CurrentProbe nil) (idlCircuit ((allDrivers "active") (ftsMode '("Typ")) (rcvrSelect "all") (simMode "Reflection") (tlineDelayMode "time") (userRevision "1.0") (autoSolve "On"))) (TheveninTerm ((resistanceUp "180 ohm") (resistanceDown "270 ohm") (voltageUp "5 V") (voltageDown "0 V") (maxDelay "0.1 ns"))) (RCTerm ((resistance "50 ohm") (capacitance "20 pF") (voltage "5 V") (maxDelay "0.1 ns"))) (LowClampTerm ((cutoffVoltage "0.7 V") (voltage "0 V") (maxDelay "0.1 ns"))) (Cable (length("1 m"))) (HiClampTerm ((cutoffVoltage "0.7 V") (voltage "5 V") (maxDelay "0.1 ns"))) (DualClampTerm ((cutoffVoltageUp "0.7 V") (cutoffVoltageDown "0.7 V") (voltageUp "5 V") (voltageDown "0 V") (maxDelay "0.1 ns"))) (IbisInputPkg ((temperature "27") (bufferModel "CDSDefaultInput_2p5v") (cycle "1") (LEFDEFPinName nil) (LEFDEFPinType nil) (mappingTag nil))) (async ((asyncTimePoints "") (asyncInitState "1"))) (clocked ((clockRise "1e-09") (clockFall "1e-09") (clockFreq "100e6") (clockInitState "0") (clockDutyCycle "0.5") (clockJitter "0"))) (Diode ((cutoffVoltage "0.7 V"))) (IbisOutput ((temperature "27") (bufferModel "CDSDefaultOutput_2p5v") (stimuli nil) (offsets nil) (state "tristate") (cycle "1") (termMap nil) (setup "2.0e-09") (hold "1.0e-09") (rise nil) (fall nil) (macroType nil) (voltage nil) (spice nil) (LEFDEFPinName nil) (LEFDEFPinType nil) (mappingTag nil))) (periodic ((periodicFreq "100e6") (periodicPattern "10") (periodicJitter "0"))) (IbisIO ((temperature "27") (bufferModel "CDSDefaultIO_2p5v") (stimuli nil) (offsets nil) (state "tristate") (cycle "1") (termMap nil) (setup "2.0e-09") (hold "1.0e-09") (rise nil) (fall nil) (macroType nil) (voltage nil) (spice nil) (LEFDEFPinName nil) (LEFDEFPinType nil) (mappingTag nil))) (Via ((model "Unknown") (viaOutputFormat "Unknown") (viaPadstack nil) (viaTopLayer nil) (viaBottomLayer nil) (viaIsPower nil) (viaIsGround nil))) (CPWMS ((d1Thickness "10 mil") (d1Constant "4.5") (d1LossTangent "0.035") (d2Thickness "0.72 mil") (d2Constant "4.5") (d2LossTangent "0.035") (d3Thickness "0.0") (d3Constant "1") (d3LossTangent "0") length("1000 mil") (spacing "5 mil") (spacing2 "5 mil") (spacing3 "5 mil") (spacing4 "5 mil") (spacing5 "5 mil") (traceConductivity "595900 mho/cm") (traceGeometry "cpwms") (traceLayerName "") (traceThickness "0.72 mil") (traceType "single") (traceWidth "5.0 mil") (traceWidth2 "5.0 mil") (traceWidth3 "5.0 mil") (traceWidth4 "5.0 mil") (traceWidth5 "5.0 mil") (traceWidth6 "5.0 mil") (offset "0 mil") (traceCount "1") (impedance nil))) (Trace ((d1Thickness "10 mil") (d1Constant "4.5") (d1LossTangent "0.035") (d2Thickness "10 mil") (d2Constant "4.5") (d2LossTangent "0.035") (d3Thickness "0.0") (d3Constant "1.0") (d3LossTangent "0") length("1000 mil") (spacing "5 mil") (spacing2 "5 mil") (spacing3 "5 mil") (spacing4 "5 mil") (spacing5 "5 mil") (traceConductivity "595900 mho/cm") (traceGeometry "microstrip") (traceLayerName "") (traceThickness "0.72 mil") (traceType "single") (traceWidth "5.0 mil") (traceWidth2 "5.0 mil") (traceWidth3 "5.0 mil") (traceWidth4 "5.0 mil") (traceWidth5 "5.0 mil") (traceWidth6 "5.0 mil") (offset "0 mil") (traceCount "1") (impedance nil))) (Source ((voltage "5 V"))) (CPWSL ((d1Thickness "10 mil") (d1Constant "4.5") (d1LossTangent "0.035") (d2Thickness "0.72 mil") (d2Constant "4.5") (d2LossTangent "0.035") (d3Thickness "10 mil") (d3Constant "4.5") (d3LossTangent "0.035") length("1000 mil") (spacing "5 mil") (spacing2 "5 mil") (spacing3 "5 mil") (spacing4 "5 mil") (spacing5 "5 mil") (traceConductivity "595900 mho/cm") (traceGeometry "cpwms") (traceLayerName "") (traceThickness "0.72 mil") (traceType "single") (traceWidth "5.0 mil") (traceWidth2 "5.0 mil") (traceWidth3 "5.0 mil") (traceWidth4 "5.0 mil") (traceWidth5 "5.0 mil") (traceWidth6 "5.0 mil") (offset "0 mil") (traceCount "1") (impedance nil))) (RLGC (length("1000 mil"))) (Capacitor ((capacitance "10 pF") (orientation "0"))) (DiffIOPkg ((temperature "27") (bufferModelNonInverting "CDSDefaultIO_2p5v") (bufferModelInverting "CDSDefaultIO_2p5v") (stimuli nil) (offsets nil) (state "tristate") (cycle "1") (termMap nil) (setup "0.9e-09") (hold "0.4e-09") (rise nil) (fall nil) (threshInputHighMin "1.7 V") (threshInputHighTyp "1.7  V") (threshInputHighMax "1.7  V") (threshInputLowMin "0.7  V") (threshInputLowTyp "0.7  V") (threshInputLowMax "0.7 ") (threshOutputHighMin "2.365  V") (threshOutputHighTyp "2.5  V") (threshOutputHighMax "2.625  V") (threshOutputLowMin "1.275  V") (threshOutputLowTyp "1.7  V") (threshOutputLowMax "1.985  V") (mappingTagNonInverting nil) (mappingTagInverting nil) (spice nil))) (Inductor ((inductance "5 nH") (orientation "0"))) (DiffIO ((temperature "27") (bufferModelNonInverting "CDSDefaultIO_2p5v") (bufferModelInverting "CDSDefaultIO_2p5v") (stimuli nil) (offsets nil) (state "tristate") (cycle "1") (termMap nil) (setup "0.9e-09") (hold "0.4e-09") (rise nil) (fall nil) (threshInputHighMin "1.7 V") (threshInputHighTyp "1.7  V") (threshInputHighMax "1.7  V") (threshInputLowMin "0.7  V") (threshInputLowTyp "0.7  V") (threshInputLowMax "0.7 ") (threshOutputHighMin "2.365  V") (threshOutputHighTyp "2.5  V") (threshOutputHighMax "2.625  V") (threshOutputLowMin "1.275  V") (threshOutputLowTyp "1.7  V") (threshOutputLowMax "1.985  V") (mappingTagNonInverting nil) (mappingTagInverting nil) (spice nil))) (CPW ((d1Thickness "10 mil") (d1Constant "4.5") (d1LossTangent "0.035") (d2Thickness "0.72 mil") (d2Constant "1") (d2LossTangent "0") (d3Thickness "0.0") (d3Constant "1") (d3LossTangent "0") length("1000 mil") (spacing "5 mil") (spacing2 "5 mil") (spacing3 "5 mil") (spacing4 "5 mil") (spacing5 "5 mil") (traceConductivity "595900 mho/cm") (traceGeometry "cpwms") (traceLayerName "") (traceThickness "0.72 mil") (traceType "single") (traceWidth "5.0 mil") (traceWidth2 "5.0 mil") (traceWidth3 "5.0 mil") (traceWidth4 "5.0 mil") (traceWidth5 "5.0 mil") (traceWidth6 "5.0 mil") (offset "0 mil") (traceCount "1") (impedance nil))) (Connector nil) (TLine ((diffImpedance "100ohm") (diffVelocity "1.4142e+08M/s") (impedance "60ohm") length("2800 mil") (propDelay "0.5 ns") (velocity "5600 mil/ns") (traceCount "1") (traceGeometry "Microstrip") (impedanceMin nil) (impedanceMax nil) (lengthMin nil) (lengthMax nil) (propDelayMin nil) (propDelayMax nil) (impedanceSweepCount nil) (propDelaySweepCount nil) (velocitySweepCount nil) (lengthSweepCount nil) (matchSetName nil))) (sync ((syncFreq "100e6") (syncInitState "1") (syncPattern "10") (syncEdgeSwitch "rise"))) (IbisIO_OpenPullDown ((temperature "27") (bufferModel "CDSDefaultIO_2p5v") (stimuli nil) (offsets nil) (state "tristate") (cycle "1") (termMap nil) (setup "2.0e-09") (hold "1.0e-09") (rise nil) (fall nil) (macroType nil) (voltage nil) (spice nil) (LEFDEFPinName nil) (LEFDEFPinType nil) (mappingTag nil))) (DiffOutputPkg ((temperature "27") (bufferModelNonInverting "CDSDefaultOutput_2p5v") (bufferModelInverting "CDSDefaultOutput_2p5v") (stimuli nil) (offsets nil) (state "tristate") (cycle "1") (termMap nil) (setup "0.9e-09") (hold "0.4e-09") (rise nil) (fall nil) (threshOutputHighMin "2.375  V") (threshOutputHighTyp "2.5  V") (threshOutputHighMax "2.625  V") (threshOutputLowMin "1.275  V") (threshOutputLowTyp "1.7  V") (threshOutputLowMax "1.985  V") (mappingTagNonInverting nil) (mappingTagInverting nil) (spice nil))) (DiffInput ((temperature "27") (bufferModelNonInverting "CDSDefaultInput_2p5v") (bufferModelInverting "CDSDefaultInput_2p5v") (threshInputHighMin "1.7 V") (threshInputHighTyp "1.7  V") (threshInputHighMax "1.7  V") (threshInputLowMin "0.7  V") (threshInputLowTyp "0.7  V") (threshInputLowMax "0.7  V") (mappingTagNonInverting nil) (mappingTagInverting nil) (cycle "1"))) (Resistor ((resistance "50 ohm") (orientation "0"))) (DiffOutput ((temperature "27") (bufferModelNonInverting "CDSDefaultOutput_2p5v") (bufferModelInverting "CDSDefaultOutput_2p5v") (stimuli nil) (offsets nil) (state "tristate") (cycle "1") (termMap nil) (setup "0.9e-09") (hold "0.4e-09") (rise nil) (fall nil) (threshOutputHighMin "2.375  V") (threshOutputHighTyp "2.5  V") (threshOutputHighMax "2.625  V") (threshOutputLowMin "1.275  V") (threshOutputLowTyp "1.7  V") (threshOutputLowMax "1.985  V") (mappingTagNonInverting nil) (mappingTagInverting nil) (spice nil))) (IbisOutput_OpenPullUp ((temperature "27") (bufferModel "CDSDefaultOutput_2p5v") (stimuli nil) (offsets nil) (state "tristate") (cycle "1") (termMap nil) (setup "2.0e-09") (hold "1.0e-09") (rise nil) (fall nil) (macroType nil) (voltage nil) (spice nil) (LEFDEFPinName nil) (LEFDEFPinType nil) (mappingTag nil))) (IbisIO_OpenPullUp ((temperature "27") (bufferModel "CDSDefaultIO_2p5v") (stimuli nil) (offsets nil) (state "tristate") (cycle "1") (termMap nil) (setup "2.0e-09") (hold "1.0e-09") (rise nil) (fall nil) (macroType nil) (voltage nil) (spice nil) (LEFDEFPinName nil) (LEFDEFPinType nil) (mappingTag nil)))))
				)
				( objectStatus "SPI_SWITCH_CLK" )
			)
			( electricalCSet "@crescent_city_bb_fab1_lib.crescent_city_bb_fab1(sch_1):\SPI_PCH_IO3\"
				( groupRef "SPI_SWITCH_IO3:SPI_MUX-U3T1" )
				( groupRef "SPI_SWITCH_IO3:SPI_MUX-U7F1" )
				( pinPairRef "SPI_SWITCH_IO3:U2T1.7:U3T1.1" )
				( pinPairRef "SPI_SWITCH_IO3:U2T1.7:U7F1.1" )
				( attribute "RATSNEST_SCHEDULE" "TEMPLATE"
					( Status sLocked )
					( Origin gBackEnd )
				)
				( attribute "TOPOLOGY_TEMPLATE_REVISION" "1.0"
					( Origin gBackEnd )
				)
				( topologyData 30315
(SKIDL (Circuits ("MAIN" (Parts ("CRESCENT_CITY_902_20150507_Q.@@U7F1.1" IbisIOPkg (xy (5507.0 4221.5)) (refDes "U7F1") (model "Unknown") (Props (_SXDesignName "CRESCENT_CITY_902_20150507_Q") (brdx "15270.2 MIL") (brdy "1217.5 MIL") (bufferModel "CDSDefaultIO_2p5v") (cycle "1") (hold "1.0e-09") (mappingTag "") (offsets ("4" "0") ("5" "0")) (setup "2.0e-09") (state "tristate") (stimuli ("5" "local10") ("4" "local9")) (temperature "27") (termMap ("4" "Data") ("5" "Enable"))) (Terms ("CRESCENT_CITY_902_20150507_Q.X1527020Y121750L2LRATS" "1"))) ("CRESCENT_CITY_902_20150507_Q.@@U2T1.7" IbisIOPkg (xy (5449.5 4233.0)) (refDes "U2T1") (model "Unknown") (Props (_SXDesignName "CRESCENT_CITY_902_20150507_Q") (brdx "15795 MIL") (brdy "1455 MIL") (bufferModel "CDSDefaultIO_2p5v") (cycle "1") (hold "1.0e-09") (mappingTag "") (offsets ("4" "0") ("5" "0")) (setup "2.0e-09") (state "tristate") (stimuli ("5" "local12") ("4" "local11")) (temperature "27") (termMap ("4" "Data") ("5" "Enable"))) (Terms ("CRESCENT_CITY_902_20150507_Q.X1579500Y145500L36LRATS" "7"))) ("CRESCENT_CITY_902_20150507_Q.@@U3T1.1" IbisIOPkg (xy (5507.0 4234.0)) (refDes "U3T1") (model "Unknown") (Props (_SXDesignName "CRESCENT_CITY_902_20150507_Q") (brdx "14925 MIL") (brdy "1210 MIL") (bufferModel "CDSDefaultIO_2p5v") (cycle "1") (hold "1.0e-09") (mappingTag "") (offsets ("4" "0") ("5" "0")) (setup "2.0e-09") (state "tristate") (stimuli ("5" "local14") ("4" "local13")) (temperature "27") (termMap ("4" "Data") ("5" "Enable"))) (Terms ("CRESCENT_CITY_902_20150507_Q.X1492500Y121000L36LRATS" "1"))) ("CRESCENT_CITY_902_20150507_Q.T@@RATS@@R3T1.2@@R3T4.2" TLine (xy (5488 4229)) (refDes "TL3") (Props (_SXDesignName "CRESCENT_CITY_902_20150507_Q") (impedance "46.577 ohm") length("40.00 MIL") (propDelay "0.00718 ns") (traceCount "1") (traceGeometry "Microstrip") (velocity "5571.02 mil/ns")) (Terms ("CRESCENT_CITY_902_20150507_Q.X1488500Y137000L36LRATS" "1") ("CRESCENT_CITY_902_20150507_Q.X1488500Y133000L36LRATS" "2"))) ("CRESCENT_CITY_902_20150507_Q.T@@RATS@@U7F1.1@@R7F3.2" TLine (xy (5496.5 4216.5)) (mirror x) (refDes "TL4") (Props (_SXDesignName "CRESCENT_CITY_902_20150507_Q") (impedance "48.412 ohm") length("117.30 MIL") (propDelay "0.02107 ns") (traceCount "1") (traceGeometry "Microstrip") (velocity "5567.17 mil/ns")) (Terms ("CRESCENT_CITY_902_20150507_Q.X1527020Y121750L2LRATS" "1") ("CRESCENT_CITY_902_20150507_Q.X1527500Y133000L2LRATS" "2"))) ("CRESCENT_CITY_902_20150507_Q.T@@RATS@@R7F3.2@@R8F15.2" TLine (xy (5496.5 4210.5)) (refDes "TL5") (Props (_SXDesignName "CRESCENT_CITY_902_20150507_Q") (impedance "48.412 ohm") length("40.00 MIL") (propDelay "0.00718 ns") (traceCount "1") (traceGeometry "Microstrip") (velocity "5571.02 mil/ns")) (Terms ("CRESCENT_CITY_902_20150507_Q.X1527500Y133000L2LRATS" "1") ("idlNode_53" "2"))) ("CRESCENT_CITY_902_20150507_Q.@@R3T4.1_SOURCE" Source (xy (5482.0 4236.0)) (refDes "P3V3_STBY_1") (value "3.3 V") (Props (_SXDesignName "CRESCENT_CITY_902_20150507_Q")) (Terms ("CRESCENT_CITY_902_20150507_Q.X1492000Y133000L36RATS" "1"))) ("CRESCENT_CITY_902_20150507_Q.@@R8F15.1_SOURCE" Source (xy (5512.0 4211.0)) (refDes "P3V3_STBY") (value "3.3 V") (Props (_SXDesignName "CRESCENT_CITY_902_20150507_Q")) (Terms ("idlNode_46" "1"))) ("CRESCENT_CITY_902_20150507_Q.T@@RATS@@R3T4.2@@U3T1.1" TLine (xy (5497 4229)) (refDes "TL6") (Props (_SXDesignName "CRESCENT_CITY_902_20150507_Q") (impedance "46.577 ohm") length("160.00 MIL") (propDelay "0.02874 ns") (traceCount "1") (traceGeometry "Microstrip") (velocity "5567.17 mil/ns")) (Terms ("CRESCENT_CITY_902_20150507_Q.X1488500Y133000L36LRATS" "1") ("CRESCENT_CITY_902_20150507_Q.X1492500Y121000L36LRATS" "2"))) ("CRESCENT_CITY_902_20150507_Q.@@R8F15.1.2" Resistor (xy (5505.0 4210.5)) (mirror x) (refDes "R7F32") (value "10000 Ohm") (Props (_SXDesignName "CRESCENT_CITY_902_20150507_Q")) (Terms ("idlNode_46" "1") ("idlNode_53" "2"))) ("CRESCENT_CITY_902_20150507_Q.T@@RATS@@R7F3.1@@R3T1.1" TLine (xy (5466.5 4228.0)) (refDes "TL7") (Props (_SXDesignName "CRESCENT_CITY_902_20150507_Q") (impedance "48.412 ohm") length("360.00 MIL") (propDelay "0.06466 ns") (traceCount "1") (traceGeometry "Microstrip") (velocity "5567.6 mil/ns")) (Terms ("CRESCENT_CITY_902_20150507_Q.X1527500Y136500L2LRATS" "1") ("CRESCENT_CITY_902_20150507_Q.X1492000Y137000L36LRATS" "2"))) ("CRESCENT_CITY_902_20150507_Q.@@R3T1.1.2" Resistor (xy (5475.0 4227.5)) (refDes "R3T1") (value "33.2 Ohm") (Props (_SXDesignName "CRESCENT_CITY_902_20150507_Q")) (Terms ("CRESCENT_CITY_902_20150507_Q.X1492000Y137000L36LRATS" "1") ("CRESCENT_CITY_902_20150507_Q.X1488500Y137000L36LRATS" "2"))) ("CRESCENT_CITY_902_20150507_Q.T@@RATS@@U2T1.7@@R7F3.1" TLine (xy (5456.5 4228.0)) (refDes "TL8") (Props (_SXDesignName "CRESCENT_CITY_902_20150507_Q") (impedance "48.412 ohm") length("610.00 MIL") (propDelay "0.10956 ns") (traceCount "1") (traceGeometry "Microstrip") (velocity "5567.72 mil/ns")) (Terms ("CRESCENT_CITY_902_20150507_Q.X1579500Y145500L36LRATS" "1") ("CRESCENT_CITY_902_20150507_Q.X1527500Y136500L2LRATS" "2"))) ("CRESCENT_CITY_902_20150507_Q.@@R7F3.1.2" Resistor (xy (5466.5 4216.5)) (refDes "R7F3") (value "33.2 Ohm") (Props (_SXDesignName "CRESCENT_CITY_902_20150507_Q")) (Terms ("CRESCENT_CITY_902_20150507_Q.X1527500Y136500L2LRATS" "1") ("CRESCENT_CITY_902_20150507_Q.X1527500Y133000L2LRATS" "2"))) ("CRESCENT_CITY_902_20150507_Q.@@R3T4.2.1" Resistor (xy (5490.0 4234.5)) (mirror x) (refDes "R3T4") (value "10000 Ohm") (Props (_SXDesignName "CRESCENT_CITY_902_20150507_Q")) (Terms ("CRESCENT_CITY_902_20150507_Q.X1488500Y133000L36LRATS" "2") ("CRESCENT_CITY_902_20150507_Q.X1492000Y133000L36RATS" "1")))) (Nodes ("CRESCENT_CITY_902_20150507_Q.X1488500Y137000L36LRATS" (terms "CRESCENT_CITY_902_20150507_Q.@@R3T1.1.2.2" "CRESCENT_CITY_902_20150507_Q.T@@RATS@@R3T1.2@@R3T4.2.1")) ("idlNode_53" (terms "CRESCENT_CITY_902_20150507_Q.@@R8F15.1.2.2" "CRESCENT_CITY_902_20150507_Q.T@@RATS@@R7F3.2@@R8F15.2.2")) ("CRESCENT_CITY_902_20150507_Q.X1492000Y133000L36RATS" (terms "CRESCENT_CITY_902_20150507_Q.@@R3T4.2.1.2" "CRESCENT_CITY_902_20150507_Q.@@R3T4.1_SOURCE.1")) ("CRESCENT_CITY_902_20150507_Q.X1527500Y133000L2LRATS" (terms "CRESCENT_CITY_902_20150507_Q.@@R7F3.1.2.2" "CRESCENT_CITY_902_20150507_Q.T@@RATS@@R7F3.2@@R8F15.2.1" "CRESCENT_CITY_902_20150507_Q.T@@RATS@@U7F1.1@@R7F3.2.2")) ("CRESCENT_CITY_902_20150507_Q.X1492000Y137000L36LRATS" (terms "CRESCENT_CITY_902_20150507_Q.@@R3T1.1.2.1" "CRESCENT_CITY_902_20150507_Q.T@@RATS@@R7F3.1@@R3T1.1.2")) ("CRESCENT_CITY_902_20150507_Q.X1579500Y145500L36LRATS" (terms "CRESCENT_CITY_902_20150507_Q.T@@RATS@@U2T1.7@@R7F3.1.1" "CRESCENT_CITY_902_20150507_Q.@@U2T1.7.1")) ("idlNode_46" (terms "CRESCENT_CITY_902_20150507_Q.@@R8F15.1.2.1" "CRESCENT_CITY_902_20150507_Q.@@R8F15.1_SOURCE.1")) ("CRESCENT_CITY_902_20150507_Q.X1488500Y133000L36LRATS" (terms "CRESCENT_CITY_902_20150507_Q.@@R3T4.2.1.1" "CRESCENT_CITY_902_20150507_Q.T@@RATS@@R3T4.2@@U3T1.1.1" "CRESCENT_CITY_902_20150507_Q.T@@RATS@@R3T1.2@@R3T4.2.2")) ("CRESCENT_CITY_902_20150507_Q.X1527020Y121750L2LRATS" (terms "CRESCENT_CITY_902_20150507_Q.T@@RATS@@U7F1.1@@R7F3.2.1" "CRESCENT_CITY_902_20150507_Q.@@U7F1.1.1")) ("CRESCENT_CITY_902_20150507_Q.X1492500Y121000L36LRATS" (terms "CRESCENT_CITY_902_20150507_Q.T@@RATS@@R3T4.2@@U3T1.1.2" "CRESCENT_CITY_902_20150507_Q.@@U3T1.1.1")) ("CRESCENT_CITY_902_20150507_Q.X1527500Y136500L2LRATS" (terms "CRESCENT_CITY_902_20150507_Q.@@R7F3.1.2.1" "CRESCENT_CITY_902_20150507_Q.T@@RATS@@U2T1.7@@R7F3.1.2" "CRESCENT_CITY_902_20150507_Q.T@@RATS@@R7F3.1@@R3T1.1.1"))) (Ports) (Stimuli ("local10" (scope local) (stimType periodic) (Props (periodicFreq "5e+007") (periodicJitter "0") (periodicPattern "1"))) ("local9" (scope local) (stimType periodic) (Props (periodicFreq "5e+007") (periodicJitter "0") (periodicPattern "1"))) ("local13" (scope local) (stimType periodic) (Props (periodicFreq "5e+007") (periodicJitter "0") (periodicPattern "1"))) ("local14" (scope local) (stimType periodic) (Props (periodicFreq "5e+007") (periodicJitter "0") (periodicPattern "1"))) ("local11" (scope local) (stimType periodic) (Props (periodicFreq "5e+007") (periodicJitter "0") (periodicPattern "1"))) ("local12" (scope local) (stimType periodic) (Props (periodicFreq "5e+007") (periodicJitter "0") (periodicPattern "1")))) (Notes) (Constraints ("RATSNEST_SCHEDULE" "TEMPLATE") ("RELATIVE_PROPAGATION_DELAY" ("SPI_U2T1-U3T1" "CRESCENT_CITY_902_20150507_Q U2T1.7" "CRESCENT_CITY_902_20150507_Q U3T1.1" "GLOBAL" "LENGTH" "0.00635" "LENGTH" "0") ("SPI_U2T1-U7F1" "CRESCENT_CITY_902_20150507_Q U2T1.7" "CRESCENT_CITY_902_20150507_Q U7F1.1" "GLOBAL" "LENGTH" "0.00635" "LENGTH" "0"))) (MeasurementSets ("EMI" ("EMIStatus" status("on")) ("PeakEmission" status("on")) ("PeakFrequency" status("on")) ("PulseFreq" status("on")) ("RiseTime" status("on")) ("VoltageSwing" status("on"))) ("Reflection" ("BufferDelayFall" status("off")) ("BufferDelayRise" status("off")) ("EyeHeight" status("off")) ("EyeJitter" status("off")) ("EyeWidth" status("off")) ("FirstIncidentFall" status("off")) ("FirstIncidentRise" status("off")) ("Glitch" status("on")) ("GlitchFall" status("off")) ("GlitchRise" status("off")) ("Monotonic" status("on")) ("MonotonicFall" status("off")) ("MonotonicRise" status("off")) ("NoiseMargin" status("on")) ("NoiseMarginHigh" status("off")) ("NoiseMarginLow" status("off")) ("OvershootHigh" status("on")) ("OvershootLow" status("on")) ("PropDelay" status("on")) ("SettleDelay" status("on")) ("SettleDelayFall" status("off")) ("SettleDelayRise" status("off")) ("SwitchDelay" status("on")) ("SwitchDelayFall" status("off")) ("SwitchDelayRise" status("off"))) ("Crosstalk" ("Crosstalk" status("on"))) ("Custom")) (VectorSets) (Props (XnetName "SPI_BIOS_SOCKET_IO3") (allDrivers "active") (autoSolve "Off") (customSimType "Reflection") (ftsMode ("Typ")) (rcvrSelect "all") (tlineDelayMode "time") (userRevision "1.0")))) (Subckts) (CrossSections ("CRESCENT_CITY_902_20150507_Q" (Props (SXDesignName "CRESCENT_CITY_902_20150507_Q")) (Layers ("" (layerType "SURFACE") (material "AIR") (thickness "0 mil") (dielectricConstant "1.000000") (lossTangent "0") (etchFactor "0.000000") (elecCondVal "0 mho/cm") (thermCondVal "0 w/cm-degC")) ("" (layerType "DIELECTRIC") (material "CONFORMAL_COAT") (thickness "0.5 mil") (dielectricConstant "3.800000") (lossTangent "0.035") (etchFactor "0.000000") (elecCondVal "0 mho/cm") (thermCondVal "0.012 w/cm-degC")) ("TOP" (layerType "CONDUCTOR") (material "COPPER") (thickness "  2.100000 mil") (width "4.00 MIL") (dielectricConstant "4.500000") (lossTangent "0") (etchFactor "70.000000") (elecCondVal "595900.000000 mho/cm") (thermCondVal "0 w/cm-degC") (signalDieConstant "3.800000") (signalLossTangent "0.035")) ("" (layerType "DIELECTRIC") (material "FR-4") (thickness "  2.670000 mil") (dielectricConstant "4.000000") (lossTangent "0.035") (etchFactor "0.000000") (elecCondVal "0 mho/cm") (thermCondVal "0.012 w/cm-degC")) ("L2_GND1" (layerType "PLANE") (material "COPPER") (isShield t) (thickness "  1.250000 mil") (dielectricConstant "4.500000") (lossTangent "0.035") (etchFactor "90.000000") (elecCondVal "595900.000000 mho/cm") (thermCondVal "0.012 w/cm-degC")) ("" (layerType "DIELECTRIC") (material "FR-4") (thickness "  9.000000 mil") (dielectricConstant "4.100000") (lossTangent "0.035") (etchFactor "0.000000") (elecCondVal "0 mho/cm") (thermCondVal "0.012 w/cm-degC")) ("L3_SIG1" (layerType "CONDUCTOR") (material "COPPER") (thickness "  1.250000 mil") (width "4.00 MIL") (dielectricConstant "4.500000") (lossTangent "0.035") (etchFactor "90.000000") (elecCondVal "595900.000000 mho/cm") (thermCondVal "0.012 w/cm-degC") (signalDieConstant "4.100000") (signalLossTangent "0.035")) ("" (layerType "DIELECTRIC") (material "FR-4") (thickness "  3.000000 mil") (dielectricConstant "4.500000") (lossTangent "0.035") (etchFactor "0.000000") (elecCondVal "0 mho/cm") (thermCondVal "0 w/cm-degC")) ("L4_GND2" (layerType "PLANE") (material "COPPER") (isShield t) (thickness "  1.250000 mil") (dielectricConstant "4.500000") (lossTangent "0.035") (etchFactor "90.000000") (elecCondVal "595900.000000 mho/cm") (thermCondVal "0 w/cm-degC")) ("" (layerType "DIELECTRIC") (material "FR-4") (thickness "  9.000000 mil") (dielectricConstant "4.000000") (lossTangent "0.035") (etchFactor "0.000000") (elecCondVal "0 mho/cm") (thermCondVal "0.012 w/cm-degC")) ("L5_SIG2" (layerType "CONDUCTOR") (material "COPPER") (thickness "  1.250000 mil") (width "4.00 MIL") (dielectricConstant "4.500000") (lossTangent "0.035") (etchFactor "90.000000") (elecCondVal "595900.000000 mho/cm") (thermCondVal "0.012 w/cm-degC") (signalDieConstant "4.000000") (signalLossTangent "0.035")) ("" (layerType "DIELECTRIC") (material "FR-4") (thickness "  3.000000 mil") (dielectricConstant "4.500000") (lossTangent "0.035") (etchFactor "0.000000") (elecCondVal "0 mho/cm") (thermCondVal "0 w/cm-degC")) ("L6_GND3" (layerType "PLANE") (material "COPPER") (isShield t) (thickness "  1.250000 mil") (dielectricConstant "4.500000") (lossTangent "0.035") (etchFactor "90.000000") (elecCondVal "595900.000000 mho/cm") (thermCondVal "0 w/cm-degC")) ("" (layerType "DIELECTRIC") (material "FR-4") (thickness "  4.500000 mil") (dielectricConstant "4.100000") (lossTangent "0.035") (etchFactor "0.000000") (elecCondVal "0 mho/cm") (thermCondVal "0.012 w/cm-degC")) ("L7_PWR1-SIG" (layerType "PLANE") (material "COPPER") (isShield t) (thickness "  2.610000 mil") (dielectricConstant "4.500000") (lossTangent "0.035") (etchFactor "90.000000") (elecCondVal "595900.000000 mho/cm") (thermCondVal "0.012 w/cm-degC")) ("" (layerType "DIELECTRIC") (material "FR-4") (thickness "  3.100000 mil") (dielectricConstant "4.500000") (lossTangent "0.035") (etchFactor "0.000000") (elecCondVal "0 mho/cm") (thermCondVal "0 w/cm-degC")) ("L8_GND_TEMP" (layerType "PLANE") (material "COPPER") (isShield t) (thickness "  1.250000 mil") (dielectricConstant "4.500000") (lossTangent "0.035") (etchFactor "90.000000") (elecCondVal "595900.000000 mho/cm") (thermCondVal "0 w/cm-degC")) ("" (layerType "DIELECTRIC") (material "FR-4") (thickness "  3.030000 mil") (dielectricConstant "4.500000") (lossTangent "0.035") (etchFactor "0.000000") (elecCondVal "0 mho/cm") (thermCondVal "0 w/cm-degC")) ("L9_SIG_TEMP" (layerType "CONDUCTOR") (material "COPPER") (thickness "  1.250000 mil") (width "3.52 MIL") (dielectricConstant "4.500000") (lossTangent "0.035") (etchFactor "90.000000") (elecCondVal "595900.000000 mho/cm") (thermCondVal "0 w/cm-degC") (signalDieConstant "4.500000") (signalLossTangent "0.035")) ("" (layerType "DIELECTRIC") (material "FR-4") (thickness "  5.000000 mil") (dielectricConstant "4.500000") (lossTangent "0.035") (etchFactor "0.000000") (elecCondVal "0 mho/cm") (thermCondVal "0 w/cm-degC")) ("L10_SIG_TEMP" (layerType "CONDUCTOR") (material "COPPER") (thickness "  1.250000 mil") (width "3.52 MIL") (dielectricConstant "4.500000") (lossTangent "0.035") (etchFactor "90.000000") (elecCondVal "595900.000000 mho/cm") (thermCondVal "0 w/cm-degC") (signalDieConstant "4.500000") (signalLossTangent "0.035")) ("" (layerType "DIELECTRIC") (material "FR-4") (thickness "  3.030000 mil") (dielectricConstant "4.500000") (lossTangent "0.035") (etchFactor "0.000000") (elecCondVal "0 mho/cm") (thermCondVal "0 w/cm-degC")) ("L11_GND_TEMP" (layerType "PLANE") (material "COPPER") (isShield t) (thickness "  1.250000 mil") (dielectricConstant "4.500000") (lossTangent "0.035") (etchFactor "90.000000") (elecCondVal "595900.000000 mho/cm") (thermCondVal "0 w/cm-degC")) ("" (layerType "DIELECTRIC") (material "FR-4") (thickness "  3.100000 mil") (dielectricConstant "4.000000") (lossTangent "0.035") (etchFactor "0.000000") (elecCondVal "0 mho/cm") (thermCondVal "0.012 w/cm-degC")) ("L12_PWR2-SIG" (layerType "PLANE") (material "COPPER") (isShield t) (thickness "  2.610000 mil") (dielectricConstant "4.500000") (lossTangent "0.035") (etchFactor "90.000000") (elecCondVal "595900.000000 mho/cm") (thermCondVal "0.012 w/cm-degC")) ("" (layerType "DIELECTRIC") (material "FR-4") (thickness "  4.500000 mil") (dielectricConstant "4.500000") (lossTangent "0.035") (etchFactor "0.000000") (elecCondVal "0 mho/cm") (thermCondVal "0 w/cm-degC")) ("L13_GND4" (layerType "PLANE") (material "COPPER") (isShield t) (thickness "  1.250000 mil") (dielectricConstant "4.500000") (lossTangent "0.035") (etchFactor "90.000000") (elecCondVal "595900.000000 mho/cm") (thermCondVal "0 w/cm-degC")) ("" (layerType "DIELECTRIC") (material "FR-4") (thickness "  3.000000 mil") (dielectricConstant "4.100000") (lossTangent "0.035") (etchFactor "0.000000") (elecCondVal "0 mho/cm") (thermCondVal "0.012 w/cm-degC")) ("L14_SIG3" (layerType "CONDUCTOR") (material "COPPER") (thickness "  1.250000 mil") (width "4.00 MIL") (dielectricConstant "4.500000") (lossTangent "0.035") (etchFactor "90.000000") (elecCondVal "595900.000000 mho/cm") (thermCondVal "0.012 w/cm-degC") (signalDieConstant "4.100000") (signalLossTangent "0.035")) ("" (layerType "DIELECTRIC") (material "FR-4") (thickness "  9.000000 mil") (dielectricConstant "4.500000") (lossTangent "0.035") (etchFactor "0.000000") (elecCondVal "0 mho/cm") (thermCondVal "0 w/cm-degC")) ("L15_GND5" (layerType "PLANE") (material "COPPER") (isShield t) (thickness "  1.250000 mil") (dielectricConstant "4.500000") (lossTangent "0.035") (etchFactor "90.000000") (elecCondVal "595900.000000 mho/cm") (thermCondVal "0 w/cm-degC")) ("" (layerType "DIELECTRIC") (material "FR-4") (thickness "  3.000000 mil") (dielectricConstant "4.500000") (lossTangent "0.035") (etchFactor "0.000000") (elecCondVal "0 mho/cm") (thermCondVal "0.012 w/cm-degC")) ("L16_SIG4" (layerType "CONDUCTOR") (material "COPPER") (thickness "  1.250000 mil") (width "4.00 MIL") (dielectricConstant "4.500000") (lossTangent "0.035") (etchFactor "90.000000") (elecCondVal "595900.000000 mho/cm") (thermCondVal "0.012 w/cm-degC") (signalDieConstant "4.500000") (signalLossTangent "0.035")) ("" (layerType "DIELECTRIC") (material "FR-4") (thickness "  9.000000 mil") (dielectricConstant "4.500000") (lossTangent "0.035") (etchFactor "0.000000") (elecCondVal "0 mho/cm") (thermCondVal "0 w/cm-degC")) ("L17_GND6" (layerType "PLANE") (material "COPPER") (isShield t) (thickness "  1.250000 mil") (dielectricConstant "4.500000") (lossTangent "0.035") (etchFactor "90.000000") (elecCondVal "595900.000000 mho/cm") (thermCondVal "0.012 w/cm-degC")) ("" (layerType "DIELECTRIC") (material "FR-4") (thickness "  2.670000 mil") (dielectricConstant "4.500000") (lossTangent "0.035") (etchFactor "0.000000") (elecCondVal "0 mho/cm") (thermCondVal "0.012 w/cm-degC")) ("BOTTOM" (layerType "CONDUCTOR") (material "COPPER") (thickness "  2.100000 mil") (width "4.00 MIL") (dielectricConstant "4.500000") (lossTangent "0") (etchFactor "70.000000") (elecCondVal "595900.000000 mho/cm") (thermCondVal "0 w/cm-degC") (signalDieConstant "3.800000") (signalLossTangent "0.035")) ("" (layerType "DIELECTRIC") (material "CONFORMAL_COAT") (thickness "0.5 mil") (dielectricConstant "3.800000") (lossTangent "0.035") (etchFactor "0.000000") (elecCondVal "0 mho/cm") (thermCondVal "0.012 w/cm-degC")) ("" (layerType "SURFACE") (material "AIR") (thickness "0 mil") (dielectricConstant "1.000000") (lossTangent "0") (etchFactor "0.000000") (elecCondVal "0 mho/cm") (thermCondVal "0 w/cm-degC"))))) (Props (DesUnits "mils 2") (LayerStack ("DIELECTRIC" "DIELECTRIC" "BOTTOM" "DIELECTRIC" "L17_GND6" "DIELECTRIC" "L16_SIG4" "DIELECTRIC" "L15_GND5" "DIELECTRIC" "L14_SIG3" "DIELECTRIC" "L13_GND4" "DIELECTRIC" "L12_PWR2-SIG" "DIELECTRIC" "L11_GND_TEMP" "DIELECTRIC" "L10_SIG_TEMP" "DIELECTRIC" "L9_SIG_TEMP" "DIELECTRIC" "L8_GND_TEMP" "DIELECTRIC" "L7_PWR1-SIG" "DIELECTRIC" "L6_GND3" "DIELECTRIC" "L5_SIG2" "DIELECTRIC" "L4_GND2" "DIELECTRIC" "L3_SIG1" "DIELECTRIC" "L2_GND1" "DIELECTRIC" "TOP" "DIELECTRIC" "DIELECTRIC")) (Revision "16.600")) (Params (DiffInputPkg ((temperature "27") (bufferModelNonInverting "CDSDefaultInput_2p5v") (bufferModelInverting "CDSDefaultInput_2p5v") (threshInputHighMin "1.7 V") (threshInputHighTyp "1.7  V") (threshInputHighMax "1.7  V") (threshInputLowMin "0.7  V") (threshInputLowTyp "0.7  V") (threshInputLowMax "0.7  V") (mappingTagNonInverting nil) (mappingTagInverting nil) (cycle "1"))) (IbisOutputPkg ((temperature "27") (bufferModel "CDSDefaultOutput_2p5v") (stimuli nil) (offsets nil) (state "tristate") (cycle "1") (termMap nil) (setup "2.0e-09") (hold "1.0e-09") (rise nil) (fall nil) (macroType nil) (voltage nil) (spice nil) (LEFDEFPinName nil) (LEFDEFPinType nil) (mappingTag nil))) (IbisIOPkg ((temperature "27") (bufferModel "CDSDefaultIO_2p5v") (stimuli nil) (offsets nil) (state "tristate") (cycle "1") (termMap nil) (setup "2.0e-09") (hold "1.0e-09") (rise nil) (fall nil) (macroType nil) (voltage nil) (spice nil) (LEFDEFPinName nil) (LEFDEFPinType nil) (mappingTag nil))) (IbisIOMacro ((temperature "27") (bufferModel "CDSDefaultIO_2p5v") (stimuli nil) (offsets nil) (state "tristate") (cycle "1") (termMap nil) (setup "2.0e-09") (hold "1.0e-09") (rise nil) (fall nil) (macroType nil) (voltage nil) (spice nil) (LEFDEFPinName nil) (LEFDEFPinType nil) (mappingTag nil))) (ESpiceDevice nil) (IbisInput ((temperature "27") (bufferModel "CDSDefaultInput_2p5v") (cycle "1") (LEFDEFPinName nil) (LEFDEFPinType nil) (mappingTag nil))) (ShuntTerm ((resistance "50 ohm") (voltage "5 V") (maxDelay "0.1 ns"))) (SeriesTerm ((resistance "22 ohm") (maxDelay "0.1 ns"))) (CurrentProbe nil) (idlCircuit ((allDrivers "active") (ftsMode '("Typ")) (rcvrSelect "all") (simMode "Reflection") (tlineDelayMode "time") (userRevision "1.0") (autoSolve "On"))) (TheveninTerm ((resistanceUp "180 ohm") (resistanceDown "270 ohm") (voltageUp "5 V") (voltageDown "0 V") (maxDelay "0.1 ns"))) (RCTerm ((resistance "50 ohm") (capacitance "20 pF") (voltage "5 V") (maxDelay "0.1 ns"))) (LowClampTerm ((cutoffVoltage "0.7 V") (voltage "0 V") (maxDelay "0.1 ns"))) (Cable (length("1 m"))) (HiClampTerm ((cutoffVoltage "0.7 V") (voltage "5 V") (maxDelay "0.1 ns"))) (DualClampTerm ((cutoffVoltageUp "0.7 V") (cutoffVoltageDown "0.7 V") (voltageUp "5 V") (voltageDown "0 V") (maxDelay "0.1 ns"))) (IbisInputPkg ((temperature "27") (bufferModel "CDSDefaultInput_2p5v") (cycle "1") (LEFDEFPinName nil) (LEFDEFPinType nil) (mappingTag nil))) (async ((asyncTimePoints "") (asyncInitState "1"))) (clocked ((clockRise "1e-09") (clockFall "1e-09") (clockFreq "100e6") (clockInitState "0") (clockDutyCycle "0.5") (clockJitter "0"))) (Diode ((cutoffVoltage "0.7 V"))) (IbisOutput ((temperature "27") (bufferModel "CDSDefaultOutput_2p5v") (stimuli nil) (offsets nil) (state "tristate") (cycle "1") (termMap nil) (setup "2.0e-09") (hold "1.0e-09") (rise nil) (fall nil) (macroType nil) (voltage nil) (spice nil) (LEFDEFPinName nil) (LEFDEFPinType nil) (mappingTag nil))) (periodic ((periodicFreq "100e6") (periodicPattern "10") (periodicJitter "0"))) (IbisIO ((temperature "27") (bufferModel "CDSDefaultIO_2p5v") (stimuli nil) (offsets nil) (state "tristate") (cycle "1") (termMap nil) (setup "2.0e-09") (hold "1.0e-09") (rise nil) (fall nil) (macroType nil) (voltage nil) (spice nil) (LEFDEFPinName nil) (LEFDEFPinType nil) (mappingTag nil))) (Via ((model "Unknown") (viaOutputFormat "Unknown") (viaPadstack nil) (viaTopLayer nil) (viaBottomLayer nil) (viaIsPower nil) (viaIsGround nil))) (CPWMS ((d1Thickness "10 mil") (d1Constant "4.5") (d1LossTangent "0.035") (d2Thickness "0.72 mil") (d2Constant "4.5") (d2LossTangent "0.035") (d3Thickness "0.0") (d3Constant "1") (d3LossTangent "0") length("1000 mil") (spacing "5 mil") (spacing2 "5 mil") (spacing3 "5 mil") (spacing4 "5 mil") (spacing5 "5 mil") (traceConductivity "595900 mho/cm") (traceGeometry "cpwms") (traceLayerName "") (traceThickness "0.72 mil") (traceType "single") (traceWidth "5.0 mil") (traceWidth2 "5.0 mil") (traceWidth3 "5.0 mil") (traceWidth4 "5.0 mil") (traceWidth5 "5.0 mil") (traceWidth6 "5.0 mil") (offset "0 mil") (traceCount "1") (impedance nil))) (Trace ((d1Thickness "10 mil") (d1Constant "4.5") (d1LossTangent "0.035") (d2Thickness "10 mil") (d2Constant "4.5") (d2LossTangent "0.035") (d3Thickness "0.0") (d3Constant "1.0") (d3LossTangent "0") length("1000 mil") (spacing "5 mil") (spacing2 "5 mil") (spacing3 "5 mil") (spacing4 "5 mil") (spacing5 "5 mil") (traceConductivity "595900 mho/cm") (traceGeometry "microstrip") (traceLayerName "") (traceThickness "0.72 mil") (traceType "single") (traceWidth "5.0 mil") (traceWidth2 "5.0 mil") (traceWidth3 "5.0 mil") (traceWidth4 "5.0 mil") (traceWidth5 "5.0 mil") (traceWidth6 "5.0 mil") (offset "0 mil") (traceCount "1") (impedance nil))) (Source ((voltage "5 V"))) (CPWSL ((d1Thickness "10 mil") (d1Constant "4.5") (d1LossTangent "0.035") (d2Thickness "0.72 mil") (d2Constant "4.5") (d2LossTangent "0.035") (d3Thickness "10 mil") (d3Constant "4.5") (d3LossTangent "0.035") length("1000 mil") (spacing "5 mil") (spacing2 "5 mil") (spacing3 "5 mil") (spacing4 "5 mil") (spacing5 "5 mil") (traceConductivity "595900 mho/cm") (traceGeometry "cpwms") (traceLayerName "") (traceThickness "0.72 mil") (traceType "single") (traceWidth "5.0 mil") (traceWidth2 "5.0 mil") (traceWidth3 "5.0 mil") (traceWidth4 "5.0 mil") (traceWidth5 "5.0 mil") (traceWidth6 "5.0 mil") (offset "0 mil") (traceCount "1") (impedance nil))) (RLGC (length("1000 mil"))) (Capacitor ((capacitance "10 pF") (orientation "0"))) (DiffIOPkg ((temperature "27") (bufferModelNonInverting "CDSDefaultIO_2p5v") (bufferModelInverting "CDSDefaultIO_2p5v") (stimuli nil) (offsets nil) (state "tristate") (cycle "1") (termMap nil) (setup "0.9e-09") (hold "0.4e-09") (rise nil) (fall nil) (threshInputHighMin "1.7 V") (threshInputHighTyp "1.7  V") (threshInputHighMax "1.7  V") (threshInputLowMin "0.7  V") (threshInputLowTyp "0.7  V") (threshInputLowMax "0.7 ") (threshOutputHighMin "2.365  V") (threshOutputHighTyp "2.5  V") (threshOutputHighMax "2.625  V") (threshOutputLowMin "1.275  V") (threshOutputLowTyp "1.7  V") (threshOutputLowMax "1.985  V") (mappingTagNonInverting nil) (mappingTagInverting nil) (spice nil))) (Inductor ((inductance "5 nH") (orientation "0"))) (DiffIO ((temperature "27") (bufferModelNonInverting "CDSDefaultIO_2p5v") (bufferModelInverting "CDSDefaultIO_2p5v") (stimuli nil) (offsets nil) (state "tristate") (cycle "1") (termMap nil) (setup "0.9e-09") (hold "0.4e-09") (rise nil) (fall nil) (threshInputHighMin "1.7 V") (threshInputHighTyp "1.7  V") (threshInputHighMax "1.7  V") (threshInputLowMin "0.7  V") (threshInputLowTyp "0.7  V") (threshInputLowMax "0.7 ") (threshOutputHighMin "2.365  V") (threshOutputHighTyp "2.5  V") (threshOutputHighMax "2.625  V") (threshOutputLowMin "1.275  V") (threshOutputLowTyp "1.7  V") (threshOutputLowMax "1.985  V") (mappingTagNonInverting nil) (mappingTagInverting nil) (spice nil))) (CPW ((d1Thickness "10 mil") (d1Constant "4.5") (d1LossTangent "0.035") (d2Thickness "0.72 mil") (d2Constant "1") (d2LossTangent "0") (d3Thickness "0.0") (d3Constant "1") (d3LossTangent "0") length("1000 mil") (spacing "5 mil") (spacing2 "5 mil") (spacing3 "5 mil") (spacing4 "5 mil") (spacing5 "5 mil") (traceConductivity "595900 mho/cm") (traceGeometry "cpwms") (traceLayerName "") (traceThickness "0.72 mil") (traceType "single") (traceWidth "5.0 mil") (traceWidth2 "5.0 mil") (traceWidth3 "5.0 mil") (traceWidth4 "5.0 mil") (traceWidth5 "5.0 mil") (traceWidth6 "5.0 mil") (offset "0 mil") (traceCount "1") (impedance nil))) (Connector nil) (TLine ((diffImpedance "100ohm") (diffVelocity "1.4142e+08M/s") (impedance "60ohm") length("2800 mil") (propDelay "0.5 ns") (velocity "5600 mil/ns") (traceCount "1") (traceGeometry "Microstrip") (impedanceMin nil) (impedanceMax nil) (lengthMin nil) (lengthMax nil) (propDelayMin nil) (propDelayMax nil) (impedanceSweepCount nil) (propDelaySweepCount nil) (velocitySweepCount nil) (lengthSweepCount nil) (matchSetName nil))) (sync ((syncFreq "100e6") (syncInitState "1") (syncPattern "10") (syncEdgeSwitch "rise"))) (IbisIO_OpenPullDown ((temperature "27") (bufferModel "CDSDefaultIO_2p5v") (stimuli nil) (offsets nil) (state "tristate") (cycle "1") (termMap nil) (setup "2.0e-09") (hold "1.0e-09") (rise nil) (fall nil) (macroType nil) (voltage nil) (spice nil) (LEFDEFPinName nil) (LEFDEFPinType nil) (mappingTag nil))) (DiffOutputPkg ((temperature "27") (bufferModelNonInverting "CDSDefaultOutput_2p5v") (bufferModelInverting "CDSDefaultOutput_2p5v") (stimuli nil) (offsets nil) (state "tristate") (cycle "1") (termMap nil) (setup "0.9e-09") (hold "0.4e-09") (rise nil) (fall nil) (threshOutputHighMin "2.375  V") (threshOutputHighTyp "2.5  V") (threshOutputHighMax "2.625  V") (threshOutputLowMin "1.275  V") (threshOutputLowTyp "1.7  V") (threshOutputLowMax "1.985  V") (mappingTagNonInverting nil) (mappingTagInverting nil) (spice nil))) (DiffInput ((temperature "27") (bufferModelNonInverting "CDSDefaultInput_2p5v") (bufferModelInverting "CDSDefaultInput_2p5v") (threshInputHighMin "1.7 V") (threshInputHighTyp "1.7  V") (threshInputHighMax "1.7  V") (threshInputLowMin "0.7  V") (threshInputLowTyp "0.7  V") (threshInputLowMax "0.7  V") (mappingTagNonInverting nil) (mappingTagInverting nil) (cycle "1"))) (Resistor ((resistance "50 ohm") (orientation "0"))) (DiffOutput ((temperature "27") (bufferModelNonInverting "CDSDefaultOutput_2p5v") (bufferModelInverting "CDSDefaultOutput_2p5v") (stimuli nil) (offsets nil) (state "tristate") (cycle "1") (termMap nil) (setup "0.9e-09") (hold "0.4e-09") (rise nil) (fall nil) (threshOutputHighMin "2.375  V") (threshOutputHighTyp "2.5  V") (threshOutputHighMax "2.625  V") (threshOutputLowMin "1.275  V") (threshOutputLowTyp "1.7  V") (threshOutputLowMax "1.985  V") (mappingTagNonInverting nil) (mappingTagInverting nil) (spice nil))) (IbisOutput_OpenPullUp ((temperature "27") (bufferModel "CDSDefaultOutput_2p5v") (stimuli nil) (offsets nil) (state "tristate") (cycle "1") (termMap nil) (setup "2.0e-09") (hold "1.0e-09") (rise nil) (fall nil) (macroType nil) (voltage nil) (spice nil) (LEFDEFPinName nil) (LEFDEFPinType nil) (mappingTag nil))) (IbisIO_OpenPullUp ((temperature "27") (bufferModel "CDSDefaultIO_2p5v") (stimuli nil) (offsets nil) (state "tristate") (cycle "1") (termMap nil) (setup "2.0e-09") (hold "1.0e-09") (rise nil) (fall nil) (macroType nil) (voltage nil) (spice nil) (LEFDEFPinName nil) (LEFDEFPinType nil) (mappingTag nil)))))
				)
				( objectStatus "SPI_SWITCH_IO3" )
			)
			( electricalCSet "@crescent_city_bb_fab1_lib.crescent_city_bb_fab1(sch_1):\MEMHOT\"
				( pinPairRef "MEMHOT:U5D1.AH13:U9G1.6" )
				( pinPairRef "MEMHOT:U5D1.AH13:R2U40.2" )
				( attribute "RATSNEST_SCHEDULE" "TEMPLATE"
					( Status sLocked )
					( Origin gBackEnd )
				)
				( attribute "TOPOLOGY_TEMPLATE_REVISION" "1.0"
					( Origin gBackEnd )
				)
				( topologyData 26331
(SKIDL (Circuits ("MAIN" (Parts ("CRESCENT_CITY_176_20141216_Q.@@Q13.3" IbisIOPkg (xy (5528 4240)) (refDes "Q4B1") (model "Unknown") (Props (_SXDesignName "CRESCENT_CITY_176_20141216_Q") (brdx "6794.3 MIL") (brdy "4999.7 MIL") (bufferModel "CDSDefaultIO_2p5v") (cycle "1") (hold "1.0e-09") (mappingTag "") (offsets ("5" "0") ("4" "0")) (setup "2.0e-09") (state "tristate") (stimuli ("5" "local75") ("4" "local74")) (temperature "27") (termMap ("4" "Data") ("5" "Enable"))) (Terms ("CRESCENT_CITY_176_20141216_Q.X679430Y499970L2LRATS" "3"))) ("CRESCENT_CITY_176_20141216_Q.@@Q4L2.6" IbisIOPkg (xy (5548 4240)) (refDes "Q2U1") (model "Unknown") (Props (_SXDesignName "CRESCENT_CITY_176_20141216_Q") (brdx "12640 MIL") (brdy "4885 MIL") (bufferModel "CDSDefaultIO_2p5v") (cycle "1") (hold "1.0e-09") (mappingTag "") (offsets ("5" "0") ("4" "0")) (setup "2.0e-09") (state "tristate") (stimuli ("5" "local77") ("4" "local76")) (temperature "27") (termMap ("4" "Data") ("5" "Enable"))) (Terms ("CRESCENT_CITY_176_20141216_Q.X1264000Y488500L2LRATS" "6"))) ("CRESCENT_CITY_176_20141216_Q.@@U36.AH13" IbisIOPkg (xy (5568 4240)) (refDes "U5D1") (model "Unknown") (Props (_SXDesignName "CRESCENT_CITY_176_20141216_Q") (brdx "11690.89 MIL") (brdy "2551.96 MIL") (bufferModel "CDSDefaultIO_2p5v") (cycle "1") (hold "1.0e-09") (mappingTag "") (offsets ("5" "0") ("4" "0")) (setup "2.0e-09") (state "tristate") (stimuli ("5" "local79") ("4" "local78")) (temperature "27") (termMap ("4" "Data") ("5" "Enable"))) (Terms ("CRESCENT_CITY_176_20141216_Q.X1169089Y255196L2LRATS" "AH13"))) ("CRESCENT_CITY_176_20141216_Q.@@U95.6" IbisIOPkg (xy (5502 4240)) (refDes "U9G1") (model "Unknown") (Props (_SXDesignName "CRESCENT_CITY_176_20141216_Q") (brdx "17196.8 MIL") (brdy "-144.1 MIL") (bufferModel "CDSDefaultIO_2p5v") (cycle "1") (hold "1.0e-09") (mappingTag "") (offsets ("5" "0") ("4" "0")) (setup "2.0e-09") (state "tristate") (stimuli ("5" "local81") ("4" "local80")) (temperature "27") (termMap ("4" "Data") ("5" "Enable"))) (Terms ("CRESCENT_CITY_176_20141216_Q.X1719680Yn14410L2LRATS" "6"))) ("CRESCENT_CITY_176_20141216_Q.@@R617.1.2" Resistor (xy (5554 4229)) (refDes "R2U40") (value "75 Ohm") (Props (_SXDesignName "CRESCENT_CITY_176_20141216_Q")) (Terms ("CRESCENT_CITY_176_20141216_Q.X1264000Y492000L28RATS" "1") ("CRESCENT_CITY_176_20141216_Q.X1264000Y488500L28LRATS" "2"))) ("CRESCENT_CITY_176_20141216_Q.T@@RATS@@Q13.3@@U95.6" TLine (xy (5513 4235)) (mirror x) (refDes "TL46") (Props (_SXDesignName "CRESCENT_CITY_176_20141216_Q") (impedance "60 ohm") length("15546.30 MIL") (propDelay "2.79222 ns") (traceCount "1") (traceGeometry "Microstrip") (velocity "5567.72 mil/ns")) (Terms ("CRESCENT_CITY_176_20141216_Q.X679430Y499970L2LRATS" "1") ("CRESCENT_CITY_176_20141216_Q.X1719680Yn14410L2LRATS" "2"))) ("CRESCENT_CITY_176_20141216_Q.T@@RATS@@Q4L2.6@@U36.AH13" TLine (xy (5559 4235)) (refDes "TL47") (Props (_SXDesignName "CRESCENT_CITY_176_20141216_Q") (impedance "60 ohm") length("3282.13 MIL") (propDelay "0.589497 ns") (traceCount "1") (traceGeometry "Microstrip") (velocity "5567.68 mil/ns")) (Terms ("CRESCENT_CITY_176_20141216_Q.X1264000Y488500L2LRATS" "1") ("CRESCENT_CITY_176_20141216_Q.X1169089Y255196L2LRATS" "2"))) ("CRESCENT_CITY_176_20141216_Q.T@@RATS@@U36.AH13@@R617.2" TLine (xy (5569 4229)) (mirror x) (refDes "TL48") (Props (_SXDesignName "CRESCENT_CITY_176_20141216_Q") (impedance "60 ohm") length("3282.13 MIL") (propDelay "0.589497 ns") (traceCount "1") (traceGeometry "Microstrip") (velocity "5567.68 mil/ns")) (Terms ("CRESCENT_CITY_176_20141216_Q.X1169089Y255196L2LRATS" "1") ("CRESCENT_CITY_176_20141216_Q.X1264000Y488500L28LRATS" "2"))) ("CRESCENT_CITY_176_20141216_Q.@@R617.1_SOURCE" Source (xy (5547 4229)) (refDes "PVCCIO_CPU0") (value "1.05 V") (Props (_SXDesignName "CRESCENT_CITY_176_20141216_Q")) (Terms ("CRESCENT_CITY_176_20141216_Q.X1264000Y492000L28RATS" "1"))) ("CRESCENT_CITY_176_20141216_Q.T@@RATS@@Q13.3@@Q4L2.6" TLine (xy (5539 4235)) (refDes "TL49") (Props (_SXDesignName "CRESCENT_CITY_176_20141216_Q") (impedance "60 ohm") length("5960.39 MIL") (propDelay "1.07053 ns") (traceCount "1") (traceGeometry "Microstrip") (velocity "5567.72 mil/ns")) (Terms ("CRESCENT_CITY_176_20141216_Q.X679430Y499970L2LRATS" "1") ("CRESCENT_CITY_176_20141216_Q.X1264000Y488500L2LRATS" "2")))) (Nodes ("CRESCENT_CITY_176_20141216_Q.X1264000Y488500L2LRATS" (terms "CRESCENT_CITY_176_20141216_Q.T@@RATS@@Q13.3@@Q4L2.6.2" "CRESCENT_CITY_176_20141216_Q.T@@RATS@@Q4L2.6@@U36.AH13.1" "CRESCENT_CITY_176_20141216_Q.@@Q4L2.6.1")) ("CRESCENT_CITY_176_20141216_Q.X1264000Y492000L28RATS" (terms "CRESCENT_CITY_176_20141216_Q.@@R617.1_SOURCE.1" "CRESCENT_CITY_176_20141216_Q.@@R617.1.2.1")) ("CRESCENT_CITY_176_20141216_Q.X1719680Yn14410L2LRATS" (terms "CRESCENT_CITY_176_20141216_Q.T@@RATS@@Q13.3@@U95.6.2" "CRESCENT_CITY_176_20141216_Q.@@U95.6.1")) ("CRESCENT_CITY_176_20141216_Q.X679430Y499970L2LRATS" (terms "CRESCENT_CITY_176_20141216_Q.T@@RATS@@Q13.3@@Q4L2.6.1" "CRESCENT_CITY_176_20141216_Q.T@@RATS@@Q13.3@@U95.6.1" "CRESCENT_CITY_176_20141216_Q.@@Q13.3.1")) ("CRESCENT_CITY_176_20141216_Q.X1169089Y255196L2LRATS" (terms "CRESCENT_CITY_176_20141216_Q.T@@RATS@@U36.AH13@@R617.2.1" "CRESCENT_CITY_176_20141216_Q.T@@RATS@@Q4L2.6@@U36.AH13.2" "CRESCENT_CITY_176_20141216_Q.@@U36.AH13.1")) ("CRESCENT_CITY_176_20141216_Q.X1264000Y488500L28LRATS" (terms "CRESCENT_CITY_176_20141216_Q.T@@RATS@@U36.AH13@@R617.2.2" "CRESCENT_CITY_176_20141216_Q.@@R617.1.2.2"))) (Ports) (Stimuli ("local75" (scope local) (stimType periodic) (Props (periodicFreq "5e+007") (periodicJitter "0") (periodicPattern "1"))) ("local78" (scope local) (stimType periodic) (Props (periodicFreq "5e+007") (periodicJitter "0") (periodicPattern "1"))) ("local81" (scope local) (stimType periodic) (Props (periodicFreq "5e+007") (periodicJitter "0") (periodicPattern "1"))) ("local74" (scope local) (stimType periodic) (Props (periodicFreq "5e+007") (periodicJitter "0") (periodicPattern "1"))) ("local76" (scope local) (stimType periodic) (Props (periodicFreq "5e+007") (periodicJitter "0") (periodicPattern "1"))) ("local79" (scope local) (stimType periodic) (Props (periodicFreq "5e+007") (periodicJitter "0") (periodicPattern "1"))) ("local77" (scope local) (stimType periodic) (Props (periodicFreq "5e+007") (periodicJitter "0") (periodicPattern "1"))) ("local80" (scope local) (stimType periodic) (Props (periodicFreq "5e+007") (periodicJitter "0") (periodicPattern "1")))) (Notes) (Constraints ("DELAY_RULE" ("CRESCENT_CITY_176_20141216_Q U36.AH13" "CRESCENT_CITY_176_20141216_Q U95.6" "LENGTH" "" "LENGTH" "0.5207") ("CRESCENT_CITY_176_20141216_Q U36.AH13" "CRESCENT_CITY_176_20141216_Q R617.2" "LENGTH" "" "LENGTH" "0.0635")) ("RATSNEST_SCHEDULE" "TEMPLATE")) (MeasurementSets ("EMI" ("EMIStatus" status("on")) ("PeakEmission" status("on")) ("PeakFrequency" status("on")) ("PulseFreq" status("on")) ("RiseTime" status("on")) ("VoltageSwing" status("on"))) ("Reflection" ("BufferDelayFall" status("off")) ("BufferDelayRise" status("off")) ("EyeHeight" status("off")) ("EyeJitter" status("off")) ("EyeWidth" status("off")) ("FirstIncidentFall" status("off")) ("FirstIncidentRise" status("off")) ("Glitch" status("on")) ("GlitchFall" status("off")) ("GlitchRise" status("off")) ("Monotonic" status("on")) ("MonotonicFall" status("off")) ("MonotonicRise" status("off")) ("NoiseMargin" status("on")) ("NoiseMarginHigh" status("off")) ("NoiseMarginLow" status("off")) ("OvershootHigh" status("on")) ("OvershootLow" status("on")) ("PropDelay" status("on")) ("SettleDelay" status("on")) ("SettleDelayFall" status("off")) ("SettleDelayRise" status("off")) ("SwitchDelay" status("on")) ("SwitchDelayFall" status("off")) ("SwitchDelayRise" status("off"))) ("Crosstalk" ("Crosstalk" status("on"))) ("Custom")) (VectorSets) (Props (XnetName "H_CPU0_MEMABC_MEMHOT_G_N") (allDrivers "active") (customSimType "Reflection") (ftsMode ("Typ")) (rcvrSelect "all") (tlineDelayMode "time") (userRevision "1.0")))) (Subckts) (CrossSections ("CRESCENT_CITY_176_20141216_Q" (Props (SXDesignName "CRESCENT_CITY_176_20141216_Q")) (Layers ("" (layerType "SURFACE") (material "AIR") (thickness "0 mil") (dielectricConstant "1.000000") (lossTangent "0") (etchFactor "0.000000") (elecCondVal "0 mho/cm") (thermCondVal "0 w/cm-degC")) ("" (layerType "DIELECTRIC") (material "CONFORMAL_COAT") (thickness "0.5 mil") (dielectricConstant "3.800000") (lossTangent "0.035") (etchFactor "0.000000") (elecCondVal "0 mho/cm") (thermCondVal "0.012 w/cm-degC")) ("TOP" (layerType "CONDUCTOR") (material "COPPER") (thickness "  2.100000 mil") (width "4.00 MIL") (dielectricConstant "4.500000") (lossTangent "0") (etchFactor "70.000000") (elecCondVal "595900.000000 mho/cm") (thermCondVal "0 w/cm-degC") (signalDieConstant "3.800000") (signalLossTangent "0.035")) ("" (layerType "DIELECTRIC") (material "FR-4") (thickness "  2.670000 mil") (dielectricConstant "4.000000") (lossTangent "0.035") (etchFactor "0.000000") (elecCondVal "0 mho/cm") (thermCondVal "0.012 w/cm-degC")) ("L2_GND1" (layerType "PLANE") (material "COPPER") (isShield t) (thickness "  1.250000 mil") (dielectricConstant "4.500000") (lossTangent "0.035") (etchFactor "90.000000") (elecCondVal "595900.000000 mho/cm") (thermCondVal "0.012 w/cm-degC")) ("" (layerType "DIELECTRIC") (material "FR-4") (thickness "  9.000000 mil") (dielectricConstant "4.100000") (lossTangent "0.035") (etchFactor "0.000000") (elecCondVal "0 mho/cm") (thermCondVal "0.012 w/cm-degC")) ("L3_SIG1" (layerType "CONDUCTOR") (material "COPPER") (thickness "  1.250000 mil") (width "4.00 MIL") (dielectricConstant "4.500000") (lossTangent "0.035") (etchFactor "90.000000") (elecCondVal "595900.000000 mho/cm") (thermCondVal "0.012 w/cm-degC") (signalDieConstant "4.100000") (signalLossTangent "0.035")) ("" (layerType "DIELECTRIC") (material "FR-4") (thickness "  3.000000 mil") (dielectricConstant "4.500000") (lossTangent "0.035") (etchFactor "0.000000") (elecCondVal "0 mho/cm") (thermCondVal "0 w/cm-degC")) ("L4_GND2" (layerType "PLANE") (material "COPPER") (isShield t) (thickness "  1.250000 mil") (dielectricConstant "4.500000") (lossTangent "0.035") (etchFactor "90.000000") (elecCondVal "595900.000000 mho/cm") (thermCondVal "0 w/cm-degC")) ("" (layerType "DIELECTRIC") (material "FR-4") (thickness "  9.000000 mil") (dielectricConstant "4.000000") (lossTangent "0.035") (etchFactor "0.000000") (elecCondVal "0 mho/cm") (thermCondVal "0.012 w/cm-degC")) ("L5_SIG2" (layerType "CONDUCTOR") (material "COPPER") (thickness "  1.250000 mil") (width "4.00 MIL") (dielectricConstant "4.500000") (lossTangent "0.035") (etchFactor "90.000000") (elecCondVal "595900.000000 mho/cm") (thermCondVal "0.012 w/cm-degC") (signalDieConstant "4.000000") (signalLossTangent "0.035")) ("" (layerType "DIELECTRIC") (material "FR-4") (thickness "  3.000000 mil") (dielectricConstant "4.500000") (lossTangent "0.035") (etchFactor "0.000000") (elecCondVal "0 mho/cm") (thermCondVal "0 w/cm-degC")) ("L6_GND3" (layerType "PLANE") (material "COPPER") (isShield t) (thickness "  1.250000 mil") (dielectricConstant "4.500000") (lossTangent "0.035") (etchFactor "90.000000") (elecCondVal "595900.000000 mho/cm") (thermCondVal "0 w/cm-degC")) ("" (layerType "DIELECTRIC") (material "FR-4") (thickness "  4.500000 mil") (dielectricConstant "4.100000") (lossTangent "0.035") (etchFactor "0.000000") (elecCondVal "0 mho/cm") (thermCondVal "0.012 w/cm-degC")) ("L7_PWR1-SIG" (layerType "PLANE") (material "COPPER") (isShield t) (thickness "  2.400000 mil") (dielectricConstant "4.500000") (lossTangent "0.035") (etchFactor "90.000000") (elecCondVal "595900.000000 mho/cm") (thermCondVal "0.012 w/cm-degC")) ("" (layerType "DIELECTRIC") (material "FR-4") (thickness "  4.600000 mil") (dielectricConstant "4.000000") (lossTangent "0.035") (etchFactor "0.000000") (elecCondVal "0 mho/cm") (thermCondVal "0.012 w/cm-degC")) ("L8_PWR2-SIG" (layerType "PLANE") (material "COPPER") (isShield t) (thickness "  2.400000 mil") (dielectricConstant "4.500000") (lossTangent "0.035") (etchFactor "90.000000") (elecCondVal "595900.000000 mho/cm") (thermCondVal "0.012 w/cm-degC")) ("" (layerType "DIELECTRIC") (material "FR-4") (thickness "  4.500000 mil") (dielectricConstant "4.500000") (lossTangent "0.035") (etchFactor "0.000000") (elecCondVal "0 mho/cm") (thermCondVal "0 w/cm-degC")) ("L9_GND4" (layerType "PLANE") (material "COPPER") (isShield t) (thickness "  1.250000 mil") (dielectricConstant "4.500000") (lossTangent "0.035") (etchFactor "90.000000") (elecCondVal "595900.000000 mho/cm") (thermCondVal "0 w/cm-degC")) ("" (layerType "DIELECTRIC") (material "FR-4") (thickness "  3.000000 mil") (dielectricConstant "4.100000") (lossTangent "0.035") (etchFactor "0.000000") (elecCondVal "0 mho/cm") (thermCondVal "0.012 w/cm-degC")) ("L10_SIG3" (layerType "CONDUCTOR") (material "COPPER") (thickness "  1.250000 mil") (width "4.00 MIL") (dielectricConstant "4.500000") (lossTangent "0.035") (etchFactor "90.000000") (elecCondVal "595900.000000 mho/cm") (thermCondVal "0.012 w/cm-degC") (signalDieConstant "4.100000") (signalLossTangent "0.035")) ("" (layerType "DIELECTRIC") (material "FR-4") (thickness "  9.000000 mil") (dielectricConstant "4.500000") (lossTangent "0.035") (etchFactor "0.000000") (elecCondVal "0 mho/cm") (thermCondVal "0 w/cm-degC")) ("L11_GND5" (layerType "PLANE") (material "COPPER") (isShield t) (thickness "  1.250000 mil") (dielectricConstant "4.500000") (lossTangent "0.035") (etchFactor "90.000000") (elecCondVal "595900.000000 mho/cm") (thermCondVal "0 w/cm-degC")) ("" (layerType "DIELECTRIC") (material "FR-4") (thickness "  3.000000 mil") (dielectricConstant "4.500000") (lossTangent "0.035") (etchFactor "0.000000") (elecCondVal "0 mho/cm") (thermCondVal "0.012 w/cm-degC")) ("L12_SIG4" (layerType "CONDUCTOR") (material "COPPER") (thickness "  1.250000 mil") (width "4.00 MIL") (dielectricConstant "4.500000") (lossTangent "0.035") (etchFactor "90.000000") (elecCondVal "595900.000000 mho/cm") (thermCondVal "0.012 w/cm-degC") (signalDieConstant "4.500000") (signalLossTangent "0.035")) ("" (layerType "DIELECTRIC") (material "FR-4") (thickness "  9.000000 mil") (dielectricConstant "4.500000") (lossTangent "0.035") (etchFactor "0.000000") (elecCondVal "0 mho/cm") (thermCondVal "0 w/cm-degC")) ("L13_GND6" (layerType "PLANE") (material "COPPER") (isShield t) (thickness "  1.250000 mil") (dielectricConstant "4.500000") (lossTangent "0.035") (etchFactor "90.000000") (elecCondVal "595900.000000 mho/cm") (thermCondVal "0.012 w/cm-degC")) ("" (layerType "DIELECTRIC") (material "FR-4") (thickness "  2.670000 mil") (dielectricConstant "4.500000") (lossTangent "0.035") (etchFactor "0.000000") (elecCondVal "0 mho/cm") (thermCondVal "0.012 w/cm-degC")) ("BOTTOM" (layerType "CONDUCTOR") (material "COPPER") (thickness "  2.100000 mil") (width "4.00 MIL") (dielectricConstant "4.500000") (lossTangent "0") (etchFactor "70.000000") (elecCondVal "595900.000000 mho/cm") (thermCondVal "0 w/cm-degC") (signalDieConstant "3.800000") (signalLossTangent "0.035")) ("" (layerType "DIELECTRIC") (material "CONFORMAL_COAT") (thickness "0.5 mil") (dielectricConstant "3.800000") (lossTangent "0.035") (etchFactor "0.000000") (elecCondVal "0 mho/cm") (thermCondVal "0.012 w/cm-degC")) ("" (layerType "SURFACE") (material "AIR") (thickness "0 mil") (dielectricConstant "1.000000") (lossTangent "0") (etchFactor "0.000000") (elecCondVal "0 mho/cm") (thermCondVal "0 w/cm-degC"))))) (Props (DesUnits "mils 2") (LayerStack ("DIELECTRIC" "DIELECTRIC" "BOTTOM" "DIELECTRIC" "L13_GND6" "DIELECTRIC" "L12_SIG4" "DIELECTRIC" "L11_GND5" "DIELECTRIC" "L10_SIG3" "DIELECTRIC" "L9_GND4" "DIELECTRIC" "L8_PWR2-SIG" "DIELECTRIC" "L7_PWR1-SIG" "DIELECTRIC" "L6_GND3" "DIELECTRIC" "L5_SIG2" "DIELECTRIC" "L4_GND2" "DIELECTRIC" "L3_SIG1" "DIELECTRIC" "L2_GND1" "DIELECTRIC" "TOP" "DIELECTRIC" "DIELECTRIC")) (Revision "16.600")) (Params (Via ((model "Unknown") (viaOutputFormat "Unknown") (viaPadstack nil) (viaTopLayer nil) (viaBottomLayer nil) (viaIsPower nil) (viaIsGround nil))) (IbisIOMacro ((temperature "27") (bufferModel "CDSDefaultIO_2p5v") (stimuli nil) (offsets nil) (state "tristate") (cycle "1") (termMap nil) (setup "2.0e-09") (hold "1.0e-09") (rise nil) (fall nil) (macroType nil) (voltage nil) (spice nil) (LEFDEFPinName nil) (LEFDEFPinType nil) (mappingTag nil))) (DiffInputPkg ((temperature "27") (bufferModelNonInverting "CDSDefaultInput_2p5v") (bufferModelInverting "CDSDefaultInput_2p5v") (threshInputHighMin "1.7 V") (threshInputHighTyp "1.7  V") (threshInputHighMax "1.7  V") (threshInputLowMin "0.7  V") (threshInputLowTyp "0.7  V") (threshInputLowMax "0.7  V") (mappingTagNonInverting nil) (mappingTagInverting nil) (cycle "1"))) (DiffIO ((temperature "27") (bufferModelNonInverting "CDSDefaultIO_2p5v") (bufferModelInverting "CDSDefaultIO_2p5v") (stimuli nil) (offsets nil) (state "tristate") (cycle "1") (termMap nil) (setup "0.9e-09") (hold "0.4e-09") (rise nil) (fall nil) (threshInputHighMin "1.7 V") (threshInputHighTyp "1.7  V") (threshInputHighMax "1.7  V") (threshInputLowMin "0.7  V") (threshInputLowTyp "0.7  V") (threshInputLowMax "0.7 ") (threshOutputHighMin "2.365  V") (threshOutputHighTyp "2.5  V") (threshOutputHighMax "2.625  V") (threshOutputLowMin "1.275  V") (threshOutputLowTyp "1.7  V") (threshOutputLowMax "1.985  V") (mappingTagNonInverting nil) (mappingTagInverting nil) (spice nil))) (Trace ((d1Thickness "10 mil") (d1Constant "4.5") (d1LossTangent "0.035") (d2Thickness "10 mil") (d2Constant "4.5") (d2LossTangent "0.035") (d3Thickness "0.0") (d3Constant "1.0") (d3LossTangent "0") length("1000 mil") (spacing "5 mil") (spacing2 "5 mil") (spacing3 "5 mil") (spacing4 "5 mil") (spacing5 "5 mil") (traceConductivity "595900 mho/cm") (traceGeometry "microstrip") (traceLayerName "") (traceThickness "0.72 mil") (traceType "single") (traceWidth "5.0 mil") (traceWidth2 "5.0 mil") (traceWidth3 "5.0 mil") (traceWidth4 "5.0 mil") (traceWidth5 "5.0 mil") (traceWidth6 "5.0 mil") (offset "0 mil") (traceCount "1") (impedance nil))) (sync ((syncFreq "100e6") (syncInitState "1") (syncPattern "10") (syncEdgeSwitch "rise"))) (DiffOutputPkg ((temperature "27") (bufferModelNonInverting "CDSDefaultOutput_2p5v") (bufferModelInverting "CDSDefaultOutput_2p5v") (stimuli nil) (offsets nil) (state "tristate") (cycle "1") (termMap nil) (setup "0.9e-09") (hold "0.4e-09") (rise nil) (fall nil) (threshOutputHighMin "2.375  V") (threshOutputHighTyp "2.5  V") (threshOutputHighMax "2.625  V") (threshOutputLowMin "1.275  V") (threshOutputLowTyp "1.7  V") (threshOutputLowMax "1.985  V") (mappingTagNonInverting nil) (mappingTagInverting nil) (spice nil))) (DiffOutput ((temperature "27") (bufferModelNonInverting "CDSDefaultOutput_2p5v") (bufferModelInverting "CDSDefaultOutput_2p5v") (stimuli nil) (offsets nil) (state "tristate") (cycle "1") (termMap nil) (setup "0.9e-09") (hold "0.4e-09") (rise nil) (fall nil) (threshOutputHighMin "2.375  V") (threshOutputHighTyp "2.5  V") (threshOutputHighMax "2.625  V") (threshOutputLowMin "1.275  V") (threshOutputLowTyp "1.7  V") (threshOutputLowMax "1.985  V") (mappingTagNonInverting nil) (mappingTagInverting nil) (spice nil))) (IbisOutputPkg ((temperature "27") (bufferModel "CDSDefaultOutput_2p5v") (stimuli nil) (offsets nil) (state "tristate") (cycle "1") (termMap nil) (setup "2.0e-09") (hold "1.0e-09") (rise nil) (fall nil) (macroType nil) (voltage nil) (spice nil) (LEFDEFPinName nil) (LEFDEFPinType nil) (mappingTag nil))) (DiffIOPkg ((temperature "27") (bufferModelNonInverting "CDSDefaultIO_2p5v") (bufferModelInverting "CDSDefaultIO_2p5v") (stimuli nil) (offsets nil) (state "tristate") (cycle "1") (termMap nil) (setup "0.9e-09") (hold "0.4e-09") (rise nil) (fall nil) (threshInputHighMin "1.7 V") (threshInputHighTyp "1.7  V") (threshInputHighMax "1.7  V") (threshInputLowMin "0.7  V") (threshInputLowTyp "0.7  V") (threshInputLowMax "0.7 ") (threshOutputHighMin "2.365  V") (threshOutputHighTyp "2.5  V") (threshOutputHighMax "2.625  V") (threshOutputLowMin "1.275  V") (threshOutputLowTyp "1.7  V") (threshOutputLowMax "1.985  V") (mappingTagNonInverting nil) (mappingTagInverting nil) (spice nil))) (IbisIOPkg ((temperature "27") (bufferModel "CDSDefaultIO_2p5v") (stimuli nil) (offsets nil) (state "tristate") (cycle "1") (termMap nil) (setup "2.0e-09") (hold "1.0e-09") (rise nil) (fall nil) (macroType nil) (voltage nil) (spice nil) (LEFDEFPinName nil) (LEFDEFPinType nil) (mappingTag nil))) (CurrentProbe nil) (DiffInput ((temperature "27") (bufferModelNonInverting "CDSDefaultInput_2p5v") (bufferModelInverting "CDSDefaultInput_2p5v") (threshInputHighMin "1.7 V") (threshInputHighTyp "1.7  V") (threshInputHighMax "1.7  V") (threshInputLowMin "0.7  V") (threshInputLowTyp "0.7  V") (threshInputLowMax "0.7  V") (mappingTagNonInverting nil) (mappingTagInverting nil) (cycle "1"))) (IbisInputPkg ((temperature "27") (bufferModel "CDSDefaultInput_2p5v") (cycle "1") (LEFDEFPinName nil) (LEFDEFPinType nil) (mappingTag nil))) (idlCircuit ((allDrivers "active") (ftsMode '("Typ")) (rcvrSelect "all") (simMode "Reflection") (tlineDelayMode "time") (userRevision "1.0") (autoSolve "On"))) (SeriesTerm ((resistance "22 ohm") (maxDelay "0.1 ns"))) (RLGC (length("1000 mil"))) (periodic ((periodicFreq "100e6") (periodicPattern "10") (periodicJitter "0"))) (Resistor ((resistance "50 ohm") (orientation "0"))) (async ((asyncTimePoints "") (asyncInitState "1"))) (Capacitor ((capacitance "10 pF") (orientation "0"))) (Inductor ((inductance "5 nH") (orientation "0"))) (clocked ((clockRise "1e-09") (clockFall "1e-09") (clockFreq "100e6") (clockInitState "0") (clockDutyCycle "0.5") (clockJitter "0"))) (TLine ((diffImpedance "100ohm") (diffVelocity "1.4142e+08M/s") (impedance "60ohm") length("2800 mil") (propDelay "0.5 ns") (velocity "5600 mil/ns") (traceCount "1") (traceGeometry "Microstrip") (impedanceMin nil) (impedanceMax nil) (lengthMin nil) (lengthMax nil) (propDelayMin nil) (propDelayMax nil) (impedanceSweepCount nil) (propDelaySweepCount nil) (velocitySweepCount nil) (lengthSweepCount nil) (matchSetName nil))) (Cable (length("1 m"))) (DualClampTerm ((cutoffVoltageUp "0.7 V") (cutoffVoltageDown "0.7 V") (voltageUp "5 V") (voltageDown "0 V") (maxDelay "0.1 ns"))) (LowClampTerm ((cutoffVoltage "0.7 V") (voltage "0 V") (maxDelay "0.1 ns"))) (HiClampTerm ((cutoffVoltage "0.7 V") (voltage "5 V") (maxDelay "0.1 ns"))) (RCTerm ((resistance "50 ohm") (capacitance "20 pF") (voltage "5 V") (maxDelay "0.1 ns"))) (IbisOutput ((temperature "27") (bufferModel "CDSDefaultOutput_2p5v") (stimuli nil) (offsets nil) (state "tristate") (cycle "1") (termMap nil) (setup "2.0e-09") (hold "1.0e-09") (rise nil) (fall nil) (macroType nil) (voltage nil) (spice nil) (LEFDEFPinName nil) (LEFDEFPinType nil) (mappingTag nil))) (IbisIO ((temperature "27") (bufferModel "CDSDefaultIO_2p5v") (stimuli nil) (offsets nil) (state "tristate") (cycle "1") (termMap nil) (setup "2.0e-09") (hold "1.0e-09") (rise nil) (fall nil) (macroType nil) (voltage nil) (spice nil) (LEFDEFPinName nil) (LEFDEFPinType nil) (mappingTag nil))) (Diode ((cutoffVoltage "0.7 V"))) (IbisInput ((temperature "27") (bufferModel "CDSDefaultInput_2p5v") (cycle "1") (LEFDEFPinName nil) (LEFDEFPinType nil) (mappingTag nil))) (ESpiceDevice nil) (CPW ((d1Thickness "10 mil") (d1Constant "4.5") (d1LossTangent "0.035") (d2Thickness "0.72 mil") (d2Constant "1") (d2LossTangent "0") (d3Thickness "0.0") (d3Constant "1") (d3LossTangent "0") length("1000 mil") (spacing "5 mil") (spacing2 "5 mil") (spacing3 "5 mil") (spacing4 "5 mil") (spacing5 "5 mil") (traceConductivity "595900 mho/cm") (traceGeometry "cpwms") (traceLayerName "") (traceThickness "0.72 mil") (traceType "single") (traceWidth "5.0 mil") (traceWidth2 "5.0 mil") (traceWidth3 "5.0 mil") (traceWidth4 "5.0 mil") (traceWidth5 "5.0 mil") (traceWidth6 "5.0 mil") (offset "0 mil") (traceCount "1") (impedance nil))) (IbisOutput_OpenPullUp ((temperature "27") (bufferModel "CDSDefaultOutput_2p5v") (stimuli nil) (offsets nil) (state "tristate") (cycle "1") (termMap nil) (setup "2.0e-09") (hold "1.0e-09") (rise nil) (fall nil) (macroType nil) (voltage nil) (spice nil) (LEFDEFPinName nil) (LEFDEFPinType nil) (mappingTag nil))) (CPWMS ((d1Thickness "10 mil") (d1Constant "4.5") (d1LossTangent "0.035") (d2Thickness "0.72 mil") (d2Constant "4.5") (d2LossTangent "0.035") (d3Thickness "0.0") (d3Constant "1") (d3LossTangent "0") length("1000 mil") (spacing "5 mil") (spacing2 "5 mil") (spacing3 "5 mil") (spacing4 "5 mil") (spacing5 "5 mil") (traceConductivity "595900 mho/cm") (traceGeometry "cpwms") (traceLayerName "") (traceThickness "0.72 mil") (traceType "single") (traceWidth "5.0 mil") (traceWidth2 "5.0 mil") (traceWidth3 "5.0 mil") (traceWidth4 "5.0 mil") (traceWidth5 "5.0 mil") (traceWidth6 "5.0 mil") (offset "0 mil") (traceCount "1") (impedance nil))) (IbisIO_OpenPullDown ((temperature "27") (bufferModel "CDSDefaultIO_2p5v") (stimuli nil) (offsets nil) (state "tristate") (cycle "1") (termMap nil) (setup "2.0e-09") (hold "1.0e-09") (rise nil) (fall nil) (macroType nil) (voltage nil) (spice nil) (LEFDEFPinName nil) (LEFDEFPinType nil) (mappingTag nil))) (Connector nil) (CPWSL ((d1Thickness "10 mil") (d1Constant "4.5") (d1LossTangent "0.035") (d2Thickness "0.72 mil") (d2Constant "4.5") (d2LossTangent "0.035") (d3Thickness "10 mil") (d3Constant "4.5") (d3LossTangent "0.035") length("1000 mil") (spacing "5 mil") (spacing2 "5 mil") (spacing3 "5 mil") (spacing4 "5 mil") (spacing5 "5 mil") (traceConductivity "595900 mho/cm") (traceGeometry "cpwms") (traceLayerName "") (traceThickness "0.72 mil") (traceType "single") (traceWidth "5.0 mil") (traceWidth2 "5.0 mil") (traceWidth3 "5.0 mil") (traceWidth4 "5.0 mil") (traceWidth5 "5.0 mil") (traceWidth6 "5.0 mil") (offset "0 mil") (traceCount "1") (impedance nil))) (IbisIO_OpenPullUp ((temperature "27") (bufferModel "CDSDefaultIO_2p5v") (stimuli nil) (offsets nil) (state "tristate") (cycle "1") (termMap nil) (setup "2.0e-09") (hold "1.0e-09") (rise nil) (fall nil) (macroType nil) (voltage nil) (spice nil) (LEFDEFPinName nil) (LEFDEFPinType nil) (mappingTag nil))) (TheveninTerm ((resistanceUp "180 ohm") (resistanceDown "270 ohm") (voltageUp "5 V") (voltageDown "0 V") (maxDelay "0.1 ns"))) (ShuntTerm ((resistance "50 ohm") (voltage "5 V") (maxDelay "0.1 ns"))) (Source ((voltage "5 V")))))
				)
				( objectStatus "MEMHOT" )
			)
			( electricalCSet "@crescent_city_bb_fab1_lib.crescent_city_bb_fab1(sch_1):\SGPIO_BMC\"
				( groupRef "SGPIO_BMC:MG_SGPIO_BMC" )
				( pinPairRef "SGPIO_BMC:R1U14.2:U8D7.J1" )
				( pinPairRef "SGPIO_BMC:U9F4.J5:R1U14.1" )
				( attribute "TOPOLOGY_TEMPLATE_REVISION" "1.0"
					( Origin gBackEnd )
				)
				( topologyData 23453
(SKIDL (Circuits ("MAIN" (Parts ("CRESCENT_CITY_195_20150129_6PIN.@@U4E2.J1" IbisIOPkg (xy (5527 4228)) (refDes "U8D7") (model "Unknown") (Props (_SXDesignName "CRESCENT_CITY_195_20150129_6PIN") (brdx "15596.22 MIL") (brdy "2615.75 MIL") (bufferModel "CDSDefaultIO_2p5v") (cycle "1") (hold "1.0e-09") (mappingTag "") (offsets ("4" "0") ("5" "0")) (setup "2.0e-09") (state "tristate") (stimuli ("4" "local14") ("5" "local15")) (temperature "27") (termMap ("4" "Data") ("5" "Enable"))) (Terms ("CRESCENT_CITY_195_20150129_6PIN.X1559622Y261575L2LRATS" "J1"))) ("CRESCENT_CITY_195_20150129_6PIN.@@U47.J5" IbisIOPkg (xy (5502 4240)) (refDes "U9F4") (model "Unknown") (Props (_SXDesignName "CRESCENT_CITY_195_20150129_6PIN") (brdx "17839.26 MIL") (brdy "614.28 MIL") (bufferModel "CDSDefaultIO_2p5v") (cycle "1") (hold "1.0e-09") (mappingTag "") (offsets ("4" "0") ("5" "0")) (setup "2.0e-09") (state "tristate") (stimuli ("4" "local16") ("5" "local17")) (temperature "27") (termMap ("4" "Data") ("5" "Enable"))) (Terms ("CRESCENT_CITY_195_20150129_6PIN.X1783926Y61428L2LRATS" "J5"))) ("CRESCENT_CITY_195_20150129_6PIN.T@@RATS@@U4E2.J1@@R65.2" TLine (xy (5512 4223)) (mirror x) (refDes "TL10") (Props (_SXDesignName "CRESCENT_CITY_195_20150129_6PIN") (impedance "49.728 ohm") length("4629.53 MIL") (propDelay "0.8315 ns") (traceCount "1") (traceGeometry "Microstrip") (velocity "5567.68 mil/ns")) (Terms ("CRESCENT_CITY_195_20150129_6PIN.X1559622Y261575L2LRATS" "1") ("CRESCENT_CITY_195_20150129_6PIN.X1795500Y34500L28LRATS" "2"))) ("CRESCENT_CITY_195_20150129_6PIN.@@R65.2.1" Resistor (xy (5497 4223)) (mirror x) (refDes "R1U14") (value "51 Ohm") (Props (_SXDesignName "CRESCENT_CITY_195_20150129_6PIN")) (Terms ("CRESCENT_CITY_195_20150129_6PIN.X1795500Y34500L28LRATS" "2") ("CRESCENT_CITY_195_20150129_6PIN.X1795500Y38000L28LRATS" "1"))) ("CRESCENT_CITY_195_20150129_6PIN.T@@RATS@@U47.J5@@R65.1" TLine (xy (5503 4229)) (mirror x) (refDes "TL11") (Props (_SXDesignName "CRESCENT_CITY_195_20150129_6PIN") (impedance "50.521 ohm") length("350.02 MIL") (propDelay "0.06287 ns") (traceCount "1") (traceGeometry "Microstrip") (velocity "5567.36 mil/ns")) (Terms ("CRESCENT_CITY_195_20150129_6PIN.X1783926Y61428L2LRATS" "1") ("CRESCENT_CITY_195_20150129_6PIN.X1795500Y38000L28LRATS" "2")))) (Nodes ("CRESCENT_CITY_195_20150129_6PIN.X1783926Y61428L2LRATS" (terms "CRESCENT_CITY_195_20150129_6PIN.T@@RATS@@U47.J5@@R65.1.1" "CRESCENT_CITY_195_20150129_6PIN.@@U47.J5.1")) ("CRESCENT_CITY_195_20150129_6PIN.X1795500Y34500L28LRATS" (terms "CRESCENT_CITY_195_20150129_6PIN.@@R65.2.1.1" "CRESCENT_CITY_195_20150129_6PIN.T@@RATS@@U4E2.J1@@R65.2.2")) ("CRESCENT_CITY_195_20150129_6PIN.X1795500Y38000L28LRATS" (terms "CRESCENT_CITY_195_20150129_6PIN.T@@RATS@@U47.J5@@R65.1.2" "CRESCENT_CITY_195_20150129_6PIN.@@R65.2.1.2")) ("CRESCENT_CITY_195_20150129_6PIN.X1559622Y261575L2LRATS" (terms "CRESCENT_CITY_195_20150129_6PIN.T@@RATS@@U4E2.J1@@R65.2.1" "CRESCENT_CITY_195_20150129_6PIN.@@U4E2.J1.1"))) (Ports) (Stimuli ("local15" (scope local) (stimType periodic) (Props (periodicFreq "5e+007") (periodicJitter "0") (periodicPattern "1"))) ("local14" (scope local) (stimType periodic) (Props (periodicFreq "5e+007") (periodicJitter "0") (periodicPattern "1"))) ("local16" (scope local) (stimType periodic) (Props (periodicFreq "5e+007") (periodicJitter "0") (periodicPattern "1"))) ("local17" (scope local) (stimType periodic) (Props (periodicFreq "5e+007") (periodicJitter "0") (periodicPattern "1")))) (Notes) (Constraints ("DELAY_RULE" ("CRESCENT_CITY_195_20150129_6PIN R65.2" "CRESCENT_CITY_195_20150129_6PIN U4E2.J1" "LENGTH" "0.0254" "LENGTH" "0.381") ("CRESCENT_CITY_195_20150129_6PIN U47.J5" "CRESCENT_CITY_195_20150129_6PIN R65.1" "LENGTH" "0.00254" "LENGTH" "0.0508") ("CRESCENT_CITY_195_20150129_6PIN U47.J5" "CRESCENT_CITY_195_20150129_6PIN U4E2.J1" "LENGTH" "" "LENGTH" "0.0762"))) (MeasurementSets ("EMI" ("EMIStatus" status("on")) ("PeakEmission" status("on")) ("PeakFrequency" status("on")) ("PulseFreq" status("on")) ("RiseTime" status("on")) ("VoltageSwing" status("on"))) ("Reflection" ("BufferDelayFall" status("off")) ("BufferDelayRise" status("off")) ("EyeHeight" status("off")) ("EyeJitter" status("off")) ("EyeWidth" status("off")) ("FirstIncidentFall" status("off")) ("FirstIncidentRise" status("off")) ("Glitch" status("on")) ("GlitchFall" status("off")) ("GlitchRise" status("off")) ("Monotonic" status("on")) ("MonotonicFall" status("off")) ("MonotonicRise" status("off")) ("NoiseMargin" status("on")) ("NoiseMarginHigh" status("off")) ("NoiseMarginLow" status("off")) ("OvershootHigh" status("on")) ("OvershootLow" status("on")) ("PropDelay" status("on")) ("SettleDelay" status("on")) ("SettleDelayFall" status("off")) ("SettleDelayRise" status("off")) ("SwitchDelay" status("on")) ("SwitchDelayFall" status("off")) ("SwitchDelayRise" status("off"))) ("Crosstalk" ("Crosstalk" status("on"))) ("Custom")) (VectorSets) (Props (XnetName "SGPIO_BMC_CLK") (allDrivers "active") (customSimType "Reflection") (ftsMode ("Typ")) (rcvrSelect "all") (tlineDelayMode "time") (userRevision "1.0")))) (Subckts) (CrossSections ("CRESCENT_CITY_195_20150129_6PIN" (Props (SXDesignName "CRESCENT_CITY_195_20150129_6PIN")) (Layers ("" (layerType "SURFACE") (material "AIR") (thickness "0 mil") (dielectricConstant "1.000000") (lossTangent "0") (etchFactor "0.000000") (elecCondVal "0 mho/cm") (thermCondVal "0 w/cm-degC")) ("" (layerType "DIELECTRIC") (material "CONFORMAL_COAT") (thickness "0.5 mil") (dielectricConstant "3.800000") (lossTangent "0.035") (etchFactor "0.000000") (elecCondVal "0 mho/cm") (thermCondVal "0.012 w/cm-degC")) ("TOP" (layerType "CONDUCTOR") (material "COPPER") (thickness "  2.100000 mil") (width "4.00 MIL") (dielectricConstant "4.500000") (lossTangent "0") (etchFactor "70.000000") (elecCondVal "595900.000000 mho/cm") (thermCondVal "0 w/cm-degC") (signalDieConstant "3.800000") (signalLossTangent "0.035")) ("" (layerType "DIELECTRIC") (material "FR-4") (thickness "  2.670000 mil") (dielectricConstant "4.000000") (lossTangent "0.035") (etchFactor "0.000000") (elecCondVal "0 mho/cm") (thermCondVal "0.012 w/cm-degC")) ("L2_GND1" (layerType "PLANE") (material "COPPER") (isShield t) (thickness "  1.250000 mil") (dielectricConstant "4.500000") (lossTangent "0.035") (etchFactor "90.000000") (elecCondVal "595900.000000 mho/cm") (thermCondVal "0.012 w/cm-degC")) ("" (layerType "DIELECTRIC") (material "FR-4") (thickness "  9.000000 mil") (dielectricConstant "4.100000") (lossTangent "0.035") (etchFactor "0.000000") (elecCondVal "0 mho/cm") (thermCondVal "0.012 w/cm-degC")) ("L3_SIG1" (layerType "CONDUCTOR") (material "COPPER") (thickness "  1.250000 mil") (width "4.00 MIL") (dielectricConstant "4.500000") (lossTangent "0.035") (etchFactor "90.000000") (elecCondVal "595900.000000 mho/cm") (thermCondVal "0.012 w/cm-degC") (signalDieConstant "4.100000") (signalLossTangent "0.035")) ("" (layerType "DIELECTRIC") (material "FR-4") (thickness "  3.000000 mil") (dielectricConstant "4.500000") (lossTangent "0.035") (etchFactor "0.000000") (elecCondVal "0 mho/cm") (thermCondVal "0 w/cm-degC")) ("L4_GND2" (layerType "PLANE") (material "COPPER") (isShield t) (thickness "  1.250000 mil") (dielectricConstant "4.500000") (lossTangent "0.035") (etchFactor "90.000000") (elecCondVal "595900.000000 mho/cm") (thermCondVal "0 w/cm-degC")) ("" (layerType "DIELECTRIC") (material "FR-4") (thickness "  9.000000 mil") (dielectricConstant "4.000000") (lossTangent "0.035") (etchFactor "0.000000") (elecCondVal "0 mho/cm") (thermCondVal "0.012 w/cm-degC")) ("L5_SIG2" (layerType "CONDUCTOR") (material "COPPER") (thickness "  1.250000 mil") (width "4.00 MIL") (dielectricConstant "4.500000") (lossTangent "0.035") (etchFactor "90.000000") (elecCondVal "595900.000000 mho/cm") (thermCondVal "0.012 w/cm-degC") (signalDieConstant "4.000000") (signalLossTangent "0.035")) ("" (layerType "DIELECTRIC") (material "FR-4") (thickness "  3.000000 mil") (dielectricConstant "4.500000") (lossTangent "0.035") (etchFactor "0.000000") (elecCondVal "0 mho/cm") (thermCondVal "0 w/cm-degC")) ("L6_GND3" (layerType "PLANE") (material "COPPER") (isShield t) (thickness "  1.250000 mil") (dielectricConstant "4.500000") (lossTangent "0.035") (etchFactor "90.000000") (elecCondVal "595900.000000 mho/cm") (thermCondVal "0 w/cm-degC")) ("" (layerType "DIELECTRIC") (material "FR-4") (thickness "  4.500000 mil") (dielectricConstant "4.100000") (lossTangent "0.035") (etchFactor "0.000000") (elecCondVal "0 mho/cm") (thermCondVal "0.012 w/cm-degC")) ("L7_PWR1-SIG" (layerType "PLANE") (material "COPPER") (isShield t) (thickness "  2.400000 mil") (dielectricConstant "4.500000") (lossTangent "0.035") (etchFactor "90.000000") (elecCondVal "595900.000000 mho/cm") (thermCondVal "0.012 w/cm-degC")) ("" (layerType "DIELECTRIC") (material "FR-4") (thickness "  4.600000 mil") (dielectricConstant "4.000000") (lossTangent "0.035") (etchFactor "0.000000") (elecCondVal "0 mho/cm") (thermCondVal "0.012 w/cm-degC")) ("L8_PWR2-SIG" (layerType "PLANE") (material "COPPER") (isShield t) (thickness "  2.400000 mil") (dielectricConstant "4.500000") (lossTangent "0.035") (etchFactor "90.000000") (elecCondVal "595900.000000 mho/cm") (thermCondVal "0.012 w/cm-degC")) ("" (layerType "DIELECTRIC") (material "FR-4") (thickness "  4.500000 mil") (dielectricConstant "4.500000") (lossTangent "0.035") (etchFactor "0.000000") (elecCondVal "0 mho/cm") (thermCondVal "0 w/cm-degC")) ("L9_GND4" (layerType "PLANE") (material "COPPER") (isShield t) (thickness "  1.250000 mil") (dielectricConstant "4.500000") (lossTangent "0.035") (etchFactor "90.000000") (elecCondVal "595900.000000 mho/cm") (thermCondVal "0 w/cm-degC")) ("" (layerType "DIELECTRIC") (material "FR-4") (thickness "  3.000000 mil") (dielectricConstant "4.100000") (lossTangent "0.035") (etchFactor "0.000000") (elecCondVal "0 mho/cm") (thermCondVal "0.012 w/cm-degC")) ("L10_SIG3" (layerType "CONDUCTOR") (material "COPPER") (thickness "  1.250000 mil") (width "4.00 MIL") (dielectricConstant "4.500000") (lossTangent "0.035") (etchFactor "90.000000") (elecCondVal "595900.000000 mho/cm") (thermCondVal "0.012 w/cm-degC") (signalDieConstant "4.100000") (signalLossTangent "0.035")) ("" (layerType "DIELECTRIC") (material "FR-4") (thickness "  9.000000 mil") (dielectricConstant "4.500000") (lossTangent "0.035") (etchFactor "0.000000") (elecCondVal "0 mho/cm") (thermCondVal "0 w/cm-degC")) ("L11_GND5" (layerType "PLANE") (material "COPPER") (isShield t) (thickness "  1.250000 mil") (dielectricConstant "4.500000") (lossTangent "0.035") (etchFactor "90.000000") (elecCondVal "595900.000000 mho/cm") (thermCondVal "0 w/cm-degC")) ("" (layerType "DIELECTRIC") (material "FR-4") (thickness "  3.000000 mil") (dielectricConstant "4.500000") (lossTangent "0.035") (etchFactor "0.000000") (elecCondVal "0 mho/cm") (thermCondVal "0.012 w/cm-degC")) ("L12_SIG4" (layerType "CONDUCTOR") (material "COPPER") (thickness "  1.250000 mil") (width "4.00 MIL") (dielectricConstant "4.500000") (lossTangent "0.035") (etchFactor "90.000000") (elecCondVal "595900.000000 mho/cm") (thermCondVal "0.012 w/cm-degC") (signalDieConstant "4.500000") (signalLossTangent "0.035")) ("" (layerType "DIELECTRIC") (material "FR-4") (thickness "  9.000000 mil") (dielectricConstant "4.500000") (lossTangent "0.035") (etchFactor "0.000000") (elecCondVal "0 mho/cm") (thermCondVal "0 w/cm-degC")) ("L13_GND6" (layerType "PLANE") (material "COPPER") (isShield t) (thickness "  1.250000 mil") (dielectricConstant "4.500000") (lossTangent "0.035") (etchFactor "90.000000") (elecCondVal "595900.000000 mho/cm") (thermCondVal "0.012 w/cm-degC")) ("" (layerType "DIELECTRIC") (material "FR-4") (thickness "  2.670000 mil") (dielectricConstant "4.500000") (lossTangent "0.035") (etchFactor "0.000000") (elecCondVal "0 mho/cm") (thermCondVal "0.012 w/cm-degC")) ("BOTTOM" (layerType "CONDUCTOR") (material "COPPER") (thickness "  2.100000 mil") (width "4.00 MIL") (dielectricConstant "4.500000") (lossTangent "0") (etchFactor "70.000000") (elecCondVal "595900.000000 mho/cm") (thermCondVal "0 w/cm-degC") (signalDieConstant "3.800000") (signalLossTangent "0.035")) ("" (layerType "DIELECTRIC") (material "CONFORMAL_COAT") (thickness "0.5 mil") (dielectricConstant "3.800000") (lossTangent "0.035") (etchFactor "0.000000") (elecCondVal "0 mho/cm") (thermCondVal "0.012 w/cm-degC")) ("" (layerType "SURFACE") (material "AIR") (thickness "0 mil") (dielectricConstant "1.000000") (lossTangent "0") (etchFactor "0.000000") (elecCondVal "0 mho/cm") (thermCondVal "0 w/cm-degC"))))) (Props (DesUnits "mils 2") (LayerStack ("DIELECTRIC" "DIELECTRIC" "BOTTOM" "DIELECTRIC" "L13_GND6" "DIELECTRIC" "L12_SIG4" "DIELECTRIC" "L11_GND5" "DIELECTRIC" "L10_SIG3" "DIELECTRIC" "L9_GND4" "DIELECTRIC" "L8_PWR2-SIG" "DIELECTRIC" "L7_PWR1-SIG" "DIELECTRIC" "L6_GND3" "DIELECTRIC" "L5_SIG2" "DIELECTRIC" "L4_GND2" "DIELECTRIC" "L3_SIG1" "DIELECTRIC" "L2_GND1" "DIELECTRIC" "TOP" "DIELECTRIC" "DIELECTRIC")) (Revision "16.600")) (Params (DiffOutputPkg ((temperature "27") (bufferModelNonInverting "CDSDefaultOutput_2p5v") (bufferModelInverting "CDSDefaultOutput_2p5v") (stimuli nil) (offsets nil) (state "tristate") (cycle "1") (termMap nil) (setup "0.9e-09") (hold "0.4e-09") (rise nil) (fall nil) (threshOutputHighMin "2.375  V") (threshOutputHighTyp "2.5  V") (threshOutputHighMax "2.625  V") (threshOutputLowMin "1.275  V") (threshOutputLowTyp "1.7  V") (threshOutputLowMax "1.985  V") (mappingTagNonInverting nil) (mappingTagInverting nil) (spice nil))) (HiClampTerm ((cutoffVoltage "0.7 V") (voltage "5 V") (maxDelay "0.1 ns"))) (LowClampTerm ((cutoffVoltage "0.7 V") (voltage "0 V") (maxDelay "0.1 ns"))) (DiffOutput ((temperature "27") (bufferModelNonInverting "CDSDefaultOutput_2p5v") (bufferModelInverting "CDSDefaultOutput_2p5v") (stimuli nil) (offsets nil) (state "tristate") (cycle "1") (termMap nil) (setup "0.9e-09") (hold "0.4e-09") (rise nil) (fall nil) (threshOutputHighMin "2.375  V") (threshOutputHighTyp "2.5  V") (threshOutputHighMax "2.625  V") (threshOutputLowMin "1.275  V") (threshOutputLowTyp "1.7  V") (threshOutputLowMax "1.985  V") (mappingTagNonInverting nil) (mappingTagInverting nil) (spice nil))) (Via ((model "Unknown") (viaOutputFormat "Unknown") (viaPadstack nil) (viaTopLayer nil) (viaBottomLayer nil) (viaIsPower nil) (viaIsGround nil))) (Resistor ((resistance "50 ohm") (orientation "0"))) (RCTerm ((resistance "50 ohm") (capacitance "20 pF") (voltage "5 V") (maxDelay "0.1 ns"))) (DiffIOPkg ((temperature "27") (bufferModelNonInverting "CDSDefaultIO_2p5v") (bufferModelInverting "CDSDefaultIO_2p5v") (stimuli nil) (offsets nil) (state "tristate") (cycle "1") (termMap nil) (setup "0.9e-09") (hold "0.4e-09") (rise nil) (fall nil) (threshInputHighMin "1.7 V") (threshInputHighTyp "1.7  V") (threshInputHighMax "1.7  V") (threshInputLowMin "0.7  V") (threshInputLowTyp "0.7  V") (threshInputLowMax "0.7 ") (threshOutputHighMin "2.365  V") (threshOutputHighTyp "2.5  V") (threshOutputHighMax "2.625  V") (threshOutputLowMin "1.275  V") (threshOutputLowTyp "1.7  V") (threshOutputLowMax "1.985  V") (mappingTagNonInverting nil) (mappingTagInverting nil) (spice nil))) (Trace ((d1Thickness "10 mil") (d1Constant "4.5") (d1LossTangent "0.035") (d2Thickness "10 mil") (d2Constant "4.5") (d2LossTangent "0.035") (d3Thickness "0.0") (d3Constant "1.0") (d3LossTangent "0") length("1000 mil") (spacing "5 mil") (spacing2 "5 mil") (spacing3 "5 mil") (spacing4 "5 mil") (spacing5 "5 mil") (traceConductivity "595900 mho/cm") (traceGeometry "microstrip") (traceLayerName "") (traceThickness "0.72 mil") (traceType "single") (traceWidth "5.0 mil") (traceWidth2 "5.0 mil") (traceWidth3 "5.0 mil") (traceWidth4 "5.0 mil") (traceWidth5 "5.0 mil") (traceWidth6 "5.0 mil") (offset "0 mil") (traceCount "1") (impedance nil))) (TheveninTerm ((resistanceUp "180 ohm") (resistanceDown "270 ohm") (voltageUp "5 V") (voltageDown "0 V") (maxDelay "0.1 ns"))) (DiffIO ((temperature "27") (bufferModelNonInverting "CDSDefaultIO_2p5v") (bufferModelInverting "CDSDefaultIO_2p5v") (stimuli nil) (offsets nil) (state "tristate") (cycle "1") (termMap nil) (setup "0.9e-09") (hold "0.4e-09") (rise nil) (fall nil) (threshInputHighMin "1.7 V") (threshInputHighTyp "1.7  V") (threshInputHighMax "1.7  V") (threshInputLowMin "0.7  V") (threshInputLowTyp "0.7  V") (threshInputLowMax "0.7 ") (threshOutputHighMin "2.365  V") (threshOutputHighTyp "2.5  V") (threshOutputHighMax "2.625  V") (threshOutputLowMin "1.275  V") (threshOutputLowTyp "1.7  V") (threshOutputLowMax "1.985  V") (mappingTagNonInverting nil) (mappingTagInverting nil) (spice nil))) (ShuntTerm ((resistance "50 ohm") (voltage "5 V") (maxDelay "0.1 ns"))) (Inductor ((inductance "5 nH") (orientation "0"))) (Capacitor ((capacitance "10 pF") (orientation "0"))) (RLGC (length("1000 mil"))) (Source ((voltage "5 V"))) (DiffInput ((temperature "27") (bufferModelNonInverting "CDSDefaultInput_2p5v") (bufferModelInverting "CDSDefaultInput_2p5v") (threshInputHighMin "1.7 V") (threshInputHighTyp "1.7  V") (threshInputHighMax "1.7  V") (threshInputLowMin "0.7  V") (threshInputLowTyp "0.7  V") (threshInputLowMax "0.7  V") (mappingTagNonInverting nil) (mappingTagInverting nil) (cycle "1"))) (CPW ((d1Thickness "10 mil") (d1Constant "4.5") (d1LossTangent "0.035") (d2Thickness "0.72 mil") (d2Constant "1") (d2LossTangent "0") (d3Thickness "0.0") (d3Constant "1") (d3LossTangent "0") length("1000 mil") (spacing "5 mil") (spacing2 "5 mil") (spacing3 "5 mil") (spacing4 "5 mil") (spacing5 "5 mil") (traceConductivity "595900 mho/cm") (traceGeometry "cpwms") (traceLayerName "") (traceThickness "0.72 mil") (traceType "single") (traceWidth "5.0 mil") (traceWidth2 "5.0 mil") (traceWidth3 "5.0 mil") (traceWidth4 "5.0 mil") (traceWidth5 "5.0 mil") (traceWidth6 "5.0 mil") (offset "0 mil") (traceCount "1") (impedance nil))) (Cable (length("1 m"))) (CPWMS ((d1Thickness "10 mil") (d1Constant "4.5") (d1LossTangent "0.035") (d2Thickness "0.72 mil") (d2Constant "4.5") (d2LossTangent "0.035") (d3Thickness "0.0") (d3Constant "1") (d3LossTangent "0") length("1000 mil") (spacing "5 mil") (spacing2 "5 mil") (spacing3 "5 mil") (spacing4 "5 mil") (spacing5 "5 mil") (traceConductivity "595900 mho/cm") (traceGeometry "cpwms") (traceLayerName "") (traceThickness "0.72 mil") (traceType "single") (traceWidth "5.0 mil") (traceWidth2 "5.0 mil") (traceWidth3 "5.0 mil") (traceWidth4 "5.0 mil") (traceWidth5 "5.0 mil") (traceWidth6 "5.0 mil") (offset "0 mil") (traceCount "1") (impedance nil))) (CPWSL ((d1Thickness "10 mil") (d1Constant "4.5") (d1LossTangent "0.035") (d2Thickness "0.72 mil") (d2Constant "4.5") (d2LossTangent "0.035") (d3Thickness "10 mil") (d3Constant "4.5") (d3LossTangent "0.035") length("1000 mil") (spacing "5 mil") (spacing2 "5 mil") (spacing3 "5 mil") (spacing4 "5 mil") (spacing5 "5 mil") (traceConductivity "595900 mho/cm") (traceGeometry "cpwms") (traceLayerName "") (traceThickness "0.72 mil") (traceType "single") (traceWidth "5.0 mil") (traceWidth2 "5.0 mil") (traceWidth3 "5.0 mil") (traceWidth4 "5.0 mil") (traceWidth5 "5.0 mil") (traceWidth6 "5.0 mil") (offset "0 mil") (traceCount "1") (impedance nil))) (ESpiceDevice nil) (Diode ((cutoffVoltage "0.7 V"))) (DualClampTerm ((cutoffVoltageUp "0.7 V") (cutoffVoltageDown "0.7 V") (voltageUp "5 V") (voltageDown "0 V") (maxDelay "0.1 ns"))) (IbisOutputPkg ((temperature "27") (bufferModel "CDSDefaultOutput_2p5v") (stimuli nil) (offsets nil) (state "tristate") (cycle "1") (termMap nil) (setup "2.0e-09") (hold "1.0e-09") (rise nil) (fall nil) (macroType nil) (voltage nil) (spice nil) (LEFDEFPinName nil) (LEFDEFPinType nil) (mappingTag nil))) (IbisIO_OpenPullDown ((temperature "27") (bufferModel "CDSDefaultIO_2p5v") (stimuli nil) (offsets nil) (state "tristate") (cycle "1") (termMap nil) (setup "2.0e-09") (hold "1.0e-09") (rise nil) (fall nil) (macroType nil) (voltage nil) (spice nil) (LEFDEFPinName nil) (LEFDEFPinType nil) (mappingTag nil))) (IbisInputPkg ((temperature "27") (bufferModel "CDSDefaultInput_2p5v") (cycle "1") (LEFDEFPinName nil) (LEFDEFPinType nil) (mappingTag nil))) (IbisIOMacro ((temperature "27") (bufferModel "CDSDefaultIO_2p5v") (stimuli nil) (offsets nil) (state "tristate") (cycle "1") (termMap nil) (setup "2.0e-09") (hold "1.0e-09") (rise nil) (fall nil) (macroType nil) (voltage nil) (spice nil) (LEFDEFPinName nil) (LEFDEFPinType nil) (mappingTag nil))) (IbisIO_OpenPullUp ((temperature "27") (bufferModel "CDSDefaultIO_2p5v") (stimuli nil) (offsets nil) (state "tristate") (cycle "1") (termMap nil) (setup "2.0e-09") (hold "1.0e-09") (rise nil) (fall nil) (macroType nil) (voltage nil) (spice nil) (LEFDEFPinName nil) (LEFDEFPinType nil) (mappingTag nil))) (IbisIOPkg ((temperature "27") (bufferModel "CDSDefaultIO_2p5v") (stimuli nil) (offsets nil) (state "tristate") (cycle "1") (termMap nil) (setup "2.0e-09") (hold "1.0e-09") (rise nil) (fall nil) (macroType nil) (voltage nil) (spice nil) (LEFDEFPinName nil) (LEFDEFPinType nil) (mappingTag nil))) (clocked ((clockRise "1e-09") (clockFall "1e-09") (clockFreq "100e6") (clockInitState "0") (clockDutyCycle "0.5") (clockJitter "0"))) (periodic ((periodicFreq "100e6") (periodicPattern "10") (periodicJitter "0"))) (IbisIO ((temperature "27") (bufferModel "CDSDefaultIO_2p5v") (stimuli nil) (offsets nil) (state "tristate") (cycle "1") (termMap nil) (setup "2.0e-09") (hold "1.0e-09") (rise nil) (fall nil) (macroType nil) (voltage nil) (spice nil) (LEFDEFPinName nil) (LEFDEFPinType nil) (mappingTag nil))) (async ((asyncTimePoints "") (asyncInitState "1"))) (IbisOutput ((temperature "27") (bufferModel "CDSDefaultOutput_2p5v") (stimuli nil) (offsets nil) (state "tristate") (cycle "1") (termMap nil) (setup "2.0e-09") (hold "1.0e-09") (rise nil) (fall nil) (macroType nil) (voltage nil) (spice nil) (LEFDEFPinName nil) (LEFDEFPinType nil) (mappingTag nil))) (TLine ((diffImpedance "100ohm") (diffVelocity "1.4142e+08M/s") (impedance "60ohm") length("2800 mil") (propDelay "0.5 ns") (velocity "5600 mil/ns") (traceCount "1") (traceGeometry "Microstrip") (impedanceMin nil) (impedanceMax nil) (lengthMin nil) (lengthMax nil) (propDelayMin nil) (propDelayMax nil) (impedanceSweepCount nil) (propDelaySweepCount nil) (velocitySweepCount nil) (lengthSweepCount nil) (matchSetName nil))) (CurrentProbe nil) (IbisInput ((temperature "27") (bufferModel "CDSDefaultInput_2p5v") (cycle "1") (LEFDEFPinName nil) (LEFDEFPinType nil) (mappingTag nil))) (SeriesTerm ((resistance "22 ohm") (maxDelay "0.1 ns"))) (Connector nil) (sync ((syncFreq "100e6") (syncInitState "1") (syncPattern "10") (syncEdgeSwitch "rise"))) (IbisOutput_OpenPullUp ((temperature "27") (bufferModel "CDSDefaultOutput_2p5v") (stimuli nil) (offsets nil) (state "tristate") (cycle "1") (termMap nil) (setup "2.0e-09") (hold "1.0e-09") (rise nil) (fall nil) (macroType nil) (voltage nil) (spice nil) (LEFDEFPinName nil) (LEFDEFPinType nil) (mappingTag nil))) (DiffInputPkg ((temperature "27") (bufferModelNonInverting "CDSDefaultInput_2p5v") (bufferModelInverting "CDSDefaultInput_2p5v") (threshInputHighMin "1.7 V") (threshInputHighTyp "1.7  V") (threshInputHighMax "1.7  V") (threshInputLowMin "0.7  V") (threshInputLowTyp "0.7  V") (threshInputLowMax "0.7  V") (mappingTagNonInverting nil) (mappingTagInverting nil) (cycle "1"))) (idlCircuit ((allDrivers "active") (ftsMode '("Typ")) (rcvrSelect "all") (simMode "Reflection") (tlineDelayMode "time") (userRevision "1.0") (autoSolve "On")))))
				)
				( objectStatus "SGPIO_BMC" )
			)
			( electricalCSet "@crescent_city_bb_fab1_lib.crescent_city_bb_fab1(sch_1):\SGPIO_BMC_DI\"
				( groupRef "SGPIO_BMC_DI:MG_SGPIO_BMC" )
				( pinPairRef "SGPIO_BMC_DI:R2R6.2:U9F4.J3" )
				( pinPairRef "SGPIO_BMC_DI:U8D7.F8:R2R6.1" )
				( attribute "TOPOLOGY_TEMPLATE_REVISION" "1.0"
					( Origin gBackEnd )
				)
				( topologyData 23333
(SKIDL (Circuits ("MAIN" (Parts ("CRESCENT_CITY_195_20150129_6PIN.@@U47.J3" IbisIOPkg (xy (5521 4228)) (refDes "U9F4") (model "Unknown") (Props (_SXDesignName "CRESCENT_CITY_195_20150129_6PIN") (brdx "17839.26 MIL") (brdy "551.28 MIL") (bufferModel "CDSDefaultIO_2p5v") (cycle "1") (hold "1.0e-09") (mappingTag "") (offsets ("4" "0") ("5" "0")) (setup "2.0e-09") (state "tristate") (stimuli ("4" "local18") ("5" "local19")) (temperature "27") (termMap ("4" "Data") ("5" "Enable"))) (Terms ("CRESCENT_CITY_195_20150129_6PIN.X1783926Y55128L2LRATS" "J3"))) ("CRESCENT_CITY_195_20150129_6PIN.@@U4E2.F8" IbisIOPkg (xy (5502 4240)) (refDes "U8D7") (model "Unknown") (Props (_SXDesignName "CRESCENT_CITY_195_20150129_6PIN") (brdx "15375.75 MIL") (brdy "2521.26 MIL") (bufferModel "CDSDefaultIO_2p5v") (cycle "1") (hold "1.0e-09") (mappingTag "") (offsets ("4" "0") ("5" "0")) (setup "2.0e-09") (state "tristate") (stimuli ("4" "local20") ("5" "local21")) (temperature "27") (termMap ("4" "Data") ("5" "Enable"))) (Terms ("CRESCENT_CITY_195_20150129_6PIN.X1537575Y252126L2LRATS" "F8"))) ("CRESCENT_CITY_195_20150129_6PIN.T@@RATS@@U4E2.F8@@R62.1" TLine (xy (5503 4229)) (mirror x) (refDes "TL12") (Props (_SXDesignName "CRESCENT_CITY_195_20150129_6PIN") (impedance "49.728 ohm") length("329.51 MIL") (propDelay "0.05918 ns") (traceCount "1") (traceGeometry "Microstrip") (velocity "5567.91 mil/ns")) (Terms ("CRESCENT_CITY_195_20150129_6PIN.X1537575Y252126L2LRATS" "1") ("CRESCENT_CITY_195_20150129_6PIN.X1570400Y252000L28LRATS" "2"))) ("CRESCENT_CITY_195_20150129_6PIN.T@@RATS@@R62.2@@U47.J3" TLine (xy (5512 4223)) (refDes "TL13") (Props (_SXDesignName "CRESCENT_CITY_195_20150129_6PIN") (impedance "50.521 ohm") length("4068.98 MIL") (propDelay "0.73082 ns") (traceCount "1") (traceGeometry "Microstrip") (velocity "5567.68 mil/ns")) (Terms ("CRESCENT_CITY_195_20150129_6PIN.X1570400Y248500L28LRATS" "1") ("CRESCENT_CITY_195_20150129_6PIN.X1783926Y55128L2LRATS" "2"))) ("CRESCENT_CITY_195_20150129_6PIN.@@R62.2.1" Resistor (xy (5497 4223)) (mirror x) (refDes "R2R6") (value "51 Ohm") (Props (_SXDesignName "CRESCENT_CITY_195_20150129_6PIN")) (Terms ("CRESCENT_CITY_195_20150129_6PIN.X1570400Y248500L28LRATS" "2") ("CRESCENT_CITY_195_20150129_6PIN.X1570400Y252000L28LRATS" "1")))) (Nodes ("CRESCENT_CITY_195_20150129_6PIN.X1570400Y252000L28LRATS" (terms "CRESCENT_CITY_195_20150129_6PIN.@@R62.2.1.2" "CRESCENT_CITY_195_20150129_6PIN.T@@RATS@@U4E2.F8@@R62.1.2")) ("CRESCENT_CITY_195_20150129_6PIN.X1570400Y248500L28LRATS" (terms "CRESCENT_CITY_195_20150129_6PIN.@@R62.2.1.1" "CRESCENT_CITY_195_20150129_6PIN.T@@RATS@@R62.2@@U47.J3.1")) ("CRESCENT_CITY_195_20150129_6PIN.X1537575Y252126L2LRATS" (terms "CRESCENT_CITY_195_20150129_6PIN.T@@RATS@@U4E2.F8@@R62.1.1" "CRESCENT_CITY_195_20150129_6PIN.@@U4E2.F8.1")) ("CRESCENT_CITY_195_20150129_6PIN.X1783926Y55128L2LRATS" (terms "CRESCENT_CITY_195_20150129_6PIN.T@@RATS@@R62.2@@U47.J3.2" "CRESCENT_CITY_195_20150129_6PIN.@@U47.J3.1"))) (Ports) (Stimuli ("local20" (scope local) (stimType periodic) (Props (periodicFreq "5e+007") (periodicJitter "0") (periodicPattern "1"))) ("local21" (scope local) (stimType periodic) (Props (periodicFreq "5e+007") (periodicJitter "0") (periodicPattern "1"))) ("local18" (scope local) (stimType periodic) (Props (periodicFreq "5e+007") (periodicJitter "0") (periodicPattern "1"))) ("local19" (scope local) (stimType periodic) (Props (periodicFreq "5e+007") (periodicJitter "0") (periodicPattern "1")))) (Notes) (Constraints ("DELAY_RULE" ("CRESCENT_CITY_195_20150129_6PIN R62.2" "CRESCENT_CITY_195_20150129_6PIN U47.J3" "LENGTH" "0.0254" "LENGTH" "0.381") ("CRESCENT_CITY_195_20150129_6PIN U4E2.F8" "CRESCENT_CITY_195_20150129_6PIN R62.1" "LENGTH" "0.00254" "LENGTH" "0.0508"))) (MeasurementSets ("EMI" ("EMIStatus" status("on")) ("PeakEmission" status("on")) ("PeakFrequency" status("on")) ("PulseFreq" status("on")) ("RiseTime" status("on")) ("VoltageSwing" status("on"))) ("Reflection" ("BufferDelayFall" status("off")) ("BufferDelayRise" status("off")) ("EyeHeight" status("off")) ("EyeJitter" status("off")) ("EyeWidth" status("off")) ("FirstIncidentFall" status("off")) ("FirstIncidentRise" status("off")) ("Glitch" status("on")) ("GlitchFall" status("off")) ("GlitchRise" status("off")) ("Monotonic" status("on")) ("MonotonicFall" status("off")) ("MonotonicRise" status("off")) ("NoiseMargin" status("on")) ("NoiseMarginHigh" status("off")) ("NoiseMarginLow" status("off")) ("OvershootHigh" status("on")) ("OvershootLow" status("on")) ("PropDelay" status("on")) ("SettleDelay" status("on")) ("SettleDelayFall" status("off")) ("SettleDelayRise" status("off")) ("SwitchDelay" status("on")) ("SwitchDelayFall" status("off")) ("SwitchDelayRise" status("off"))) ("Crosstalk" ("Crosstalk" status("on"))) ("Custom")) (VectorSets) (Props (XnetName "SGPIO_BMC_DIN") (allDrivers "active") (customSimType "Reflection") (ftsMode ("Typ")) (rcvrSelect "all") (tlineDelayMode "time") (userRevision "1.0")))) (Subckts) (CrossSections ("CRESCENT_CITY_195_20150129_6PIN" (Props (SXDesignName "CRESCENT_CITY_195_20150129_6PIN")) (Layers ("" (layerType "SURFACE") (material "AIR") (thickness "0 mil") (dielectricConstant "1.000000") (lossTangent "0") (etchFactor "0.000000") (elecCondVal "0 mho/cm") (thermCondVal "0 w/cm-degC")) ("" (layerType "DIELECTRIC") (material "CONFORMAL_COAT") (thickness "0.5 mil") (dielectricConstant "3.800000") (lossTangent "0.035") (etchFactor "0.000000") (elecCondVal "0 mho/cm") (thermCondVal "0.012 w/cm-degC")) ("TOP" (layerType "CONDUCTOR") (material "COPPER") (thickness "  2.100000 mil") (width "4.00 MIL") (dielectricConstant "4.500000") (lossTangent "0") (etchFactor "70.000000") (elecCondVal "595900.000000 mho/cm") (thermCondVal "0 w/cm-degC") (signalDieConstant "3.800000") (signalLossTangent "0.035")) ("" (layerType "DIELECTRIC") (material "FR-4") (thickness "  2.670000 mil") (dielectricConstant "4.000000") (lossTangent "0.035") (etchFactor "0.000000") (elecCondVal "0 mho/cm") (thermCondVal "0.012 w/cm-degC")) ("L2_GND1" (layerType "PLANE") (material "COPPER") (isShield t) (thickness "  1.250000 mil") (dielectricConstant "4.500000") (lossTangent "0.035") (etchFactor "90.000000") (elecCondVal "595900.000000 mho/cm") (thermCondVal "0.012 w/cm-degC")) ("" (layerType "DIELECTRIC") (material "FR-4") (thickness "  9.000000 mil") (dielectricConstant "4.100000") (lossTangent "0.035") (etchFactor "0.000000") (elecCondVal "0 mho/cm") (thermCondVal "0.012 w/cm-degC")) ("L3_SIG1" (layerType "CONDUCTOR") (material "COPPER") (thickness "  1.250000 mil") (width "4.00 MIL") (dielectricConstant "4.500000") (lossTangent "0.035") (etchFactor "90.000000") (elecCondVal "595900.000000 mho/cm") (thermCondVal "0.012 w/cm-degC") (signalDieConstant "4.100000") (signalLossTangent "0.035")) ("" (layerType "DIELECTRIC") (material "FR-4") (thickness "  3.000000 mil") (dielectricConstant "4.500000") (lossTangent "0.035") (etchFactor "0.000000") (elecCondVal "0 mho/cm") (thermCondVal "0 w/cm-degC")) ("L4_GND2" (layerType "PLANE") (material "COPPER") (isShield t) (thickness "  1.250000 mil") (dielectricConstant "4.500000") (lossTangent "0.035") (etchFactor "90.000000") (elecCondVal "595900.000000 mho/cm") (thermCondVal "0 w/cm-degC")) ("" (layerType "DIELECTRIC") (material "FR-4") (thickness "  9.000000 mil") (dielectricConstant "4.000000") (lossTangent "0.035") (etchFactor "0.000000") (elecCondVal "0 mho/cm") (thermCondVal "0.012 w/cm-degC")) ("L5_SIG2" (layerType "CONDUCTOR") (material "COPPER") (thickness "  1.250000 mil") (width "4.00 MIL") (dielectricConstant "4.500000") (lossTangent "0.035") (etchFactor "90.000000") (elecCondVal "595900.000000 mho/cm") (thermCondVal "0.012 w/cm-degC") (signalDieConstant "4.000000") (signalLossTangent "0.035")) ("" (layerType "DIELECTRIC") (material "FR-4") (thickness "  3.000000 mil") (dielectricConstant "4.500000") (lossTangent "0.035") (etchFactor "0.000000") (elecCondVal "0 mho/cm") (thermCondVal "0 w/cm-degC")) ("L6_GND3" (layerType "PLANE") (material "COPPER") (isShield t) (thickness "  1.250000 mil") (dielectricConstant "4.500000") (lossTangent "0.035") (etchFactor "90.000000") (elecCondVal "595900.000000 mho/cm") (thermCondVal "0 w/cm-degC")) ("" (layerType "DIELECTRIC") (material "FR-4") (thickness "  4.500000 mil") (dielectricConstant "4.100000") (lossTangent "0.035") (etchFactor "0.000000") (elecCondVal "0 mho/cm") (thermCondVal "0.012 w/cm-degC")) ("L7_PWR1-SIG" (layerType "PLANE") (material "COPPER") (isShield t) (thickness "  2.400000 mil") (dielectricConstant "4.500000") (lossTangent "0.035") (etchFactor "90.000000") (elecCondVal "595900.000000 mho/cm") (thermCondVal "0.012 w/cm-degC")) ("" (layerType "DIELECTRIC") (material "FR-4") (thickness "  4.600000 mil") (dielectricConstant "4.000000") (lossTangent "0.035") (etchFactor "0.000000") (elecCondVal "0 mho/cm") (thermCondVal "0.012 w/cm-degC")) ("L8_PWR2-SIG" (layerType "PLANE") (material "COPPER") (isShield t) (thickness "  2.400000 mil") (dielectricConstant "4.500000") (lossTangent "0.035") (etchFactor "90.000000") (elecCondVal "595900.000000 mho/cm") (thermCondVal "0.012 w/cm-degC")) ("" (layerType "DIELECTRIC") (material "FR-4") (thickness "  4.500000 mil") (dielectricConstant "4.500000") (lossTangent "0.035") (etchFactor "0.000000") (elecCondVal "0 mho/cm") (thermCondVal "0 w/cm-degC")) ("L9_GND4" (layerType "PLANE") (material "COPPER") (isShield t) (thickness "  1.250000 mil") (dielectricConstant "4.500000") (lossTangent "0.035") (etchFactor "90.000000") (elecCondVal "595900.000000 mho/cm") (thermCondVal "0 w/cm-degC")) ("" (layerType "DIELECTRIC") (material "FR-4") (thickness "  3.000000 mil") (dielectricConstant "4.100000") (lossTangent "0.035") (etchFactor "0.000000") (elecCondVal "0 mho/cm") (thermCondVal "0.012 w/cm-degC")) ("L10_SIG3" (layerType "CONDUCTOR") (material "COPPER") (thickness "  1.250000 mil") (width "4.00 MIL") (dielectricConstant "4.500000") (lossTangent "0.035") (etchFactor "90.000000") (elecCondVal "595900.000000 mho/cm") (thermCondVal "0.012 w/cm-degC") (signalDieConstant "4.100000") (signalLossTangent "0.035")) ("" (layerType "DIELECTRIC") (material "FR-4") (thickness "  9.000000 mil") (dielectricConstant "4.500000") (lossTangent "0.035") (etchFactor "0.000000") (elecCondVal "0 mho/cm") (thermCondVal "0 w/cm-degC")) ("L11_GND5" (layerType "PLANE") (material "COPPER") (isShield t) (thickness "  1.250000 mil") (dielectricConstant "4.500000") (lossTangent "0.035") (etchFactor "90.000000") (elecCondVal "595900.000000 mho/cm") (thermCondVal "0 w/cm-degC")) ("" (layerType "DIELECTRIC") (material "FR-4") (thickness "  3.000000 mil") (dielectricConstant "4.500000") (lossTangent "0.035") (etchFactor "0.000000") (elecCondVal "0 mho/cm") (thermCondVal "0.012 w/cm-degC")) ("L12_SIG4" (layerType "CONDUCTOR") (material "COPPER") (thickness "  1.250000 mil") (width "4.00 MIL") (dielectricConstant "4.500000") (lossTangent "0.035") (etchFactor "90.000000") (elecCondVal "595900.000000 mho/cm") (thermCondVal "0.012 w/cm-degC") (signalDieConstant "4.500000") (signalLossTangent "0.035")) ("" (layerType "DIELECTRIC") (material "FR-4") (thickness "  9.000000 mil") (dielectricConstant "4.500000") (lossTangent "0.035") (etchFactor "0.000000") (elecCondVal "0 mho/cm") (thermCondVal "0 w/cm-degC")) ("L13_GND6" (layerType "PLANE") (material "COPPER") (isShield t) (thickness "  1.250000 mil") (dielectricConstant "4.500000") (lossTangent "0.035") (etchFactor "90.000000") (elecCondVal "595900.000000 mho/cm") (thermCondVal "0.012 w/cm-degC")) ("" (layerType "DIELECTRIC") (material "FR-4") (thickness "  2.670000 mil") (dielectricConstant "4.500000") (lossTangent "0.035") (etchFactor "0.000000") (elecCondVal "0 mho/cm") (thermCondVal "0.012 w/cm-degC")) ("BOTTOM" (layerType "CONDUCTOR") (material "COPPER") (thickness "  2.100000 mil") (width "4.00 MIL") (dielectricConstant "4.500000") (lossTangent "0") (etchFactor "70.000000") (elecCondVal "595900.000000 mho/cm") (thermCondVal "0 w/cm-degC") (signalDieConstant "3.800000") (signalLossTangent "0.035")) ("" (layerType "DIELECTRIC") (material "CONFORMAL_COAT") (thickness "0.5 mil") (dielectricConstant "3.800000") (lossTangent "0.035") (etchFactor "0.000000") (elecCondVal "0 mho/cm") (thermCondVal "0.012 w/cm-degC")) ("" (layerType "SURFACE") (material "AIR") (thickness "0 mil") (dielectricConstant "1.000000") (lossTangent "0") (etchFactor "0.000000") (elecCondVal "0 mho/cm") (thermCondVal "0 w/cm-degC"))))) (Props (DesUnits "mils 2") (LayerStack ("DIELECTRIC" "DIELECTRIC" "BOTTOM" "DIELECTRIC" "L13_GND6" "DIELECTRIC" "L12_SIG4" "DIELECTRIC" "L11_GND5" "DIELECTRIC" "L10_SIG3" "DIELECTRIC" "L9_GND4" "DIELECTRIC" "L8_PWR2-SIG" "DIELECTRIC" "L7_PWR1-SIG" "DIELECTRIC" "L6_GND3" "DIELECTRIC" "L5_SIG2" "DIELECTRIC" "L4_GND2" "DIELECTRIC" "L3_SIG1" "DIELECTRIC" "L2_GND1" "DIELECTRIC" "TOP" "DIELECTRIC" "DIELECTRIC")) (Revision "16.600")) (Params (DiffOutputPkg ((temperature "27") (bufferModelNonInverting "CDSDefaultOutput_2p5v") (bufferModelInverting "CDSDefaultOutput_2p5v") (stimuli nil) (offsets nil) (state "tristate") (cycle "1") (termMap nil) (setup "0.9e-09") (hold "0.4e-09") (rise nil) (fall nil) (threshOutputHighMin "2.375  V") (threshOutputHighTyp "2.5  V") (threshOutputHighMax "2.625  V") (threshOutputLowMin "1.275  V") (threshOutputLowTyp "1.7  V") (threshOutputLowMax "1.985  V") (mappingTagNonInverting nil) (mappingTagInverting nil) (spice nil))) (HiClampTerm ((cutoffVoltage "0.7 V") (voltage "5 V") (maxDelay "0.1 ns"))) (LowClampTerm ((cutoffVoltage "0.7 V") (voltage "0 V") (maxDelay "0.1 ns"))) (DiffOutput ((temperature "27") (bufferModelNonInverting "CDSDefaultOutput_2p5v") (bufferModelInverting "CDSDefaultOutput_2p5v") (stimuli nil) (offsets nil) (state "tristate") (cycle "1") (termMap nil) (setup "0.9e-09") (hold "0.4e-09") (rise nil) (fall nil) (threshOutputHighMin "2.375  V") (threshOutputHighTyp "2.5  V") (threshOutputHighMax "2.625  V") (threshOutputLowMin "1.275  V") (threshOutputLowTyp "1.7  V") (threshOutputLowMax "1.985  V") (mappingTagNonInverting nil) (mappingTagInverting nil) (spice nil))) (Via ((model "Unknown") (viaOutputFormat "Unknown") (viaPadstack nil) (viaTopLayer nil) (viaBottomLayer nil) (viaIsPower nil) (viaIsGround nil))) (Resistor ((resistance "50 ohm") (orientation "0"))) (RCTerm ((resistance "50 ohm") (capacitance "20 pF") (voltage "5 V") (maxDelay "0.1 ns"))) (DiffIOPkg ((temperature "27") (bufferModelNonInverting "CDSDefaultIO_2p5v") (bufferModelInverting "CDSDefaultIO_2p5v") (stimuli nil) (offsets nil) (state "tristate") (cycle "1") (termMap nil) (setup "0.9e-09") (hold "0.4e-09") (rise nil) (fall nil) (threshInputHighMin "1.7 V") (threshInputHighTyp "1.7  V") (threshInputHighMax "1.7  V") (threshInputLowMin "0.7  V") (threshInputLowTyp "0.7  V") (threshInputLowMax "0.7 ") (threshOutputHighMin "2.365  V") (threshOutputHighTyp "2.5  V") (threshOutputHighMax "2.625  V") (threshOutputLowMin "1.275  V") (threshOutputLowTyp "1.7  V") (threshOutputLowMax "1.985  V") (mappingTagNonInverting nil) (mappingTagInverting nil) (spice nil))) (Trace ((d1Thickness "10 mil") (d1Constant "4.5") (d1LossTangent "0.035") (d2Thickness "10 mil") (d2Constant "4.5") (d2LossTangent "0.035") (d3Thickness "0.0") (d3Constant "1.0") (d3LossTangent "0") length("1000 mil") (spacing "5 mil") (spacing2 "5 mil") (spacing3 "5 mil") (spacing4 "5 mil") (spacing5 "5 mil") (traceConductivity "595900 mho/cm") (traceGeometry "microstrip") (traceLayerName "") (traceThickness "0.72 mil") (traceType "single") (traceWidth "5.0 mil") (traceWidth2 "5.0 mil") (traceWidth3 "5.0 mil") (traceWidth4 "5.0 mil") (traceWidth5 "5.0 mil") (traceWidth6 "5.0 mil") (offset "0 mil") (traceCount "1") (impedance nil))) (TheveninTerm ((resistanceUp "180 ohm") (resistanceDown "270 ohm") (voltageUp "5 V") (voltageDown "0 V") (maxDelay "0.1 ns"))) (DiffIO ((temperature "27") (bufferModelNonInverting "CDSDefaultIO_2p5v") (bufferModelInverting "CDSDefaultIO_2p5v") (stimuli nil) (offsets nil) (state "tristate") (cycle "1") (termMap nil) (setup "0.9e-09") (hold "0.4e-09") (rise nil) (fall nil) (threshInputHighMin "1.7 V") (threshInputHighTyp "1.7  V") (threshInputHighMax "1.7  V") (threshInputLowMin "0.7  V") (threshInputLowTyp "0.7  V") (threshInputLowMax "0.7 ") (threshOutputHighMin "2.365  V") (threshOutputHighTyp "2.5  V") (threshOutputHighMax "2.625  V") (threshOutputLowMin "1.275  V") (threshOutputLowTyp "1.7  V") (threshOutputLowMax "1.985  V") (mappingTagNonInverting nil) (mappingTagInverting nil) (spice nil))) (ShuntTerm ((resistance "50 ohm") (voltage "5 V") (maxDelay "0.1 ns"))) (Inductor ((inductance "5 nH") (orientation "0"))) (Capacitor ((capacitance "10 pF") (orientation "0"))) (RLGC (length("1000 mil"))) (Source ((voltage "5 V"))) (DiffInput ((temperature "27") (bufferModelNonInverting "CDSDefaultInput_2p5v") (bufferModelInverting "CDSDefaultInput_2p5v") (threshInputHighMin "1.7 V") (threshInputHighTyp "1.7  V") (threshInputHighMax "1.7  V") (threshInputLowMin "0.7  V") (threshInputLowTyp "0.7  V") (threshInputLowMax "0.7  V") (mappingTagNonInverting nil) (mappingTagInverting nil) (cycle "1"))) (CPW ((d1Thickness "10 mil") (d1Constant "4.5") (d1LossTangent "0.035") (d2Thickness "0.72 mil") (d2Constant "1") (d2LossTangent "0") (d3Thickness "0.0") (d3Constant "1") (d3LossTangent "0") length("1000 mil") (spacing "5 mil") (spacing2 "5 mil") (spacing3 "5 mil") (spacing4 "5 mil") (spacing5 "5 mil") (traceConductivity "595900 mho/cm") (traceGeometry "cpwms") (traceLayerName "") (traceThickness "0.72 mil") (traceType "single") (traceWidth "5.0 mil") (traceWidth2 "5.0 mil") (traceWidth3 "5.0 mil") (traceWidth4 "5.0 mil") (traceWidth5 "5.0 mil") (traceWidth6 "5.0 mil") (offset "0 mil") (traceCount "1") (impedance nil))) (Cable (length("1 m"))) (CPWMS ((d1Thickness "10 mil") (d1Constant "4.5") (d1LossTangent "0.035") (d2Thickness "0.72 mil") (d2Constant "4.5") (d2LossTangent "0.035") (d3Thickness "0.0") (d3Constant "1") (d3LossTangent "0") length("1000 mil") (spacing "5 mil") (spacing2 "5 mil") (spacing3 "5 mil") (spacing4 "5 mil") (spacing5 "5 mil") (traceConductivity "595900 mho/cm") (traceGeometry "cpwms") (traceLayerName "") (traceThickness "0.72 mil") (traceType "single") (traceWidth "5.0 mil") (traceWidth2 "5.0 mil") (traceWidth3 "5.0 mil") (traceWidth4 "5.0 mil") (traceWidth5 "5.0 mil") (traceWidth6 "5.0 mil") (offset "0 mil") (traceCount "1") (impedance nil))) (CPWSL ((d1Thickness "10 mil") (d1Constant "4.5") (d1LossTangent "0.035") (d2Thickness "0.72 mil") (d2Constant "4.5") (d2LossTangent "0.035") (d3Thickness "10 mil") (d3Constant "4.5") (d3LossTangent "0.035") length("1000 mil") (spacing "5 mil") (spacing2 "5 mil") (spacing3 "5 mil") (spacing4 "5 mil") (spacing5 "5 mil") (traceConductivity "595900 mho/cm") (traceGeometry "cpwms") (traceLayerName "") (traceThickness "0.72 mil") (traceType "single") (traceWidth "5.0 mil") (traceWidth2 "5.0 mil") (traceWidth3 "5.0 mil") (traceWidth4 "5.0 mil") (traceWidth5 "5.0 mil") (traceWidth6 "5.0 mil") (offset "0 mil") (traceCount "1") (impedance nil))) (ESpiceDevice nil) (Diode ((cutoffVoltage "0.7 V"))) (DualClampTerm ((cutoffVoltageUp "0.7 V") (cutoffVoltageDown "0.7 V") (voltageUp "5 V") (voltageDown "0 V") (maxDelay "0.1 ns"))) (IbisOutputPkg ((temperature "27") (bufferModel "CDSDefaultOutput_2p5v") (stimuli nil) (offsets nil) (state "tristate") (cycle "1") (termMap nil) (setup "2.0e-09") (hold "1.0e-09") (rise nil) (fall nil) (macroType nil) (voltage nil) (spice nil) (LEFDEFPinName nil) (LEFDEFPinType nil) (mappingTag nil))) (IbisIO_OpenPullDown ((temperature "27") (bufferModel "CDSDefaultIO_2p5v") (stimuli nil) (offsets nil) (state "tristate") (cycle "1") (termMap nil) (setup "2.0e-09") (hold "1.0e-09") (rise nil) (fall nil) (macroType nil) (voltage nil) (spice nil) (LEFDEFPinName nil) (LEFDEFPinType nil) (mappingTag nil))) (IbisInputPkg ((temperature "27") (bufferModel "CDSDefaultInput_2p5v") (cycle "1") (LEFDEFPinName nil) (LEFDEFPinType nil) (mappingTag nil))) (IbisIOMacro ((temperature "27") (bufferModel "CDSDefaultIO_2p5v") (stimuli nil) (offsets nil) (state "tristate") (cycle "1") (termMap nil) (setup "2.0e-09") (hold "1.0e-09") (rise nil) (fall nil) (macroType nil) (voltage nil) (spice nil) (LEFDEFPinName nil) (LEFDEFPinType nil) (mappingTag nil))) (IbisIO_OpenPullUp ((temperature "27") (bufferModel "CDSDefaultIO_2p5v") (stimuli nil) (offsets nil) (state "tristate") (cycle "1") (termMap nil) (setup "2.0e-09") (hold "1.0e-09") (rise nil) (fall nil) (macroType nil) (voltage nil) (spice nil) (LEFDEFPinName nil) (LEFDEFPinType nil) (mappingTag nil))) (IbisIOPkg ((temperature "27") (bufferModel "CDSDefaultIO_2p5v") (stimuli nil) (offsets nil) (state "tristate") (cycle "1") (termMap nil) (setup "2.0e-09") (hold "1.0e-09") (rise nil) (fall nil) (macroType nil) (voltage nil) (spice nil) (LEFDEFPinName nil) (LEFDEFPinType nil) (mappingTag nil))) (clocked ((clockRise "1e-09") (clockFall "1e-09") (clockFreq "100e6") (clockInitState "0") (clockDutyCycle "0.5") (clockJitter "0"))) (periodic ((periodicFreq "100e6") (periodicPattern "10") (periodicJitter "0"))) (IbisIO ((temperature "27") (bufferModel "CDSDefaultIO_2p5v") (stimuli nil) (offsets nil) (state "tristate") (cycle "1") (termMap nil) (setup "2.0e-09") (hold "1.0e-09") (rise nil) (fall nil) (macroType nil) (voltage nil) (spice nil) (LEFDEFPinName nil) (LEFDEFPinType nil) (mappingTag nil))) (async ((asyncTimePoints "") (asyncInitState "1"))) (IbisOutput ((temperature "27") (bufferModel "CDSDefaultOutput_2p5v") (stimuli nil) (offsets nil) (state "tristate") (cycle "1") (termMap nil) (setup "2.0e-09") (hold "1.0e-09") (rise nil) (fall nil) (macroType nil) (voltage nil) (spice nil) (LEFDEFPinName nil) (LEFDEFPinType nil) (mappingTag nil))) (TLine ((diffImpedance "100ohm") (diffVelocity "1.4142e+08M/s") (impedance "60ohm") length("2800 mil") (propDelay "0.5 ns") (velocity "5600 mil/ns") (traceCount "1") (traceGeometry "Microstrip") (impedanceMin nil) (impedanceMax nil) (lengthMin nil) (lengthMax nil) (propDelayMin nil) (propDelayMax nil) (impedanceSweepCount nil) (propDelaySweepCount nil) (velocitySweepCount nil) (lengthSweepCount nil) (matchSetName nil))) (CurrentProbe nil) (IbisInput ((temperature "27") (bufferModel "CDSDefaultInput_2p5v") (cycle "1") (LEFDEFPinName nil) (LEFDEFPinType nil) (mappingTag nil))) (SeriesTerm ((resistance "22 ohm") (maxDelay "0.1 ns"))) (Connector nil) (sync ((syncFreq "100e6") (syncInitState "1") (syncPattern "10") (syncEdgeSwitch "rise"))) (IbisOutput_OpenPullUp ((temperature "27") (bufferModel "CDSDefaultOutput_2p5v") (stimuli nil) (offsets nil) (state "tristate") (cycle "1") (termMap nil) (setup "2.0e-09") (hold "1.0e-09") (rise nil) (fall nil) (macroType nil) (voltage nil) (spice nil) (LEFDEFPinName nil) (LEFDEFPinType nil) (mappingTag nil))) (DiffInputPkg ((temperature "27") (bufferModelNonInverting "CDSDefaultInput_2p5v") (bufferModelInverting "CDSDefaultInput_2p5v") (threshInputHighMin "1.7 V") (threshInputHighTyp "1.7  V") (threshInputHighMax "1.7  V") (threshInputLowMin "0.7  V") (threshInputLowTyp "0.7  V") (threshInputLowMax "0.7  V") (mappingTagNonInverting nil) (mappingTagInverting nil) (cycle "1"))) (idlCircuit ((allDrivers "active") (ftsMode '("Typ")) (rcvrSelect "all") (simMode "Reflection") (tlineDelayMode "time") (userRevision "1.0") (autoSolve "On")))))
				)
				( objectStatus "SGPIO_BMC_DI" )
			)
			( electricalCSet "@crescent_city_bb_fab1_lib.crescent_city_bb_fab1(sch_1):\RMII_RX_NEW\"
				( pinPairRef "RMII_RX_NEW:U9F4.D8:U7C1.AN3" )
				( attribute "TOPOLOGY_TEMPLATE_REVISION" "1.0"
					( Origin gBackEnd )
				)
				( topologyData 28759
(SKIDL (Circuits ("MAIN" (Parts ("CRESCENT_CITY_638_20150416_B.@@U47.D8" IbisInputPkg (xy (5552.0 4235.0)) (refDes "U9F4") (model "Unknown") (Props (_SXDesignName "CRESCENT_CITY_638_20150416_B") (brdx "17681.78 MIL") (brdy "708.76 MIL") (bufferModel "CDSDefaultInput_2p5v") (mappingTag "") (temperature "27")) (Terms ("CRESCENT_CITY_638_20150416_B.X1768178Y70876L2LRATS" "D8"))) ("CRESCENT_CITY_638_20150416_B.@@U22.AN3" IbisIOPkg (xy (5541 4218)) (refDes "U7C1") (model "Unknown") (Props (_SXDesignName "CRESCENT_CITY_638_20150416_B") (brdx "15314.37 MIL") (brdy "3715.55 MIL") (bufferModel "CDSDefaultIO_2p5v") (cycle "1") (hold "1.0e-09") (mappingTag "") (offsets ("4" "0") ("5" "0")) (setup "2.0e-09") (state "tristate") (stimuli ("4" "local0") ("5" "local1")) (temperature "27") (termMap ("4" "Data") ("5" "Enable"))) (Terms ("CRESCENT_CITY_638_20150416_B.X1531437Y371555L2LRATS" "AN3"))) ("CRESCENT_CITY_638_20150416_B.@@EU46.3" IbisOutputPkg (xy (5498 4235)) (refDes "EU9E1") (model "Unknown") (Props (_SXDesignName "CRESCENT_CITY_638_20150416_B") (brdx "19352 MIL") (brdy "1656.73 MIL") (bufferModel "CDSDefaultOutput_2p5v") (cycle "1") (hold "1.0e-09") (mappingTag "") (offsets ("4" "0")) (setup "2.0e-09") (state "tristate") (stimuli ("4" "local8")) (temperature "27") (termMap ("4" "Data"))) (Terms ("CRESCENT_CITY_638_20150416_B.X1935200Y165673L2LRATS" "3"))) ("CRESCENT_CITY_638_20150416_B.@@R3498.1.2" Resistor (xy (5521 4235)) (refDes "R9F1") (value "22 Ohm") (Props (_SXDesignName "CRESCENT_CITY_638_20150416_B")) (Terms ("CRESCENT_CITY_638_20150416_B.X1943000Y160000L2LRATS" "1") ("CRESCENT_CITY_638_20150416_B.X1946500Y160000L2LRATS" "2"))) ("CRESCENT_CITY_638_20150416_B.@@R3442.2.1" Resistor (xy (5512 4220)) (refDes "R1T1") (value "10000 Ohm") (Props (_SXDesignName "CRESCENT_CITY_638_20150416_B")) (Terms ("CRESCENT_CITY_638_20150416_B.X1943000Y160000L36RATS" "2") ("CRESCENT_CITY_638_20150416_B.X1946500Y160000L36LRATS" "1"))) ("CRESCENT_CITY_638_20150416_B.T@@RATS@@U47.D8@@R3498.2" TLine (xy (5530 4235)) (mirror x) (refDes "TL1") (Props (_SXDesignName "CRESCENT_CITY_638_20150416_B") (impedance "48.412 ohm") length("2674.46 MIL") (propDelay "0.48035 ns") (traceCount "1") (traceGeometry "Microstrip") (velocity "5567.72 mil/ns")) (Terms ("CRESCENT_CITY_638_20150416_B.X1768178Y70876L2LRATS" "1") ("CRESCENT_CITY_638_20150416_B.X1946500Y160000L2LRATS" "2"))) ("CRESCENT_CITY_638_20150416_B.T@@RATS@@R613.2@@U22.AN3" TLine (xy (5532 4213)) (refDes "TL2") (Props (_SXDesignName "CRESCENT_CITY_638_20150416_B") (impedance "52.449 ohm") length("210.32 MIL") (propDelay "0.03777 ns") (traceCount "1") (traceGeometry "Microstrip") (velocity "5568.43 mil/ns")) (Terms ("CRESCENT_CITY_638_20150416_B.X1530976Y350984L36LRATS" "1") ("CRESCENT_CITY_638_20150416_B.X1531437Y371555L2LRATS" "2"))) ("CRESCENT_CITY_638_20150416_B.T@@RATS@@U47.D8@@R613.1" TLine (xy (5547 4227)) (mirror x) (refDes "TL3") (Props (_SXDesignName "CRESCENT_CITY_638_20150416_B") (impedance "48.412 ohm") length("5138.11 MIL") (propDelay "0.92284 ns") (traceCount "1") (traceGeometry "Microstrip") (velocity "5567.72 mil/ns")) (Terms ("CRESCENT_CITY_638_20150416_B.X1768178Y70876L2LRATS" "1") ("CRESCENT_CITY_638_20150416_B.X1530976Y347484L36LRATS" "2"))) ("CRESCENT_CITY_638_20150416_B.T@@RATS@@R3498.2@@R3442.1" TLine (xy (5521.5 4220.0)) (mirror x) (refDes "TL4") (Props (_SXDesignName "CRESCENT_CITY_638_20150416_B") (impedance "48.412 ohm") (propDelay "1.79607e-006 ns") (traceCount "1") (traceGeometry "Microstrip")) (Terms ("CRESCENT_CITY_638_20150416_B.X1946500Y160000L2LRATS" "1") ("CRESCENT_CITY_638_20150416_B.X1946500Y160000L36LRATS" "2"))) ("CRESCENT_CITY_638_20150416_B.@@R3442.2_SOURCE" Source (xy (5505 4220)) (refDes "GND") (value "0 V") (Props (_SXDesignName "CRESCENT_CITY_638_20150416_B")) (Terms ("CRESCENT_CITY_638_20150416_B.X1943000Y160000L36RATS" "1"))) ("CRESCENT_CITY_638_20150416_B.T@@RATS@@R3498.1@@EU46.3" TLine (xy (5506 4235)) (mirror x) (refDes "TL5") (Props (_SXDesignName "CRESCENT_CITY_638_20150416_B") (impedance "48.412 ohm") length("134.73 MIL") (propDelay "0.0242 ns") (traceCount "1") (traceGeometry "Microstrip") (velocity "5567.36 mil/ns")) (Terms ("CRESCENT_CITY_638_20150416_B.X1943000Y160000L2LRATS" "1") ("CRESCENT_CITY_638_20150416_B.X1935200Y165673L2LRATS" "2"))) ("CRESCENT_CITY_638_20150416_B.@@R613.1.2" Resistor (xy (5532 4227)) (mirror x) (refDes "R3P2") (value "1 Ohm") (Props (_SXDesignName "CRESCENT_CITY_638_20150416_B")) (Terms ("CRESCENT_CITY_638_20150416_B.X1530976Y347484L36LRATS" "1") ("CRESCENT_CITY_638_20150416_B.X1530976Y350984L36LRATS" "2")))) (Nodes ("CRESCENT_CITY_638_20150416_B.X1943000Y160000L36RATS" (terms "CRESCENT_CITY_638_20150416_B.@@R3442.2_SOURCE.1" "CRESCENT_CITY_638_20150416_B.@@R3442.2.1.1")) ("CRESCENT_CITY_638_20150416_B.X1531437Y371555L2LRATS" (terms "CRESCENT_CITY_638_20150416_B.T@@RATS@@R613.2@@U22.AN3.2" "CRESCENT_CITY_638_20150416_B.@@U22.AN3.1")) ("CRESCENT_CITY_638_20150416_B.X1946500Y160000L36LRATS" (terms "CRESCENT_CITY_638_20150416_B.T@@RATS@@R3498.2@@R3442.1.2" "CRESCENT_CITY_638_20150416_B.@@R3442.2.1.2")) ("CRESCENT_CITY_638_20150416_B.X1530976Y347484L36LRATS" (terms "CRESCENT_CITY_638_20150416_B.@@R613.1.2.1" "CRESCENT_CITY_638_20150416_B.T@@RATS@@U47.D8@@R613.1.2")) ("CRESCENT_CITY_638_20150416_B.X1768178Y70876L2LRATS" (terms "CRESCENT_CITY_638_20150416_B.T@@RATS@@U47.D8@@R613.1.1" "CRESCENT_CITY_638_20150416_B.T@@RATS@@U47.D8@@R3498.2.1" "CRESCENT_CITY_638_20150416_B.@@U47.D8.1")) ("CRESCENT_CITY_638_20150416_B.X1935200Y165673L2LRATS" (terms "CRESCENT_CITY_638_20150416_B.T@@RATS@@R3498.1@@EU46.3.2" "CRESCENT_CITY_638_20150416_B.@@EU46.3.1")) ("CRESCENT_CITY_638_20150416_B.X1946500Y160000L2LRATS" (terms "CRESCENT_CITY_638_20150416_B.T@@RATS@@R3498.2@@R3442.1.1" "CRESCENT_CITY_638_20150416_B.T@@RATS@@U47.D8@@R3498.2.2" "CRESCENT_CITY_638_20150416_B.@@R3498.1.2.2")) ("CRESCENT_CITY_638_20150416_B.X1530976Y350984L36LRATS" (terms "CRESCENT_CITY_638_20150416_B.@@R613.1.2.2" "CRESCENT_CITY_638_20150416_B.T@@RATS@@R613.2@@U22.AN3.1")) ("CRESCENT_CITY_638_20150416_B.X1943000Y160000L2LRATS" (terms "CRESCENT_CITY_638_20150416_B.T@@RATS@@R3498.1@@EU46.3.1" "CRESCENT_CITY_638_20150416_B.@@R3498.1.2.1"))) (Ports) (Stimuli ("local8" (scope local) (stimType periodic) (Props (periodicFreq "5e+007") (periodicJitter "0") (periodicPattern "1"))) ("local15" (scope local) (stimType periodic) (Props (periodicFreq "5e+007") (periodicJitter "0") (periodicPattern "1"))) ("local14" (scope local) (stimType periodic) (Props (periodicFreq "5e+007") (periodicJitter "0") (periodicPattern "1"))) ("local16" (scope local) (stimType periodic) (Props (periodicFreq "5e+007") (periodicJitter "0") (periodicPattern "1"))) ("local0" (scope local) (stimType periodic) (Props (periodicFreq "5e+007") (periodicJitter "0") (periodicPattern "1"))) ("local1" (scope local) (stimType periodic) (Props (periodicFreq "5e+007") (periodicJitter "0") (periodicPattern "1")))) (Notes) (Constraints ("DELAY_RULE" ("CRESCENT_CITY_638_20150416_B U47.D8" "CRESCENT_CITY_638_20150416_B U22.AN3" "LENGTH" "0.2032" "LENGTH" "0.3556"))) (MeasurementSets ("EMI" ("EMIStatus" status("on")) ("PeakEmission" status("on")) ("PeakFrequency" status("on")) ("PulseFreq" status("on")) ("RiseTime" status("on")) ("VoltageSwing" status("on"))) ("Reflection" ("BufferDelayFall" status("off")) ("BufferDelayRise" status("off")) ("EyeHeight" status("off")) ("EyeJitter" status("off")) ("EyeWidth" status("off")) ("FirstIncidentFall" status("off")) ("FirstIncidentRise" status("off")) ("Glitch" status("on")) ("GlitchFall" status("off")) ("GlitchRise" status("off")) ("Monotonic" status("on")) ("MonotonicFall" status("off")) ("MonotonicRise" status("off")) ("NoiseMargin" status("on")) ("NoiseMarginHigh" status("off")) ("NoiseMarginLow" status("off")) ("OvershootHigh" status("on")) ("OvershootLow" status("on")) ("PropDelay" status("on")) ("SettleDelay" status("on")) ("SettleDelayFall" status("off")) ("SettleDelayRise" status("off")) ("SwitchDelay" status("on")) ("SwitchDelayFall" status("off")) ("SwitchDelayRise" status("off"))) ("Crosstalk" ("Crosstalk" status("on"))) ("Custom")) (VectorSets) (Props (XnetName "RMII_BMC_PCH_SPRNGVLLE_CRSDV") (allDrivers "active") (customSimType "Reflection") (ftsMode ("Typ")) (rcvrSelect "all") (tlineDelayMode "time") (userRevision "1.0")))) (Subckts) (CrossSections ("CRESCENT_CITY_638_20150416_B" (Props (SXDesignName "CRESCENT_CITY_638_20150416_B")) (Layers ("" (layerType "SURFACE") (material "AIR") (thickness "0 mil") (dielectricConstant "1.000000") (lossTangent "0") (etchFactor "0.000000") (elecCondVal "0 mho/cm") (thermCondVal "0 w/cm-degC")) ("" (layerType "DIELECTRIC") (material "CONFORMAL_COAT") (thickness "0.5 mil") (dielectricConstant "3.800000") (lossTangent "0.035") (etchFactor "0.000000") (elecCondVal "0 mho/cm") (thermCondVal "0.012 w/cm-degC")) ("TOP" (layerType "CONDUCTOR") (material "COPPER") (thickness "  2.100000 mil") (width "4.00 MIL") (dielectricConstant "4.500000") (lossTangent "0") (etchFactor "70.000000") (elecCondVal "595900.000000 mho/cm") (thermCondVal "0 w/cm-degC") (signalDieConstant "3.800000") (signalLossTangent "0.035")) ("" (layerType "DIELECTRIC") (material "FR-4") (thickness "  2.670000 mil") (dielectricConstant "4.000000") (lossTangent "0.035") (etchFactor "0.000000") (elecCondVal "0 mho/cm") (thermCondVal "0.012 w/cm-degC")) ("L2_GND1" (layerType "PLANE") (material "COPPER") (isShield t) (thickness "  1.250000 mil") (dielectricConstant "4.500000") (lossTangent "0.035") (etchFactor "90.000000") (elecCondVal "595900.000000 mho/cm") (thermCondVal "0.012 w/cm-degC")) ("" (layerType "DIELECTRIC") (material "FR-4") (thickness "  9.000000 mil") (dielectricConstant "4.100000") (lossTangent "0.035") (etchFactor "0.000000") (elecCondVal "0 mho/cm") (thermCondVal "0.012 w/cm-degC")) ("L3_SIG1" (layerType "CONDUCTOR") (material "COPPER") (thickness "  1.250000 mil") (width "4.00 MIL") (dielectricConstant "4.500000") (lossTangent "0.035") (etchFactor "90.000000") (elecCondVal "595900.000000 mho/cm") (thermCondVal "0.012 w/cm-degC") (signalDieConstant "4.100000") (signalLossTangent "0.035")) ("" (layerType "DIELECTRIC") (material "FR-4") (thickness "  3.000000 mil") (dielectricConstant "4.500000") (lossTangent "0.035") (etchFactor "0.000000") (elecCondVal "0 mho/cm") (thermCondVal "0 w/cm-degC")) ("L4_GND2" (layerType "PLANE") (material "COPPER") (isShield t) (thickness "  1.250000 mil") (dielectricConstant "4.500000") (lossTangent "0.035") (etchFactor "90.000000") (elecCondVal "595900.000000 mho/cm") (thermCondVal "0 w/cm-degC")) ("" (layerType "DIELECTRIC") (material "FR-4") (thickness "  9.000000 mil") (dielectricConstant "4.000000") (lossTangent "0.035") (etchFactor "0.000000") (elecCondVal "0 mho/cm") (thermCondVal "0.012 w/cm-degC")) ("L5_SIG2" (layerType "CONDUCTOR") (material "COPPER") (thickness "  1.250000 mil") (width "4.00 MIL") (dielectricConstant "4.500000") (lossTangent "0.035") (etchFactor "90.000000") (elecCondVal "595900.000000 mho/cm") (thermCondVal "0.012 w/cm-degC") (signalDieConstant "4.000000") (signalLossTangent "0.035")) ("" (layerType "DIELECTRIC") (material "FR-4") (thickness "  3.000000 mil") (dielectricConstant "4.500000") (lossTangent "0.035") (etchFactor "0.000000") (elecCondVal "0 mho/cm") (thermCondVal "0 w/cm-degC")) ("L6_GND3" (layerType "PLANE") (material "COPPER") (isShield t) (thickness "  1.250000 mil") (dielectricConstant "4.500000") (lossTangent "0.035") (etchFactor "90.000000") (elecCondVal "595900.000000 mho/cm") (thermCondVal "0 w/cm-degC")) ("" (layerType "DIELECTRIC") (material "FR-4") (thickness "  4.500000 mil") (dielectricConstant "4.100000") (lossTangent "0.035") (etchFactor "0.000000") (elecCondVal "0 mho/cm") (thermCondVal "0.012 w/cm-degC")) ("L7_PWR1-SIG" (layerType "PLANE") (material "COPPER") (isShield t) (thickness "  2.610000 mil") (dielectricConstant "4.500000") (lossTangent "0.035") (etchFactor "90.000000") (elecCondVal "595900.000000 mho/cm") (thermCondVal "0.012 w/cm-degC")) ("" (layerType "DIELECTRIC") (material "FR-4") (thickness "  3.100000 mil") (dielectricConstant "4.500000") (lossTangent "0.035") (etchFactor "0.000000") (elecCondVal "0 mho/cm") (thermCondVal "0 w/cm-degC")) ("L8_GND_TEMP" (layerType "PLANE") (material "COPPER") (isShield t) (thickness "  1.250000 mil") (dielectricConstant "4.500000") (lossTangent "0.035") (etchFactor "90.000000") (elecCondVal "595900.000000 mho/cm") (thermCondVal "0 w/cm-degC")) ("" (layerType "DIELECTRIC") (material "FR-4") (thickness "  3.030000 mil") (dielectricConstant "4.500000") (lossTangent "0.035") (etchFactor "0.000000") (elecCondVal "0 mho/cm") (thermCondVal "0 w/cm-degC")) ("L9_SIG_TEMP" (layerType "CONDUCTOR") (material "COPPER") (thickness "  1.250000 mil") (width "3.52 MIL") (dielectricConstant "4.500000") (lossTangent "0.035") (etchFactor "90.000000") (elecCondVal "595900.000000 mho/cm") (thermCondVal "0 w/cm-degC") (signalDieConstant "4.500000") (signalLossTangent "0.035")) ("" (layerType "DIELECTRIC") (material "FR-4") (thickness "  5.000000 mil") (dielectricConstant "4.500000") (lossTangent "0.035") (etchFactor "0.000000") (elecCondVal "0 mho/cm") (thermCondVal "0 w/cm-degC")) ("L10_SIG_TEMP" (layerType "CONDUCTOR") (material "COPPER") (thickness "  1.250000 mil") (width "3.52 MIL") (dielectricConstant "4.500000") (lossTangent "0.035") (etchFactor "90.000000") (elecCondVal "595900.000000 mho/cm") (thermCondVal "0 w/cm-degC") (signalDieConstant "4.500000") (signalLossTangent "0.035")) ("" (layerType "DIELECTRIC") (material "FR-4") (thickness "  3.030000 mil") (dielectricConstant "4.500000") (lossTangent "0.035") (etchFactor "0.000000") (elecCondVal "0 mho/cm") (thermCondVal "0 w/cm-degC")) ("L11_GND_TEMP" (layerType "PLANE") (material "COPPER") (isShield t) (thickness "  1.250000 mil") (dielectricConstant "4.500000") (lossTangent "0.035") (etchFactor "90.000000") (elecCondVal "595900.000000 mho/cm") (thermCondVal "0 w/cm-degC")) ("" (layerType "DIELECTRIC") (material "FR-4") (thickness "  3.100000 mil") (dielectricConstant "4.000000") (lossTangent "0.035") (etchFactor "0.000000") (elecCondVal "0 mho/cm") (thermCondVal "0.012 w/cm-degC")) ("L12_PWR2-SIG" (layerType "PLANE") (material "COPPER") (isShield t) (thickness "  2.610000 mil") (dielectricConstant "4.500000") (lossTangent "0.035") (etchFactor "90.000000") (elecCondVal "595900.000000 mho/cm") (thermCondVal "0.012 w/cm-degC")) ("" (layerType "DIELECTRIC") (material "FR-4") (thickness "  4.500000 mil") (dielectricConstant "4.500000") (lossTangent "0.035") (etchFactor "0.000000") (elecCondVal "0 mho/cm") (thermCondVal "0 w/cm-degC")) ("L13_GND4" (layerType "PLANE") (material "COPPER") (isShield t) (thickness "  1.250000 mil") (dielectricConstant "4.500000") (lossTangent "0.035") (etchFactor "90.000000") (elecCondVal "595900.000000 mho/cm") (thermCondVal "0 w/cm-degC")) ("" (layerType "DIELECTRIC") (material "FR-4") (thickness "  3.000000 mil") (dielectricConstant "4.100000") (lossTangent "0.035") (etchFactor "0.000000") (elecCondVal "0 mho/cm") (thermCondVal "0.012 w/cm-degC")) ("L14_SIG3" (layerType "CONDUCTOR") (material "COPPER") (thickness "  1.250000 mil") (width "4.00 MIL") (dielectricConstant "4.500000") (lossTangent "0.035") (etchFactor "90.000000") (elecCondVal "595900.000000 mho/cm") (thermCondVal "0.012 w/cm-degC") (signalDieConstant "4.100000") (signalLossTangent "0.035")) ("" (layerType "DIELECTRIC") (material "FR-4") (thickness "  9.000000 mil") (dielectricConstant "4.500000") (lossTangent "0.035") (etchFactor "0.000000") (elecCondVal "0 mho/cm") (thermCondVal "0 w/cm-degC")) ("L15_GND5" (layerType "PLANE") (material "COPPER") (isShield t) (thickness "  1.250000 mil") (dielectricConstant "4.500000") (lossTangent "0.035") (etchFactor "90.000000") (elecCondVal "595900.000000 mho/cm") (thermCondVal "0 w/cm-degC")) ("" (layerType "DIELECTRIC") (material "FR-4") (thickness "  3.000000 mil") (dielectricConstant "4.500000") (lossTangent "0.035") (etchFactor "0.000000") (elecCondVal "0 mho/cm") (thermCondVal "0.012 w/cm-degC")) ("L16_SIG4" (layerType "CONDUCTOR") (material "COPPER") (thickness "  1.250000 mil") (width "4.00 MIL") (dielectricConstant "4.500000") (lossTangent "0.035") (etchFactor "90.000000") (elecCondVal "595900.000000 mho/cm") (thermCondVal "0.012 w/cm-degC") (signalDieConstant "4.500000") (signalLossTangent "0.035")) ("" (layerType "DIELECTRIC") (material "FR-4") (thickness "  9.000000 mil") (dielectricConstant "4.500000") (lossTangent "0.035") (etchFactor "0.000000") (elecCondVal "0 mho/cm") (thermCondVal "0 w/cm-degC")) ("L17_GND6" (layerType "PLANE") (material "COPPER") (isShield t) (thickness "  1.250000 mil") (dielectricConstant "4.500000") (lossTangent "0.035") (etchFactor "90.000000") (elecCondVal "595900.000000 mho/cm") (thermCondVal "0.012 w/cm-degC")) ("" (layerType "DIELECTRIC") (material "FR-4") (thickness "  2.670000 mil") (dielectricConstant "4.500000") (lossTangent "0.035") (etchFactor "0.000000") (elecCondVal "0 mho/cm") (thermCondVal "0.012 w/cm-degC")) ("BOTTOM" (layerType "CONDUCTOR") (material "COPPER") (thickness "  2.100000 mil") (width "4.00 MIL") (dielectricConstant "4.500000") (lossTangent "0") (etchFactor "70.000000") (elecCondVal "595900.000000 mho/cm") (thermCondVal "0 w/cm-degC") (signalDieConstant "3.800000") (signalLossTangent "0.035")) ("" (layerType "DIELECTRIC") (material "CONFORMAL_COAT") (thickness "0.5 mil") (dielectricConstant "3.800000") (lossTangent "0.035") (etchFactor "0.000000") (elecCondVal "0 mho/cm") (thermCondVal "0.012 w/cm-degC")) ("" (layerType "SURFACE") (material "AIR") (thickness "0 mil") (dielectricConstant "1.000000") (lossTangent "0") (etchFactor "0.000000") (elecCondVal "0 mho/cm") (thermCondVal "0 w/cm-degC"))))) (Props (DesUnits "mils 2") (LayerStack ("DIELECTRIC" "DIELECTRIC" "BOTTOM" "DIELECTRIC" "L17_GND6" "DIELECTRIC" "L16_SIG4" "DIELECTRIC" "L15_GND5" "DIELECTRIC" "L14_SIG3" "DIELECTRIC" "L13_GND4" "DIELECTRIC" "L12_PWR2-SIG" "DIELECTRIC" "L11_GND_TEMP" "DIELECTRIC" "L10_SIG_TEMP" "DIELECTRIC" "L9_SIG_TEMP" "DIELECTRIC" "L8_GND_TEMP" "DIELECTRIC" "L7_PWR1-SIG" "DIELECTRIC" "L6_GND3" "DIELECTRIC" "L5_SIG2" "DIELECTRIC" "L4_GND2" "DIELECTRIC" "L3_SIG1" "DIELECTRIC" "L2_GND1" "DIELECTRIC" "TOP" "DIELECTRIC" "DIELECTRIC")) (Revision "16.600")) (Params (DiffInput ((temperature "27") (bufferModelNonInverting "CDSDefaultInput_2p5v") (bufferModelInverting "CDSDefaultInput_2p5v") (threshInputHighMin "1.7 V") (threshInputHighTyp "1.7  V") (threshInputHighMax "1.7  V") (threshInputLowMin "0.7  V") (threshInputLowTyp "0.7  V") (threshInputLowMax "0.7  V") (mappingTagNonInverting nil) (mappingTagInverting nil) (cycle "1"))) (Resistor ((resistance "50 ohm") (orientation "0"))) (DiffOutputPkg ((temperature "27") (bufferModelNonInverting "CDSDefaultOutput_2p5v") (bufferModelInverting "CDSDefaultOutput_2p5v") (stimuli nil) (offsets nil) (state "tristate") (cycle "1") (termMap nil) (setup "0.9e-09") (hold "0.4e-09") (rise nil) (fall nil) (threshOutputHighMin "2.375  V") (threshOutputHighTyp "2.5  V") (threshOutputHighMax "2.625  V") (threshOutputLowMin "1.275  V") (threshOutputLowTyp "1.7  V") (threshOutputLowMax "1.985  V") (mappingTagNonInverting nil) (mappingTagInverting nil) (spice nil))) (DiffOutput ((temperature "27") (bufferModelNonInverting "CDSDefaultOutput_2p5v") (bufferModelInverting "CDSDefaultOutput_2p5v") (stimuli nil) (offsets nil) (state "tristate") (cycle "1") (termMap nil) (setup "0.9e-09") (hold "0.4e-09") (rise nil) (fall nil) (threshOutputHighMin "2.375  V") (threshOutputHighTyp "2.5  V") (threshOutputHighMax "2.625  V") (threshOutputLowMin "1.275  V") (threshOutputLowTyp "1.7  V") (threshOutputLowMax "1.985  V") (mappingTagNonInverting nil) (mappingTagInverting nil) (spice nil))) (Inductor ((inductance "5 nH") (orientation "0"))) (Capacitor ((capacitance "10 pF") (orientation "0"))) (DiffIOPkg ((temperature "27") (bufferModelNonInverting "CDSDefaultIO_2p5v") (bufferModelInverting "CDSDefaultIO_2p5v") (stimuli nil) (offsets nil) (state "tristate") (cycle "1") (termMap nil) (setup "0.9e-09") (hold "0.4e-09") (rise nil) (fall nil) (threshInputHighMin "1.7 V") (threshInputHighTyp "1.7  V") (threshInputHighMax "1.7  V") (threshInputLowMin "0.7  V") (threshInputLowTyp "0.7  V") (threshInputLowMax "0.7 ") (threshOutputHighMin "2.365  V") (threshOutputHighTyp "2.5  V") (threshOutputHighMax "2.625  V") (threshOutputLowMin "1.275  V") (threshOutputLowTyp "1.7  V") (threshOutputLowMax "1.985  V") (mappingTagNonInverting nil) (mappingTagInverting nil) (spice nil))) (Source ((voltage "5 V"))) (DiffIO ((temperature "27") (bufferModelNonInverting "CDSDefaultIO_2p5v") (bufferModelInverting "CDSDefaultIO_2p5v") (stimuli nil) (offsets nil) (state "tristate") (cycle "1") (termMap nil) (setup "0.9e-09") (hold "0.4e-09") (rise nil) (fall nil) (threshInputHighMin "1.7 V") (threshInputHighTyp "1.7  V") (threshInputHighMax "1.7  V") (threshInputLowMin "0.7  V") (threshInputLowTyp "0.7  V") (threshInputLowMax "0.7 ") (threshOutputHighMin "2.365  V") (threshOutputHighTyp "2.5  V") (threshOutputHighMax "2.625  V") (threshOutputLowMin "1.275  V") (threshOutputLowTyp "1.7  V") (threshOutputLowMax "1.985  V") (mappingTagNonInverting nil) (mappingTagInverting nil) (spice nil))) (RLGC (length("1000 mil"))) (DiffInputPkg ((temperature "27") (bufferModelNonInverting "CDSDefaultInput_2p5v") (bufferModelInverting "CDSDefaultInput_2p5v") (threshInputHighMin "1.7 V") (threshInputHighTyp "1.7  V") (threshInputHighMax "1.7  V") (threshInputLowMin "0.7  V") (threshInputLowTyp "0.7  V") (threshInputLowMax "0.7  V") (mappingTagNonInverting nil) (mappingTagInverting nil) (cycle "1"))) (IbisInput ((temperature "27") (bufferModel "CDSDefaultInput_2p5v") (cycle "1") (LEFDEFPinName nil) (LEFDEFPinType nil) (mappingTag nil))) (Diode ((cutoffVoltage "0.7 V"))) (idlCircuit ((allDrivers "active") (ftsMode '("Typ")) (rcvrSelect "all") (simMode "Reflection") (tlineDelayMode "time") (userRevision "1.0") (autoSolve "On"))) (CPW ((d1Thickness "10 mil") (d1Constant "4.5") (d1LossTangent "0.035") (d2Thickness "0.72 mil") (d2Constant "1") (d2LossTangent "0") (d3Thickness "0.0") (d3Constant "1") (d3LossTangent "0") length("1000 mil") (spacing "5 mil") (spacing2 "5 mil") (spacing3 "5 mil") (spacing4 "5 mil") (spacing5 "5 mil") (traceConductivity "595900 mho/cm") (traceGeometry "cpwms") (traceLayerName "") (traceThickness "0.72 mil") (traceType "single") (traceWidth "5.0 mil") (traceWidth2 "5.0 mil") (traceWidth3 "5.0 mil") (traceWidth4 "5.0 mil") (traceWidth5 "5.0 mil") (traceWidth6 "5.0 mil") (offset "0 mil") (traceCount "1") (impedance nil))) (DualClampTerm ((cutoffVoltageUp "0.7 V") (cutoffVoltageDown "0.7 V") (voltageUp "5 V") (voltageDown "0 V") (maxDelay "0.1 ns"))) (ESpiceDevice nil) (HiClampTerm ((cutoffVoltage "0.7 V") (voltage "5 V") (maxDelay "0.1 ns"))) (IbisOutput ((temperature "27") (bufferModel "CDSDefaultOutput_2p5v") (stimuli nil) (offsets nil) (state "tristate") (cycle "1") (termMap nil) (setup "2.0e-09") (hold "1.0e-09") (rise nil) (fall nil) (macroType nil) (voltage nil) (spice nil) (LEFDEFPinName nil) (LEFDEFPinType nil) (mappingTag nil))) (sync ((syncFreq "100e6") (syncInitState "1") (syncPattern "10") (syncEdgeSwitch "rise"))) (IbisIO ((temperature "27") (bufferModel "CDSDefaultIO_2p5v") (stimuli nil) (offsets nil) (state "tristate") (cycle "1") (termMap nil) (setup "2.0e-09") (hold "1.0e-09") (rise nil) (fall nil) (macroType nil) (voltage nil) (spice nil) (LEFDEFPinName nil) (LEFDEFPinType nil) (mappingTag nil))) (RCTerm ((resistance "50 ohm") (capacitance "20 pF") (voltage "5 V") (maxDelay "0.1 ns"))) (TLine ((diffImpedance "100ohm") (diffVelocity "1.4142e+08M/s") (impedance "60ohm") length("2800 mil") (propDelay "0.5 ns") (velocity "5600 mil/ns") (traceCount "1") (traceGeometry "Microstrip") (impedanceMin nil) (impedanceMax nil) (lengthMin nil) (lengthMax nil) (propDelayMin nil) (propDelayMax nil) (impedanceSweepCount nil) (propDelaySweepCount nil) (velocitySweepCount nil) (lengthSweepCount nil) (matchSetName nil))) (LowClampTerm ((cutoffVoltage "0.7 V") (voltage "0 V") (maxDelay "0.1 ns"))) (Connector nil) (ShuntTerm ((resistance "50 ohm") (voltage "5 V") (maxDelay "0.1 ns"))) (IbisIO_OpenPullDown ((temperature "27") (bufferModel "CDSDefaultIO_2p5v") (stimuli nil) (offsets nil) (state "tristate") (cycle "1") (termMap nil) (setup "2.0e-09") (hold "1.0e-09") (rise nil) (fall nil) (macroType nil) (voltage nil) (spice nil) (LEFDEFPinName nil) (LEFDEFPinType nil) (mappingTag nil))) (clocked ((clockRise "1e-09") (clockFall "1e-09") (clockFreq "100e6") (clockInitState "0") (clockDutyCycle "0.5") (clockJitter "0"))) (TheveninTerm ((resistanceUp "180 ohm") (resistanceDown "270 ohm") (voltageUp "5 V") (voltageDown "0 V") (maxDelay "0.1 ns"))) (IbisIO_OpenPullUp ((temperature "27") (bufferModel "CDSDefaultIO_2p5v") (stimuli nil) (offsets nil) (state "tristate") (cycle "1") (termMap nil) (setup "2.0e-09") (hold "1.0e-09") (rise nil) (fall nil) (macroType nil) (voltage nil) (spice nil) (LEFDEFPinName nil) (LEFDEFPinType nil) (mappingTag nil))) (CPWSL ((d1Thickness "10 mil") (d1Constant "4.5") (d1LossTangent "0.035") (d2Thickness "0.72 mil") (d2Constant "4.5") (d2LossTangent "0.035") (d3Thickness "10 mil") (d3Constant "4.5") (d3LossTangent "0.035") length("1000 mil") (spacing "5 mil") (spacing2 "5 mil") (spacing3 "5 mil") (spacing4 "5 mil") (spacing5 "5 mil") (traceConductivity "595900 mho/cm") (traceGeometry "cpwms") (traceLayerName "") (traceThickness "0.72 mil") (traceType "single") (traceWidth "5.0 mil") (traceWidth2 "5.0 mil") (traceWidth3 "5.0 mil") (traceWidth4 "5.0 mil") (traceWidth5 "5.0 mil") (traceWidth6 "5.0 mil") (offset "0 mil") (traceCount "1") (impedance nil))) (IbisOutput_OpenPullUp ((temperature "27") (bufferModel "CDSDefaultOutput_2p5v") (stimuli nil) (offsets nil) (state "tristate") (cycle "1") (termMap nil) (setup "2.0e-09") (hold "1.0e-09") (rise nil) (fall nil) (macroType nil) (voltage nil) (spice nil) (LEFDEFPinName nil) (LEFDEFPinType nil) (mappingTag nil))) (CPWMS ((d1Thickness "10 mil") (d1Constant "4.5") (d1LossTangent "0.035") (d2Thickness "0.72 mil") (d2Constant "4.5") (d2LossTangent "0.035") (d3Thickness "0.0") (d3Constant "1") (d3LossTangent "0") length("1000 mil") (spacing "5 mil") (spacing2 "5 mil") (spacing3 "5 mil") (spacing4 "5 mil") (spacing5 "5 mil") (traceConductivity "595900 mho/cm") (traceGeometry "cpwms") (traceLayerName "") (traceThickness "0.72 mil") (traceType "single") (traceWidth "5.0 mil") (traceWidth2 "5.0 mil") (traceWidth3 "5.0 mil") (traceWidth4 "5.0 mil") (traceWidth5 "5.0 mil") (traceWidth6 "5.0 mil") (offset "0 mil") (traceCount "1") (impedance nil))) (periodic ((periodicFreq "100e6") (periodicPattern "10") (periodicJitter "0"))) (IbisInputPkg ((temperature "27") (bufferModel "CDSDefaultInput_2p5v") (cycle "1") (LEFDEFPinName nil) (LEFDEFPinType nil) (mappingTag nil))) (IbisIOMacro ((temperature "27") (bufferModel "CDSDefaultIO_2p5v") (stimuli nil) (offsets nil) (state "tristate") (cycle "1") (termMap nil) (setup "2.0e-09") (hold "1.0e-09") (rise nil) (fall nil) (macroType nil) (voltage nil) (spice nil) (LEFDEFPinName nil) (LEFDEFPinType nil) (mappingTag nil))) (CurrentProbe nil) (IbisOutputPkg ((temperature "27") (bufferModel "CDSDefaultOutput_2p5v") (stimuli nil) (offsets nil) (state "tristate") (cycle "1") (termMap nil) (setup "2.0e-09") (hold "1.0e-09") (rise nil) (fall nil) (macroType nil) (voltage nil) (spice nil) (LEFDEFPinName nil) (LEFDEFPinType nil) (mappingTag nil))) (IbisIOPkg ((temperature "27") (bufferModel "CDSDefaultIO_2p5v") (stimuli nil) (offsets nil) (state "tristate") (cycle "1") (termMap nil) (setup "2.0e-09") (hold "1.0e-09") (rise nil) (fall nil) (macroType nil) (voltage nil) (spice nil) (LEFDEFPinName nil) (LEFDEFPinType nil) (mappingTag nil))) (SeriesTerm ((resistance "22 ohm") (maxDelay "0.1 ns"))) (Trace ((d1Thickness "10 mil") (d1Constant "4.5") (d1LossTangent "0.035") (d2Thickness "10 mil") (d2Constant "4.5") (d2LossTangent "0.035") (d3Thickness "0.0") (d3Constant "1.0") (d3LossTangent "0") length("1000 mil") (spacing "5 mil") (spacing2 "5 mil") (spacing3 "5 mil") (spacing4 "5 mil") (spacing5 "5 mil") (traceConductivity "595900 mho/cm") (traceGeometry "microstrip") (traceLayerName "") (traceThickness "0.72 mil") (traceType "single") (traceWidth "5.0 mil") (traceWidth2 "5.0 mil") (traceWidth3 "5.0 mil") (traceWidth4 "5.0 mil") (traceWidth5 "5.0 mil") (traceWidth6 "5.0 mil") (offset "0 mil") (traceCount "1") (impedance nil))) (async ((asyncTimePoints "") (asyncInitState "1"))) (Cable (length("1 m"))) (Via ((model "Unknown") (viaOutputFormat "Unknown") (viaPadstack nil) (viaTopLayer nil) (viaBottomLayer nil) (viaIsPower nil) (viaIsGround nil)))))
				)
				( objectStatus "RMII_RX_NEW" )
			)
			( electricalCSet "@crescent_city_bb_fab1_lib.crescent_city_bb_fab1(sch_1):\JTAG_PCH_GBE_CLK\"
				( groupRef "JTAG_PCH:MG_JTAG_PLD" )
				( groupRef "JTAG_PCH:MG_JTAG_PCH_PLD" )
				( groupRef "JTAG_PCH:MG_JTAG_PCH_GBE" )
				( groupRef "JTAG_PCH:MG_JTAG" )
				( pinPairRef "JTAG_PCH:U9F4.F2:U8D7.A7" )
				( pinPairRef "JTAG_PCH:U9F4.F2:U7C1.AL18" )
				( pinPairRef "JTAG_PCH:U9F4.F2:U7C1.BV21" )
				( pinPairRef "JTAG_PCH:J7G2.8:U9F4.F2" )
				( pinPairRef "JTAG_PCH:J7G2.8:U7C1.BV21" )
				( pinPairRef "JTAG_PCH:J7G2.8:U7C1.AL18" )
				( pinPairRef "JTAG_PCH:J7G2.8:U8D7.A7" )
				( pinPairRef "JTAG_PCH:J7G2.8:R8G18.2" )
				( pinPairRef "JTAG_PCH:J7G2.8:R8G17.2" )
				( pinPairRef "JTAG_PCH:J7G2.8:R8G15.2" )
				( pinPairRef "JTAG_PCH:J7G2.8:R8G16.2" )
				( attribute "TOPOLOGY_TEMPLATE_REVISION" "1.0"
					( Origin gBackEnd )
				)
				( topologyData 33647
(SKIDL (Circuits ("MAIN" (Parts ("CRESCENT_CITY_195_20150129_6PIN.@@U22.AL18" IbisIOPkg (xy (5527 4187)) (refDes "U7C1") (model "Unknown") (Props (_SXDesignName "CRESCENT_CITY_195_20150129_6PIN") (brdx "15284.75 MIL") (brdy "3987 MIL") (bufferModel "CDSDefaultIO_2p5v") (cycle "1") (hold "1.0e-09") (mappingTag "") (offsets ("4" "0") ("5" "0")) (setup "2.0e-09") (state "tristate") (stimuli ("4" "local57") ("5" "local58")) (temperature "27") (termMap ("4" "Data") ("5" "Enable"))) (Terms ("CRESCENT_CITY_195_20150129_6PIN.X1528475Y398700L2LRATS" "AL18"))) ("CRESCENT_CITY_195_20150129_6PIN.@@U4E2.A7" IbisIOPkg (xy (5536 4201)) (refDes "U8D7") (model "Unknown") (Props (_SXDesignName "CRESCENT_CITY_195_20150129_6PIN") (brdx "15407.24 MIL") (brdy "2363.78 MIL") (bufferModel "CDSDefaultIO_2p5v") (cycle "1") (hold "1.0e-09") (mappingTag "") (offsets ("4" "0") ("5" "0")) (setup "2.0e-09") (state "tristate") (stimuli ("4" "local59") ("5" "local60")) (temperature "27") (termMap ("4" "Data") ("5" "Enable"))) (Terms ("CRESCENT_CITY_195_20150129_6PIN.X1540724Y236378L2LRATS" "A7"))) ("CRESCENT_CITY_195_20150129_6PIN.@@U47.F2" IbisIOPkg (xy (5553 4215)) (refDes "U9F4") (model "Unknown") (Props (_SXDesignName "CRESCENT_CITY_195_20150129_6PIN") (brdx "17744.77 MIL") (brdy "519.79 MIL") (bufferModel "CDSDefaultIO_2p5v") (cycle "1") (hold "1.0e-09") (mappingTag "") (offsets ("4" "0") ("5" "0")) (setup "2.0e-09") (state "tristate") (stimuli ("4" "local61") ("5" "local62")) (temperature "27") (termMap ("4" "Data") ("5" "Enable"))) (Terms ("CRESCENT_CITY_195_20150129_6PIN.X1774477Y51979L2LRATS" "F2"))) ("CRESCENT_CITY_195_20150129_6PIN.@@U22.BV21" IbisIOPkg (xy (5502 4240)) (refDes "U7C1") (model "Unknown") (Props (_SXDesignName "CRESCENT_CITY_195_20150129_6PIN") (brdx "15750 MIL") (brdy "4029.72 MIL") (bufferModel "CDSDefaultIO_2p5v") (cycle "1") (hold "1.0e-09") (mappingTag "") (offsets ("4" "0") ("5" "0")) (setup "2.0e-09") (state "tristate") (stimuli ("4" "local63") ("5" "local64")) (temperature "27") (termMap ("4" "Data") ("5" "Enable"))) (Terms ("CRESCENT_CITY_195_20150129_6PIN.X1575000Y402972L2LRATS" "BV21"))) ("CRESCENT_CITY_195_20150129_6PIN.@@J122.8" IbisIOPkg (xy (5528 4227)) (refDes "J7G2") (model "Unknown") (Props (_SXDesignName "CRESCENT_CITY_195_20150129_6PIN") (brdx "15750 MIL") (brdy "-150 MIL") (bufferModel "CDSDefaultIO_2p5v") (cycle "1") (hold "1.0e-09") (mappingTag "") (offsets ("4" "0") ("5" "0")) (setup "2.0e-09") (state "tristate") (stimuli ("4" "local65") ("5" "local66")) (temperature "27") (termMap ("4" "Data") ("5" "Enable"))) (Terms ("CRESCENT_CITY_195_20150129_6PIN.X1575000Yn15000L2LRATS" "8"))) ("CRESCENT_CITY_195_20150129_6PIN.@@R462.2.1" Resistor (xy (5513 4216)) (refDes "R8G23") (value "4750 Ohm") (Props (_SXDesignName "CRESCENT_CITY_195_20150129_6PIN")) (Terms ("CRESCENT_CITY_195_20150129_6PIN.X1563600Yn2800L2RATS" "2") ("CRESCENT_CITY_195_20150129_6PIN.X1563600Yn6300L2LRATS" "1"))) ("CRESCENT_CITY_195_20150129_6PIN.@@R3450.1.2" Resistor (xy (5523 4210)) (mirror x) (refDes "R8G17") (value "2.2e-007 Ohm") (Props (_SXDesignName "CRESCENT_CITY_195_20150129_6PIN")) (Terms ("CRESCENT_CITY_195_20150129_6PIN.X1783400Y38500L2LRATS" "1") ("CRESCENT_CITY_195_20150129_6PIN.X1783400Y35000L2LRATS" "2"))) ("CRESCENT_CITY_195_20150129_6PIN.T@@RATS@@R462.1@@J122.8" TLine (xy (5520.0 4222.5)) (refDes "TL37") (Props (_SXDesignName "CRESCENT_CITY_195_20150129_6PIN") (impedance "48.412 ohm") length("201.00 MIL") (propDelay "0.0361 ns") (traceCount "1") (traceGeometry "Microstrip") (velocity "5567.87 mil/ns")) (Terms ("CRESCENT_CITY_195_20150129_6PIN.X1563600Yn6300L2LRATS" "1") ("CRESCENT_CITY_195_20150129_6PIN.X1575000Yn15000L2LRATS" "2"))) ("CRESCENT_CITY_195_20150129_6PIN.T@@RATS@@R182.2@@R3571.2" TLine (xy (5497 4222)) (refDes "TL38") (Props (_SXDesignName "CRESCENT_CITY_195_20150129_6PIN") (impedance "48.412 ohm") length("1720.00 MIL") (propDelay "0.30892 ns") (traceCount "1") (traceGeometry "Microstrip") (velocity "5567.8 mil/ns")) (Terms ("CRESCENT_CITY_195_20150129_6PIN.X1521500Y370500L28LRATS" "1") ("CRESCENT_CITY_195_20150129_6PIN.X1545500Y222500L2LRATS" "2"))) ("CRESCENT_CITY_195_20150129_6PIN.@@R3449.1.2" Resistor (xy (5488 4229)) (mirror x) (refDes "R8G15") (value "1 Ohm") (Props (_SXDesignName "CRESCENT_CITY_195_20150129_6PIN")) (Terms ("CRESCENT_CITY_195_20150129_6PIN.X1605500Y403000L2LRATS" "1") ("CRESCENT_CITY_195_20150129_6PIN.X1609000Y403000L2LRATS" "2"))) ("CRESCENT_CITY_195_20150129_6PIN.T@@RATS@@U22.BV21@@R3449.1" TLine (xy (5503 4229)) (mirror x) (refDes "TL39") (Props (_SXDesignName "CRESCENT_CITY_195_20150129_6PIN") (impedance "52.449 ohm") length("305.28 MIL") (propDelay "0.05483 ns") (traceCount "1") (traceGeometry "Microstrip") (velocity "5567.76 mil/ns")) (Terms ("CRESCENT_CITY_195_20150129_6PIN.X1575000Y402972L2LRATS" "1") ("CRESCENT_CITY_195_20150129_6PIN.X1605500Y403000L2LRATS" "2"))) ("CRESCENT_CITY_195_20150129_6PIN.T@@RATS@@R3449.2@@R182.2" TLine (xy (5488 4222)) (refDes "TL40") (Props (_SXDesignName "CRESCENT_CITY_195_20150129_6PIN") (impedance "48.412 ohm") length("1200.00 MIL") (propDelay "0.21553 ns") (traceCount "1") (traceGeometry "Microstrip") (velocity "5567.68 mil/ns")) (Terms ("CRESCENT_CITY_195_20150129_6PIN.X1609000Y403000L2LRATS" "1") ("CRESCENT_CITY_195_20150129_6PIN.X1521500Y370500L28LRATS" "2"))) ("CRESCENT_CITY_195_20150129_6PIN.T@@RATS@@J122.8@@R3450.2" TLine (xy (5529 4216)) (mirror x) (refDes "TL41") (Props (_SXDesignName "CRESCENT_CITY_195_20150129_6PIN") (impedance "48.412 ohm") length("2584.00 MIL") (propDelay "0.4641 ns") (traceCount "1") (traceGeometry "Microstrip") (velocity "5567.76 mil/ns")) (Terms ("CRESCENT_CITY_195_20150129_6PIN.X1575000Yn15000L2LRATS" "1") ("CRESCENT_CITY_195_20150129_6PIN.X1783400Y35000L2LRATS" "2"))) ("CRESCENT_CITY_195_20150129_6PIN.@@R182.1.2" Resistor (xy (5497 4182)) (mirror x) (refDes "R8G16") (value "1 Ohm") (Props (_SXDesignName "CRESCENT_CITY_195_20150129_6PIN")) (Terms ("CRESCENT_CITY_195_20150129_6PIN.X1521500Y374000L28LRATS" "1") ("CRESCENT_CITY_195_20150129_6PIN.X1521500Y370500L28LRATS" "2"))) ("CRESCENT_CITY_195_20150129_6PIN.@@R462.2_SOURCE" Source (xy (5506 4216)) (refDes "GND") (value "0 V") (Props (_SXDesignName "CRESCENT_CITY_195_20150129_6PIN")) (Terms ("CRESCENT_CITY_195_20150129_6PIN.X1563600Yn2800L2RATS" "1"))) ("CRESCENT_CITY_195_20150129_6PIN.T@@RATS@@U4E2.A7@@R3571.1" TLine (xy (5521 4196)) (mirror x) (refDes "TL42") (Props (_SXDesignName "CRESCENT_CITY_195_20150129_6PIN") (impedance "48.412 ohm") length("151.54 MIL") (propDelay "0.02722 ns") (traceCount "1") (traceGeometry "Microstrip") (velocity "5567.24 mil/ns")) (Terms ("CRESCENT_CITY_195_20150129_6PIN.X1540724Y236378L2LRATS" "1") ("CRESCENT_CITY_195_20150129_6PIN.X1545500Y226000L2LRATS" "2"))) ("CRESCENT_CITY_195_20150129_6PIN.@@R3571.1.2" Resistor (xy (5506 4196)) (mirror x) (refDes "R8G18") (value "1 Ohm") (Props (_SXDesignName "CRESCENT_CITY_195_20150129_6PIN")) (Terms ("CRESCENT_CITY_195_20150129_6PIN.X1545500Y226000L2LRATS" "1") ("CRESCENT_CITY_195_20150129_6PIN.X1545500Y222500L2LRATS" "2"))) ("CRESCENT_CITY_195_20150129_6PIN.T@@RATS@@U47.F2@@R3450.1" TLine (xy (5538 4210)) (mirror x) (refDes "TL43") (Props (_SXDesignName "CRESCENT_CITY_195_20150129_6PIN") (impedance "49.728 ohm") length("224.02 MIL") (propDelay "0.04024 ns") (traceCount "1") (traceGeometry "Microstrip") (velocity "5567.09 mil/ns")) (Terms ("CRESCENT_CITY_195_20150129_6PIN.X1774477Y51979L2LRATS" "1") ("CRESCENT_CITY_195_20150129_6PIN.X1783400Y38500L2LRATS" "2"))) ("CRESCENT_CITY_195_20150129_6PIN.T@@RATS@@U22.AL18@@R182.1" TLine (xy (5512 4182)) (mirror x) (refDes "TL44") (Props (_SXDesignName "CRESCENT_CITY_195_20150129_6PIN") (impedance "48.412 ohm") length("316.75 MIL") (propDelay "0.05689 ns") (traceCount "1") (traceGeometry "Microstrip") (velocity "5567.76 mil/ns")) (Terms ("CRESCENT_CITY_195_20150129_6PIN.X1528475Y398700L2LRATS" "1") ("CRESCENT_CITY_195_20150129_6PIN.X1521500Y374000L28LRATS" "2"))) ("CRESCENT_CITY_195_20150129_6PIN.T@@RATS@@R3571.2@@R462.1" TLine (xy (5506 4222)) (refDes "TL45") (Props (_SXDesignName "CRESCENT_CITY_195_20150129_6PIN") (impedance "48.412 ohm") length("2469.00 MIL") (propDelay "0.44345 ns") (traceCount "1") (traceGeometry "Microstrip") (velocity "5567.72 mil/ns")) (Terms ("CRESCENT_CITY_195_20150129_6PIN.X1545500Y222500L2LRATS" "1") ("CRESCENT_CITY_195_20150129_6PIN.X1563600Yn6300L2LRATS" "2")))) (Nodes ("CRESCENT_CITY_195_20150129_6PIN.X1609000Y403000L2LRATS" (terms "CRESCENT_CITY_195_20150129_6PIN.T@@RATS@@R3449.2@@R182.2.1" "CRESCENT_CITY_195_20150129_6PIN.@@R3449.1.2.2")) ("CRESCENT_CITY_195_20150129_6PIN.X1563600Yn6300L2LRATS" (terms "CRESCENT_CITY_195_20150129_6PIN.T@@RATS@@R3571.2@@R462.1.2" "CRESCENT_CITY_195_20150129_6PIN.T@@RATS@@R462.1@@J122.8.1" "CRESCENT_CITY_195_20150129_6PIN.@@R462.2.1.2")) ("CRESCENT_CITY_195_20150129_6PIN.X1774477Y51979L2LRATS" (terms "CRESCENT_CITY_195_20150129_6PIN.T@@RATS@@U47.F2@@R3450.1.1" "CRESCENT_CITY_195_20150129_6PIN.@@U47.F2.1")) ("CRESCENT_CITY_195_20150129_6PIN.X1521500Y370500L28LRATS" (terms "CRESCENT_CITY_195_20150129_6PIN.@@R182.1.2.2" "CRESCENT_CITY_195_20150129_6PIN.T@@RATS@@R3449.2@@R182.2.2" "CRESCENT_CITY_195_20150129_6PIN.T@@RATS@@R182.2@@R3571.2.1")) ("CRESCENT_CITY_195_20150129_6PIN.X1545500Y222500L2LRATS" (terms "CRESCENT_CITY_195_20150129_6PIN.T@@RATS@@R3571.2@@R462.1.1" "CRESCENT_CITY_195_20150129_6PIN.@@R3571.1.2.2" "CRESCENT_CITY_195_20150129_6PIN.T@@RATS@@R182.2@@R3571.2.2")) ("CRESCENT_CITY_195_20150129_6PIN.X1545500Y226000L2LRATS" (terms "CRESCENT_CITY_195_20150129_6PIN.@@R3571.1.2.1" "CRESCENT_CITY_195_20150129_6PIN.T@@RATS@@U4E2.A7@@R3571.1.2")) ("CRESCENT_CITY_195_20150129_6PIN.X1521500Y374000L28LRATS" (terms "CRESCENT_CITY_195_20150129_6PIN.T@@RATS@@U22.AL18@@R182.1.2" "CRESCENT_CITY_195_20150129_6PIN.@@R182.1.2.1")) ("CRESCENT_CITY_195_20150129_6PIN.X1563600Yn2800L2RATS" (terms "CRESCENT_CITY_195_20150129_6PIN.@@R462.2_SOURCE.1" "CRESCENT_CITY_195_20150129_6PIN.@@R462.2.1.1")) ("CRESCENT_CITY_195_20150129_6PIN.X1528475Y398700L2LRATS" (terms "CRESCENT_CITY_195_20150129_6PIN.T@@RATS@@U22.AL18@@R182.1.1" "CRESCENT_CITY_195_20150129_6PIN.@@U22.AL18.1")) ("CRESCENT_CITY_195_20150129_6PIN.X1540724Y236378L2LRATS" (terms "CRESCENT_CITY_195_20150129_6PIN.T@@RATS@@U4E2.A7@@R3571.1.1" "CRESCENT_CITY_195_20150129_6PIN.@@U4E2.A7.1")) ("CRESCENT_CITY_195_20150129_6PIN.X1783400Y35000L2LRATS" (terms "CRESCENT_CITY_195_20150129_6PIN.T@@RATS@@J122.8@@R3450.2.2" "CRESCENT_CITY_195_20150129_6PIN.@@R3450.1.2.2")) ("CRESCENT_CITY_195_20150129_6PIN.X1575000Yn15000L2LRATS" (terms "CRESCENT_CITY_195_20150129_6PIN.T@@RATS@@J122.8@@R3450.2.1" "CRESCENT_CITY_195_20150129_6PIN.T@@RATS@@R462.1@@J122.8.2" "CRESCENT_CITY_195_20150129_6PIN.@@J122.8.1")) ("CRESCENT_CITY_195_20150129_6PIN.X1575000Y402972L2LRATS" (terms "CRESCENT_CITY_195_20150129_6PIN.T@@RATS@@U22.BV21@@R3449.1.1" "CRESCENT_CITY_195_20150129_6PIN.@@U22.BV21.1")) ("CRESCENT_CITY_195_20150129_6PIN.X1783400Y38500L2LRATS" (terms "CRESCENT_CITY_195_20150129_6PIN.T@@RATS@@U47.F2@@R3450.1.2" "CRESCENT_CITY_195_20150129_6PIN.@@R3450.1.2.1")) ("CRESCENT_CITY_195_20150129_6PIN.X1605500Y403000L2LRATS" (terms "CRESCENT_CITY_195_20150129_6PIN.T@@RATS@@U22.BV21@@R3449.1.2" "CRESCENT_CITY_195_20150129_6PIN.@@R3449.1.2.1"))) (Ports) (Stimuli ("local57" (scope local) (stimType periodic) (Props (periodicFreq "5e+007") (periodicJitter "0") (periodicPattern "1"))) ("local62" (scope local) (stimType periodic) (Props (periodicFreq "5e+007") (periodicJitter "0") (periodicPattern "1"))) ("local59" (scope local) (stimType periodic) (Props (periodicFreq "5e+007") (periodicJitter "0") (periodicPattern "1"))) ("local60" (scope local) (stimType periodic) (Props (periodicFreq "5e+007") (periodicJitter "0") (periodicPattern "1"))) ("local66" (scope local) (stimType periodic) (Props (periodicFreq "5e+007") (periodicJitter "0") (periodicPattern "1"))) ("local58" (scope local) (stimType periodic) (Props (periodicFreq "5e+007") (periodicJitter "0") (periodicPattern "1"))) ("local63" (scope local) (stimType periodic) (Props (periodicFreq "5e+007") (periodicJitter "0") (periodicPattern "1"))) ("local61" (scope local) (stimType periodic) (Props (periodicFreq "5e+007") (periodicJitter "0") (periodicPattern "1"))) ("local65" (scope local) (stimType periodic) (Props (periodicFreq "5e+007") (periodicJitter "0") (periodicPattern "1"))) ("local64" (scope local) (stimType periodic) (Props (periodicFreq "5e+007") (periodicJitter "0") (periodicPattern "1")))) (Notes) (Constraints ("DELAY_RULE" ("CRESCENT_CITY_195_20150129_6PIN J122.8" "CRESCENT_CITY_195_20150129_6PIN R182.2" "LENGTH" "" "LENGTH" "0.02794") ("CRESCENT_CITY_195_20150129_6PIN J122.8" "CRESCENT_CITY_195_20150129_6PIN R3449.2" "LENGTH" "" "LENGTH" "0.02794") ("CRESCENT_CITY_195_20150129_6PIN J122.8" "CRESCENT_CITY_195_20150129_6PIN R3450.2" "LENGTH" "" "LENGTH" "0.02794") ("CRESCENT_CITY_195_20150129_6PIN J122.8" "CRESCENT_CITY_195_20150129_6PIN R3571.2" "LENGTH" "" "LENGTH" "0.02794") ("CRESCENT_CITY_195_20150129_6PIN J122.8" "CRESCENT_CITY_195_20150129_6PIN U4E2.A7" "LENGTH" "" "LENGTH" "0.6096") ("CRESCENT_CITY_195_20150129_6PIN J122.8" "CRESCENT_CITY_195_20150129_6PIN U22.AL18" "LENGTH" "" "LENGTH" "0.6096") ("CRESCENT_CITY_195_20150129_6PIN J122.8" "CRESCENT_CITY_195_20150129_6PIN U22.BV21" "LENGTH" "" "LENGTH" "0.6096") ("CRESCENT_CITY_195_20150129_6PIN J122.8" "CRESCENT_CITY_195_20150129_6PIN U47.F2" "LENGTH" "" "LENGTH" "0.6096")) ("RELATIVE_PROPAGATION_DELAY" ("MG_JTAG_PLD" "CRESCENT_CITY_195_20150129_6PIN U47.F2" "CRESCENT_CITY_195_20150129_6PIN U4E2.A7" "GLOBAL" "LENGTH" "0.0254" "DELAY" "") ("MG_JTAG_PCH_PLD" "CRESCENT_CITY_195_20150129_6PIN U47.F2" "CRESCENT_CITY_195_20150129_6PIN U22.AL18" "GLOBAL" "LENGTH" "0.0254" "DELAY" "") ("MG_JTAG_PCH_GBE" "CRESCENT_CITY_195_20150129_6PIN U47.F2" "CRESCENT_CITY_195_20150129_6PIN U22.BV21" "GLOBAL" "LENGTH" "0.0254" "DELAY" "") ("MG_JTAG" "CRESCENT_CITY_195_20150129_6PIN U47.F2" "CRESCENT_CITY_195_20150129_6PIN J122.8" "GLOBAL" "LENGTH" "0.0254" "DELAY" ""))) (MeasurementSets ("EMI" ("EMIStatus" status("on")) ("PeakEmission" status("on")) ("PeakFrequency" status("on")) ("PulseFreq" status("on")) ("RiseTime" status("on")) ("VoltageSwing" status("on"))) ("Reflection" ("BufferDelayFall" status("off")) ("BufferDelayRise" status("off")) ("EyeHeight" status("off")) ("EyeJitter" status("off")) ("EyeWidth" status("off")) ("FirstIncidentFall" status("off")) ("FirstIncidentRise" status("off")) ("Glitch" status("on")) ("GlitchFall" status("off")) ("GlitchRise" status("off")) ("Monotonic" status("on")) ("MonotonicFall" status("off")) ("MonotonicRise" status("off")) ("NoiseMargin" status("on")) ("NoiseMarginHigh" status("off")) ("NoiseMarginLow" status("off")) ("OvershootHigh" status("on")) ("OvershootLow" status("on")) ("PropDelay" status("on")) ("SettleDelay" status("on")) ("SettleDelayFall" status("off")) ("SettleDelayRise" status("off")) ("SwitchDelay" status("on")) ("SwitchDelayFall" status("off")) ("SwitchDelayRise" status("off"))) ("Crosstalk" ("Crosstalk" status("on"))) ("Custom")) (VectorSets) (Props (XnetName "JTAG_PCH_GBE_CLK") (allDrivers "active") (customSimType "Reflection") (ftsMode ("Typ")) (rcvrSelect "all") (tlineDelayMode "time") (userRevision "1.0")))) (Subckts) (CrossSections ("CRESCENT_CITY_195_20150129_6PIN" (Props (SXDesignName "CRESCENT_CITY_195_20150129_6PIN")) (Layers ("" (layerType "SURFACE") (material "AIR") (thickness "0 mil") (dielectricConstant "1.000000") (lossTangent "0") (etchFactor "0.000000") (elecCondVal "0 mho/cm") (thermCondVal "0 w/cm-degC")) ("" (layerType "DIELECTRIC") (material "CONFORMAL_COAT") (thickness "0.5 mil") (dielectricConstant "3.800000") (lossTangent "0.035") (etchFactor "0.000000") (elecCondVal "0 mho/cm") (thermCondVal "0.012 w/cm-degC")) ("TOP" (layerType "CONDUCTOR") (material "COPPER") (thickness "  2.100000 mil") (width "4.00 MIL") (dielectricConstant "4.500000") (lossTangent "0") (etchFactor "70.000000") (elecCondVal "595900.000000 mho/cm") (thermCondVal "0 w/cm-degC") (signalDieConstant "3.800000") (signalLossTangent "0.035")) ("" (layerType "DIELECTRIC") (material "FR-4") (thickness "  2.670000 mil") (dielectricConstant "4.000000") (lossTangent "0.035") (etchFactor "0.000000") (elecCondVal "0 mho/cm") (thermCondVal "0.012 w/cm-degC")) ("L2_GND1" (layerType "PLANE") (material "COPPER") (isShield t) (thickness "  1.250000 mil") (dielectricConstant "4.500000") (lossTangent "0.035") (etchFactor "90.000000") (elecCondVal "595900.000000 mho/cm") (thermCondVal "0.012 w/cm-degC")) ("" (layerType "DIELECTRIC") (material "FR-4") (thickness "  9.000000 mil") (dielectricConstant "4.100000") (lossTangent "0.035") (etchFactor "0.000000") (elecCondVal "0 mho/cm") (thermCondVal "0.012 w/cm-degC")) ("L3_SIG1" (layerType "CONDUCTOR") (material "COPPER") (thickness "  1.250000 mil") (width "4.00 MIL") (dielectricConstant "4.500000") (lossTangent "0.035") (etchFactor "90.000000") (elecCondVal "595900.000000 mho/cm") (thermCondVal "0.012 w/cm-degC") (signalDieConstant "4.100000") (signalLossTangent "0.035")) ("" (layerType "DIELECTRIC") (material "FR-4") (thickness "  3.000000 mil") (dielectricConstant "4.500000") (lossTangent "0.035") (etchFactor "0.000000") (elecCondVal "0 mho/cm") (thermCondVal "0 w/cm-degC")) ("L4_GND2" (layerType "PLANE") (material "COPPER") (isShield t) (thickness "  1.250000 mil") (dielectricConstant "4.500000") (lossTangent "0.035") (etchFactor "90.000000") (elecCondVal "595900.000000 mho/cm") (thermCondVal "0 w/cm-degC")) ("" (layerType "DIELECTRIC") (material "FR-4") (thickness "  9.000000 mil") (dielectricConstant "4.000000") (lossTangent "0.035") (etchFactor "0.000000") (elecCondVal "0 mho/cm") (thermCondVal "0.012 w/cm-degC")) ("L5_SIG2" (layerType "CONDUCTOR") (material "COPPER") (thickness "  1.250000 mil") (width "4.00 MIL") (dielectricConstant "4.500000") (lossTangent "0.035") (etchFactor "90.000000") (elecCondVal "595900.000000 mho/cm") (thermCondVal "0.012 w/cm-degC") (signalDieConstant "4.000000") (signalLossTangent "0.035")) ("" (layerType "DIELECTRIC") (material "FR-4") (thickness "  3.000000 mil") (dielectricConstant "4.500000") (lossTangent "0.035") (etchFactor "0.000000") (elecCondVal "0 mho/cm") (thermCondVal "0 w/cm-degC")) ("L6_GND3" (layerType "PLANE") (material "COPPER") (isShield t) (thickness "  1.250000 mil") (dielectricConstant "4.500000") (lossTangent "0.035") (etchFactor "90.000000") (elecCondVal "595900.000000 mho/cm") (thermCondVal "0 w/cm-degC")) ("" (layerType "DIELECTRIC") (material "FR-4") (thickness "  4.500000 mil") (dielectricConstant "4.100000") (lossTangent "0.035") (etchFactor "0.000000") (elecCondVal "0 mho/cm") (thermCondVal "0.012 w/cm-degC")) ("L7_PWR1-SIG" (layerType "PLANE") (material "COPPER") (isShield t) (thickness "  2.400000 mil") (dielectricConstant "4.500000") (lossTangent "0.035") (etchFactor "90.000000") (elecCondVal "595900.000000 mho/cm") (thermCondVal "0.012 w/cm-degC")) ("" (layerType "DIELECTRIC") (material "FR-4") (thickness "  4.600000 mil") (dielectricConstant "4.000000") (lossTangent "0.035") (etchFactor "0.000000") (elecCondVal "0 mho/cm") (thermCondVal "0.012 w/cm-degC")) ("L8_PWR2-SIG" (layerType "PLANE") (material "COPPER") (isShield t) (thickness "  2.400000 mil") (dielectricConstant "4.500000") (lossTangent "0.035") (etchFactor "90.000000") (elecCondVal "595900.000000 mho/cm") (thermCondVal "0.012 w/cm-degC")) ("" (layerType "DIELECTRIC") (material "FR-4") (thickness "  4.500000 mil") (dielectricConstant "4.500000") (lossTangent "0.035") (etchFactor "0.000000") (elecCondVal "0 mho/cm") (thermCondVal "0 w/cm-degC")) ("L9_GND4" (layerType "PLANE") (material "COPPER") (isShield t) (thickness "  1.250000 mil") (dielectricConstant "4.500000") (lossTangent "0.035") (etchFactor "90.000000") (elecCondVal "595900.000000 mho/cm") (thermCondVal "0 w/cm-degC")) ("" (layerType "DIELECTRIC") (material "FR-4") (thickness "  3.000000 mil") (dielectricConstant "4.100000") (lossTangent "0.035") (etchFactor "0.000000") (elecCondVal "0 mho/cm") (thermCondVal "0.012 w/cm-degC")) ("L10_SIG3" (layerType "CONDUCTOR") (material "COPPER") (thickness "  1.250000 mil") (width "4.00 MIL") (dielectricConstant "4.500000") (lossTangent "0.035") (etchFactor "90.000000") (elecCondVal "595900.000000 mho/cm") (thermCondVal "0.012 w/cm-degC") (signalDieConstant "4.100000") (signalLossTangent "0.035")) ("" (layerType "DIELECTRIC") (material "FR-4") (thickness "  9.000000 mil") (dielectricConstant "4.500000") (lossTangent "0.035") (etchFactor "0.000000") (elecCondVal "0 mho/cm") (thermCondVal "0 w/cm-degC")) ("L11_GND5" (layerType "PLANE") (material "COPPER") (isShield t) (thickness "  1.250000 mil") (dielectricConstant "4.500000") (lossTangent "0.035") (etchFactor "90.000000") (elecCondVal "595900.000000 mho/cm") (thermCondVal "0 w/cm-degC")) ("" (layerType "DIELECTRIC") (material "FR-4") (thickness "  3.000000 mil") (dielectricConstant "4.500000") (lossTangent "0.035") (etchFactor "0.000000") (elecCondVal "0 mho/cm") (thermCondVal "0.012 w/cm-degC")) ("L12_SIG4" (layerType "CONDUCTOR") (material "COPPER") (thickness "  1.250000 mil") (width "4.00 MIL") (dielectricConstant "4.500000") (lossTangent "0.035") (etchFactor "90.000000") (elecCondVal "595900.000000 mho/cm") (thermCondVal "0.012 w/cm-degC") (signalDieConstant "4.500000") (signalLossTangent "0.035")) ("" (layerType "DIELECTRIC") (material "FR-4") (thickness "  9.000000 mil") (dielectricConstant "4.500000") (lossTangent "0.035") (etchFactor "0.000000") (elecCondVal "0 mho/cm") (thermCondVal "0 w/cm-degC")) ("L13_GND6" (layerType "PLANE") (material "COPPER") (isShield t) (thickness "  1.250000 mil") (dielectricConstant "4.500000") (lossTangent "0.035") (etchFactor "90.000000") (elecCondVal "595900.000000 mho/cm") (thermCondVal "0.012 w/cm-degC")) ("" (layerType "DIELECTRIC") (material "FR-4") (thickness "  2.670000 mil") (dielectricConstant "4.500000") (lossTangent "0.035") (etchFactor "0.000000") (elecCondVal "0 mho/cm") (thermCondVal "0.012 w/cm-degC")) ("BOTTOM" (layerType "CONDUCTOR") (material "COPPER") (thickness "  2.100000 mil") (width "4.00 MIL") (dielectricConstant "4.500000") (lossTangent "0") (etchFactor "70.000000") (elecCondVal "595900.000000 mho/cm") (thermCondVal "0 w/cm-degC") (signalDieConstant "3.800000") (signalLossTangent "0.035")) ("" (layerType "DIELECTRIC") (material "CONFORMAL_COAT") (thickness "0.5 mil") (dielectricConstant "3.800000") (lossTangent "0.035") (etchFactor "0.000000") (elecCondVal "0 mho/cm") (thermCondVal "0.012 w/cm-degC")) ("" (layerType "SURFACE") (material "AIR") (thickness "0 mil") (dielectricConstant "1.000000") (lossTangent "0") (etchFactor "0.000000") (elecCondVal "0 mho/cm") (thermCondVal "0 w/cm-degC"))))) (Props (DesUnits "mils 2") (LayerStack ("DIELECTRIC" "DIELECTRIC" "BOTTOM" "DIELECTRIC" "L13_GND6" "DIELECTRIC" "L12_SIG4" "DIELECTRIC" "L11_GND5" "DIELECTRIC" "L10_SIG3" "DIELECTRIC" "L9_GND4" "DIELECTRIC" "L8_PWR2-SIG" "DIELECTRIC" "L7_PWR1-SIG" "DIELECTRIC" "L6_GND3" "DIELECTRIC" "L5_SIG2" "DIELECTRIC" "L4_GND2" "DIELECTRIC" "L3_SIG1" "DIELECTRIC" "L2_GND1" "DIELECTRIC" "TOP" "DIELECTRIC" "DIELECTRIC")) (Revision "16.600")) (Params (DiffOutputPkg ((temperature "27") (bufferModelNonInverting "CDSDefaultOutput_2p5v") (bufferModelInverting "CDSDefaultOutput_2p5v") (stimuli nil) (offsets nil) (state "tristate") (cycle "1") (termMap nil) (setup "0.9e-09") (hold "0.4e-09") (rise nil) (fall nil) (threshOutputHighMin "2.375  V") (threshOutputHighTyp "2.5  V") (threshOutputHighMax "2.625  V") (threshOutputLowMin "1.275  V") (threshOutputLowTyp "1.7  V") (threshOutputLowMax "1.985  V") (mappingTagNonInverting nil) (mappingTagInverting nil) (spice nil))) (HiClampTerm ((cutoffVoltage "0.7 V") (voltage "5 V") (maxDelay "0.1 ns"))) (LowClampTerm ((cutoffVoltage "0.7 V") (voltage "0 V") (maxDelay "0.1 ns"))) (DiffOutput ((temperature "27") (bufferModelNonInverting "CDSDefaultOutput_2p5v") (bufferModelInverting "CDSDefaultOutput_2p5v") (stimuli nil) (offsets nil) (state "tristate") (cycle "1") (termMap nil) (setup "0.9e-09") (hold "0.4e-09") (rise nil) (fall nil) (threshOutputHighMin "2.375  V") (threshOutputHighTyp "2.5  V") (threshOutputHighMax "2.625  V") (threshOutputLowMin "1.275  V") (threshOutputLowTyp "1.7  V") (threshOutputLowMax "1.985  V") (mappingTagNonInverting nil) (mappingTagInverting nil) (spice nil))) (Via ((model "Unknown") (viaOutputFormat "Unknown") (viaPadstack nil) (viaTopLayer nil) (viaBottomLayer nil) (viaIsPower nil) (viaIsGround nil))) (Resistor ((resistance "50 ohm") (orientation "0"))) (RCTerm ((resistance "50 ohm") (capacitance "20 pF") (voltage "5 V") (maxDelay "0.1 ns"))) (DiffIOPkg ((temperature "27") (bufferModelNonInverting "CDSDefaultIO_2p5v") (bufferModelInverting "CDSDefaultIO_2p5v") (stimuli nil) (offsets nil) (state "tristate") (cycle "1") (termMap nil) (setup "0.9e-09") (hold "0.4e-09") (rise nil) (fall nil) (threshInputHighMin "1.7 V") (threshInputHighTyp "1.7  V") (threshInputHighMax "1.7  V") (threshInputLowMin "0.7  V") (threshInputLowTyp "0.7  V") (threshInputLowMax "0.7 ") (threshOutputHighMin "2.365  V") (threshOutputHighTyp "2.5  V") (threshOutputHighMax "2.625  V") (threshOutputLowMin "1.275  V") (threshOutputLowTyp "1.7  V") (threshOutputLowMax "1.985  V") (mappingTagNonInverting nil) (mappingTagInverting nil) (spice nil))) (Trace ((d1Thickness "10 mil") (d1Constant "4.5") (d1LossTangent "0.035") (d2Thickness "10 mil") (d2Constant "4.5") (d2LossTangent "0.035") (d3Thickness "0.0") (d3Constant "1.0") (d3LossTangent "0") length("1000 mil") (spacing "5 mil") (spacing2 "5 mil") (spacing3 "5 mil") (spacing4 "5 mil") (spacing5 "5 mil") (traceConductivity "595900 mho/cm") (traceGeometry "microstrip") (traceLayerName "") (traceThickness "0.72 mil") (traceType "single") (traceWidth "5.0 mil") (traceWidth2 "5.0 mil") (traceWidth3 "5.0 mil") (traceWidth4 "5.0 mil") (traceWidth5 "5.0 mil") (traceWidth6 "5.0 mil") (offset "0 mil") (traceCount "1") (impedance nil))) (TheveninTerm ((resistanceUp "180 ohm") (resistanceDown "270 ohm") (voltageUp "5 V") (voltageDown "0 V") (maxDelay "0.1 ns"))) (DiffIO ((temperature "27") (bufferModelNonInverting "CDSDefaultIO_2p5v") (bufferModelInverting "CDSDefaultIO_2p5v") (stimuli nil) (offsets nil) (state "tristate") (cycle "1") (termMap nil) (setup "0.9e-09") (hold "0.4e-09") (rise nil) (fall nil) (threshInputHighMin "1.7 V") (threshInputHighTyp "1.7  V") (threshInputHighMax "1.7  V") (threshInputLowMin "0.7  V") (threshInputLowTyp "0.7  V") (threshInputLowMax "0.7 ") (threshOutputHighMin "2.365  V") (threshOutputHighTyp "2.5  V") (threshOutputHighMax "2.625  V") (threshOutputLowMin "1.275  V") (threshOutputLowTyp "1.7  V") (threshOutputLowMax "1.985  V") (mappingTagNonInverting nil) (mappingTagInverting nil) (spice nil))) (ShuntTerm ((resistance "50 ohm") (voltage "5 V") (maxDelay "0.1 ns"))) (Inductor ((inductance "5 nH") (orientation "0"))) (Capacitor ((capacitance "10 pF") (orientation "0"))) (RLGC (length("1000 mil"))) (Source ((voltage "5 V"))) (DiffInput ((temperature "27") (bufferModelNonInverting "CDSDefaultInput_2p5v") (bufferModelInverting "CDSDefaultInput_2p5v") (threshInputHighMin "1.7 V") (threshInputHighTyp "1.7  V") (threshInputHighMax "1.7  V") (threshInputLowMin "0.7  V") (threshInputLowTyp "0.7  V") (threshInputLowMax "0.7  V") (mappingTagNonInverting nil) (mappingTagInverting nil) (cycle "1"))) (CPW ((d1Thickness "10 mil") (d1Constant "4.5") (d1LossTangent "0.035") (d2Thickness "0.72 mil") (d2Constant "1") (d2LossTangent "0") (d3Thickness "0.0") (d3Constant "1") (d3LossTangent "0") length("1000 mil") (spacing "5 mil") (spacing2 "5 mil") (spacing3 "5 mil") (spacing4 "5 mil") (spacing5 "5 mil") (traceConductivity "595900 mho/cm") (traceGeometry "cpwms") (traceLayerName "") (traceThickness "0.72 mil") (traceType "single") (traceWidth "5.0 mil") (traceWidth2 "5.0 mil") (traceWidth3 "5.0 mil") (traceWidth4 "5.0 mil") (traceWidth5 "5.0 mil") (traceWidth6 "5.0 mil") (offset "0 mil") (traceCount "1") (impedance nil))) (Cable (length("1 m"))) (CPWMS ((d1Thickness "10 mil") (d1Constant "4.5") (d1LossTangent "0.035") (d2Thickness "0.72 mil") (d2Constant "4.5") (d2LossTangent "0.035") (d3Thickness "0.0") (d3Constant "1") (d3LossTangent "0") length("1000 mil") (spacing "5 mil") (spacing2 "5 mil") (spacing3 "5 mil") (spacing4 "5 mil") (spacing5 "5 mil") (traceConductivity "595900 mho/cm") (traceGeometry "cpwms") (traceLayerName "") (traceThickness "0.72 mil") (traceType "single") (traceWidth "5.0 mil") (traceWidth2 "5.0 mil") (traceWidth3 "5.0 mil") (traceWidth4 "5.0 mil") (traceWidth5 "5.0 mil") (traceWidth6 "5.0 mil") (offset "0 mil") (traceCount "1") (impedance nil))) (CPWSL ((d1Thickness "10 mil") (d1Constant "4.5") (d1LossTangent "0.035") (d2Thickness "0.72 mil") (d2Constant "4.5") (d2LossTangent "0.035") (d3Thickness "10 mil") (d3Constant "4.5") (d3LossTangent "0.035") length("1000 mil") (spacing "5 mil") (spacing2 "5 mil") (spacing3 "5 mil") (spacing4 "5 mil") (spacing5 "5 mil") (traceConductivity "595900 mho/cm") (traceGeometry "cpwms") (traceLayerName "") (traceThickness "0.72 mil") (traceType "single") (traceWidth "5.0 mil") (traceWidth2 "5.0 mil") (traceWidth3 "5.0 mil") (traceWidth4 "5.0 mil") (traceWidth5 "5.0 mil") (traceWidth6 "5.0 mil") (offset "0 mil") (traceCount "1") (impedance nil))) (ESpiceDevice nil) (Diode ((cutoffVoltage "0.7 V"))) (DualClampTerm ((cutoffVoltageUp "0.7 V") (cutoffVoltageDown "0.7 V") (voltageUp "5 V") (voltageDown "0 V") (maxDelay "0.1 ns"))) (IbisOutputPkg ((temperature "27") (bufferModel "CDSDefaultOutput_2p5v") (stimuli nil) (offsets nil) (state "tristate") (cycle "1") (termMap nil) (setup "2.0e-09") (hold "1.0e-09") (rise nil) (fall nil) (macroType nil) (voltage nil) (spice nil) (LEFDEFPinName nil) (LEFDEFPinType nil) (mappingTag nil))) (IbisIO_OpenPullDown ((temperature "27") (bufferModel "CDSDefaultIO_2p5v") (stimuli nil) (offsets nil) (state "tristate") (cycle "1") (termMap nil) (setup "2.0e-09") (hold "1.0e-09") (rise nil) (fall nil) (macroType nil) (voltage nil) (spice nil) (LEFDEFPinName nil) (LEFDEFPinType nil) (mappingTag nil))) (IbisInputPkg ((temperature "27") (bufferModel "CDSDefaultInput_2p5v") (cycle "1") (LEFDEFPinName nil) (LEFDEFPinType nil) (mappingTag nil))) (IbisIOMacro ((temperature "27") (bufferModel "CDSDefaultIO_2p5v") (stimuli nil) (offsets nil) (state "tristate") (cycle "1") (termMap nil) (setup "2.0e-09") (hold "1.0e-09") (rise nil) (fall nil) (macroType nil) (voltage nil) (spice nil) (LEFDEFPinName nil) (LEFDEFPinType nil) (mappingTag nil))) (IbisIO_OpenPullUp ((temperature "27") (bufferModel "CDSDefaultIO_2p5v") (stimuli nil) (offsets nil) (state "tristate") (cycle "1") (termMap nil) (setup "2.0e-09") (hold "1.0e-09") (rise nil) (fall nil) (macroType nil) (voltage nil) (spice nil) (LEFDEFPinName nil) (LEFDEFPinType nil) (mappingTag nil))) (IbisIOPkg ((temperature "27") (bufferModel "CDSDefaultIO_2p5v") (stimuli nil) (offsets nil) (state "tristate") (cycle "1") (termMap nil) (setup "2.0e-09") (hold "1.0e-09") (rise nil) (fall nil) (macroType nil) (voltage nil) (spice nil) (LEFDEFPinName nil) (LEFDEFPinType nil) (mappingTag nil))) (clocked ((clockRise "1e-09") (clockFall "1e-09") (clockFreq "100e6") (clockInitState "0") (clockDutyCycle "0.5") (clockJitter "0"))) (periodic ((periodicFreq "100e6") (periodicPattern "10") (periodicJitter "0"))) (IbisIO ((temperature "27") (bufferModel "CDSDefaultIO_2p5v") (stimuli nil) (offsets nil) (state "tristate") (cycle "1") (termMap nil) (setup "2.0e-09") (hold "1.0e-09") (rise nil) (fall nil) (macroType nil) (voltage nil) (spice nil) (LEFDEFPinName nil) (LEFDEFPinType nil) (mappingTag nil))) (async ((asyncTimePoints "") (asyncInitState "1"))) (IbisOutput ((temperature "27") (bufferModel "CDSDefaultOutput_2p5v") (stimuli nil) (offsets nil) (state "tristate") (cycle "1") (termMap nil) (setup "2.0e-09") (hold "1.0e-09") (rise nil) (fall nil) (macroType nil) (voltage nil) (spice nil) (LEFDEFPinName nil) (LEFDEFPinType nil) (mappingTag nil))) (TLine ((diffImpedance "100ohm") (diffVelocity "1.4142e+08M/s") (impedance "60ohm") length("2800 mil") (propDelay "0.5 ns") (velocity "5600 mil/ns") (traceCount "1") (traceGeometry "Microstrip") (impedanceMin nil) (impedanceMax nil) (lengthMin nil) (lengthMax nil) (propDelayMin nil) (propDelayMax nil) (impedanceSweepCount nil) (propDelaySweepCount nil) (velocitySweepCount nil) (lengthSweepCount nil) (matchSetName nil))) (CurrentProbe nil) (IbisInput ((temperature "27") (bufferModel "CDSDefaultInput_2p5v") (cycle "1") (LEFDEFPinName nil) (LEFDEFPinType nil) (mappingTag nil))) (SeriesTerm ((resistance "22 ohm") (maxDelay "0.1 ns"))) (Connector nil) (sync ((syncFreq "100e6") (syncInitState "1") (syncPattern "10") (syncEdgeSwitch "rise"))) (IbisOutput_OpenPullUp ((temperature "27") (bufferModel "CDSDefaultOutput_2p5v") (stimuli nil) (offsets nil) (state "tristate") (cycle "1") (termMap nil) (setup "2.0e-09") (hold "1.0e-09") (rise nil) (fall nil) (macroType nil) (voltage nil) (spice nil) (LEFDEFPinName nil) (LEFDEFPinType nil) (mappingTag nil))) (DiffInputPkg ((temperature "27") (bufferModelNonInverting "CDSDefaultInput_2p5v") (bufferModelInverting "CDSDefaultInput_2p5v") (threshInputHighMin "1.7 V") (threshInputHighTyp "1.7  V") (threshInputHighMax "1.7  V") (threshInputLowMin "0.7  V") (threshInputLowTyp "0.7  V") (threshInputLowMax "0.7  V") (mappingTagNonInverting nil) (mappingTagInverting nil) (cycle "1"))) (idlCircuit ((allDrivers "active") (ftsMode '("Typ")) (rcvrSelect "all") (simMode "Reflection") (tlineDelayMode "time") (userRevision "1.0") (autoSolve "On")))))
				)
				( objectStatus "JTAG_PCH" )
			)
			( electricalCSet "@crescent_city_bb_fab1_lib.crescent_city_bb_fab1(sch_1):\JTAG_BMC\"
				( pinPairRef "JTAG_BMC:J7G2.8:R8G16.2" )
				( pinPairRef "JTAG_BMC:J7G2.8:R8G15.2" )
				( pinPairRef "JTAG_BMC:J7G2.8:R8G17.2" )
				( pinPairRef "JTAG_BMC:J7G2.8:R8G18.2" )
				( pinPairRef "JTAG_BMC:J7G2.8:U8D7.A7" )
				( pinPairRef "JTAG_BMC:J7G2.8:U7C1.AL18" )
				( pinPairRef "JTAG_BMC:J7G2.8:U7C1.BV21" )
				( pinPairRef "JTAG_BMC:J7G2.8:U9F4.F2" )
				( attribute "TOPOLOGY_TEMPLATE_REVISION" "1.0"
					( Origin gBackEnd )
				)
				( topologyData 33564
(SKIDL (Circuits ("MAIN" (Parts ("CRESCENT_CITY_198_20150202_Q.@@U22.BV21" IbisIOPkg (xy (5490 4220)) (refDes "U7C1") (model "Unknown") (Props (_SXDesignName "CRESCENT_CITY_198_20150202_Q") (brdx "15750 MIL") (brdy "4029.72 MIL") (bufferModel "CDSDefaultIO_2p5v") (cycle "1") (hold "1.0e-09") (mappingTag "") (offsets ("4" "0") ("5" "0")) (setup "2.0e-09") (state "tristate") (stimuli ("4" "local21") ("5" "local22")) (temperature "27") (termMap ("4" "Data") ("5" "Enable"))) (Terms ("CRESCENT_CITY_198_20150202_Q.X1575000Y402972L2LRATS" "BV21"))) ("CRESCENT_CITY_198_20150202_Q.@@U22.AL18" IbisIOPkg (xy (5475 4206)) (refDes "U7C1") (model "Unknown") (Props (_SXDesignName "CRESCENT_CITY_198_20150202_Q") (brdx "15284.75 MIL") (brdy "3987 MIL") (bufferModel "CDSDefaultIO_2p5v") (cycle "1") (hold "1.0e-09") (mappingTag "") (offsets ("4" "0") ("5" "0")) (setup "2.0e-09") (state "tristate") (stimuli ("4" "local23") ("5" "local24")) (temperature "27") (termMap ("4" "Data") ("5" "Enable"))) (Terms ("CRESCENT_CITY_198_20150202_Q.X1528475Y398700L2LRATS" "AL18"))) ("CRESCENT_CITY_198_20150202_Q.@@U47.F2" IbisIOPkg (xy (5472 4192)) (refDes "U9F4") (model "Unknown") (Props (_SXDesignName "CRESCENT_CITY_198_20150202_Q") (brdx "17744.77 MIL") (brdy "519.79 MIL") (bufferModel "CDSDefaultIO_2p5v") (cycle "1") (hold "1.0e-09") (mappingTag "") (offsets ("4" "0") ("5" "0")) (setup "2.0e-09") (state "tristate") (stimuli ("4" "local25") ("5" "local26")) (temperature "27") (termMap ("4" "Data") ("5" "Enable"))) (Terms ("CRESCENT_CITY_198_20150202_Q.X1774477Y51979L2LRATS" "F2"))) ("CRESCENT_CITY_198_20150202_Q.@@J122.8" IbisIOPkg (xy (5502 4240)) (refDes "J7G2") (model "Unknown") (Props (_SXDesignName "CRESCENT_CITY_198_20150202_Q") (brdx "15750 MIL") (brdy "-150 MIL") (bufferModel "CDSDefaultIO_2p5v") (cycle "1") (hold "1.0e-09") (mappingTag "") (offsets ("4" "0") ("5" "0")) (setup "2.0e-09") (state "tristate") (stimuli ("4" "local27") ("5" "local28")) (temperature "27") (termMap ("4" "Data") ("5" "Enable"))) (Terms ("CRESCENT_CITY_198_20150202_Q.X1575000Yn15000L2LRATS" "8"))) ("CRESCENT_CITY_198_20150202_Q.@@U4E2.A7" IbisIOPkg (xy (5481 4179)) (refDes "U8D7") (model "Unknown") (Props (_SXDesignName "CRESCENT_CITY_198_20150202_Q") (brdx "15407.24 MIL") (brdy "2363.78 MIL") (bufferModel "CDSDefaultIO_2p5v") (cycle "1") (hold "1.0e-09") (mappingTag "") (offsets ("4" "0") ("5" "0")) (setup "2.0e-09") (state "tristate") (stimuli ("4" "local29") ("5" "local30")) (temperature "27") (termMap ("4" "Data") ("5" "Enable"))) (Terms ("CRESCENT_CITY_198_20150202_Q.X1540724Y236378L2LRATS" "A7"))) ("CRESCENT_CITY_198_20150202_Q.T@@RATS@@R3450.2@@R3571.2" TLine (xy (5448 4174)) (refDes "TL11") (Props (_SXDesignName "CRESCENT_CITY_198_20150202_Q") (impedance "48.412 ohm") length("35.00 MIL") (propDelay "0.00629 ns") (traceCount "1") (traceGeometry "Microstrip") (velocity "5564.37 mil/ns")) (Terms ("CRESCENT_CITY_198_20150202_Q.X1568000Yn2500L2LRATS" "1") ("CRESCENT_CITY_198_20150202_Q.X1571500Yn2500L2LRATS" "2"))) ("CRESCENT_CITY_198_20150202_Q.@@R462.2_SOURCE" Source (xy (5481 4198)) (refDes "GND") (value "0 V") (Props (_SXDesignName "CRESCENT_CITY_198_20150202_Q")) (Terms ("CRESCENT_CITY_198_20150202_Q.X1577500Yn6500L2RATS" "1"))) ("CRESCENT_CITY_198_20150202_Q.T@@RATS@@R3571.1@@U4E2.A7" TLine (xy (5472 4174)) (refDes "TL12") (Props (_SXDesignName "CRESCENT_CITY_198_20150202_Q") (impedance "60 ohm") length("2661.54 MIL") (propDelay "0.478031 ns") (traceCount "1") (traceGeometry "Microstrip") (velocity "5567.72 mil/ns")) (Terms ("CRESCENT_CITY_198_20150202_Q.X1571500Y1000L2LRATS" "1") ("CRESCENT_CITY_198_20150202_Q.X1540724Y236378L2LRATS" "2"))) ("CRESCENT_CITY_198_20150202_Q.@@R520.1.2" Resistor (xy (5439 4229)) (refDes "R8G22") (value "1 Ohm") (Props (_SXDesignName "CRESCENT_CITY_198_20150202_Q")) (Terms ("CRESCENT_CITY_198_20150202_Q.X1566500Yn6500L2LRATS" "1") ("CRESCENT_CITY_198_20150202_Q.X1570000Yn6500L2LRATS" "2"))) ("CRESCENT_CITY_198_20150202_Q.T@@RATS@@R462.1@@R520.2" TLine (xy (5488 4229)) (mirror x) (refDes "TL13") (Props (_SXDesignName "CRESCENT_CITY_198_20150202_Q") (impedance "48.412 ohm") length("40.00 MIL") (propDelay "0.00718 ns") (traceCount "1") (traceGeometry "Microstrip") (velocity "5571.02 mil/ns")) (Terms ("CRESCENT_CITY_198_20150202_Q.X1574000Yn6500L2LRATS" "1") ("CRESCENT_CITY_198_20150202_Q.X1570000Yn6500L2LRATS" "2"))) ("CRESCENT_CITY_198_20150202_Q.T@@RATS@@R462.1@@J122.8" TLine (xy (5497 4229)) (refDes "TL14") (Props (_SXDesignName "CRESCENT_CITY_198_20150202_Q") (impedance "48.412 ohm") length("95.00 MIL") (propDelay "0.01706 ns") (traceCount "1") (traceGeometry "Microstrip") (velocity "5568.58 mil/ns")) (Terms ("CRESCENT_CITY_198_20150202_Q.X1574000Yn6500L2LRATS" "1") ("CRESCENT_CITY_198_20150202_Q.X1575000Yn15000L2LRATS" "2"))) ("CRESCENT_CITY_198_20150202_Q.T@@RATS@@R3449.1@@U22.BV21" TLine (xy (5481 4215)) (refDes "TL15") (Props (_SXDesignName "CRESCENT_CITY_198_20150202_Q") (impedance "60 ohm") length("4159.72 MIL") (propDelay "0.747114 ns") (traceCount "1") (traceGeometry "Microstrip") (velocity "5567.76 mil/ns")) (Terms ("CRESCENT_CITY_198_20150202_Q.X1561000Y1000L2LRATS" "1") ("CRESCENT_CITY_198_20150202_Q.X1575000Y402972L2LRATS" "2"))) ("CRESCENT_CITY_198_20150202_Q.T@@RATS@@R3450.2@@R520.1" TLine (xy (5433 4215)) (mirror x) (refDes "TL16") (Props (_SXDesignName "CRESCENT_CITY_198_20150202_Q") (impedance "48.412 ohm") length("55.00 MIL") (propDelay "0.00988 ns") (traceCount "1") (traceGeometry "Microstrip") (velocity "5566.81 mil/ns")) (Terms ("CRESCENT_CITY_198_20150202_Q.X1568000Yn2500L2LRATS" "1") ("CRESCENT_CITY_198_20150202_Q.X1566500Yn6500L2LRATS" "2"))) ("CRESCENT_CITY_198_20150202_Q.T@@RATS@@R3450.2@@R182.2" TLine (xy (5448 4215)) (refDes "TL17") (Props (_SXDesignName "CRESCENT_CITY_198_20150202_Q") (impedance "48.412 ohm") length("35.00 MIL") (propDelay "0.00629 ns") (traceCount "1") (traceGeometry "Microstrip") (velocity "5564.37 mil/ns")) (Terms ("CRESCENT_CITY_198_20150202_Q.X1568000Yn2500L2LRATS" "1") ("CRESCENT_CITY_198_20150202_Q.X1564500Yn2500L2LRATS" "2"))) ("CRESCENT_CITY_198_20150202_Q.@@R462.2.1" Resistor (xy (5488 4198)) (refDes "R8G23") (value "4750 Ohm") (Props (_SXDesignName "CRESCENT_CITY_198_20150202_Q")) (Terms ("CRESCENT_CITY_198_20150202_Q.X1577500Yn6500L2RATS" "2") ("CRESCENT_CITY_198_20150202_Q.X1574000Yn6500L2LRATS" "1"))) ("CRESCENT_CITY_198_20150202_Q.T@@RATS@@R3450.1@@U47.F2" TLine (xy (5463 4187)) (refDes "TL18") (Props (_SXDesignName "CRESCENT_CITY_198_20150202_Q") (impedance "60 ohm") length("2574.55 MIL") (propDelay "0.462409 ns") (traceCount "1") (traceGeometry "Microstrip") (velocity "5567.72 mil/ns")) (Terms ("CRESCENT_CITY_198_20150202_Q.X1568000Y1000L2LRATS" "1") ("CRESCENT_CITY_198_20150202_Q.X1774477Y51979L2LRATS" "2"))) ("CRESCENT_CITY_198_20150202_Q.@@R3450.1.2" Resistor (xy (5448 4187)) (mirror x) (refDes "R8G17") (value "1 Ohm") (Props (_SXDesignName "CRESCENT_CITY_198_20150202_Q")) (Terms ("CRESCENT_CITY_198_20150202_Q.X1568000Y1000L2LRATS" "1") ("CRESCENT_CITY_198_20150202_Q.X1568000Yn2500L2LRATS" "2"))) ("CRESCENT_CITY_198_20150202_Q.@@R3449.1.2" Resistor (xy (5466 4215)) (mirror x) (refDes "R8G15") (value "1 Ohm") (Props (_SXDesignName "CRESCENT_CITY_198_20150202_Q")) (Terms ("CRESCENT_CITY_198_20150202_Q.X1561000Y1000L2LRATS" "1") ("CRESCENT_CITY_198_20150202_Q.X1561000Yn2500L2LRATS" "2"))) ("CRESCENT_CITY_198_20150202_Q.@@R182.2.1" Resistor (xy (5457 4201)) (refDes "R8G16") (value "1 Ohm") (Props (_SXDesignName "CRESCENT_CITY_198_20150202_Q")) (Terms ("CRESCENT_CITY_198_20150202_Q.X1564500Yn2500L2LRATS" "2") ("CRESCENT_CITY_198_20150202_Q.X1564500Y1000L2LRATS" "1"))) ("CRESCENT_CITY_198_20150202_Q.T@@RATS@@R182.1@@U22.AL18" TLine (xy (5466 4201)) (refDes "TL19") (Props (_SXDesignName "CRESCENT_CITY_198_20150202_Q") (impedance "60 ohm") length("4337.24 MIL") (propDelay "0.779 ns") (traceCount "1") (traceGeometry "Microstrip") (velocity "5567.72 mil/ns")) (Terms ("CRESCENT_CITY_198_20150202_Q.X1564500Y1000L2LRATS" "1") ("CRESCENT_CITY_198_20150202_Q.X1528475Y398700L2LRATS" "2"))) ("CRESCENT_CITY_198_20150202_Q.@@R3571.1.2" Resistor (xy (5457 4174)) (mirror x) (refDes "R8G18") (value "1 Ohm") (Props (_SXDesignName "CRESCENT_CITY_198_20150202_Q")) (Terms ("CRESCENT_CITY_198_20150202_Q.X1571500Y1000L2LRATS" "1") ("CRESCENT_CITY_198_20150202_Q.X1571500Yn2500L2LRATS" "2"))) ("CRESCENT_CITY_198_20150202_Q.T@@RATS@@R182.2@@R3449.2" TLine (xy (5457 4215)) (refDes "TL20") (Props (_SXDesignName "CRESCENT_CITY_198_20150202_Q") (impedance "48.412 ohm") length("35.00 MIL") (propDelay "0.00629 ns") (traceCount "1") (traceGeometry "Microstrip") (velocity "5564.37 mil/ns")) (Terms ("CRESCENT_CITY_198_20150202_Q.X1564500Yn2500L2LRATS" "1") ("CRESCENT_CITY_198_20150202_Q.X1561000Yn2500L2LRATS" "2")))) (Nodes ("CRESCENT_CITY_198_20150202_Q.X1575000Yn15000L2LRATS" (terms "CRESCENT_CITY_198_20150202_Q.T@@RATS@@R462.1@@J122.8.2" "CRESCENT_CITY_198_20150202_Q.@@J122.8.1")) ("CRESCENT_CITY_198_20150202_Q.X1564500Y1000L2LRATS" (terms "CRESCENT_CITY_198_20150202_Q.T@@RATS@@R182.1@@U22.AL18.1" "CRESCENT_CITY_198_20150202_Q.@@R182.2.1.2")) ("CRESCENT_CITY_198_20150202_Q.X1575000Y402972L2LRATS" (terms "CRESCENT_CITY_198_20150202_Q.T@@RATS@@R3449.1@@U22.BV21.2" "CRESCENT_CITY_198_20150202_Q.@@U22.BV21.1")) ("CRESCENT_CITY_198_20150202_Q.X1528475Y398700L2LRATS" (terms "CRESCENT_CITY_198_20150202_Q.T@@RATS@@R182.1@@U22.AL18.2" "CRESCENT_CITY_198_20150202_Q.@@U22.AL18.1")) ("CRESCENT_CITY_198_20150202_Q.X1574000Yn6500L2LRATS" (terms "CRESCENT_CITY_198_20150202_Q.@@R462.2.1.2" "CRESCENT_CITY_198_20150202_Q.T@@RATS@@R462.1@@J122.8.1" "CRESCENT_CITY_198_20150202_Q.T@@RATS@@R462.1@@R520.2.1")) ("CRESCENT_CITY_198_20150202_Q.X1570000Yn6500L2LRATS" (terms "CRESCENT_CITY_198_20150202_Q.T@@RATS@@R462.1@@R520.2.2" "CRESCENT_CITY_198_20150202_Q.@@R520.1.2.2")) ("CRESCENT_CITY_198_20150202_Q.X1564500Yn2500L2LRATS" (terms "CRESCENT_CITY_198_20150202_Q.T@@RATS@@R182.2@@R3449.2.1" "CRESCENT_CITY_198_20150202_Q.@@R182.2.1.1" "CRESCENT_CITY_198_20150202_Q.T@@RATS@@R3450.2@@R182.2.2")) ("CRESCENT_CITY_198_20150202_Q.X1568000Yn2500L2LRATS" (terms "CRESCENT_CITY_198_20150202_Q.@@R3450.1.2.2" "CRESCENT_CITY_198_20150202_Q.T@@RATS@@R3450.2@@R182.2.1" "CRESCENT_CITY_198_20150202_Q.T@@RATS@@R3450.2@@R520.1.1" "CRESCENT_CITY_198_20150202_Q.T@@RATS@@R3450.2@@R3571.2.1")) ("CRESCENT_CITY_198_20150202_Q.X1561000Y1000L2LRATS" (terms "CRESCENT_CITY_198_20150202_Q.@@R3449.1.2.1" "CRESCENT_CITY_198_20150202_Q.T@@RATS@@R3449.1@@U22.BV21.1")) ("CRESCENT_CITY_198_20150202_Q.X1568000Y1000L2LRATS" (terms "CRESCENT_CITY_198_20150202_Q.@@R3450.1.2.1" "CRESCENT_CITY_198_20150202_Q.T@@RATS@@R3450.1@@U47.F2.1")) ("CRESCENT_CITY_198_20150202_Q.X1571500Y1000L2LRATS" (terms "CRESCENT_CITY_198_20150202_Q.@@R3571.1.2.1" "CRESCENT_CITY_198_20150202_Q.T@@RATS@@R3571.1@@U4E2.A7.1")) ("CRESCENT_CITY_198_20150202_Q.X1540724Y236378L2LRATS" (terms "CRESCENT_CITY_198_20150202_Q.T@@RATS@@R3571.1@@U4E2.A7.2" "CRESCENT_CITY_198_20150202_Q.@@U4E2.A7.1")) ("CRESCENT_CITY_198_20150202_Q.X1577500Yn6500L2RATS" (terms "CRESCENT_CITY_198_20150202_Q.@@R462.2.1.1" "CRESCENT_CITY_198_20150202_Q.@@R462.2_SOURCE.1")) ("CRESCENT_CITY_198_20150202_Q.X1561000Yn2500L2LRATS" (terms "CRESCENT_CITY_198_20150202_Q.T@@RATS@@R182.2@@R3449.2.2" "CRESCENT_CITY_198_20150202_Q.@@R3449.1.2.2")) ("CRESCENT_CITY_198_20150202_Q.X1566500Yn6500L2LRATS" (terms "CRESCENT_CITY_198_20150202_Q.T@@RATS@@R3450.2@@R520.1.2" "CRESCENT_CITY_198_20150202_Q.@@R520.1.2.1")) ("CRESCENT_CITY_198_20150202_Q.X1571500Yn2500L2LRATS" (terms "CRESCENT_CITY_198_20150202_Q.@@R3571.1.2.2" "CRESCENT_CITY_198_20150202_Q.T@@RATS@@R3450.2@@R3571.2.2")) ("CRESCENT_CITY_198_20150202_Q.X1774477Y51979L2LRATS" (terms "CRESCENT_CITY_198_20150202_Q.T@@RATS@@R3450.1@@U47.F2.2" "CRESCENT_CITY_198_20150202_Q.@@U47.F2.1"))) (Ports) (Stimuli ("local25" (scope local) (stimType periodic) (Props (periodicFreq "5e+007") (periodicJitter "0") (periodicPattern "1"))) ("local30" (scope local) (stimType periodic) (Props (periodicFreq "5e+007") (periodicJitter "0") (periodicPattern "1"))) ("local29" (scope local) (stimType periodic) (Props (periodicFreq "5e+007") (periodicJitter "0") (periodicPattern "1"))) ("local22" (scope local) (stimType periodic) (Props (periodicFreq "5e+007") (periodicJitter "0") (periodicPattern "1"))) ("local24" (scope local) (stimType periodic) (Props (periodicFreq "5e+007") (periodicJitter "0") (periodicPattern "1"))) ("local27" (scope local) (stimType periodic) (Props (periodicFreq "5e+007") (periodicJitter "0") (periodicPattern "1"))) ("local26" (scope local) (stimType periodic) (Props (periodicFreq "5e+007") (periodicJitter "0") (periodicPattern "1"))) ("local21" (scope local) (stimType periodic) (Props (periodicFreq "5e+007") (periodicJitter "0") (periodicPattern "1"))) ("local23" (scope local) (stimType periodic) (Props (periodicFreq "5e+007") (periodicJitter "0") (periodicPattern "1"))) ("local28" (scope local) (stimType periodic) (Props (periodicFreq "5e+007") (periodicJitter "0") (periodicPattern "1")))) (Notes) (Constraints ("DELAY_RULE" ("CRESCENT_CITY_198_20150202_Q J122.8" "CRESCENT_CITY_198_20150202_Q R182.2" "LENGTH" "" "LENGTH" "0.02794") ("CRESCENT_CITY_198_20150202_Q J122.8" "CRESCENT_CITY_198_20150202_Q R3449.2" "LENGTH" "" "LENGTH" "0.02794") ("CRESCENT_CITY_198_20150202_Q J122.8" "CRESCENT_CITY_198_20150202_Q R3450.2" "LENGTH" "" "LENGTH" "0.02794") ("CRESCENT_CITY_198_20150202_Q J122.8" "CRESCENT_CITY_198_20150202_Q R3571.2" "LENGTH" "" "LENGTH" "0.02794") ("CRESCENT_CITY_198_20150202_Q J122.8" "CRESCENT_CITY_198_20150202_Q U4E2.A7" "LENGTH" "" "LENGTH" "0.6096") ("CRESCENT_CITY_198_20150202_Q J122.8" "CRESCENT_CITY_198_20150202_Q U22.AL18" "LENGTH" "" "LENGTH" "0.6096") ("CRESCENT_CITY_198_20150202_Q J122.8" "CRESCENT_CITY_198_20150202_Q U22.BV21" "LENGTH" "" "LENGTH" "0.6096") ("CRESCENT_CITY_198_20150202_Q J122.8" "CRESCENT_CITY_198_20150202_Q U47.F2" "LENGTH" "" "LENGTH" "0.6096"))) (MeasurementSets ("EMI" ("EMIStatus" status("on")) ("PeakEmission" status("on")) ("PeakFrequency" status("on")) ("PulseFreq" status("on")) ("RiseTime" status("on")) ("VoltageSwing" status("on"))) ("Reflection" ("BufferDelayFall" status("off")) ("BufferDelayRise" status("off")) ("EyeHeight" status("off")) ("EyeJitter" status("off")) ("EyeWidth" status("off")) ("FirstIncidentFall" status("off")) ("FirstIncidentRise" status("off")) ("Glitch" status("on")) ("GlitchFall" status("off")) ("GlitchRise" status("off")) ("Monotonic" status("on")) ("MonotonicFall" status("off")) ("MonotonicRise" status("off")) ("NoiseMargin" status("on")) ("NoiseMarginHigh" status("off")) ("NoiseMarginLow" status("off")) ("OvershootHigh" status("on")) ("OvershootLow" status("on")) ("PropDelay" status("on")) ("SettleDelay" status("on")) ("SettleDelayFall" status("off")) ("SettleDelayRise" status("off")) ("SwitchDelay" status("on")) ("SwitchDelayFall" status("off")) ("SwitchDelayRise" status("off"))) ("Crosstalk" ("Crosstalk" status("on"))) ("Custom")) (VectorSets) (Props (XnetName "JTAG_PCH_GBE_CLK") (allDrivers "active") (customSimType "Reflection") (ftsMode ("Typ")) (rcvrSelect "all") (tlineDelayMode "time") (userRevision "1.0")))) (Subckts) (CrossSections ("CRESCENT_CITY_198_20150202_Q" (Props (SXDesignName "CRESCENT_CITY_198_20150202_Q")) (Layers ("" (layerType "SURFACE") (material "AIR") (thickness "0 mil") (dielectricConstant "1.000000") (lossTangent "0") (etchFactor "0.000000") (elecCondVal "0 mho/cm") (thermCondVal "0 w/cm-degC")) ("" (layerType "DIELECTRIC") (material "CONFORMAL_COAT") (thickness "0.5 mil") (dielectricConstant "3.800000") (lossTangent "0.035") (etchFactor "0.000000") (elecCondVal "0 mho/cm") (thermCondVal "0.012 w/cm-degC")) ("TOP" (layerType "CONDUCTOR") (material "COPPER") (thickness "  2.100000 mil") (width "4.00 MIL") (dielectricConstant "4.500000") (lossTangent "0") (etchFactor "70.000000") (elecCondVal "595900.000000 mho/cm") (thermCondVal "0 w/cm-degC") (signalDieConstant "3.800000") (signalLossTangent "0.035")) ("" (layerType "DIELECTRIC") (material "FR-4") (thickness "  2.670000 mil") (dielectricConstant "4.000000") (lossTangent "0.035") (etchFactor "0.000000") (elecCondVal "0 mho/cm") (thermCondVal "0.012 w/cm-degC")) ("L2_GND1" (layerType "PLANE") (material "COPPER") (isShield t) (thickness "  1.250000 mil") (dielectricConstant "4.500000") (lossTangent "0.035") (etchFactor "90.000000") (elecCondVal "595900.000000 mho/cm") (thermCondVal "0.012 w/cm-degC")) ("" (layerType "DIELECTRIC") (material "FR-4") (thickness "  9.000000 mil") (dielectricConstant "4.100000") (lossTangent "0.035") (etchFactor "0.000000") (elecCondVal "0 mho/cm") (thermCondVal "0.012 w/cm-degC")) ("L3_SIG1" (layerType "CONDUCTOR") (material "COPPER") (thickness "  1.250000 mil") (width "4.00 MIL") (dielectricConstant "4.500000") (lossTangent "0.035") (etchFactor "90.000000") (elecCondVal "595900.000000 mho/cm") (thermCondVal "0.012 w/cm-degC") (signalDieConstant "4.100000") (signalLossTangent "0.035")) ("" (layerType "DIELECTRIC") (material "FR-4") (thickness "  3.000000 mil") (dielectricConstant "4.500000") (lossTangent "0.035") (etchFactor "0.000000") (elecCondVal "0 mho/cm") (thermCondVal "0 w/cm-degC")) ("L4_GND2" (layerType "PLANE") (material "COPPER") (isShield t) (thickness "  1.250000 mil") (dielectricConstant "4.500000") (lossTangent "0.035") (etchFactor "90.000000") (elecCondVal "595900.000000 mho/cm") (thermCondVal "0 w/cm-degC")) ("" (layerType "DIELECTRIC") (material "FR-4") (thickness "  9.000000 mil") (dielectricConstant "4.000000") (lossTangent "0.035") (etchFactor "0.000000") (elecCondVal "0 mho/cm") (thermCondVal "0.012 w/cm-degC")) ("L5_SIG2" (layerType "CONDUCTOR") (material "COPPER") (thickness "  1.250000 mil") (width "4.00 MIL") (dielectricConstant "4.500000") (lossTangent "0.035") (etchFactor "90.000000") (elecCondVal "595900.000000 mho/cm") (thermCondVal "0.012 w/cm-degC") (signalDieConstant "4.000000") (signalLossTangent "0.035")) ("" (layerType "DIELECTRIC") (material "FR-4") (thickness "  3.000000 mil") (dielectricConstant "4.500000") (lossTangent "0.035") (etchFactor "0.000000") (elecCondVal "0 mho/cm") (thermCondVal "0 w/cm-degC")) ("L6_GND3" (layerType "PLANE") (material "COPPER") (isShield t) (thickness "  1.250000 mil") (dielectricConstant "4.500000") (lossTangent "0.035") (etchFactor "90.000000") (elecCondVal "595900.000000 mho/cm") (thermCondVal "0 w/cm-degC")) ("" (layerType "DIELECTRIC") (material "FR-4") (thickness "  4.500000 mil") (dielectricConstant "4.100000") (lossTangent "0.035") (etchFactor "0.000000") (elecCondVal "0 mho/cm") (thermCondVal "0.012 w/cm-degC")) ("L7_PWR1-SIG" (layerType "PLANE") (material "COPPER") (isShield t) (thickness "  2.400000 mil") (dielectricConstant "4.500000") (lossTangent "0.035") (etchFactor "90.000000") (elecCondVal "595900.000000 mho/cm") (thermCondVal "0.012 w/cm-degC")) ("" (layerType "DIELECTRIC") (material "FR-4") (thickness "  4.600000 mil") (dielectricConstant "4.000000") (lossTangent "0.035") (etchFactor "0.000000") (elecCondVal "0 mho/cm") (thermCondVal "0.012 w/cm-degC")) ("L8_PWR2-SIG" (layerType "PLANE") (material "COPPER") (isShield t) (thickness "  2.400000 mil") (dielectricConstant "4.500000") (lossTangent "0.035") (etchFactor "90.000000") (elecCondVal "595900.000000 mho/cm") (thermCondVal "0.012 w/cm-degC")) ("" (layerType "DIELECTRIC") (material "FR-4") (thickness "  4.500000 mil") (dielectricConstant "4.500000") (lossTangent "0.035") (etchFactor "0.000000") (elecCondVal "0 mho/cm") (thermCondVal "0 w/cm-degC")) ("L9_GND4" (layerType "PLANE") (material "COPPER") (isShield t) (thickness "  1.250000 mil") (dielectricConstant "4.500000") (lossTangent "0.035") (etchFactor "90.000000") (elecCondVal "595900.000000 mho/cm") (thermCondVal "0 w/cm-degC")) ("" (layerType "DIELECTRIC") (material "FR-4") (thickness "  3.000000 mil") (dielectricConstant "4.100000") (lossTangent "0.035") (etchFactor "0.000000") (elecCondVal "0 mho/cm") (thermCondVal "0.012 w/cm-degC")) ("L10_SIG3" (layerType "CONDUCTOR") (material "COPPER") (thickness "  1.250000 mil") (width "4.00 MIL") (dielectricConstant "4.500000") (lossTangent "0.035") (etchFactor "90.000000") (elecCondVal "595900.000000 mho/cm") (thermCondVal "0.012 w/cm-degC") (signalDieConstant "4.100000") (signalLossTangent "0.035")) ("" (layerType "DIELECTRIC") (material "FR-4") (thickness "  9.000000 mil") (dielectricConstant "4.500000") (lossTangent "0.035") (etchFactor "0.000000") (elecCondVal "0 mho/cm") (thermCondVal "0 w/cm-degC")) ("L11_GND5" (layerType "PLANE") (material "COPPER") (isShield t) (thickness "  1.250000 mil") (dielectricConstant "4.500000") (lossTangent "0.035") (etchFactor "90.000000") (elecCondVal "595900.000000 mho/cm") (thermCondVal "0 w/cm-degC")) ("" (layerType "DIELECTRIC") (material "FR-4") (thickness "  3.000000 mil") (dielectricConstant "4.500000") (lossTangent "0.035") (etchFactor "0.000000") (elecCondVal "0 mho/cm") (thermCondVal "0.012 w/cm-degC")) ("L12_SIG4" (layerType "CONDUCTOR") (material "COPPER") (thickness "  1.250000 mil") (width "4.00 MIL") (dielectricConstant "4.500000") (lossTangent "0.035") (etchFactor "90.000000") (elecCondVal "595900.000000 mho/cm") (thermCondVal "0.012 w/cm-degC") (signalDieConstant "4.500000") (signalLossTangent "0.035")) ("" (layerType "DIELECTRIC") (material "FR-4") (thickness "  9.000000 mil") (dielectricConstant "4.500000") (lossTangent "0.035") (etchFactor "0.000000") (elecCondVal "0 mho/cm") (thermCondVal "0 w/cm-degC")) ("L13_GND6" (layerType "PLANE") (material "COPPER") (isShield t) (thickness "  1.250000 mil") (dielectricConstant "4.500000") (lossTangent "0.035") (etchFactor "90.000000") (elecCondVal "595900.000000 mho/cm") (thermCondVal "0.012 w/cm-degC")) ("" (layerType "DIELECTRIC") (material "FR-4") (thickness "  2.670000 mil") (dielectricConstant "4.500000") (lossTangent "0.035") (etchFactor "0.000000") (elecCondVal "0 mho/cm") (thermCondVal "0.012 w/cm-degC")) ("BOTTOM" (layerType "CONDUCTOR") (material "COPPER") (thickness "  2.100000 mil") (width "4.00 MIL") (dielectricConstant "4.500000") (lossTangent "0") (etchFactor "70.000000") (elecCondVal "595900.000000 mho/cm") (thermCondVal "0 w/cm-degC") (signalDieConstant "3.800000") (signalLossTangent "0.035")) ("" (layerType "DIELECTRIC") (material "CONFORMAL_COAT") (thickness "0.5 mil") (dielectricConstant "3.800000") (lossTangent "0.035") (etchFactor "0.000000") (elecCondVal "0 mho/cm") (thermCondVal "0.012 w/cm-degC")) ("" (layerType "SURFACE") (material "AIR") (thickness "0 mil") (dielectricConstant "1.000000") (lossTangent "0") (etchFactor "0.000000") (elecCondVal "0 mho/cm") (thermCondVal "0 w/cm-degC"))))) (Props (DesUnits "mils 2") (LayerStack ("DIELECTRIC" "DIELECTRIC" "BOTTOM" "DIELECTRIC" "L13_GND6" "DIELECTRIC" "L12_SIG4" "DIELECTRIC" "L11_GND5" "DIELECTRIC" "L10_SIG3" "DIELECTRIC" "L9_GND4" "DIELECTRIC" "L8_PWR2-SIG" "DIELECTRIC" "L7_PWR1-SIG" "DIELECTRIC" "L6_GND3" "DIELECTRIC" "L5_SIG2" "DIELECTRIC" "L4_GND2" "DIELECTRIC" "L3_SIG1" "DIELECTRIC" "L2_GND1" "DIELECTRIC" "TOP" "DIELECTRIC" "DIELECTRIC")) (Revision "16.600")) (Params (IbisIOPkg ((temperature "27") (bufferModel "CDSDefaultIO_2p5v") (stimuli nil) (offsets nil) (state "tristate") (cycle "1") (termMap nil) (setup "2.0e-09") (hold "1.0e-09") (rise nil) (fall nil) (macroType nil) (voltage nil) (spice nil) (LEFDEFPinName nil) (LEFDEFPinType nil) (mappingTag nil))) (IbisIOMacro ((temperature "27") (bufferModel "CDSDefaultIO_2p5v") (stimuli nil) (offsets nil) (state "tristate") (cycle "1") (termMap nil) (setup "2.0e-09") (hold "1.0e-09") (rise nil) (fall nil) (macroType nil) (voltage nil) (spice nil) (LEFDEFPinName nil) (LEFDEFPinType nil) (mappingTag nil))) (IbisOutput ((temperature "27") (bufferModel "CDSDefaultOutput_2p5v") (stimuli nil) (offsets nil) (state "tristate") (cycle "1") (termMap nil) (setup "2.0e-09") (hold "1.0e-09") (rise nil) (fall nil) (macroType nil) (voltage nil) (spice nil) (LEFDEFPinName nil) (LEFDEFPinType nil) (mappingTag nil))) (IbisInputPkg ((temperature "27") (bufferModel "CDSDefaultInput_2p5v") (cycle "1") (LEFDEFPinName nil) (LEFDEFPinType nil) (mappingTag nil))) (IbisIO ((temperature "27") (bufferModel "CDSDefaultIO_2p5v") (stimuli nil) (offsets nil) (state "tristate") (cycle "1") (termMap nil) (setup "2.0e-09") (hold "1.0e-09") (rise nil) (fall nil) (macroType nil) (voltage nil) (spice nil) (LEFDEFPinName nil) (LEFDEFPinType nil) (mappingTag nil))) (IbisOutputPkg ((temperature "27") (bufferModel "CDSDefaultOutput_2p5v") (stimuli nil) (offsets nil) (state "tristate") (cycle "1") (termMap nil) (setup "2.0e-09") (hold "1.0e-09") (rise nil) (fall nil) (macroType nil) (voltage nil) (spice nil) (LEFDEFPinName nil) (LEFDEFPinType nil) (mappingTag nil))) (periodic ((periodicFreq "100e6") (periodicPattern "10") (periodicJitter "0"))) (IbisIO_OpenPullUp ((temperature "27") (bufferModel "CDSDefaultIO_2p5v") (stimuli nil) (offsets nil) (state "tristate") (cycle "1") (termMap nil) (setup "2.0e-09") (hold "1.0e-09") (rise nil) (fall nil) (macroType nil) (voltage nil) (spice nil) (LEFDEFPinName nil) (LEFDEFPinType nil) (mappingTag nil))) (clocked ((clockRise "1e-09") (clockFall "1e-09") (clockFreq "100e6") (clockInitState "0") (clockDutyCycle "0.5") (clockJitter "0"))) (IbisIO_OpenPullDown ((temperature "27") (bufferModel "CDSDefaultIO_2p5v") (stimuli nil) (offsets nil) (state "tristate") (cycle "1") (termMap nil) (setup "2.0e-09") (hold "1.0e-09") (rise nil) (fall nil) (macroType nil) (voltage nil) (spice nil) (LEFDEFPinName nil) (LEFDEFPinType nil) (mappingTag nil))) (async ((asyncTimePoints "") (asyncInitState "1"))) (TLine ((diffImpedance "100ohm") (diffVelocity "1.4142e+08M/s") (impedance "60ohm") length("2800 mil") (propDelay "0.5 ns") (velocity "5600 mil/ns") (traceCount "1") (traceGeometry "Microstrip") (impedanceMin nil) (impedanceMax nil) (lengthMin nil) (lengthMax nil) (propDelayMin nil) (propDelayMax nil) (impedanceSweepCount nil) (propDelaySweepCount nil) (velocitySweepCount nil) (lengthSweepCount nil) (matchSetName nil))) (Connector nil) (CurrentProbe nil) (SeriesTerm ((resistance "22 ohm") (maxDelay "0.1 ns"))) (IbisOutput_OpenPullUp ((temperature "27") (bufferModel "CDSDefaultOutput_2p5v") (stimuli nil) (offsets nil) (state "tristate") (cycle "1") (termMap nil) (setup "2.0e-09") (hold "1.0e-09") (rise nil) (fall nil) (macroType nil) (voltage nil) (spice nil) (LEFDEFPinName nil) (LEFDEFPinType nil) (mappingTag nil))) (DiffInputPkg ((temperature "27") (bufferModelNonInverting "CDSDefaultInput_2p5v") (bufferModelInverting "CDSDefaultInput_2p5v") (threshInputHighMin "1.7 V") (threshInputHighTyp "1.7  V") (threshInputHighMax "1.7  V") (threshInputLowMin "0.7  V") (threshInputLowTyp "0.7  V") (threshInputLowMax "0.7  V") (mappingTagNonInverting nil) (mappingTagInverting nil) (cycle "1"))) (idlCircuit ((allDrivers "active") (ftsMode '("Typ")) (rcvrSelect "all") (simMode "Reflection") (tlineDelayMode "time") (userRevision "1.0") (autoSolve "On"))) (IbisInput ((temperature "27") (bufferModel "CDSDefaultInput_2p5v") (cycle "1") (LEFDEFPinName nil) (LEFDEFPinType nil) (mappingTag nil))) (sync ((syncFreq "100e6") (syncInitState "1") (syncPattern "10") (syncEdgeSwitch "rise"))) (Trace ((d1Thickness "10 mil") (d1Constant "4.5") (d1LossTangent "0.035") (d2Thickness "10 mil") (d2Constant "4.5") (d2LossTangent "0.035") (d3Thickness "0.0") (d3Constant "1.0") (d3LossTangent "0") length("1000 mil") (spacing "5 mil") (spacing2 "5 mil") (spacing3 "5 mil") (spacing4 "5 mil") (spacing5 "5 mil") (traceConductivity "595900 mho/cm") (traceGeometry "microstrip") (traceLayerName "") (traceThickness "0.72 mil") (traceType "single") (traceWidth "5.0 mil") (traceWidth2 "5.0 mil") (traceWidth3 "5.0 mil") (traceWidth4 "5.0 mil") (traceWidth5 "5.0 mil") (traceWidth6 "5.0 mil") (offset "0 mil") (traceCount "1") (impedance nil))) (DiffOutput ((temperature "27") (bufferModelNonInverting "CDSDefaultOutput_2p5v") (bufferModelInverting "CDSDefaultOutput_2p5v") (stimuli nil) (offsets nil) (state "tristate") (cycle "1") (termMap nil) (setup "0.9e-09") (hold "0.4e-09") (rise nil) (fall nil) (threshOutputHighMin "2.375  V") (threshOutputHighTyp "2.5  V") (threshOutputHighMax "2.625  V") (threshOutputLowMin "1.275  V") (threshOutputLowTyp "1.7  V") (threshOutputLowMax "1.985  V") (mappingTagNonInverting nil) (mappingTagInverting nil) (spice nil))) (DualClampTerm ((cutoffVoltageUp "0.7 V") (cutoffVoltageDown "0.7 V") (voltageUp "5 V") (voltageDown "0 V") (maxDelay "0.1 ns"))) (Via ((model "Unknown") (viaOutputFormat "Unknown") (viaPadstack nil) (viaTopLayer nil) (viaBottomLayer nil) (viaIsPower nil) (viaIsGround nil))) (Resistor ((resistance "50 ohm") (orientation "0"))) (DiffOutputPkg ((temperature "27") (bufferModelNonInverting "CDSDefaultOutput_2p5v") (bufferModelInverting "CDSDefaultOutput_2p5v") (stimuli nil) (offsets nil) (state "tristate") (cycle "1") (termMap nil) (setup "0.9e-09") (hold "0.4e-09") (rise nil) (fall nil) (threshOutputHighMin "2.375  V") (threshOutputHighTyp "2.5  V") (threshOutputHighMax "2.625  V") (threshOutputLowMin "1.275  V") (threshOutputLowTyp "1.7  V") (threshOutputLowMax "1.985  V") (mappingTagNonInverting nil) (mappingTagInverting nil) (spice nil))) (DiffIO ((temperature "27") (bufferModelNonInverting "CDSDefaultIO_2p5v") (bufferModelInverting "CDSDefaultIO_2p5v") (stimuli nil) (offsets nil) (state "tristate") (cycle "1") (termMap nil) (setup "0.9e-09") (hold "0.4e-09") (rise nil) (fall nil) (threshInputHighMin "1.7 V") (threshInputHighTyp "1.7  V") (threshInputHighMax "1.7  V") (threshInputLowMin "0.7  V") (threshInputLowTyp "0.7  V") (threshInputLowMax "0.7 ") (threshOutputHighMin "2.365  V") (threshOutputHighTyp "2.5  V") (threshOutputHighMax "2.625  V") (threshOutputLowMin "1.275  V") (threshOutputLowTyp "1.7  V") (threshOutputLowMax "1.985  V") (mappingTagNonInverting nil) (mappingTagInverting nil) (spice nil))) (Diode ((cutoffVoltage "0.7 V"))) (DiffIOPkg ((temperature "27") (bufferModelNonInverting "CDSDefaultIO_2p5v") (bufferModelInverting "CDSDefaultIO_2p5v") (stimuli nil) (offsets nil) (state "tristate") (cycle "1") (termMap nil) (setup "0.9e-09") (hold "0.4e-09") (rise nil) (fall nil) (threshInputHighMin "1.7 V") (threshInputHighTyp "1.7  V") (threshInputHighMax "1.7  V") (threshInputLowMin "0.7  V") (threshInputLowTyp "0.7  V") (threshInputLowMax "0.7 ") (threshOutputHighMin "2.365  V") (threshOutputHighTyp "2.5  V") (threshOutputHighMax "2.625  V") (threshOutputLowMin "1.275  V") (threshOutputLowTyp "1.7  V") (threshOutputLowMax "1.985  V") (mappingTagNonInverting nil) (mappingTagInverting nil) (spice nil))) (Source ((voltage "5 V"))) (RLGC (length("1000 mil"))) (Capacitor ((capacitance "10 pF") (orientation "0"))) (DiffInput ((temperature "27") (bufferModelNonInverting "CDSDefaultInput_2p5v") (bufferModelInverting "CDSDefaultInput_2p5v") (threshInputHighMin "1.7 V") (threshInputHighTyp "1.7  V") (threshInputHighMax "1.7  V") (threshInputLowMin "0.7  V") (threshInputLowTyp "0.7  V") (threshInputLowMax "0.7  V") (mappingTagNonInverting nil) (mappingTagInverting nil) (cycle "1"))) (Inductor ((inductance "5 nH") (orientation "0"))) (Cable (length("1 m"))) (ShuntTerm ((resistance "50 ohm") (voltage "5 V") (maxDelay "0.1 ns"))) (CPWSL ((d1Thickness "10 mil") (d1Constant "4.5") (d1LossTangent "0.035") (d2Thickness "0.72 mil") (d2Constant "4.5") (d2LossTangent "0.035") (d3Thickness "10 mil") (d3Constant "4.5") (d3LossTangent "0.035") length("1000 mil") (spacing "5 mil") (spacing2 "5 mil") (spacing3 "5 mil") (spacing4 "5 mil") (spacing5 "5 mil") (traceConductivity "595900 mho/cm") (traceGeometry "cpwms") (traceLayerName "") (traceThickness "0.72 mil") (traceType "single") (traceWidth "5.0 mil") (traceWidth2 "5.0 mil") (traceWidth3 "5.0 mil") (traceWidth4 "5.0 mil") (traceWidth5 "5.0 mil") (traceWidth6 "5.0 mil") (offset "0 mil") (traceCount "1") (impedance nil))) (TheveninTerm ((resistanceUp "180 ohm") (resistanceDown "270 ohm") (voltageUp "5 V") (voltageDown "0 V") (maxDelay "0.1 ns"))) (CPWMS ((d1Thickness "10 mil") (d1Constant "4.5") (d1LossTangent "0.035") (d2Thickness "0.72 mil") (d2Constant "4.5") (d2LossTangent "0.035") (d3Thickness "0.0") (d3Constant "1") (d3LossTangent "0") length("1000 mil") (spacing "5 mil") (spacing2 "5 mil") (spacing3 "5 mil") (spacing4 "5 mil") (spacing5 "5 mil") (traceConductivity "595900 mho/cm") (traceGeometry "cpwms") (traceLayerName "") (traceThickness "0.72 mil") (traceType "single") (traceWidth "5.0 mil") (traceWidth2 "5.0 mil") (traceWidth3 "5.0 mil") (traceWidth4 "5.0 mil") (traceWidth5 "5.0 mil") (traceWidth6 "5.0 mil") (offset "0 mil") (traceCount "1") (impedance nil))) (RCTerm ((resistance "50 ohm") (capacitance "20 pF") (voltage "5 V") (maxDelay "0.1 ns"))) (CPW ((d1Thickness "10 mil") (d1Constant "4.5") (d1LossTangent "0.035") (d2Thickness "0.72 mil") (d2Constant "1") (d2LossTangent "0") (d3Thickness "0.0") (d3Constant "1") (d3LossTangent "0") length("1000 mil") (spacing "5 mil") (spacing2 "5 mil") (spacing3 "5 mil") (spacing4 "5 mil") (spacing5 "5 mil") (traceConductivity "595900 mho/cm") (traceGeometry "cpwms") (traceLayerName "") (traceThickness "0.72 mil") (traceType "single") (traceWidth "5.0 mil") (traceWidth2 "5.0 mil") (traceWidth3 "5.0 mil") (traceWidth4 "5.0 mil") (traceWidth5 "5.0 mil") (traceWidth6 "5.0 mil") (offset "0 mil") (traceCount "1") (impedance nil))) (LowClampTerm ((cutoffVoltage "0.7 V") (voltage "0 V") (maxDelay "0.1 ns"))) (ESpiceDevice nil) (HiClampTerm ((cutoffVoltage "0.7 V") (voltage "5 V") (maxDelay "0.1 ns")))))
				)
				( objectStatus "JTAG_BMC" )
			)
			( electricalCSet "@crescent_city_bb_fab1_lib.crescent_city_bb_fab1(sch_1):\JTAG_PCH_GBE_TRST_N\"
				( pinPairRef "JTAG_PCH_GBE_TRST_N:J7G2.4:R8G10.2" )
				( pinPairRef "JTAG_PCH_GBE_TRST_N:J7G2.4:R8G9.2" )
				( pinPairRef "JTAG_PCH_GBE_TRST_N:J7G2.4:U7C1.CA24" )
				( pinPairRef "JTAG_PCH_GBE_TRST_N:J7G2.4:U9F4.E1" )
				( attribute "TOPOLOGY_TEMPLATE_REVISION" "1.0"
					( Origin gBackEnd )
				)
				( topologyData 26143
(SKIDL (Circuits ("MAIN" (Parts ("CRESCENT_CITY_195_20150129_6PIN.@@J122.4" IbisIOPkg (xy (5517.5 4229.5)) (refDes "J7G2") (model "Unknown") (Props (_SXDesignName "CRESCENT_CITY_195_20150129_6PIN") (brdx "15350 MIL") (brdy "-150 MIL") (bufferModel "CDSDefaultIO_2p5v") (cycle "1") (hold "1.0e-09") (mappingTag "") (offsets ("4" "0") ("5" "0")) (setup "2.0e-09") (state "tristate") (stimuli ("4" "local67") ("5" "local68")) (temperature "27") (termMap ("4" "Data") ("5" "Enable"))) (Terms ("CRESCENT_CITY_195_20150129_6PIN.X1535000Yn15000L2LRATS" "4"))) ("CRESCENT_CITY_195_20150129_6PIN.@@U47.E1" IbisIOPkg (xy (5521 4214)) (refDes "U9F4") (model "Unknown") (Props (_SXDesignName "CRESCENT_CITY_195_20150129_6PIN") (brdx "17713.28 MIL") (brdy "488.29 MIL") (bufferModel "CDSDefaultIO_2p5v") (cycle "1") (hold "1.0e-09") (mappingTag "") (offsets ("4" "0") ("5" "0")) (setup "2.0e-09") (state "tristate") (stimuli ("4" "local69") ("5" "local70")) (temperature "27") (termMap ("4" "Data") ("5" "Enable"))) (Terms ("CRESCENT_CITY_195_20150129_6PIN.X1771328Y48829L2LRATS" "E1"))) ("CRESCENT_CITY_195_20150129_6PIN.@@U22.CA24" IbisIOPkg (xy (5511.0 4239.5)) (refDes "U7C1") (model "Unknown") (Props (_SXDesignName "CRESCENT_CITY_195_20150129_6PIN") (brdx "15799.02 MIL") (brdy "4088.78 MIL") (bufferModel "CDSDefaultIO_2p5v") (cycle "1") (hold "1.0e-09") (mappingTag "") (offsets ("4" "0") ("5" "0")) (setup "2.0e-09") (state "tristate") (stimuli ("4" "local71") ("5" "local72")) (temperature "27") (termMap ("4" "Data") ("5" "Enable"))) (Terms ("CRESCENT_CITY_195_20150129_6PIN.X1579902Y408878L2LRATS" "CA24"))) ("CRESCENT_CITY_195_20150129_6PIN.T@@RATS@@U22.CA24@@R3558.1" TLine (xy (5502.0 4234.5)) (mirror x) (refDes "TL46") (Props (_SXDesignName "CRESCENT_CITY_195_20150129_6PIN") (impedance "52.449 ohm") length("4667.80 MIL") (propDelay "0.83837 ns") (traceCount "1") (traceGeometry "Microstrip") (velocity "5567.72 mil/ns")) (Terms ("CRESCENT_CITY_195_20150129_6PIN.X1579902Y408878L2LRATS" "1") ("CRESCENT_CITY_195_20150129_6PIN.X1524500Yn2500L2LRATS" "2"))) ("CRESCENT_CITY_195_20150129_6PIN.T@@RATS@@R3557.2@@J122.4" TLine (xy (5506.5 4224.5)) (refDes "TL47") (Props (_SXDesignName "CRESCENT_CITY_195_20150129_6PIN") (impedance "48.412 ohm") length("165.00 MIL") (propDelay "0.02964 ns") (traceCount "1") (traceGeometry "Microstrip") (velocity "5566.81 mil/ns")) (Terms ("CRESCENT_CITY_195_20150129_6PIN.X1527500Yn6000L2LRATS" "1") ("CRESCENT_CITY_195_20150129_6PIN.X1535000Yn15000L2LRATS" "2"))) ("CRESCENT_CITY_195_20150129_6PIN.@@R3557.1.2" Resistor (xy (5498.0 4209.0)) (mirror x) (refDes "R8G10") (value "1 Ohm") (Props (_SXDesignName "CRESCENT_CITY_195_20150129_6PIN")) (Terms ("CRESCENT_CITY_195_20150129_6PIN.X1527500Yn2500L2LRATS" "1") ("CRESCENT_CITY_195_20150129_6PIN.X1527500Yn6000L2LRATS" "2"))) ("CRESCENT_CITY_195_20150129_6PIN.T@@RATS@@R3557.2@@R3558.2" TLine (xy (5492.0 4224.5)) (mirror x) (refDes "TL48") (Props (_SXDesignName "CRESCENT_CITY_195_20150129_6PIN") (impedance "48.412 ohm") length("30.00 MIL") (propDelay "0.00539 ns") (traceCount "1") (traceGeometry "Microstrip") (velocity "5565.87 mil/ns")) (Terms ("CRESCENT_CITY_195_20150129_6PIN.X1527500Yn6000L2LRATS" "1") ("CRESCENT_CITY_195_20150129_6PIN.X1524500Yn6000L2LRATS" "2"))) ("CRESCENT_CITY_195_20150129_6PIN.T@@RATS@@R3557.1@@U47.E1" TLine (xy (5512 4209)) (refDes "TL49") (Props (_SXDesignName "CRESCENT_CITY_195_20150129_6PIN") (impedance "49.728 ohm") length("2951.57 MIL") (propDelay "0.53012 ns") (traceCount "1") (traceGeometry "Microstrip") (velocity "5567.76 mil/ns")) (Terms ("CRESCENT_CITY_195_20150129_6PIN.X1527500Yn2500L2LRATS" "1") ("CRESCENT_CITY_195_20150129_6PIN.X1771328Y48829L2LRATS" "2"))) ("CRESCENT_CITY_195_20150129_6PIN.@@R3558.1.2" Resistor (xy (5492.0 4234.5)) (mirror x) (refDes "R8G9") (value "2.2e-007 Ohm") (Props (_SXDesignName "CRESCENT_CITY_195_20150129_6PIN")) (Terms ("CRESCENT_CITY_195_20150129_6PIN.X1524500Yn2500L2LRATS" "1") ("CRESCENT_CITY_195_20150129_6PIN.X1524500Yn6000L2LRATS" "2")))) (Nodes ("CRESCENT_CITY_195_20150129_6PIN.X1527500Yn6000L2LRATS" (terms "CRESCENT_CITY_195_20150129_6PIN.T@@RATS@@R3557.2@@R3558.2.1" "CRESCENT_CITY_195_20150129_6PIN.@@R3557.1.2.2" "CRESCENT_CITY_195_20150129_6PIN.T@@RATS@@R3557.2@@J122.4.1")) ("CRESCENT_CITY_195_20150129_6PIN.X1524500Yn6000L2LRATS" (terms "CRESCENT_CITY_195_20150129_6PIN.@@R3558.1.2.2" "CRESCENT_CITY_195_20150129_6PIN.T@@RATS@@R3557.2@@R3558.2.2")) ("CRESCENT_CITY_195_20150129_6PIN.X1771328Y48829L2LRATS" (terms "CRESCENT_CITY_195_20150129_6PIN.T@@RATS@@R3557.1@@U47.E1.2" "CRESCENT_CITY_195_20150129_6PIN.@@U47.E1.1")) ("CRESCENT_CITY_195_20150129_6PIN.X1579902Y408878L2LRATS" (terms "CRESCENT_CITY_195_20150129_6PIN.T@@RATS@@U22.CA24@@R3558.1.1" "CRESCENT_CITY_195_20150129_6PIN.@@U22.CA24.1")) ("CRESCENT_CITY_195_20150129_6PIN.X1524500Yn2500L2LRATS" (terms "CRESCENT_CITY_195_20150129_6PIN.@@R3558.1.2.1" "CRESCENT_CITY_195_20150129_6PIN.T@@RATS@@U22.CA24@@R3558.1.2")) ("CRESCENT_CITY_195_20150129_6PIN.X1535000Yn15000L2LRATS" (terms "CRESCENT_CITY_195_20150129_6PIN.T@@RATS@@R3557.2@@J122.4.2" "CRESCENT_CITY_195_20150129_6PIN.@@J122.4.1")) ("CRESCENT_CITY_195_20150129_6PIN.X1527500Yn2500L2LRATS" (terms "CRESCENT_CITY_195_20150129_6PIN.T@@RATS@@R3557.1@@U47.E1.1" "CRESCENT_CITY_195_20150129_6PIN.@@R3557.1.2.1"))) (Ports) (Stimuli ("local67" (scope local) (stimType periodic) (Props (periodicFreq "5e+007") (periodicJitter "0") (periodicPattern "1"))) ("local71" (scope local) (stimType periodic) (Props (periodicFreq "5e+007") (periodicJitter "0") (periodicPattern "1"))) ("local72" (scope local) (stimType periodic) (Props (periodicFreq "5e+007") (periodicJitter "0") (periodicPattern "1"))) ("local68" (scope local) (stimType periodic) (Props (periodicFreq "5e+007") (periodicJitter "0") (periodicPattern "1"))) ("local69" (scope local) (stimType periodic) (Props (periodicFreq "5e+007") (periodicJitter "0") (periodicPattern "1"))) ("local70" (scope local) (stimType periodic) (Props (periodicFreq "5e+007") (periodicJitter "0") (periodicPattern "1")))) (Notes) (Constraints ("DELAY_RULE" ("CRESCENT_CITY_195_20150129_6PIN J122.4" "CRESCENT_CITY_195_20150129_6PIN R3557.2" "LENGTH" "" "LENGTH" "0.0254") ("CRESCENT_CITY_195_20150129_6PIN J122.4" "CRESCENT_CITY_195_20150129_6PIN R3558.2" "LENGTH" "" "LENGTH" "0.0254") ("CRESCENT_CITY_195_20150129_6PIN J122.4" "CRESCENT_CITY_195_20150129_6PIN U22.CA24" "LENGTH" "" "LENGTH" "0.6096") ("CRESCENT_CITY_195_20150129_6PIN J122.4" "CRESCENT_CITY_195_20150129_6PIN U47.E1" "LENGTH" "" "LENGTH" "0.6096"))) (MeasurementSets ("EMI" ("EMIStatus" status("on")) ("PeakEmission" status("on")) ("PeakFrequency" status("on")) ("PulseFreq" status("on")) ("RiseTime" status("on")) ("VoltageSwing" status("on"))) ("Reflection" ("BufferDelayFall" status("off")) ("BufferDelayRise" status("off")) ("EyeHeight" status("off")) ("EyeJitter" status("off")) ("EyeWidth" status("off")) ("FirstIncidentFall" status("off")) ("FirstIncidentRise" status("off")) ("Glitch" status("on")) ("GlitchFall" status("off")) ("GlitchRise" status("off")) ("Monotonic" status("on")) ("MonotonicFall" status("off")) ("MonotonicRise" status("off")) ("NoiseMargin" status("on")) ("NoiseMarginHigh" status("off")) ("NoiseMarginLow" status("off")) ("OvershootHigh" status("on")) ("OvershootLow" status("on")) ("PropDelay" status("on")) ("SettleDelay" status("on")) ("SettleDelayFall" status("off")) ("SettleDelayRise" status("off")) ("SwitchDelay" status("on")) ("SwitchDelayFall" status("off")) ("SwitchDelayRise" status("off"))) ("Crosstalk" ("Crosstalk" status("on"))) ("Custom")) (VectorSets) (Props (XnetName "JTAG_PCH_GBE_TRST_N") (allDrivers "active") (customSimType "Reflection") (ftsMode ("Typ")) (rcvrSelect "all") (tlineDelayMode "time") (userRevision "1.0")))) (Subckts) (CrossSections ("CRESCENT_CITY_195_20150129_6PIN" (Props (SXDesignName "CRESCENT_CITY_195_20150129_6PIN")) (Layers ("" (layerType "SURFACE") (material "AIR") (thickness "0 mil") (dielectricConstant "1.000000") (lossTangent "0") (etchFactor "0.000000") (elecCondVal "0 mho/cm") (thermCondVal "0 w/cm-degC")) ("" (layerType "DIELECTRIC") (material "CONFORMAL_COAT") (thickness "0.5 mil") (dielectricConstant "3.800000") (lossTangent "0.035") (etchFactor "0.000000") (elecCondVal "0 mho/cm") (thermCondVal "0.012 w/cm-degC")) ("TOP" (layerType "CONDUCTOR") (material "COPPER") (thickness "  2.100000 mil") (width "4.00 MIL") (dielectricConstant "4.500000") (lossTangent "0") (etchFactor "70.000000") (elecCondVal "595900.000000 mho/cm") (thermCondVal "0 w/cm-degC") (signalDieConstant "3.800000") (signalLossTangent "0.035")) ("" (layerType "DIELECTRIC") (material "FR-4") (thickness "  2.670000 mil") (dielectricConstant "4.000000") (lossTangent "0.035") (etchFactor "0.000000") (elecCondVal "0 mho/cm") (thermCondVal "0.012 w/cm-degC")) ("L2_GND1" (layerType "PLANE") (material "COPPER") (isShield t) (thickness "  1.250000 mil") (dielectricConstant "4.500000") (lossTangent "0.035") (etchFactor "90.000000") (elecCondVal "595900.000000 mho/cm") (thermCondVal "0.012 w/cm-degC")) ("" (layerType "DIELECTRIC") (material "FR-4") (thickness "  9.000000 mil") (dielectricConstant "4.100000") (lossTangent "0.035") (etchFactor "0.000000") (elecCondVal "0 mho/cm") (thermCondVal "0.012 w/cm-degC")) ("L3_SIG1" (layerType "CONDUCTOR") (material "COPPER") (thickness "  1.250000 mil") (width "4.00 MIL") (dielectricConstant "4.500000") (lossTangent "0.035") (etchFactor "90.000000") (elecCondVal "595900.000000 mho/cm") (thermCondVal "0.012 w/cm-degC") (signalDieConstant "4.100000") (signalLossTangent "0.035")) ("" (layerType "DIELECTRIC") (material "FR-4") (thickness "  3.000000 mil") (dielectricConstant "4.500000") (lossTangent "0.035") (etchFactor "0.000000") (elecCondVal "0 mho/cm") (thermCondVal "0 w/cm-degC")) ("L4_GND2" (layerType "PLANE") (material "COPPER") (isShield t) (thickness "  1.250000 mil") (dielectricConstant "4.500000") (lossTangent "0.035") (etchFactor "90.000000") (elecCondVal "595900.000000 mho/cm") (thermCondVal "0 w/cm-degC")) ("" (layerType "DIELECTRIC") (material "FR-4") (thickness "  9.000000 mil") (dielectricConstant "4.000000") (lossTangent "0.035") (etchFactor "0.000000") (elecCondVal "0 mho/cm") (thermCondVal "0.012 w/cm-degC")) ("L5_SIG2" (layerType "CONDUCTOR") (material "COPPER") (thickness "  1.250000 mil") (width "4.00 MIL") (dielectricConstant "4.500000") (lossTangent "0.035") (etchFactor "90.000000") (elecCondVal "595900.000000 mho/cm") (thermCondVal "0.012 w/cm-degC") (signalDieConstant "4.000000") (signalLossTangent "0.035")) ("" (layerType "DIELECTRIC") (material "FR-4") (thickness "  3.000000 mil") (dielectricConstant "4.500000") (lossTangent "0.035") (etchFactor "0.000000") (elecCondVal "0 mho/cm") (thermCondVal "0 w/cm-degC")) ("L6_GND3" (layerType "PLANE") (material "COPPER") (isShield t) (thickness "  1.250000 mil") (dielectricConstant "4.500000") (lossTangent "0.035") (etchFactor "90.000000") (elecCondVal "595900.000000 mho/cm") (thermCondVal "0 w/cm-degC")) ("" (layerType "DIELECTRIC") (material "FR-4") (thickness "  4.500000 mil") (dielectricConstant "4.100000") (lossTangent "0.035") (etchFactor "0.000000") (elecCondVal "0 mho/cm") (thermCondVal "0.012 w/cm-degC")) ("L7_PWR1-SIG" (layerType "PLANE") (material "COPPER") (isShield t) (thickness "  2.400000 mil") (dielectricConstant "4.500000") (lossTangent "0.035") (etchFactor "90.000000") (elecCondVal "595900.000000 mho/cm") (thermCondVal "0.012 w/cm-degC")) ("" (layerType "DIELECTRIC") (material "FR-4") (thickness "  4.600000 mil") (dielectricConstant "4.000000") (lossTangent "0.035") (etchFactor "0.000000") (elecCondVal "0 mho/cm") (thermCondVal "0.012 w/cm-degC")) ("L8_PWR2-SIG" (layerType "PLANE") (material "COPPER") (isShield t) (thickness "  2.400000 mil") (dielectricConstant "4.500000") (lossTangent "0.035") (etchFactor "90.000000") (elecCondVal "595900.000000 mho/cm") (thermCondVal "0.012 w/cm-degC")) ("" (layerType "DIELECTRIC") (material "FR-4") (thickness "  4.500000 mil") (dielectricConstant "4.500000") (lossTangent "0.035") (etchFactor "0.000000") (elecCondVal "0 mho/cm") (thermCondVal "0 w/cm-degC")) ("L9_GND4" (layerType "PLANE") (material "COPPER") (isShield t) (thickness "  1.250000 mil") (dielectricConstant "4.500000") (lossTangent "0.035") (etchFactor "90.000000") (elecCondVal "595900.000000 mho/cm") (thermCondVal "0 w/cm-degC")) ("" (layerType "DIELECTRIC") (material "FR-4") (thickness "  3.000000 mil") (dielectricConstant "4.100000") (lossTangent "0.035") (etchFactor "0.000000") (elecCondVal "0 mho/cm") (thermCondVal "0.012 w/cm-degC")) ("L10_SIG3" (layerType "CONDUCTOR") (material "COPPER") (thickness "  1.250000 mil") (width "4.00 MIL") (dielectricConstant "4.500000") (lossTangent "0.035") (etchFactor "90.000000") (elecCondVal "595900.000000 mho/cm") (thermCondVal "0.012 w/cm-degC") (signalDieConstant "4.100000") (signalLossTangent "0.035")) ("" (layerType "DIELECTRIC") (material "FR-4") (thickness "  9.000000 mil") (dielectricConstant "4.500000") (lossTangent "0.035") (etchFactor "0.000000") (elecCondVal "0 mho/cm") (thermCondVal "0 w/cm-degC")) ("L11_GND5" (layerType "PLANE") (material "COPPER") (isShield t) (thickness "  1.250000 mil") (dielectricConstant "4.500000") (lossTangent "0.035") (etchFactor "90.000000") (elecCondVal "595900.000000 mho/cm") (thermCondVal "0 w/cm-degC")) ("" (layerType "DIELECTRIC") (material "FR-4") (thickness "  3.000000 mil") (dielectricConstant "4.500000") (lossTangent "0.035") (etchFactor "0.000000") (elecCondVal "0 mho/cm") (thermCondVal "0.012 w/cm-degC")) ("L12_SIG4" (layerType "CONDUCTOR") (material "COPPER") (thickness "  1.250000 mil") (width "4.00 MIL") (dielectricConstant "4.500000") (lossTangent "0.035") (etchFactor "90.000000") (elecCondVal "595900.000000 mho/cm") (thermCondVal "0.012 w/cm-degC") (signalDieConstant "4.500000") (signalLossTangent "0.035")) ("" (layerType "DIELECTRIC") (material "FR-4") (thickness "  9.000000 mil") (dielectricConstant "4.500000") (lossTangent "0.035") (etchFactor "0.000000") (elecCondVal "0 mho/cm") (thermCondVal "0 w/cm-degC")) ("L13_GND6" (layerType "PLANE") (material "COPPER") (isShield t) (thickness "  1.250000 mil") (dielectricConstant "4.500000") (lossTangent "0.035") (etchFactor "90.000000") (elecCondVal "595900.000000 mho/cm") (thermCondVal "0.012 w/cm-degC")) ("" (layerType "DIELECTRIC") (material "FR-4") (thickness "  2.670000 mil") (dielectricConstant "4.500000") (lossTangent "0.035") (etchFactor "0.000000") (elecCondVal "0 mho/cm") (thermCondVal "0.012 w/cm-degC")) ("BOTTOM" (layerType "CONDUCTOR") (material "COPPER") (thickness "  2.100000 mil") (width "4.00 MIL") (dielectricConstant "4.500000") (lossTangent "0") (etchFactor "70.000000") (elecCondVal "595900.000000 mho/cm") (thermCondVal "0 w/cm-degC") (signalDieConstant "3.800000") (signalLossTangent "0.035")) ("" (layerType "DIELECTRIC") (material "CONFORMAL_COAT") (thickness "0.5 mil") (dielectricConstant "3.800000") (lossTangent "0.035") (etchFactor "0.000000") (elecCondVal "0 mho/cm") (thermCondVal "0.012 w/cm-degC")) ("" (layerType "SURFACE") (material "AIR") (thickness "0 mil") (dielectricConstant "1.000000") (lossTangent "0") (etchFactor "0.000000") (elecCondVal "0 mho/cm") (thermCondVal "0 w/cm-degC"))))) (Props (DesUnits "mils 2") (LayerStack ("DIELECTRIC" "DIELECTRIC" "BOTTOM" "DIELECTRIC" "L13_GND6" "DIELECTRIC" "L12_SIG4" "DIELECTRIC" "L11_GND5" "DIELECTRIC" "L10_SIG3" "DIELECTRIC" "L9_GND4" "DIELECTRIC" "L8_PWR2-SIG" "DIELECTRIC" "L7_PWR1-SIG" "DIELECTRIC" "L6_GND3" "DIELECTRIC" "L5_SIG2" "DIELECTRIC" "L4_GND2" "DIELECTRIC" "L3_SIG1" "DIELECTRIC" "L2_GND1" "DIELECTRIC" "TOP" "DIELECTRIC" "DIELECTRIC")) (Revision "16.600")) (Params (DiffOutputPkg ((temperature "27") (bufferModelNonInverting "CDSDefaultOutput_2p5v") (bufferModelInverting "CDSDefaultOutput_2p5v") (stimuli nil) (offsets nil) (state "tristate") (cycle "1") (termMap nil) (setup "0.9e-09") (hold "0.4e-09") (rise nil) (fall nil) (threshOutputHighMin "2.375  V") (threshOutputHighTyp "2.5  V") (threshOutputHighMax "2.625  V") (threshOutputLowMin "1.275  V") (threshOutputLowTyp "1.7  V") (threshOutputLowMax "1.985  V") (mappingTagNonInverting nil) (mappingTagInverting nil) (spice nil))) (HiClampTerm ((cutoffVoltage "0.7 V") (voltage "5 V") (maxDelay "0.1 ns"))) (LowClampTerm ((cutoffVoltage "0.7 V") (voltage "0 V") (maxDelay "0.1 ns"))) (DiffOutput ((temperature "27") (bufferModelNonInverting "CDSDefaultOutput_2p5v") (bufferModelInverting "CDSDefaultOutput_2p5v") (stimuli nil) (offsets nil) (state "tristate") (cycle "1") (termMap nil) (setup "0.9e-09") (hold "0.4e-09") (rise nil) (fall nil) (threshOutputHighMin "2.375  V") (threshOutputHighTyp "2.5  V") (threshOutputHighMax "2.625  V") (threshOutputLowMin "1.275  V") (threshOutputLowTyp "1.7  V") (threshOutputLowMax "1.985  V") (mappingTagNonInverting nil) (mappingTagInverting nil) (spice nil))) (Via ((model "Unknown") (viaOutputFormat "Unknown") (viaPadstack nil) (viaTopLayer nil) (viaBottomLayer nil) (viaIsPower nil) (viaIsGround nil))) (Resistor ((resistance "50 ohm") (orientation "0"))) (RCTerm ((resistance "50 ohm") (capacitance "20 pF") (voltage "5 V") (maxDelay "0.1 ns"))) (DiffIOPkg ((temperature "27") (bufferModelNonInverting "CDSDefaultIO_2p5v") (bufferModelInverting "CDSDefaultIO_2p5v") (stimuli nil) (offsets nil) (state "tristate") (cycle "1") (termMap nil) (setup "0.9e-09") (hold "0.4e-09") (rise nil) (fall nil) (threshInputHighMin "1.7 V") (threshInputHighTyp "1.7  V") (threshInputHighMax "1.7  V") (threshInputLowMin "0.7  V") (threshInputLowTyp "0.7  V") (threshInputLowMax "0.7 ") (threshOutputHighMin "2.365  V") (threshOutputHighTyp "2.5  V") (threshOutputHighMax "2.625  V") (threshOutputLowMin "1.275  V") (threshOutputLowTyp "1.7  V") (threshOutputLowMax "1.985  V") (mappingTagNonInverting nil) (mappingTagInverting nil) (spice nil))) (Trace ((d1Thickness "10 mil") (d1Constant "4.5") (d1LossTangent "0.035") (d2Thickness "10 mil") (d2Constant "4.5") (d2LossTangent "0.035") (d3Thickness "0.0") (d3Constant "1.0") (d3LossTangent "0") length("1000 mil") (spacing "5 mil") (spacing2 "5 mil") (spacing3 "5 mil") (spacing4 "5 mil") (spacing5 "5 mil") (traceConductivity "595900 mho/cm") (traceGeometry "microstrip") (traceLayerName "") (traceThickness "0.72 mil") (traceType "single") (traceWidth "5.0 mil") (traceWidth2 "5.0 mil") (traceWidth3 "5.0 mil") (traceWidth4 "5.0 mil") (traceWidth5 "5.0 mil") (traceWidth6 "5.0 mil") (offset "0 mil") (traceCount "1") (impedance nil))) (TheveninTerm ((resistanceUp "180 ohm") (resistanceDown "270 ohm") (voltageUp "5 V") (voltageDown "0 V") (maxDelay "0.1 ns"))) (DiffIO ((temperature "27") (bufferModelNonInverting "CDSDefaultIO_2p5v") (bufferModelInverting "CDSDefaultIO_2p5v") (stimuli nil) (offsets nil) (state "tristate") (cycle "1") (termMap nil) (setup "0.9e-09") (hold "0.4e-09") (rise nil) (fall nil) (threshInputHighMin "1.7 V") (threshInputHighTyp "1.7  V") (threshInputHighMax "1.7  V") (threshInputLowMin "0.7  V") (threshInputLowTyp "0.7  V") (threshInputLowMax "0.7 ") (threshOutputHighMin "2.365  V") (threshOutputHighTyp "2.5  V") (threshOutputHighMax "2.625  V") (threshOutputLowMin "1.275  V") (threshOutputLowTyp "1.7  V") (threshOutputLowMax "1.985  V") (mappingTagNonInverting nil) (mappingTagInverting nil) (spice nil))) (ShuntTerm ((resistance "50 ohm") (voltage "5 V") (maxDelay "0.1 ns"))) (Inductor ((inductance "5 nH") (orientation "0"))) (Capacitor ((capacitance "10 pF") (orientation "0"))) (RLGC (length("1000 mil"))) (Source ((voltage "5 V"))) (DiffInput ((temperature "27") (bufferModelNonInverting "CDSDefaultInput_2p5v") (bufferModelInverting "CDSDefaultInput_2p5v") (threshInputHighMin "1.7 V") (threshInputHighTyp "1.7  V") (threshInputHighMax "1.7  V") (threshInputLowMin "0.7  V") (threshInputLowTyp "0.7  V") (threshInputLowMax "0.7  V") (mappingTagNonInverting nil) (mappingTagInverting nil) (cycle "1"))) (CPW ((d1Thickness "10 mil") (d1Constant "4.5") (d1LossTangent "0.035") (d2Thickness "0.72 mil") (d2Constant "1") (d2LossTangent "0") (d3Thickness "0.0") (d3Constant "1") (d3LossTangent "0") length("1000 mil") (spacing "5 mil") (spacing2 "5 mil") (spacing3 "5 mil") (spacing4 "5 mil") (spacing5 "5 mil") (traceConductivity "595900 mho/cm") (traceGeometry "cpwms") (traceLayerName "") (traceThickness "0.72 mil") (traceType "single") (traceWidth "5.0 mil") (traceWidth2 "5.0 mil") (traceWidth3 "5.0 mil") (traceWidth4 "5.0 mil") (traceWidth5 "5.0 mil") (traceWidth6 "5.0 mil") (offset "0 mil") (traceCount "1") (impedance nil))) (Cable (length("1 m"))) (CPWMS ((d1Thickness "10 mil") (d1Constant "4.5") (d1LossTangent "0.035") (d2Thickness "0.72 mil") (d2Constant "4.5") (d2LossTangent "0.035") (d3Thickness "0.0") (d3Constant "1") (d3LossTangent "0") length("1000 mil") (spacing "5 mil") (spacing2 "5 mil") (spacing3 "5 mil") (spacing4 "5 mil") (spacing5 "5 mil") (traceConductivity "595900 mho/cm") (traceGeometry "cpwms") (traceLayerName "") (traceThickness "0.72 mil") (traceType "single") (traceWidth "5.0 mil") (traceWidth2 "5.0 mil") (traceWidth3 "5.0 mil") (traceWidth4 "5.0 mil") (traceWidth5 "5.0 mil") (traceWidth6 "5.0 mil") (offset "0 mil") (traceCount "1") (impedance nil))) (CPWSL ((d1Thickness "10 mil") (d1Constant "4.5") (d1LossTangent "0.035") (d2Thickness "0.72 mil") (d2Constant "4.5") (d2LossTangent "0.035") (d3Thickness "10 mil") (d3Constant "4.5") (d3LossTangent "0.035") length("1000 mil") (spacing "5 mil") (spacing2 "5 mil") (spacing3 "5 mil") (spacing4 "5 mil") (spacing5 "5 mil") (traceConductivity "595900 mho/cm") (traceGeometry "cpwms") (traceLayerName "") (traceThickness "0.72 mil") (traceType "single") (traceWidth "5.0 mil") (traceWidth2 "5.0 mil") (traceWidth3 "5.0 mil") (traceWidth4 "5.0 mil") (traceWidth5 "5.0 mil") (traceWidth6 "5.0 mil") (offset "0 mil") (traceCount "1") (impedance nil))) (ESpiceDevice nil) (Diode ((cutoffVoltage "0.7 V"))) (DualClampTerm ((cutoffVoltageUp "0.7 V") (cutoffVoltageDown "0.7 V") (voltageUp "5 V") (voltageDown "0 V") (maxDelay "0.1 ns"))) (IbisOutputPkg ((temperature "27") (bufferModel "CDSDefaultOutput_2p5v") (stimuli nil) (offsets nil) (state "tristate") (cycle "1") (termMap nil) (setup "2.0e-09") (hold "1.0e-09") (rise nil) (fall nil) (macroType nil) (voltage nil) (spice nil) (LEFDEFPinName nil) (LEFDEFPinType nil) (mappingTag nil))) (IbisIO_OpenPullDown ((temperature "27") (bufferModel "CDSDefaultIO_2p5v") (stimuli nil) (offsets nil) (state "tristate") (cycle "1") (termMap nil) (setup "2.0e-09") (hold "1.0e-09") (rise nil) (fall nil) (macroType nil) (voltage nil) (spice nil) (LEFDEFPinName nil) (LEFDEFPinType nil) (mappingTag nil))) (IbisInputPkg ((temperature "27") (bufferModel "CDSDefaultInput_2p5v") (cycle "1") (LEFDEFPinName nil) (LEFDEFPinType nil) (mappingTag nil))) (IbisIOMacro ((temperature "27") (bufferModel "CDSDefaultIO_2p5v") (stimuli nil) (offsets nil) (state "tristate") (cycle "1") (termMap nil) (setup "2.0e-09") (hold "1.0e-09") (rise nil) (fall nil) (macroType nil) (voltage nil) (spice nil) (LEFDEFPinName nil) (LEFDEFPinType nil) (mappingTag nil))) (IbisIO_OpenPullUp ((temperature "27") (bufferModel "CDSDefaultIO_2p5v") (stimuli nil) (offsets nil) (state "tristate") (cycle "1") (termMap nil) (setup "2.0e-09") (hold "1.0e-09") (rise nil) (fall nil) (macroType nil) (voltage nil) (spice nil) (LEFDEFPinName nil) (LEFDEFPinType nil) (mappingTag nil))) (IbisIOPkg ((temperature "27") (bufferModel "CDSDefaultIO_2p5v") (stimuli nil) (offsets nil) (state "tristate") (cycle "1") (termMap nil) (setup "2.0e-09") (hold "1.0e-09") (rise nil) (fall nil) (macroType nil) (voltage nil) (spice nil) (LEFDEFPinName nil) (LEFDEFPinType nil) (mappingTag nil))) (clocked ((clockRise "1e-09") (clockFall "1e-09") (clockFreq "100e6") (clockInitState "0") (clockDutyCycle "0.5") (clockJitter "0"))) (periodic ((periodicFreq "100e6") (periodicPattern "10") (periodicJitter "0"))) (IbisIO ((temperature "27") (bufferModel "CDSDefaultIO_2p5v") (stimuli nil) (offsets nil) (state "tristate") (cycle "1") (termMap nil) (setup "2.0e-09") (hold "1.0e-09") (rise nil) (fall nil) (macroType nil) (voltage nil) (spice nil) (LEFDEFPinName nil) (LEFDEFPinType nil) (mappingTag nil))) (async ((asyncTimePoints "") (asyncInitState "1"))) (IbisOutput ((temperature "27") (bufferModel "CDSDefaultOutput_2p5v") (stimuli nil) (offsets nil) (state "tristate") (cycle "1") (termMap nil) (setup "2.0e-09") (hold "1.0e-09") (rise nil) (fall nil) (macroType nil) (voltage nil) (spice nil) (LEFDEFPinName nil) (LEFDEFPinType nil) (mappingTag nil))) (TLine ((diffImpedance "100ohm") (diffVelocity "1.4142e+08M/s") (impedance "60ohm") length("2800 mil") (propDelay "0.5 ns") (velocity "5600 mil/ns") (traceCount "1") (traceGeometry "Microstrip") (impedanceMin nil) (impedanceMax nil) (lengthMin nil) (lengthMax nil) (propDelayMin nil) (propDelayMax nil) (impedanceSweepCount nil) (propDelaySweepCount nil) (velocitySweepCount nil) (lengthSweepCount nil) (matchSetName nil))) (CurrentProbe nil) (IbisInput ((temperature "27") (bufferModel "CDSDefaultInput_2p5v") (cycle "1") (LEFDEFPinName nil) (LEFDEFPinType nil) (mappingTag nil))) (SeriesTerm ((resistance "22 ohm") (maxDelay "0.1 ns"))) (Connector nil) (sync ((syncFreq "100e6") (syncInitState "1") (syncPattern "10") (syncEdgeSwitch "rise"))) (IbisOutput_OpenPullUp ((temperature "27") (bufferModel "CDSDefaultOutput_2p5v") (stimuli nil) (offsets nil) (state "tristate") (cycle "1") (termMap nil) (setup "2.0e-09") (hold "1.0e-09") (rise nil) (fall nil) (macroType nil) (voltage nil) (spice nil) (LEFDEFPinName nil) (LEFDEFPinType nil) (mappingTag nil))) (DiffInputPkg ((temperature "27") (bufferModelNonInverting "CDSDefaultInput_2p5v") (bufferModelInverting "CDSDefaultInput_2p5v") (threshInputHighMin "1.7 V") (threshInputHighTyp "1.7  V") (threshInputHighMax "1.7  V") (threshInputLowMin "0.7  V") (threshInputLowTyp "0.7  V") (threshInputLowMax "0.7  V") (mappingTagNonInverting nil) (mappingTagInverting nil) (cycle "1"))) (idlCircuit ((allDrivers "active") (ftsMode '("Typ")) (rcvrSelect "all") (simMode "Reflection") (tlineDelayMode "time") (userRevision "1.0") (autoSolve "On")))))
				)
				( objectStatus "JTAG_PCH_GBE_TRST_N" )
			)
			( electricalCSet "@crescent_city_bb_fab1_lib.crescent_city_bb_fab1(sch_1):\RMII_TX_1\"
				( pinPairRef "RMII_TX_1:U9F4.D9:R8F33.1" )
				( pinPairRef "RMII_TX_1:U9F4.D9:U7C1.AL3" )
				( attribute "TOPOLOGY_TEMPLATE_REVISION" "1.0"
					( Origin gBackEnd )
				)
				( topologyData 25741
(SKIDL (Circuits ("MAIN" (Parts ("CRESCENT_CITY_180_20141223_Q.@@EU46.7" IbisInputPkg (xy (5538 4228)) (refDes "EU9E1") (model "Unknown") (Props (_SXDesignName "CRESCENT_CITY_180_20141223_Q") (brdx "19352 MIL") (brdy "1735.47 MIL") (bufferModel "CDSDefaultInput_2p5v") (mappingTag "") (temperature "27")) (Terms ("CRESCENT_CITY_180_20141223_Q.X1935200Y173547L2LRATS" "7"))) ("CRESCENT_CITY_180_20141223_Q.@@U22.AL3" IbisIOPkg (xy (5539 4240)) (refDes "U7C1") (model "Unknown") (Props (_SXDesignName "CRESCENT_CITY_180_20141223_Q") (brdx "15275 MIL") (brdy "3715.55 MIL") (bufferModel "CDSDefaultIO_2p5v") (cycle "1") (hold "1.0e-09") (mappingTag "") (offsets ("4" "0") ("5" "0")) (setup "2.0e-09") (state "tristate") (stimuli ("4" "local5") ("5" "local6")) (temperature "27") (termMap ("4" "Data") ("5" "Enable"))) (Terms ("CRESCENT_CITY_180_20141223_Q.X1527500Y371555L2LRATS" "AL3"))) ("CRESCENT_CITY_180_20141223_Q.@@U47.D9" IbisOutputPkg (xy (5498 4235)) (refDes "U9F4") (model "Unknown") (Props (_SXDesignName "CRESCENT_CITY_180_20141223_Q") (brdx "17681.78 MIL") (brdy "740.26 MIL") (bufferModel "CDSDefaultOutput_2p5v") (cycle "1") (hold "1.0e-09") (mappingTag "") (offsets ("4" "0")) (setup "2.0e-09") (state "tristate") (stimuli ("4" "local7")) (temperature "27") (termMap ("4" "Data"))) (Terms ("CRESCENT_CITY_180_20141223_Q.X1768178Y74026L2LRATS" "D9"))) ("CRESCENT_CITY_180_20141223_Q.@@R3440.2.1" Resistor (xy (5521 4220)) (refDes "R9E13") (value "10000 Ohm") (Props (_SXDesignName "CRESCENT_CITY_180_20141223_Q")) (Terms ("CRESCENT_CITY_180_20141223_Q.X1946500Y176000L2RATS" "2") ("CRESCENT_CITY_180_20141223_Q.X1943000Y176000L2LRATS" "1"))) ("CRESCENT_CITY_180_20141223_Q.T@@RATS@@R263.2@@EU46.7" TLine (xy (5530 4228)) (refDes "TL9") (Props (_SXDesignName "CRESCENT_CITY_180_20141223_Q") (impedance "48.412 ohm") length("2897.47 MIL") (propDelay "0.52041 ns") (traceCount "1") (traceGeometry "Microstrip") (velocity "5567.68 mil/ns")) (Terms ("CRESCENT_CITY_180_20141223_Q.X1745500Y73500L2LRATS" "1") ("CRESCENT_CITY_180_20141223_Q.X1935200Y173547L2LRATS" "2"))) ("CRESCENT_CITY_180_20141223_Q.T@@RATS@@R263.1@@U47.D9" TLine (xy (5506 4235)) (mirror x) (refDes "TL10") (Props (_SXDesignName "CRESCENT_CITY_180_20141223_Q") (impedance "52.449 ohm") length("197.04 MIL") (propDelay "0.03539 ns") (traceCount "1") (traceGeometry "Microstrip") (velocity "5567.68 mil/ns")) (Terms ("CRESCENT_CITY_180_20141223_Q.X1749000Y73500L2LRATS" "1") ("CRESCENT_CITY_180_20141223_Q.X1768178Y74026L2LRATS" "2"))) ("CRESCENT_CITY_180_20141223_Q.T@@RATS@@EU46.7@@R3440.1" TLine (xy (5536 4220)) (mirror x) (refDes "TL11") (Props (_SXDesignName "CRESCENT_CITY_180_20141223_Q") (impedance "48.412 ohm") length("102.53 MIL") (propDelay "0.01842 ns") (traceCount "1") (traceGeometry "Microstrip") (velocity "5566.22 mil/ns")) (Terms ("CRESCENT_CITY_180_20141223_Q.X1935200Y173547L2LRATS" "1") ("CRESCENT_CITY_180_20141223_Q.X1943000Y176000L2LRATS" "2"))) ("CRESCENT_CITY_180_20141223_Q.@@R3440.2_SOURCE" Source (xy (5514 4220)) (refDes "GND") (value "0 V") (Props (_SXDesignName "CRESCENT_CITY_180_20141223_Q")) (Terms ("CRESCENT_CITY_180_20141223_Q.X1946500Y176000L2RATS" "1"))) ("CRESCENT_CITY_180_20141223_Q.T@@RATS@@R263.2@@U22.AL3" TLine (xy (5530 4235)) (refDes "TL12") (Props (_SXDesignName "CRESCENT_CITY_180_20141223_Q") (impedance "60 ohm") length("5160.55 MIL") (propDelay "0.92687 ns") (traceCount "1") (traceGeometry "Microstrip") (velocity "5567.72 mil/ns")) (Terms ("CRESCENT_CITY_180_20141223_Q.X1745500Y73500L2LRATS" "1") ("CRESCENT_CITY_180_20141223_Q.X1527500Y371555L2LRATS" "2"))) ("CRESCENT_CITY_180_20141223_Q.@@R263.1.2" Resistor (xy (5521 4235)) (refDes "R8F33") (value "2.2e-007 Ohm") (Props (_SXDesignName "CRESCENT_CITY_180_20141223_Q")) (Terms ("CRESCENT_CITY_180_20141223_Q.X1749000Y73500L2LRATS" "1") ("CRESCENT_CITY_180_20141223_Q.X1745500Y73500L2LRATS" "2")))) (Nodes ("CRESCENT_CITY_180_20141223_Q.X1943000Y176000L2LRATS" (terms "CRESCENT_CITY_180_20141223_Q.T@@RATS@@EU46.7@@R3440.1.2" "CRESCENT_CITY_180_20141223_Q.@@R3440.2.1.2")) ("CRESCENT_CITY_180_20141223_Q.X1946500Y176000L2RATS" (terms "CRESCENT_CITY_180_20141223_Q.@@R3440.2_SOURCE.1" "CRESCENT_CITY_180_20141223_Q.@@R3440.2.1.1")) ("CRESCENT_CITY_180_20141223_Q.X1527500Y371555L2LRATS" (terms "CRESCENT_CITY_180_20141223_Q.T@@RATS@@R263.2@@U22.AL3.2" "CRESCENT_CITY_180_20141223_Q.@@U22.AL3.1")) ("CRESCENT_CITY_180_20141223_Q.X1745500Y73500L2LRATS" (terms "CRESCENT_CITY_180_20141223_Q.@@R263.1.2.2" "CRESCENT_CITY_180_20141223_Q.T@@RATS@@R263.2@@U22.AL3.1" "CRESCENT_CITY_180_20141223_Q.T@@RATS@@R263.2@@EU46.7.1")) ("CRESCENT_CITY_180_20141223_Q.X1935200Y173547L2LRATS" (terms "CRESCENT_CITY_180_20141223_Q.T@@RATS@@EU46.7@@R3440.1.1" "CRESCENT_CITY_180_20141223_Q.T@@RATS@@R263.2@@EU46.7.2" "CRESCENT_CITY_180_20141223_Q.@@EU46.7.1")) ("CRESCENT_CITY_180_20141223_Q.X1749000Y73500L2LRATS" (terms "CRESCENT_CITY_180_20141223_Q.@@R263.1.2.1" "CRESCENT_CITY_180_20141223_Q.T@@RATS@@R263.1@@U47.D9.1")) ("CRESCENT_CITY_180_20141223_Q.X1768178Y74026L2LRATS" (terms "CRESCENT_CITY_180_20141223_Q.T@@RATS@@R263.1@@U47.D9.2" "CRESCENT_CITY_180_20141223_Q.@@U47.D9.1"))) (Ports) (Stimuli ("local2" (scope local) (stimType periodic) (Props (periodicFreq "5e+007") (periodicJitter "0") (periodicPattern "1"))) ("local6" (scope local) (stimType periodic) (Props (periodicFreq "5e+007") (periodicJitter "0") (periodicPattern "1"))) ("local7" (scope local) (stimType periodic) (Props (periodicFreq "5e+007") (periodicJitter "0") (periodicPattern "1"))) ("local3" (scope local) (stimType periodic) (Props (periodicFreq "5e+007") (periodicJitter "0") (periodicPattern "1"))) ("local4" (scope local) (stimType periodic) (Props (periodicFreq "5e+007") (periodicJitter "0") (periodicPattern "1"))) ("local5" (scope local) (stimType periodic) (Props (periodicFreq "5e+007") (periodicJitter "0") (periodicPattern "1")))) (Notes) (Constraints ("DELAY_RULE" ("CRESCENT_CITY_180_20141223_Q U47.D9" "CRESCENT_CITY_180_20141223_Q R263.1" "LENGTH" "" "LENGTH" "0.0127") ("CRESCENT_CITY_180_20141223_Q U47.D9" "CRESCENT_CITY_180_20141223_Q U22.AL3" "LENGTH" "0.2032" "LENGTH" "0.3556"))) (MeasurementSets ("EMI" ("EMIStatus" status("on")) ("PeakEmission" status("on")) ("PeakFrequency" status("on")) ("PulseFreq" status("on")) ("RiseTime" status("on")) ("VoltageSwing" status("on"))) ("Reflection" ("BufferDelayFall" status("off")) ("BufferDelayRise" status("off")) ("EyeHeight" status("off")) ("EyeJitter" status("off")) ("EyeWidth" status("off")) ("FirstIncidentFall" status("off")) ("FirstIncidentRise" status("off")) ("Glitch" status("on")) ("GlitchFall" status("off")) ("GlitchRise" status("off")) ("Monotonic" status("on")) ("MonotonicFall" status("off")) ("MonotonicRise" status("off")) ("NoiseMargin" status("on")) ("NoiseMarginHigh" status("off")) ("NoiseMarginLow" status("off")) ("OvershootHigh" status("on")) ("OvershootLow" status("on")) ("PropDelay" status("on")) ("SettleDelay" status("on")) ("SettleDelayFall" status("off")) ("SettleDelayRise" status("off")) ("SwitchDelay" status("on")) ("SwitchDelayFall" status("off")) ("SwitchDelayRise" status("off"))) ("Crosstalk" ("Crosstalk" status("on"))) ("Custom")) (VectorSets) (Props (XnetName "RMII_BMC_PCH_SPRNGVLLE_TXEN") (allDrivers "active") (customSimType "Reflection") (ftsMode ("Typ")) (rcvrSelect "all") (tlineDelayMode "time") (userRevision "1.0")))) (Subckts) (CrossSections ("CRESCENT_CITY_180_20141223_Q" (Props (SXDesignName "CRESCENT_CITY_180_20141223_Q")) (Layers ("" (layerType "SURFACE") (material "AIR") (thickness "0 mil") (dielectricConstant "1.000000") (lossTangent "0") (etchFactor "0.000000") (elecCondVal "0 mho/cm") (thermCondVal "0 w/cm-degC")) ("" (layerType "DIELECTRIC") (material "CONFORMAL_COAT") (thickness "0.5 mil") (dielectricConstant "3.800000") (lossTangent "0.035") (etchFactor "0.000000") (elecCondVal "0 mho/cm") (thermCondVal "0.012 w/cm-degC")) ("TOP" (layerType "CONDUCTOR") (material "COPPER") (thickness "  2.100000 mil") (width "4.00 MIL") (dielectricConstant "4.500000") (lossTangent "0") (etchFactor "70.000000") (elecCondVal "595900.000000 mho/cm") (thermCondVal "0 w/cm-degC") (signalDieConstant "3.800000") (signalLossTangent "0.035")) ("" (layerType "DIELECTRIC") (material "FR-4") (thickness "  2.670000 mil") (dielectricConstant "4.000000") (lossTangent "0.035") (etchFactor "0.000000") (elecCondVal "0 mho/cm") (thermCondVal "0.012 w/cm-degC")) ("L2_GND1" (layerType "PLANE") (material "COPPER") (isShield t) (thickness "  1.250000 mil") (dielectricConstant "4.500000") (lossTangent "0.035") (etchFactor "90.000000") (elecCondVal "595900.000000 mho/cm") (thermCondVal "0.012 w/cm-degC")) ("" (layerType "DIELECTRIC") (material "FR-4") (thickness "  9.000000 mil") (dielectricConstant "4.100000") (lossTangent "0.035") (etchFactor "0.000000") (elecCondVal "0 mho/cm") (thermCondVal "0.012 w/cm-degC")) ("L3_SIG1" (layerType "CONDUCTOR") (material "COPPER") (thickness "  1.250000 mil") (width "4.00 MIL") (dielectricConstant "4.500000") (lossTangent "0.035") (etchFactor "90.000000") (elecCondVal "595900.000000 mho/cm") (thermCondVal "0.012 w/cm-degC") (signalDieConstant "4.100000") (signalLossTangent "0.035")) ("" (layerType "DIELECTRIC") (material "FR-4") (thickness "  3.000000 mil") (dielectricConstant "4.500000") (lossTangent "0.035") (etchFactor "0.000000") (elecCondVal "0 mho/cm") (thermCondVal "0 w/cm-degC")) ("L4_GND2" (layerType "PLANE") (material "COPPER") (isShield t) (thickness "  1.250000 mil") (dielectricConstant "4.500000") (lossTangent "0.035") (etchFactor "90.000000") (elecCondVal "595900.000000 mho/cm") (thermCondVal "0 w/cm-degC")) ("" (layerType "DIELECTRIC") (material "FR-4") (thickness "  9.000000 mil") (dielectricConstant "4.000000") (lossTangent "0.035") (etchFactor "0.000000") (elecCondVal "0 mho/cm") (thermCondVal "0.012 w/cm-degC")) ("L5_SIG2" (layerType "CONDUCTOR") (material "COPPER") (thickness "  1.250000 mil") (width "4.00 MIL") (dielectricConstant "4.500000") (lossTangent "0.035") (etchFactor "90.000000") (elecCondVal "595900.000000 mho/cm") (thermCondVal "0.012 w/cm-degC") (signalDieConstant "4.000000") (signalLossTangent "0.035")) ("" (layerType "DIELECTRIC") (material "FR-4") (thickness "  3.000000 mil") (dielectricConstant "4.500000") (lossTangent "0.035") (etchFactor "0.000000") (elecCondVal "0 mho/cm") (thermCondVal "0 w/cm-degC")) ("L6_GND3" (layerType "PLANE") (material "COPPER") (isShield t) (thickness "  1.250000 mil") (dielectricConstant "4.500000") (lossTangent "0.035") (etchFactor "90.000000") (elecCondVal "595900.000000 mho/cm") (thermCondVal "0 w/cm-degC")) ("" (layerType "DIELECTRIC") (material "FR-4") (thickness "  4.500000 mil") (dielectricConstant "4.100000") (lossTangent "0.035") (etchFactor "0.000000") (elecCondVal "0 mho/cm") (thermCondVal "0.012 w/cm-degC")) ("L7_PWR1-SIG" (layerType "PLANE") (material "COPPER") (isShield t) (thickness "  2.400000 mil") (dielectricConstant "4.500000") (lossTangent "0.035") (etchFactor "90.000000") (elecCondVal "595900.000000 mho/cm") (thermCondVal "0.012 w/cm-degC")) ("" (layerType "DIELECTRIC") (material "FR-4") (thickness "  4.600000 mil") (dielectricConstant "4.000000") (lossTangent "0.035") (etchFactor "0.000000") (elecCondVal "0 mho/cm") (thermCondVal "0.012 w/cm-degC")) ("L8_PWR2-SIG" (layerType "PLANE") (material "COPPER") (isShield t) (thickness "  2.400000 mil") (dielectricConstant "4.500000") (lossTangent "0.035") (etchFactor "90.000000") (elecCondVal "595900.000000 mho/cm") (thermCondVal "0.012 w/cm-degC")) ("" (layerType "DIELECTRIC") (material "FR-4") (thickness "  4.500000 mil") (dielectricConstant "4.500000") (lossTangent "0.035") (etchFactor "0.000000") (elecCondVal "0 mho/cm") (thermCondVal "0 w/cm-degC")) ("L9_GND4" (layerType "PLANE") (material "COPPER") (isShield t) (thickness "  1.250000 mil") (dielectricConstant "4.500000") (lossTangent "0.035") (etchFactor "90.000000") (elecCondVal "595900.000000 mho/cm") (thermCondVal "0 w/cm-degC")) ("" (layerType "DIELECTRIC") (material "FR-4") (thickness "  3.000000 mil") (dielectricConstant "4.100000") (lossTangent "0.035") (etchFactor "0.000000") (elecCondVal "0 mho/cm") (thermCondVal "0.012 w/cm-degC")) ("L10_SIG3" (layerType "CONDUCTOR") (material "COPPER") (thickness "  1.250000 mil") (width "4.00 MIL") (dielectricConstant "4.500000") (lossTangent "0.035") (etchFactor "90.000000") (elecCondVal "595900.000000 mho/cm") (thermCondVal "0.012 w/cm-degC") (signalDieConstant "4.100000") (signalLossTangent "0.035")) ("" (layerType "DIELECTRIC") (material "FR-4") (thickness "  9.000000 mil") (dielectricConstant "4.500000") (lossTangent "0.035") (etchFactor "0.000000") (elecCondVal "0 mho/cm") (thermCondVal "0 w/cm-degC")) ("L11_GND5" (layerType "PLANE") (material "COPPER") (isShield t) (thickness "  1.250000 mil") (dielectricConstant "4.500000") (lossTangent "0.035") (etchFactor "90.000000") (elecCondVal "595900.000000 mho/cm") (thermCondVal "0 w/cm-degC")) ("" (layerType "DIELECTRIC") (material "FR-4") (thickness "  3.000000 mil") (dielectricConstant "4.500000") (lossTangent "0.035") (etchFactor "0.000000") (elecCondVal "0 mho/cm") (thermCondVal "0.012 w/cm-degC")) ("L12_SIG4" (layerType "CONDUCTOR") (material "COPPER") (thickness "  1.250000 mil") (width "4.00 MIL") (dielectricConstant "4.500000") (lossTangent "0.035") (etchFactor "90.000000") (elecCondVal "595900.000000 mho/cm") (thermCondVal "0.012 w/cm-degC") (signalDieConstant "4.500000") (signalLossTangent "0.035")) ("" (layerType "DIELECTRIC") (material "FR-4") (thickness "  9.000000 mil") (dielectricConstant "4.500000") (lossTangent "0.035") (etchFactor "0.000000") (elecCondVal "0 mho/cm") (thermCondVal "0 w/cm-degC")) ("L13_GND6" (layerType "PLANE") (material "COPPER") (isShield t) (thickness "  1.250000 mil") (dielectricConstant "4.500000") (lossTangent "0.035") (etchFactor "90.000000") (elecCondVal "595900.000000 mho/cm") (thermCondVal "0.012 w/cm-degC")) ("" (layerType "DIELECTRIC") (material "FR-4") (thickness "  2.670000 mil") (dielectricConstant "4.500000") (lossTangent "0.035") (etchFactor "0.000000") (elecCondVal "0 mho/cm") (thermCondVal "0.012 w/cm-degC")) ("BOTTOM" (layerType "CONDUCTOR") (material "COPPER") (thickness "  2.100000 mil") (width "4.00 MIL") (dielectricConstant "4.500000") (lossTangent "0") (etchFactor "70.000000") (elecCondVal "595900.000000 mho/cm") (thermCondVal "0 w/cm-degC") (signalDieConstant "3.800000") (signalLossTangent "0.035")) ("" (layerType "DIELECTRIC") (material "CONFORMAL_COAT") (thickness "0.5 mil") (dielectricConstant "3.800000") (lossTangent "0.035") (etchFactor "0.000000") (elecCondVal "0 mho/cm") (thermCondVal "0.012 w/cm-degC")) ("" (layerType "SURFACE") (material "AIR") (thickness "0 mil") (dielectricConstant "1.000000") (lossTangent "0") (etchFactor "0.000000") (elecCondVal "0 mho/cm") (thermCondVal "0 w/cm-degC"))))) (Props (DesUnits "mils 2") (LayerStack ("DIELECTRIC" "DIELECTRIC" "BOTTOM" "DIELECTRIC" "L13_GND6" "DIELECTRIC" "L12_SIG4" "DIELECTRIC" "L11_GND5" "DIELECTRIC" "L10_SIG3" "DIELECTRIC" "L9_GND4" "DIELECTRIC" "L8_PWR2-SIG" "DIELECTRIC" "L7_PWR1-SIG" "DIELECTRIC" "L6_GND3" "DIELECTRIC" "L5_SIG2" "DIELECTRIC" "L4_GND2" "DIELECTRIC" "L3_SIG1" "DIELECTRIC" "L2_GND1" "DIELECTRIC" "TOP" "DIELECTRIC" "DIELECTRIC")) (Revision "16.600")) (Params (IbisIOPkg ((temperature "27") (bufferModel "CDSDefaultIO_2p5v") (stimuli nil) (offsets nil) (state "tristate") (cycle "1") (termMap nil) (setup "2.0e-09") (hold "1.0e-09") (rise nil) (fall nil) (macroType nil) (voltage nil) (spice nil) (LEFDEFPinName nil) (LEFDEFPinType nil) (mappingTag nil))) (IbisIOMacro ((temperature "27") (bufferModel "CDSDefaultIO_2p5v") (stimuli nil) (offsets nil) (state "tristate") (cycle "1") (termMap nil) (setup "2.0e-09") (hold "1.0e-09") (rise nil) (fall nil) (macroType nil) (voltage nil) (spice nil) (LEFDEFPinName nil) (LEFDEFPinType nil) (mappingTag nil))) (IbisInputPkg ((temperature "27") (bufferModel "CDSDefaultInput_2p5v") (cycle "1") (LEFDEFPinName nil) (LEFDEFPinType nil) (mappingTag nil))) (IbisOutputPkg ((temperature "27") (bufferModel "CDSDefaultOutput_2p5v") (stimuli nil) (offsets nil) (state "tristate") (cycle "1") (termMap nil) (setup "2.0e-09") (hold "1.0e-09") (rise nil) (fall nil) (macroType nil) (voltage nil) (spice nil) (LEFDEFPinName nil) (LEFDEFPinType nil) (mappingTag nil))) (periodic ((periodicFreq "100e6") (periodicPattern "10") (periodicJitter "0"))) (IbisIO_OpenPullUp ((temperature "27") (bufferModel "CDSDefaultIO_2p5v") (stimuli nil) (offsets nil) (state "tristate") (cycle "1") (termMap nil) (setup "2.0e-09") (hold "1.0e-09") (rise nil) (fall nil) (macroType nil) (voltage nil) (spice nil) (LEFDEFPinName nil) (LEFDEFPinType nil) (mappingTag nil))) (clocked ((clockRise "1e-09") (clockFall "1e-09") (clockFreq "100e6") (clockInitState "0") (clockDutyCycle "0.5") (clockJitter "0"))) (IbisIO ((temperature "27") (bufferModel "CDSDefaultIO_2p5v") (stimuli nil) (offsets nil) (state "tristate") (cycle "1") (termMap nil) (setup "2.0e-09") (hold "1.0e-09") (rise nil) (fall nil) (macroType nil) (voltage nil) (spice nil) (LEFDEFPinName nil) (LEFDEFPinType nil) (mappingTag nil))) (IbisIO_OpenPullDown ((temperature "27") (bufferModel "CDSDefaultIO_2p5v") (stimuli nil) (offsets nil) (state "tristate") (cycle "1") (termMap nil) (setup "2.0e-09") (hold "1.0e-09") (rise nil) (fall nil) (macroType nil) (voltage nil) (spice nil) (LEFDEFPinName nil) (LEFDEFPinType nil) (mappingTag nil))) (IbisOutput ((temperature "27") (bufferModel "CDSDefaultOutput_2p5v") (stimuli nil) (offsets nil) (state "tristate") (cycle "1") (termMap nil) (setup "2.0e-09") (hold "1.0e-09") (rise nil) (fall nil) (macroType nil) (voltage nil) (spice nil) (LEFDEFPinName nil) (LEFDEFPinType nil) (mappingTag nil))) (async ((asyncTimePoints "") (asyncInitState "1"))) (TLine ((diffImpedance "100ohm") (diffVelocity "1.4142e+08M/s") (impedance "60ohm") length("2800 mil") (propDelay "0.5 ns") (velocity "5600 mil/ns") (traceCount "1") (traceGeometry "Microstrip") (impedanceMin nil) (impedanceMax nil) (lengthMin nil) (lengthMax nil) (propDelayMin nil) (propDelayMax nil) (impedanceSweepCount nil) (propDelaySweepCount nil) (velocitySweepCount nil) (lengthSweepCount nil) (matchSetName nil))) (IbisInput ((temperature "27") (bufferModel "CDSDefaultInput_2p5v") (cycle "1") (LEFDEFPinName nil) (LEFDEFPinType nil) (mappingTag nil))) (SeriesTerm ((resistance "22 ohm") (maxDelay "0.1 ns"))) (Connector nil) (CurrentProbe nil) (IbisOutput_OpenPullUp ((temperature "27") (bufferModel "CDSDefaultOutput_2p5v") (stimuli nil) (offsets nil) (state "tristate") (cycle "1") (termMap nil) (setup "2.0e-09") (hold "1.0e-09") (rise nil) (fall nil) (macroType nil) (voltage nil) (spice nil) (LEFDEFPinName nil) (LEFDEFPinType nil) (mappingTag nil))) (sync ((syncFreq "100e6") (syncInitState "1") (syncPattern "10") (syncEdgeSwitch "rise"))) (DiffInputPkg ((temperature "27") (bufferModelNonInverting "CDSDefaultInput_2p5v") (bufferModelInverting "CDSDefaultInput_2p5v") (threshInputHighMin "1.7 V") (threshInputHighTyp "1.7  V") (threshInputHighMax "1.7  V") (threshInputLowMin "0.7  V") (threshInputLowTyp "0.7  V") (threshInputLowMax "0.7  V") (mappingTagNonInverting nil) (mappingTagInverting nil) (cycle "1"))) (idlCircuit ((allDrivers "active") (ftsMode '("Typ")) (rcvrSelect "all") (simMode "Reflection") (tlineDelayMode "time") (userRevision "1.0") (autoSolve "On"))) (Trace ((d1Thickness "10 mil") (d1Constant "4.5") (d1LossTangent "0.035") (d2Thickness "10 mil") (d2Constant "4.5") (d2LossTangent "0.035") (d3Thickness "0.0") (d3Constant "1.0") (d3LossTangent "0") length("1000 mil") (spacing "5 mil") (spacing2 "5 mil") (spacing3 "5 mil") (spacing4 "5 mil") (spacing5 "5 mil") (traceConductivity "595900 mho/cm") (traceGeometry "microstrip") (traceLayerName "") (traceThickness "0.72 mil") (traceType "single") (traceWidth "5.0 mil") (traceWidth2 "5.0 mil") (traceWidth3 "5.0 mil") (traceWidth4 "5.0 mil") (traceWidth5 "5.0 mil") (traceWidth6 "5.0 mil") (offset "0 mil") (traceCount "1") (impedance nil))) (DiffOutput ((temperature "27") (bufferModelNonInverting "CDSDefaultOutput_2p5v") (bufferModelInverting "CDSDefaultOutput_2p5v") (stimuli nil) (offsets nil) (state "tristate") (cycle "1") (termMap nil) (setup "0.9e-09") (hold "0.4e-09") (rise nil) (fall nil) (threshOutputHighMin "2.375  V") (threshOutputHighTyp "2.5  V") (threshOutputHighMax "2.625  V") (threshOutputLowMin "1.275  V") (threshOutputLowTyp "1.7  V") (threshOutputLowMax "1.985  V") (mappingTagNonInverting nil) (mappingTagInverting nil) (spice nil))) (HiClampTerm ((cutoffVoltage "0.7 V") (voltage "5 V") (maxDelay "0.1 ns"))) (Via ((model "Unknown") (viaOutputFormat "Unknown") (viaPadstack nil) (viaTopLayer nil) (viaBottomLayer nil) (viaIsPower nil) (viaIsGround nil))) (Resistor ((resistance "50 ohm") (orientation "0"))) (LowClampTerm ((cutoffVoltage "0.7 V") (voltage "0 V") (maxDelay "0.1 ns"))) (DiffOutputPkg ((temperature "27") (bufferModelNonInverting "CDSDefaultOutput_2p5v") (bufferModelInverting "CDSDefaultOutput_2p5v") (stimuli nil) (offsets nil) (state "tristate") (cycle "1") (termMap nil) (setup "0.9e-09") (hold "0.4e-09") (rise nil) (fall nil) (threshOutputHighMin "2.375  V") (threshOutputHighTyp "2.5  V") (threshOutputHighMax "2.625  V") (threshOutputLowMin "1.275  V") (threshOutputLowTyp "1.7  V") (threshOutputLowMax "1.985  V") (mappingTagNonInverting nil) (mappingTagInverting nil) (spice nil))) (RCTerm ((resistance "50 ohm") (capacitance "20 pF") (voltage "5 V") (maxDelay "0.1 ns"))) (DiffIO ((temperature "27") (bufferModelNonInverting "CDSDefaultIO_2p5v") (bufferModelInverting "CDSDefaultIO_2p5v") (stimuli nil) (offsets nil) (state "tristate") (cycle "1") (termMap nil) (setup "0.9e-09") (hold "0.4e-09") (rise nil) (fall nil) (threshInputHighMin "1.7 V") (threshInputHighTyp "1.7  V") (threshInputHighMax "1.7  V") (threshInputLowMin "0.7  V") (threshInputLowTyp "0.7  V") (threshInputLowMax "0.7 ") (threshOutputHighMin "2.365  V") (threshOutputHighTyp "2.5  V") (threshOutputHighMax "2.625  V") (threshOutputLowMin "1.275  V") (threshOutputLowTyp "1.7  V") (threshOutputLowMax "1.985  V") (mappingTagNonInverting nil) (mappingTagInverting nil) (spice nil))) (TheveninTerm ((resistanceUp "180 ohm") (resistanceDown "270 ohm") (voltageUp "5 V") (voltageDown "0 V") (maxDelay "0.1 ns"))) (DiffIOPkg ((temperature "27") (bufferModelNonInverting "CDSDefaultIO_2p5v") (bufferModelInverting "CDSDefaultIO_2p5v") (stimuli nil) (offsets nil) (state "tristate") (cycle "1") (termMap nil) (setup "0.9e-09") (hold "0.4e-09") (rise nil) (fall nil) (threshInputHighMin "1.7 V") (threshInputHighTyp "1.7  V") (threshInputHighMax "1.7  V") (threshInputLowMin "0.7  V") (threshInputLowTyp "0.7  V") (threshInputLowMax "0.7 ") (threshOutputHighMin "2.365  V") (threshOutputHighTyp "2.5  V") (threshOutputHighMax "2.625  V") (threshOutputLowMin "1.275  V") (threshOutputLowTyp "1.7  V") (threshOutputLowMax "1.985  V") (mappingTagNonInverting nil) (mappingTagInverting nil) (spice nil))) (Source ((voltage "5 V"))) (ShuntTerm ((resistance "50 ohm") (voltage "5 V") (maxDelay "0.1 ns"))) (RLGC (length("1000 mil"))) (Capacitor ((capacitance "10 pF") (orientation "0"))) (DiffInput ((temperature "27") (bufferModelNonInverting "CDSDefaultInput_2p5v") (bufferModelInverting "CDSDefaultInput_2p5v") (threshInputHighMin "1.7 V") (threshInputHighTyp "1.7  V") (threshInputHighMax "1.7  V") (threshInputLowMin "0.7  V") (threshInputLowTyp "0.7  V") (threshInputLowMax "0.7  V") (mappingTagNonInverting nil) (mappingTagInverting nil) (cycle "1"))) (Inductor ((inductance "5 nH") (orientation "0"))) (Cable (length("1 m"))) (CPWSL ((d1Thickness "10 mil") (d1Constant "4.5") (d1LossTangent "0.035") (d2Thickness "0.72 mil") (d2Constant "4.5") (d2LossTangent "0.035") (d3Thickness "10 mil") (d3Constant "4.5") (d3LossTangent "0.035") length("1000 mil") (spacing "5 mil") (spacing2 "5 mil") (spacing3 "5 mil") (spacing4 "5 mil") (spacing5 "5 mil") (traceConductivity "595900 mho/cm") (traceGeometry "cpwms") (traceLayerName "") (traceThickness "0.72 mil") (traceType "single") (traceWidth "5.0 mil") (traceWidth2 "5.0 mil") (traceWidth3 "5.0 mil") (traceWidth4 "5.0 mil") (traceWidth5 "5.0 mil") (traceWidth6 "5.0 mil") (offset "0 mil") (traceCount "1") (impedance nil))) (CPWMS ((d1Thickness "10 mil") (d1Constant "4.5") (d1LossTangent "0.035") (d2Thickness "0.72 mil") (d2Constant "4.5") (d2LossTangent "0.035") (d3Thickness "0.0") (d3Constant "1") (d3LossTangent "0") length("1000 mil") (spacing "5 mil") (spacing2 "5 mil") (spacing3 "5 mil") (spacing4 "5 mil") (spacing5 "5 mil") (traceConductivity "595900 mho/cm") (traceGeometry "cpwms") (traceLayerName "") (traceThickness "0.72 mil") (traceType "single") (traceWidth "5.0 mil") (traceWidth2 "5.0 mil") (traceWidth3 "5.0 mil") (traceWidth4 "5.0 mil") (traceWidth5 "5.0 mil") (traceWidth6 "5.0 mil") (offset "0 mil") (traceCount "1") (impedance nil))) (Diode ((cutoffVoltage "0.7 V"))) (CPW ((d1Thickness "10 mil") (d1Constant "4.5") (d1LossTangent "0.035") (d2Thickness "0.72 mil") (d2Constant "1") (d2LossTangent "0") (d3Thickness "0.0") (d3Constant "1") (d3LossTangent "0") length("1000 mil") (spacing "5 mil") (spacing2 "5 mil") (spacing3 "5 mil") (spacing4 "5 mil") (spacing5 "5 mil") (traceConductivity "595900 mho/cm") (traceGeometry "cpwms") (traceLayerName "") (traceThickness "0.72 mil") (traceType "single") (traceWidth "5.0 mil") (traceWidth2 "5.0 mil") (traceWidth3 "5.0 mil") (traceWidth4 "5.0 mil") (traceWidth5 "5.0 mil") (traceWidth6 "5.0 mil") (offset "0 mil") (traceCount "1") (impedance nil))) (DualClampTerm ((cutoffVoltageUp "0.7 V") (cutoffVoltageDown "0.7 V") (voltageUp "5 V") (voltageDown "0 V") (maxDelay "0.1 ns"))) (ESpiceDevice nil)))
				)
				( objectStatus "RMII_TX_1" )
			)
			( electricalCSet "@crescent_city_bb_fab1_lib.crescent_city_bb_fab1(sch_1):\CLK_100M_BMC_PE_R_DN\"
				( groupRef "CLK_100M_BMC_PE_R_DN:MG_CLK_G1-BCLK" )
				( pinPairRef "CLK_100M_BMC_PE_R_DN:U9F4.G21:U7C1.B29" )
				( attribute "DIFFP_GATHER_CONTROL" "IGNORE"
					( Origin gBackEnd )
				)
				( attribute "DIFFP_UNCOUPLED_LENGTH" "10.00"
					( Origin gBackEnd )
				)
				( attribute "DIFFP_COUPLED_PLUS" "0.50"
					( Origin gBackEnd )
				)
				( attribute "DIFFP_COUPLED_MINUS" "0.50"
					( Origin gBackEnd )
				)
				( attribute "DIFFP_PHASE_TOL" "10 mil"
					( Units "uPhaseTol" "ns" 1.000000)
					( Origin gBackEnd )
				)
				( attribute "TOPOLOGY_TEMPLATE_REVISION" "1.0"
					( Origin gBackEnd )
				)
				( topologyData 26670
(SKIDL (Circuits ("MAIN" (Parts ("CRESCENT_CITY_623_20150314_B.@@U47.G21" IbisIOPkg (xy (5512 4227)) (refDes "U9F4") (model "Unknown") (Props (_SXDesignName "CRESCENT_CITY_623_20150314_B") (brdx "17776.27 MIL") (brdy "1118.21 MIL") (bufferModel "CDSDefaultIO_2p5v") (cycle "1") (hold "1.0e-09") (mappingTag "") (offsets ("4" "0") ("5" "0")) (setup "2.0e-09") (state "tristate") (stimuli ("4" "local4") ("5" "local5")) (temperature "27") (termMap ("4" "Data") ("5" "Enable"))) (Terms ("CRESCENT_CITY_623_20150314_B.X1777627Y111821L2LRATS" "G21"))) ("CRESCENT_CITY_623_20150314_B.@@U22.B29" IbisIOPkg (xy (5502 4240)) (refDes "U7C1") (model "Unknown") (Props (_SXDesignName "CRESCENT_CITY_623_20150314_B") (brdx "14767.32 MIL") (brdy "4187.2 MIL") (bufferModel "CDSDefaultIO_2p5v") (cycle "1") (hold "1.0e-09") (mappingTag "") (offsets ("4" "0") ("5" "0")) (setup "2.0e-09") (state "tristate") (stimuli ("4" "local6") ("5" "local7")) (temperature "27") (termMap ("4" "Data") ("5" "Enable"))) (Terms ("CRESCENT_CITY_623_20150314_B.X1476732Y418720L2LRATS" "B29"))) ("CRESCENT_CITY_623_20150314_B.@@R3491.1.2" Resistor (xy (5488 4229)) (refDes "R7C2") (value "1 Ohm") (Props (_SXDesignName "CRESCENT_CITY_623_20150314_B")) (Terms ("CRESCENT_CITY_623_20150314_B.X1453600Y414800L2LRATS" "1") ("CRESCENT_CITY_623_20150314_B.X1457100Y414800L2LRATS" "2"))) ("CRESCENT_CITY_623_20150314_B.@@R3458.2.1" Resistor (xy (5482 4216)) (refDes "R9F44") (value "100000 Ohm") (Props (_SXDesignName "CRESCENT_CITY_623_20150314_B")) (Terms ("CRESCENT_CITY_623_20150314_B.X1777000Y132500L2RATS" "2") ("CRESCENT_CITY_623_20150314_B.X1777000Y129000L2LRATS" "1"))) ("CRESCENT_CITY_623_20150314_B.T@@RATS@@R3491.2@@U22.B29" TLine (xy (5497 4229)) (refDes "TL2") (Props (_SXDesignName "CRESCENT_CITY_623_20150314_B") (impedance "52.449 ohm") length("235.52 MIL") (propDelay "0.0423 ns") (traceCount "1") (traceGeometry "Microstrip") (velocity "5567.83 mil/ns")) (Terms ("CRESCENT_CITY_623_20150314_B.X1457100Y414800L2LRATS" "1") ("CRESCENT_CITY_623_20150314_B.X1476732Y418720L2LRATS" "2"))) ("CRESCENT_CITY_623_20150314_B.@@R3458.2_SOURCE" Source (xy (5475 4216)) (refDes "GND") (value "0 V") (Props (_SXDesignName "CRESCENT_CITY_623_20150314_B")) (Terms ("CRESCENT_CITY_623_20150314_B.X1777000Y132500L2RATS" "1"))) ("CRESCENT_CITY_623_20150314_B.T@@RATS@@U47.G21@@R3458.1" TLine (xy (5497 4222)) (mirror x) (refDes "TL3") (Props (_SXDesignName "CRESCENT_CITY_623_20150314_B") (impedance "52.449 ohm") length("178.06 MIL") (propDelay "0.03198 ns") (traceCount "1") (traceGeometry "Microstrip") (velocity "5567.87 mil/ns")) (Terms ("CRESCENT_CITY_623_20150314_B.X1777627Y111821L2LRATS" "1") ("CRESCENT_CITY_623_20150314_B.X1777000Y129000L2LRATS" "2"))) ("CRESCENT_CITY_623_20150314_B.T@@RATS@@R3458.1@@R3491.1" TLine (xy (5482 4222)) (mirror x) (refDes "TL4") (Props (_SXDesignName "CRESCENT_CITY_623_20150314_B") (impedance "47.169 ohm") length("6092.01 MIL") (propDelay "1.09416 ns") (traceCount "1") (traceGeometry "Microstrip") (velocity "5567.76 mil/ns")) (Terms ("CRESCENT_CITY_623_20150314_B.X1777000Y129000L2LRATS" "1") ("CRESCENT_CITY_623_20150314_B.X1453600Y414800L2LRATS" "2")))) (Nodes ("CRESCENT_CITY_623_20150314_B.X1777627Y111821L2LRATS" (terms "CRESCENT_CITY_623_20150314_B.T@@RATS@@U47.G21@@R3458.1.1" "CRESCENT_CITY_623_20150314_B.@@U47.G21.1")) ("CRESCENT_CITY_623_20150314_B.X1777000Y129000L2LRATS" (terms "CRESCENT_CITY_623_20150314_B.T@@RATS@@R3458.1@@R3491.1.1" "CRESCENT_CITY_623_20150314_B.T@@RATS@@U47.G21@@R3458.1.2" "CRESCENT_CITY_623_20150314_B.@@R3458.2.1.2")) ("CRESCENT_CITY_623_20150314_B.X1457100Y414800L2LRATS" (terms "CRESCENT_CITY_623_20150314_B.T@@RATS@@R3491.2@@U22.B29.1" "CRESCENT_CITY_623_20150314_B.@@R3491.1.2.2")) ("CRESCENT_CITY_623_20150314_B.X1453600Y414800L2LRATS" (terms "CRESCENT_CITY_623_20150314_B.T@@RATS@@R3458.1@@R3491.1.2" "CRESCENT_CITY_623_20150314_B.@@R3491.1.2.1")) ("CRESCENT_CITY_623_20150314_B.X1476732Y418720L2LRATS" (terms "CRESCENT_CITY_623_20150314_B.T@@RATS@@R3491.2@@U22.B29.2" "CRESCENT_CITY_623_20150314_B.@@U22.B29.1")) ("CRESCENT_CITY_623_20150314_B.X1777000Y132500L2RATS" (terms "CRESCENT_CITY_623_20150314_B.@@R3458.2_SOURCE.1" "CRESCENT_CITY_623_20150314_B.@@R3458.2.1.1"))) (Ports) (Stimuli ("local6" (scope local) (stimType periodic) (Props (periodicFreq "5e+007") (periodicJitter "0") (periodicPattern "1"))) ("local7" (scope local) (stimType periodic) (Props (periodicFreq "5e+007") (periodicJitter "0") (periodicPattern "1"))) ("local4" (scope local) (stimType periodic) (Props (periodicFreq "5e+007") (periodicJitter "0") (periodicPattern "1"))) ("local5" (scope local) (stimType periodic) (Props (periodicFreq "5e+007") (periodicJitter "0") (periodicPattern "1")))) (Notes) (Constraints ("DP_GATHER_CONTROL" "IGNORE") ("DP_MAX_UNCOUPLED_LENGTH" "0.000254") ("DP_PHASE_TOLERANCE" ("LENGTH" "0.000254")) ("RELATIVE_PROPAGATION_DELAY" ("MG_CLK_G1-BCLK" "CRESCENT_CITY_623_20150314_B U47.G21" "CRESCENT_CITY_623_20150314_B U22.B29" "GLOBAL" "LENGTH" "0.127" "LENGTH" "0"))) (MeasurementSets ("EMI" ("EMIStatus" status("on")) ("PeakEmission" status("on")) ("PeakFrequency" status("on")) ("PulseFreq" status("on")) ("RiseTime" status("on")) ("VoltageSwing" status("on"))) ("Reflection" ("BufferDelayFall" status("off")) ("BufferDelayRise" status("off")) ("EyeHeight" status("off")) ("EyeJitter" status("off")) ("EyeWidth" status("off")) ("FirstIncidentFall" status("off")) ("FirstIncidentRise" status("off")) ("Glitch" status("on")) ("GlitchFall" status("off")) ("GlitchRise" status("off")) ("Monotonic" status("on")) ("MonotonicFall" status("off")) ("MonotonicRise" status("off")) ("NoiseMargin" status("on")) ("NoiseMarginHigh" status("off")) ("NoiseMarginLow" status("off")) ("OvershootHigh" status("on")) ("OvershootLow" status("on")) ("PropDelay" status("on")) ("SettleDelay" status("on")) ("SettleDelayFall" status("off")) ("SettleDelayRise" status("off")) ("SwitchDelay" status("on")) ("SwitchDelayFall" status("off")) ("SwitchDelayRise" status("off"))) ("Crosstalk" ("Crosstalk" status("on"))) ("Custom")) (VectorSets) (Props (XnetName "CLK_100M_BMC_PE_R_DN") (allDrivers "active") (customSimType "Reflection") (ftsMode ("Typ")) (rcvrSelect "all") (tlineDelayMode "time") (userRevision "1.0")))) (Subckts) (CrossSections ("CRESCENT_CITY_623_20150314_B" (Props (SXDesignName "CRESCENT_CITY_623_20150314_B")) (Layers ("" (layerType "SURFACE") (material "AIR") (thickness "0 mil") (dielectricConstant "1.000000") (lossTangent "0") (etchFactor "0.000000") (elecCondVal "0 mho/cm") (thermCondVal "0 w/cm-degC")) ("" (layerType "DIELECTRIC") (material "CONFORMAL_COAT") (thickness "0.5 mil") (dielectricConstant "3.800000") (lossTangent "0.035") (etchFactor "0.000000") (elecCondVal "0 mho/cm") (thermCondVal "0.012 w/cm-degC")) ("TOP" (layerType "CONDUCTOR") (material "COPPER") (thickness "  2.100000 mil") (width "4.00 MIL") (dielectricConstant "4.500000") (lossTangent "0") (etchFactor "70.000000") (elecCondVal "595900.000000 mho/cm") (thermCondVal "0 w/cm-degC") (signalDieConstant "3.800000") (signalLossTangent "0.035")) ("" (layerType "DIELECTRIC") (material "FR-4") (thickness "  2.670000 mil") (dielectricConstant "4.000000") (lossTangent "0.035") (etchFactor "0.000000") (elecCondVal "0 mho/cm") (thermCondVal "0.012 w/cm-degC")) ("L2_GND1" (layerType "PLANE") (material "COPPER") (isShield t) (thickness "  1.250000 mil") (dielectricConstant "4.500000") (lossTangent "0.035") (etchFactor "90.000000") (elecCondVal "595900.000000 mho/cm") (thermCondVal "0.012 w/cm-degC")) ("" (layerType "DIELECTRIC") (material "FR-4") (thickness "  9.000000 mil") (dielectricConstant "4.100000") (lossTangent "0.035") (etchFactor "0.000000") (elecCondVal "0 mho/cm") (thermCondVal "0.012 w/cm-degC")) ("L3_SIG1" (layerType "CONDUCTOR") (material "COPPER") (thickness "  1.250000 mil") (width "4.00 MIL") (dielectricConstant "4.500000") (lossTangent "0.035") (etchFactor "90.000000") (elecCondVal "595900.000000 mho/cm") (thermCondVal "0.012 w/cm-degC") (signalDieConstant "4.100000") (signalLossTangent "0.035")) ("" (layerType "DIELECTRIC") (material "FR-4") (thickness "  3.000000 mil") (dielectricConstant "4.500000") (lossTangent "0.035") (etchFactor "0.000000") (elecCondVal "0 mho/cm") (thermCondVal "0 w/cm-degC")) ("L4_GND2" (layerType "PLANE") (material "COPPER") (isShield t) (thickness "  1.250000 mil") (dielectricConstant "4.500000") (lossTangent "0.035") (etchFactor "90.000000") (elecCondVal "595900.000000 mho/cm") (thermCondVal "0 w/cm-degC")) ("" (layerType "DIELECTRIC") (material "FR-4") (thickness "  9.000000 mil") (dielectricConstant "4.000000") (lossTangent "0.035") (etchFactor "0.000000") (elecCondVal "0 mho/cm") (thermCondVal "0.012 w/cm-degC")) ("L5_SIG2" (layerType "CONDUCTOR") (material "COPPER") (thickness "  1.250000 mil") (width "4.00 MIL") (dielectricConstant "4.500000") (lossTangent "0.035") (etchFactor "90.000000") (elecCondVal "595900.000000 mho/cm") (thermCondVal "0.012 w/cm-degC") (signalDieConstant "4.000000") (signalLossTangent "0.035")) ("" (layerType "DIELECTRIC") (material "FR-4") (thickness "  3.000000 mil") (dielectricConstant "4.500000") (lossTangent "0.035") (etchFactor "0.000000") (elecCondVal "0 mho/cm") (thermCondVal "0 w/cm-degC")) ("L6_GND3" (layerType "PLANE") (material "COPPER") (isShield t) (thickness "  1.250000 mil") (dielectricConstant "4.500000") (lossTangent "0.035") (etchFactor "90.000000") (elecCondVal "595900.000000 mho/cm") (thermCondVal "0 w/cm-degC")) ("" (layerType "DIELECTRIC") (material "FR-4") (thickness "  4.500000 mil") (dielectricConstant "4.100000") (lossTangent "0.035") (etchFactor "0.000000") (elecCondVal "0 mho/cm") (thermCondVal "0.012 w/cm-degC")) ("L7_PWR1-SIG" (layerType "PLANE") (material "COPPER") (isShield t) (thickness "  2.610000 mil") (dielectricConstant "4.500000") (lossTangent "0.035") (etchFactor "90.000000") (elecCondVal "595900.000000 mho/cm") (thermCondVal "0.012 w/cm-degC")) ("" (layerType "DIELECTRIC") (material "FR-4") (thickness "  3.100000 mil") (dielectricConstant "4.500000") (lossTangent "0.035") (etchFactor "0.000000") (elecCondVal "0 mho/cm") (thermCondVal "0 w/cm-degC")) ("L8_GND_TEMP" (layerType "PLANE") (material "COPPER") (isShield t) (thickness "  1.250000 mil") (dielectricConstant "4.500000") (lossTangent "0.035") (etchFactor "90.000000") (elecCondVal "595900.000000 mho/cm") (thermCondVal "0 w/cm-degC")) ("" (layerType "DIELECTRIC") (material "FR-4") (thickness "  3.030000 mil") (dielectricConstant "4.500000") (lossTangent "0.035") (etchFactor "0.000000") (elecCondVal "0 mho/cm") (thermCondVal "0 w/cm-degC")) ("L9_SIG_TEMP" (layerType "CONDUCTOR") (material "COPPER") (thickness "  1.250000 mil") (width "3.52 MIL") (dielectricConstant "4.500000") (lossTangent "0.035") (etchFactor "90.000000") (elecCondVal "595900.000000 mho/cm") (thermCondVal "0 w/cm-degC") (signalDieConstant "4.500000") (signalLossTangent "0.035")) ("" (layerType "DIELECTRIC") (material "FR-4") (thickness "  5.000000 mil") (dielectricConstant "4.500000") (lossTangent "0.035") (etchFactor "0.000000") (elecCondVal "0 mho/cm") (thermCondVal "0 w/cm-degC")) ("L10_SIG_TEMP" (layerType "CONDUCTOR") (material "COPPER") (thickness "  1.250000 mil") (width "3.52 MIL") (dielectricConstant "4.500000") (lossTangent "0.035") (etchFactor "90.000000") (elecCondVal "595900.000000 mho/cm") (thermCondVal "0 w/cm-degC") (signalDieConstant "4.500000") (signalLossTangent "0.035")) ("" (layerType "DIELECTRIC") (material "FR-4") (thickness "  3.030000 mil") (dielectricConstant "4.500000") (lossTangent "0.035") (etchFactor "0.000000") (elecCondVal "0 mho/cm") (thermCondVal "0 w/cm-degC")) ("L11_GND_TEMP" (layerType "PLANE") (material "COPPER") (isShield t) (thickness "  1.250000 mil") (dielectricConstant "4.500000") (lossTangent "0.035") (etchFactor "90.000000") (elecCondVal "595900.000000 mho/cm") (thermCondVal "0 w/cm-degC")) ("" (layerType "DIELECTRIC") (material "FR-4") (thickness "  3.100000 mil") (dielectricConstant "4.000000") (lossTangent "0.035") (etchFactor "0.000000") (elecCondVal "0 mho/cm") (thermCondVal "0.012 w/cm-degC")) ("L12_PWR2-SIG" (layerType "PLANE") (material "COPPER") (isShield t) (thickness "  2.610000 mil") (dielectricConstant "4.500000") (lossTangent "0.035") (etchFactor "90.000000") (elecCondVal "595900.000000 mho/cm") (thermCondVal "0.012 w/cm-degC")) ("" (layerType "DIELECTRIC") (material "FR-4") (thickness "  4.500000 mil") (dielectricConstant "4.500000") (lossTangent "0.035") (etchFactor "0.000000") (elecCondVal "0 mho/cm") (thermCondVal "0 w/cm-degC")) ("L13_GND4" (layerType "PLANE") (material "COPPER") (isShield t) (thickness "  1.250000 mil") (dielectricConstant "4.500000") (lossTangent "0.035") (etchFactor "90.000000") (elecCondVal "595900.000000 mho/cm") (thermCondVal "0 w/cm-degC")) ("" (layerType "DIELECTRIC") (material "FR-4") (thickness "  3.000000 mil") (dielectricConstant "4.100000") (lossTangent "0.035") (etchFactor "0.000000") (elecCondVal "0 mho/cm") (thermCondVal "0.012 w/cm-degC")) ("L14_SIG3" (layerType "CONDUCTOR") (material "COPPER") (thickness "  1.250000 mil") (width "4.00 MIL") (dielectricConstant "4.500000") (lossTangent "0.035") (etchFactor "90.000000") (elecCondVal "595900.000000 mho/cm") (thermCondVal "0.012 w/cm-degC") (signalDieConstant "4.100000") (signalLossTangent "0.035")) ("" (layerType "DIELECTRIC") (material "FR-4") (thickness "  9.000000 mil") (dielectricConstant "4.500000") (lossTangent "0.035") (etchFactor "0.000000") (elecCondVal "0 mho/cm") (thermCondVal "0 w/cm-degC")) ("L15_GND5" (layerType "PLANE") (material "COPPER") (isShield t) (thickness "  1.250000 mil") (dielectricConstant "4.500000") (lossTangent "0.035") (etchFactor "90.000000") (elecCondVal "595900.000000 mho/cm") (thermCondVal "0 w/cm-degC")) ("" (layerType "DIELECTRIC") (material "FR-4") (thickness "  3.000000 mil") (dielectricConstant "4.500000") (lossTangent "0.035") (etchFactor "0.000000") (elecCondVal "0 mho/cm") (thermCondVal "0.012 w/cm-degC")) ("L16_SIG4" (layerType "CONDUCTOR") (material "COPPER") (thickness "  1.250000 mil") (width "4.00 MIL") (dielectricConstant "4.500000") (lossTangent "0.035") (etchFactor "90.000000") (elecCondVal "595900.000000 mho/cm") (thermCondVal "0.012 w/cm-degC") (signalDieConstant "4.500000") (signalLossTangent "0.035")) ("" (layerType "DIELECTRIC") (material "FR-4") (thickness "  9.000000 mil") (dielectricConstant "4.500000") (lossTangent "0.035") (etchFactor "0.000000") (elecCondVal "0 mho/cm") (thermCondVal "0 w/cm-degC")) ("L17_GND6" (layerType "PLANE") (material "COPPER") (isShield t) (thickness "  1.250000 mil") (dielectricConstant "4.500000") (lossTangent "0.035") (etchFactor "90.000000") (elecCondVal "595900.000000 mho/cm") (thermCondVal "0.012 w/cm-degC")) ("" (layerType "DIELECTRIC") (material "FR-4") (thickness "  2.670000 mil") (dielectricConstant "4.500000") (lossTangent "0.035") (etchFactor "0.000000") (elecCondVal "0 mho/cm") (thermCondVal "0.012 w/cm-degC")) ("BOTTOM" (layerType "CONDUCTOR") (material "COPPER") (thickness "  2.100000 mil") (width "4.00 MIL") (dielectricConstant "4.500000") (lossTangent "0") (etchFactor "70.000000") (elecCondVal "595900.000000 mho/cm") (thermCondVal "0 w/cm-degC") (signalDieConstant "3.800000") (signalLossTangent "0.035")) ("" (layerType "DIELECTRIC") (material "CONFORMAL_COAT") (thickness "0.5 mil") (dielectricConstant "3.800000") (lossTangent "0.035") (etchFactor "0.000000") (elecCondVal "0 mho/cm") (thermCondVal "0.012 w/cm-degC")) ("" (layerType "SURFACE") (material "AIR") (thickness "0 mil") (dielectricConstant "1.000000") (lossTangent "0") (etchFactor "0.000000") (elecCondVal "0 mho/cm") (thermCondVal "0 w/cm-degC"))))) (Props (DesUnits "mils 2") (LayerStack ("DIELECTRIC" "DIELECTRIC" "BOTTOM" "DIELECTRIC" "L17_GND6" "DIELECTRIC" "L16_SIG4" "DIELECTRIC" "L15_GND5" "DIELECTRIC" "L14_SIG3" "DIELECTRIC" "L13_GND4" "DIELECTRIC" "L12_PWR2-SIG" "DIELECTRIC" "L11_GND_TEMP" "DIELECTRIC" "L10_SIG_TEMP" "DIELECTRIC" "L9_SIG_TEMP" "DIELECTRIC" "L8_GND_TEMP" "DIELECTRIC" "L7_PWR1-SIG" "DIELECTRIC" "L6_GND3" "DIELECTRIC" "L5_SIG2" "DIELECTRIC" "L4_GND2" "DIELECTRIC" "L3_SIG1" "DIELECTRIC" "L2_GND1" "DIELECTRIC" "TOP" "DIELECTRIC" "DIELECTRIC")) (Revision "16.600")) (Params (RLGC (length("1000 mil"))) (DiffIO ((temperature "27") (bufferModelNonInverting "CDSDefaultIO_2p5v") (bufferModelInverting "CDSDefaultIO_2p5v") (stimuli nil) (offsets nil) (state "tristate") (cycle "1") (termMap nil) (setup "0.9e-09") (hold "0.4e-09") (rise nil) (fall nil) (threshInputHighMin "1.7 V") (threshInputHighTyp "1.7  V") (threshInputHighMax "1.7  V") (threshInputLowMin "0.7  V") (threshInputLowTyp "0.7  V") (threshInputLowMax "0.7 ") (threshOutputHighMin "2.365  V") (threshOutputHighTyp "2.5  V") (threshOutputHighMax "2.625  V") (threshOutputLowMin "1.275  V") (threshOutputLowTyp "1.7  V") (threshOutputLowMax "1.985  V") (mappingTagNonInverting nil) (mappingTagInverting nil) (spice nil))) (Source ((voltage "5 V"))) (DiffIOPkg ((temperature "27") (bufferModelNonInverting "CDSDefaultIO_2p5v") (bufferModelInverting "CDSDefaultIO_2p5v") (stimuli nil) (offsets nil) (state "tristate") (cycle "1") (termMap nil) (setup "0.9e-09") (hold "0.4e-09") (rise nil) (fall nil) (threshInputHighMin "1.7 V") (threshInputHighTyp "1.7  V") (threshInputHighMax "1.7  V") (threshInputLowMin "0.7  V") (threshInputLowTyp "0.7  V") (threshInputLowMax "0.7 ") (threshOutputHighMin "2.365  V") (threshOutputHighTyp "2.5  V") (threshOutputHighMax "2.625  V") (threshOutputLowMin "1.275  V") (threshOutputLowTyp "1.7  V") (threshOutputLowMax "1.985  V") (mappingTagNonInverting nil) (mappingTagInverting nil) (spice nil))) (Inductor ((inductance "5 nH") (orientation "0"))) (DiffOutput ((temperature "27") (bufferModelNonInverting "CDSDefaultOutput_2p5v") (bufferModelInverting "CDSDefaultOutput_2p5v") (stimuli nil) (offsets nil) (state "tristate") (cycle "1") (termMap nil) (setup "0.9e-09") (hold "0.4e-09") (rise nil) (fall nil) (threshOutputHighMin "2.375  V") (threshOutputHighTyp "2.5  V") (threshOutputHighMax "2.625  V") (threshOutputLowMin "1.275  V") (threshOutputLowTyp "1.7  V") (threshOutputLowMax "1.985  V") (mappingTagNonInverting nil) (mappingTagInverting nil) (spice nil))) (Capacitor ((capacitance "10 pF") (orientation "0"))) (DiffOutputPkg ((temperature "27") (bufferModelNonInverting "CDSDefaultOutput_2p5v") (bufferModelInverting "CDSDefaultOutput_2p5v") (stimuli nil) (offsets nil) (state "tristate") (cycle "1") (termMap nil) (setup "0.9e-09") (hold "0.4e-09") (rise nil) (fall nil) (threshOutputHighMin "2.375  V") (threshOutputHighTyp "2.5  V") (threshOutputHighMax "2.625  V") (threshOutputLowMin "1.275  V") (threshOutputLowTyp "1.7  V") (threshOutputLowMax "1.985  V") (mappingTagNonInverting nil) (mappingTagInverting nil) (spice nil))) (IbisOutput ((temperature "27") (bufferModel "CDSDefaultOutput_2p5v") (stimuli nil) (offsets nil) (state "tristate") (cycle "1") (termMap nil) (setup "2.0e-09") (hold "1.0e-09") (rise nil) (fall nil) (macroType nil) (voltage nil) (spice nil) (LEFDEFPinName nil) (LEFDEFPinType nil) (mappingTag nil))) (IbisIO ((temperature "27") (bufferModel "CDSDefaultIO_2p5v") (stimuli nil) (offsets nil) (state "tristate") (cycle "1") (termMap nil) (setup "2.0e-09") (hold "1.0e-09") (rise nil) (fall nil) (macroType nil) (voltage nil) (spice nil) (LEFDEFPinName nil) (LEFDEFPinType nil) (mappingTag nil))) (CPWMS ((d1Thickness "10 mil") (d1Constant "4.5") (d1LossTangent "0.035") (d2Thickness "0.72 mil") (d2Constant "4.5") (d2LossTangent "0.035") (d3Thickness "0.0") (d3Constant "1") (d3LossTangent "0") length("1000 mil") (spacing "5 mil") (spacing2 "5 mil") (spacing3 "5 mil") (spacing4 "5 mil") (spacing5 "5 mil") (traceConductivity "595900 mho/cm") (traceGeometry "cpwms") (traceLayerName "") (traceThickness "0.72 mil") (traceType "single") (traceWidth "5.0 mil") (traceWidth2 "5.0 mil") (traceWidth3 "5.0 mil") (traceWidth4 "5.0 mil") (traceWidth5 "5.0 mil") (traceWidth6 "5.0 mil") (offset "0 mil") (traceCount "1") (impedance nil))) (CPW ((d1Thickness "10 mil") (d1Constant "4.5") (d1LossTangent "0.035") (d2Thickness "0.72 mil") (d2Constant "1") (d2LossTangent "0") (d3Thickness "0.0") (d3Constant "1") (d3LossTangent "0") length("1000 mil") (spacing "5 mil") (spacing2 "5 mil") (spacing3 "5 mil") (spacing4 "5 mil") (spacing5 "5 mil") (traceConductivity "595900 mho/cm") (traceGeometry "cpwms") (traceLayerName "") (traceThickness "0.72 mil") (traceType "single") (traceWidth "5.0 mil") (traceWidth2 "5.0 mil") (traceWidth3 "5.0 mil") (traceWidth4 "5.0 mil") (traceWidth5 "5.0 mil") (traceWidth6 "5.0 mil") (offset "0 mil") (traceCount "1") (impedance nil))) (Resistor ((resistance "50 ohm") (orientation "0"))) (async ((asyncTimePoints "") (asyncInitState "1"))) (DiffInput ((temperature "27") (bufferModelNonInverting "CDSDefaultInput_2p5v") (bufferModelInverting "CDSDefaultInput_2p5v") (threshInputHighMin "1.7 V") (threshInputHighTyp "1.7  V") (threshInputHighMax "1.7  V") (threshInputLowMin "0.7  V") (threshInputLowTyp "0.7  V") (threshInputLowMax "0.7  V") (mappingTagNonInverting nil) (mappingTagInverting nil) (cycle "1"))) (Cable (length("1 m"))) (CPWSL ((d1Thickness "10 mil") (d1Constant "4.5") (d1LossTangent "0.035") (d2Thickness "0.72 mil") (d2Constant "4.5") (d2LossTangent "0.035") (d3Thickness "10 mil") (d3Constant "4.5") (d3LossTangent "0.035") length("1000 mil") (spacing "5 mil") (spacing2 "5 mil") (spacing3 "5 mil") (spacing4 "5 mil") (spacing5 "5 mil") (traceConductivity "595900 mho/cm") (traceGeometry "cpwms") (traceLayerName "") (traceThickness "0.72 mil") (traceType "single") (traceWidth "5.0 mil") (traceWidth2 "5.0 mil") (traceWidth3 "5.0 mil") (traceWidth4 "5.0 mil") (traceWidth5 "5.0 mil") (traceWidth6 "5.0 mil") (offset "0 mil") (traceCount "1") (impedance nil))) (Trace ((d1Thickness "10 mil") (d1Constant "4.5") (d1LossTangent "0.035") (d2Thickness "10 mil") (d2Constant "4.5") (d2LossTangent "0.035") (d3Thickness "0.0") (d3Constant "1.0") (d3LossTangent "0") length("1000 mil") (spacing "5 mil") (spacing2 "5 mil") (spacing3 "5 mil") (spacing4 "5 mil") (spacing5 "5 mil") (traceConductivity "595900 mho/cm") (traceGeometry "microstrip") (traceLayerName "") (traceThickness "0.72 mil") (traceType "single") (traceWidth "5.0 mil") (traceWidth2 "5.0 mil") (traceWidth3 "5.0 mil") (traceWidth4 "5.0 mil") (traceWidth5 "5.0 mil") (traceWidth6 "5.0 mil") (offset "0 mil") (traceCount "1") (impedance nil))) (Via ((model "Unknown") (viaOutputFormat "Unknown") (viaPadstack nil) (viaTopLayer nil) (viaBottomLayer nil) (viaIsPower nil) (viaIsGround nil))) (Connector nil) (IbisOutput_OpenPullUp ((temperature "27") (bufferModel "CDSDefaultOutput_2p5v") (stimuli nil) (offsets nil) (state "tristate") (cycle "1") (termMap nil) (setup "2.0e-09") (hold "1.0e-09") (rise nil) (fall nil) (macroType nil) (voltage nil) (spice nil) (LEFDEFPinName nil) (LEFDEFPinType nil) (mappingTag nil))) (TLine ((diffImpedance "100ohm") (diffVelocity "1.4142e+08M/s") (impedance "60ohm") length("2800 mil") (propDelay "0.5 ns") (velocity "5600 mil/ns") (traceCount "1") (traceGeometry "Microstrip") (impedanceMin nil) (impedanceMax nil) (lengthMin nil) (lengthMax nil) (propDelayMin nil) (propDelayMax nil) (impedanceSweepCount nil) (propDelaySweepCount nil) (velocitySweepCount nil) (lengthSweepCount nil) (matchSetName nil))) (sync ((syncFreq "100e6") (syncInitState "1") (syncPattern "10") (syncEdgeSwitch "rise"))) (idlCircuit ((allDrivers "active") (ftsMode '("Typ")) (rcvrSelect "all") (simMode "Reflection") (tlineDelayMode "time") (userRevision "1.0") (autoSolve "On"))) (IbisInputPkg ((temperature "27") (bufferModel "CDSDefaultInput_2p5v") (cycle "1") (LEFDEFPinName nil) (LEFDEFPinType nil) (mappingTag nil))) (IbisOutputPkg ((temperature "27") (bufferModel "CDSDefaultOutput_2p5v") (stimuli nil) (offsets nil) (state "tristate") (cycle "1") (termMap nil) (setup "2.0e-09") (hold "1.0e-09") (rise nil) (fall nil) (macroType nil) (voltage nil) (spice nil) (LEFDEFPinName nil) (LEFDEFPinType nil) (mappingTag nil))) (IbisIOPkg ((temperature "27") (bufferModel "CDSDefaultIO_2p5v") (stimuli nil) (offsets nil) (state "tristate") (cycle "1") (termMap nil) (setup "2.0e-09") (hold "1.0e-09") (rise nil) (fall nil) (macroType nil) (voltage nil) (spice nil) (LEFDEFPinName nil) (LEFDEFPinType nil) (mappingTag nil))) (IbisIOMacro ((temperature "27") (bufferModel "CDSDefaultIO_2p5v") (stimuli nil) (offsets nil) (state "tristate") (cycle "1") (termMap nil) (setup "2.0e-09") (hold "1.0e-09") (rise nil) (fall nil) (macroType nil) (voltage nil) (spice nil) (LEFDEFPinName nil) (LEFDEFPinType nil) (mappingTag nil))) (CurrentProbe nil) (DiffInputPkg ((temperature "27") (bufferModelNonInverting "CDSDefaultInput_2p5v") (bufferModelInverting "CDSDefaultInput_2p5v") (threshInputHighMin "1.7 V") (threshInputHighTyp "1.7  V") (threshInputHighMax "1.7  V") (threshInputLowMin "0.7  V") (threshInputLowTyp "0.7  V") (threshInputLowMax "0.7  V") (mappingTagNonInverting nil) (mappingTagInverting nil) (cycle "1"))) (Diode ((cutoffVoltage "0.7 V"))) (HiClampTerm ((cutoffVoltage "0.7 V") (voltage "5 V") (maxDelay "0.1 ns"))) (DualClampTerm ((cutoffVoltageUp "0.7 V") (cutoffVoltageDown "0.7 V") (voltageUp "5 V") (voltageDown "0 V") (maxDelay "0.1 ns"))) (RCTerm ((resistance "50 ohm") (capacitance "20 pF") (voltage "5 V") (maxDelay "0.1 ns"))) (LowClampTerm ((cutoffVoltage "0.7 V") (voltage "0 V") (maxDelay "0.1 ns"))) (ShuntTerm ((resistance "50 ohm") (voltage "5 V") (maxDelay "0.1 ns"))) (SeriesTerm ((resistance "22 ohm") (maxDelay "0.1 ns"))) (periodic ((periodicFreq "100e6") (periodicPattern "10") (periodicJitter "0"))) (IbisIO_OpenPullDown ((temperature "27") (bufferModel "CDSDefaultIO_2p5v") (stimuli nil) (offsets nil) (state "tristate") (cycle "1") (termMap nil) (setup "2.0e-09") (hold "1.0e-09") (rise nil) (fall nil) (macroType nil) (voltage nil) (spice nil) (LEFDEFPinName nil) (LEFDEFPinType nil) (mappingTag nil))) (IbisIO_OpenPullUp ((temperature "27") (bufferModel "CDSDefaultIO_2p5v") (stimuli nil) (offsets nil) (state "tristate") (cycle "1") (termMap nil) (setup "2.0e-09") (hold "1.0e-09") (rise nil) (fall nil) (macroType nil) (voltage nil) (spice nil) (LEFDEFPinName nil) (LEFDEFPinType nil) (mappingTag nil))) (TheveninTerm ((resistanceUp "180 ohm") (resistanceDown "270 ohm") (voltageUp "5 V") (voltageDown "0 V") (maxDelay "0.1 ns"))) (clocked ((clockRise "1e-09") (clockFall "1e-09") (clockFreq "100e6") (clockInitState "0") (clockDutyCycle "0.5") (clockJitter "0"))) (ESpiceDevice nil) (IbisInput ((temperature "27") (bufferModel "CDSDefaultInput_2p5v") (cycle "1") (LEFDEFPinName nil) (LEFDEFPinType nil) (mappingTag nil)))))
				)
				( objectStatus "CLK_100M_BMC_PE_R_DN" )
			)
			( electricalCSet "@crescent_city_bb_fab1_lib.crescent_city_bb_fab1(sch_1):\RMII_TX_NEW\"
				( pinPairRef "RMII_TX_NEW:U9F4.A10:U7C1.AM2" )
				( attribute "TOPOLOGY_TEMPLATE_REVISION" "1.0"
					( Origin gBackEnd )
				)
				( topologyData 27735
(SKIDL (Circuits ("MAIN" (Parts ("CRESCENT_CITY_638_20150416_B.@@U22.AM2" IbisIOPkg (xy (5539 4218)) (refDes "U7C1") (model "Unknown") (Props (_SXDesignName "CRESCENT_CITY_638_20150416_B") (brdx "15294.69 MIL") (brdy "3699.21 MIL") (bufferModel "CDSDefaultIO_2p5v") (cycle "1") (hold "1.0e-09") (mappingTag "") (offsets ("4" "0") ("5" "0")) (setup "2.0e-09") (state "tristate") (stimuli ("4" "local9") ("5" "local10")) (temperature "27") (termMap ("4" "Data") ("5" "Enable"))) (Terms ("CRESCENT_CITY_638_20150416_B.X1529469Y369921L2LRATS" "AM2"))) ("CRESCENT_CITY_638_20150416_B.@@U47.A10" IbisOutputPkg (xy (5498 4235)) (refDes "U9F4") (model "Unknown") (Props (_SXDesignName "CRESCENT_CITY_638_20150416_B") (brdx "17587.29 MIL") (brdy "771.76 MIL") (bufferModel "CDSDefaultOutput_2p5v") (cycle "1") (hold "1.0e-09") (mappingTag "") (offsets ("4" "0")) (setup "2.0e-09") (state "tristate") (stimuli ("4" "local11")) (temperature "27") (termMap ("4" "Data"))) (Terms ("CRESCENT_CITY_638_20150416_B.X1758729Y77176L2LRATS" "A10"))) ("CRESCENT_CITY_638_20150416_B.@@EU46.9" IbisInputPkg (xy (5539 4235)) (refDes "EU9E1") (model "Unknown") (Props (_SXDesignName "CRESCENT_CITY_638_20150416_B") (brdx "19352 MIL") (brdy "1774.84 MIL") (bufferModel "CDSDefaultInput_2p5v") (mappingTag "") (temperature "27")) (Terms ("CRESCENT_CITY_638_20150416_B.X1935200Y177484L2LRATS" "9"))) ("CRESCENT_CITY_638_20150416_B.T@@RATS@@U22.AM2@@R3478.2" TLine (xy (5524 4213)) (mirror x) (refDes "TL6") (Props (_SXDesignName "CRESCENT_CITY_638_20150416_B") (impedance "52.449 ohm") length("5137.91 MIL") (propDelay "0.92281 ns") (traceCount "1") (traceGeometry "Microstrip") (velocity "5567.68 mil/ns")) (Terms ("CRESCENT_CITY_638_20150416_B.X1529469Y369921L2LRATS" "1") ("CRESCENT_CITY_638_20150416_B.X1755140Y81800L36LRATS" "2"))) ("CRESCENT_CITY_638_20150416_B.@@R3439.1.2" Resistor (xy (5525 4227)) (refDes "R1R4") (value "10000 Ohm") (Props (_SXDesignName "CRESCENT_CITY_638_20150416_B")) (Terms ("CRESCENT_CITY_638_20150416_B.X1943000Y180000L36RATS" "1") ("CRESCENT_CITY_638_20150416_B.X1946500Y180000L36LRATS" "2"))) ("CRESCENT_CITY_638_20150416_B.T@@RATS@@EU46.9@@R3439.2" TLine (xy (5540 4227)) (mirror x) (refDes "TL7") (Props (_SXDesignName "CRESCENT_CITY_638_20150416_B") (impedance "48.412 ohm") length("138.16 MIL") (propDelay "0.02481 ns") (traceCount "1") (traceGeometry "Microstrip") (velocity "5568.74 mil/ns")) (Terms ("CRESCENT_CITY_638_20150416_B.X1935200Y177484L2LRATS" "1") ("CRESCENT_CITY_638_20150416_B.X1946500Y180000L36LRATS" "2"))) ("CRESCENT_CITY_638_20150416_B.@@R3439.1_SOURCE" Source (xy (5518 4227)) (refDes "P3V3_STBY") (value "3.3 V") (Props (_SXDesignName "CRESCENT_CITY_638_20150416_B")) (Terms ("CRESCENT_CITY_638_20150416_B.X1943000Y180000L36RATS" "1"))) ("CRESCENT_CITY_638_20150416_B.@@R3478.1.2" Resistor (xy (5515 4235)) (refDes "R1T28") (value "22 Ohm") (Props (_SXDesignName "CRESCENT_CITY_638_20150416_B")) (Terms ("CRESCENT_CITY_638_20150416_B.X1758640Y81800L36LRATS" "1") ("CRESCENT_CITY_638_20150416_B.X1755140Y81800L36LRATS" "2"))) ("CRESCENT_CITY_638_20150416_B.T@@RATS@@U47.A10@@R3478.1" TLine (xy (5506 4235)) (refDes "TL8") (Props (_SXDesignName "CRESCENT_CITY_638_20150416_B") (impedance "50.521 ohm") length("47.13 MIL") (propDelay "0.00846 ns") (traceCount "1") (traceGeometry "Microstrip") (velocity "5570.91 mil/ns")) (Terms ("CRESCENT_CITY_638_20150416_B.X1758729Y77176L2LRATS" "1") ("CRESCENT_CITY_638_20150416_B.X1758640Y81800L36LRATS" "2"))) ("CRESCENT_CITY_638_20150416_B.T@@RATS@@R3478.2@@EU46.9" TLine (xy (5524 4235)) (refDes "TL9") (Props (_SXDesignName "CRESCENT_CITY_638_20150416_B") (impedance "50.521 ohm") length("2757.44 MIL") (propDelay "0.49526 ns") (traceCount "1") (traceGeometry "Microstrip") (velocity "5567.68 mil/ns")) (Terms ("CRESCENT_CITY_638_20150416_B.X1755140Y81800L36LRATS" "1") ("CRESCENT_CITY_638_20150416_B.X1935200Y177484L2LRATS" "2")))) (Nodes ("CRESCENT_CITY_638_20150416_B.X1758729Y77176L2LRATS" (terms "CRESCENT_CITY_638_20150416_B.T@@RATS@@U47.A10@@R3478.1.1" "CRESCENT_CITY_638_20150416_B.@@U47.A10.1")) ("CRESCENT_CITY_638_20150416_B.X1935200Y177484L2LRATS" (terms "CRESCENT_CITY_638_20150416_B.T@@RATS@@R3478.2@@EU46.9.2" "CRESCENT_CITY_638_20150416_B.T@@RATS@@EU46.9@@R3439.2.1" "CRESCENT_CITY_638_20150416_B.@@EU46.9.1")) ("CRESCENT_CITY_638_20150416_B.X1946500Y180000L36LRATS" (terms "CRESCENT_CITY_638_20150416_B.T@@RATS@@EU46.9@@R3439.2.2" "CRESCENT_CITY_638_20150416_B.@@R3439.1.2.2")) ("CRESCENT_CITY_638_20150416_B.X1755140Y81800L36LRATS" (terms "CRESCENT_CITY_638_20150416_B.T@@RATS@@R3478.2@@EU46.9.1" "CRESCENT_CITY_638_20150416_B.@@R3478.1.2.2" "CRESCENT_CITY_638_20150416_B.T@@RATS@@U22.AM2@@R3478.2.2")) ("CRESCENT_CITY_638_20150416_B.X1758640Y81800L36LRATS" (terms "CRESCENT_CITY_638_20150416_B.T@@RATS@@U47.A10@@R3478.1.2" "CRESCENT_CITY_638_20150416_B.@@R3478.1.2.1")) ("CRESCENT_CITY_638_20150416_B.X1529469Y369921L2LRATS" (terms "CRESCENT_CITY_638_20150416_B.T@@RATS@@U22.AM2@@R3478.2.1" "CRESCENT_CITY_638_20150416_B.@@U22.AM2.1")) ("CRESCENT_CITY_638_20150416_B.X1943000Y180000L36RATS" (terms "CRESCENT_CITY_638_20150416_B.@@R3439.1_SOURCE.1" "CRESCENT_CITY_638_20150416_B.@@R3439.1.2.1"))) (Ports) (Stimuli ("local2" (scope local) (stimType periodic) (Props (periodicFreq "5e+007") (periodicJitter "0") (periodicPattern "1"))) ("local10" (scope local) (stimType periodic) (Props (periodicFreq "5e+007") (periodicJitter "0") (periodicPattern "1"))) ("local9" (scope local) (stimType periodic) (Props (periodicFreq "5e+007") (periodicJitter "0") (periodicPattern "1"))) ("local3" (scope local) (stimType periodic) (Props (periodicFreq "5e+007") (periodicJitter "0") (periodicPattern "1"))) ("local4" (scope local) (stimType periodic) (Props (periodicFreq "5e+007") (periodicJitter "0") (periodicPattern "1"))) ("local11" (scope local) (stimType periodic) (Props (periodicFreq "5e+007") (periodicJitter "0") (periodicPattern "1")))) (Notes) (Constraints ("DELAY_RULE" ("CRESCENT_CITY_638_20150416_B U47.A10" "CRESCENT_CITY_638_20150416_B U22.AM2" "LENGTH" "0.2032" "LENGTH" "0.3556"))) (MeasurementSets ("EMI" ("EMIStatus" status("on")) ("PeakEmission" status("on")) ("PeakFrequency" status("on")) ("PulseFreq" status("on")) ("RiseTime" status("on")) ("VoltageSwing" status("on"))) ("Reflection" ("BufferDelayFall" status("off")) ("BufferDelayRise" status("off")) ("EyeHeight" status("off")) ("EyeJitter" status("off")) ("EyeWidth" status("off")) ("FirstIncidentFall" status("off")) ("FirstIncidentRise" status("off")) ("Glitch" status("on")) ("GlitchFall" status("off")) ("GlitchRise" status("off")) ("Monotonic" status("on")) ("MonotonicFall" status("off")) ("MonotonicRise" status("off")) ("NoiseMargin" status("on")) ("NoiseMarginHigh" status("off")) ("NoiseMarginLow" status("off")) ("OvershootHigh" status("on")) ("OvershootLow" status("on")) ("PropDelay" status("on")) ("SettleDelay" status("on")) ("SettleDelayFall" status("off")) ("SettleDelayRise" status("off")) ("SwitchDelay" status("on")) ("SwitchDelayFall" status("off")) ("SwitchDelayRise" status("off"))) ("Crosstalk" ("Crosstalk" status("on"))) ("Custom")) (VectorSets) (Props (XnetName "RMII_BMC_PCH_SPRNGVLLE_TXD0") (allDrivers "active") (customSimType "Reflection") (ftsMode ("Typ")) (rcvrSelect "all") (tlineDelayMode "time") (userRevision "1.0")))) (Subckts) (CrossSections ("CRESCENT_CITY_638_20150416_B" (Props (SXDesignName "CRESCENT_CITY_638_20150416_B")) (Layers ("" (layerType "SURFACE") (material "AIR") (thickness "0 mil") (dielectricConstant "1.000000") (lossTangent "0") (etchFactor "0.000000") (elecCondVal "0 mho/cm") (thermCondVal "0 w/cm-degC")) ("" (layerType "DIELECTRIC") (material "CONFORMAL_COAT") (thickness "0.5 mil") (dielectricConstant "3.800000") (lossTangent "0.035") (etchFactor "0.000000") (elecCondVal "0 mho/cm") (thermCondVal "0.012 w/cm-degC")) ("TOP" (layerType "CONDUCTOR") (material "COPPER") (thickness "  2.100000 mil") (width "4.00 MIL") (dielectricConstant "4.500000") (lossTangent "0") (etchFactor "70.000000") (elecCondVal "595900.000000 mho/cm") (thermCondVal "0 w/cm-degC") (signalDieConstant "3.800000") (signalLossTangent "0.035")) ("" (layerType "DIELECTRIC") (material "FR-4") (thickness "  2.670000 mil") (dielectricConstant "4.000000") (lossTangent "0.035") (etchFactor "0.000000") (elecCondVal "0 mho/cm") (thermCondVal "0.012 w/cm-degC")) ("L2_GND1" (layerType "PLANE") (material "COPPER") (isShield t) (thickness "  1.250000 mil") (dielectricConstant "4.500000") (lossTangent "0.035") (etchFactor "90.000000") (elecCondVal "595900.000000 mho/cm") (thermCondVal "0.012 w/cm-degC")) ("" (layerType "DIELECTRIC") (material "FR-4") (thickness "  9.000000 mil") (dielectricConstant "4.100000") (lossTangent "0.035") (etchFactor "0.000000") (elecCondVal "0 mho/cm") (thermCondVal "0.012 w/cm-degC")) ("L3_SIG1" (layerType "CONDUCTOR") (material "COPPER") (thickness "  1.250000 mil") (width "4.00 MIL") (dielectricConstant "4.500000") (lossTangent "0.035") (etchFactor "90.000000") (elecCondVal "595900.000000 mho/cm") (thermCondVal "0.012 w/cm-degC") (signalDieConstant "4.100000") (signalLossTangent "0.035")) ("" (layerType "DIELECTRIC") (material "FR-4") (thickness "  3.000000 mil") (dielectricConstant "4.500000") (lossTangent "0.035") (etchFactor "0.000000") (elecCondVal "0 mho/cm") (thermCondVal "0 w/cm-degC")) ("L4_GND2" (layerType "PLANE") (material "COPPER") (isShield t) (thickness "  1.250000 mil") (dielectricConstant "4.500000") (lossTangent "0.035") (etchFactor "90.000000") (elecCondVal "595900.000000 mho/cm") (thermCondVal "0 w/cm-degC")) ("" (layerType "DIELECTRIC") (material "FR-4") (thickness "  9.000000 mil") (dielectricConstant "4.000000") (lossTangent "0.035") (etchFactor "0.000000") (elecCondVal "0 mho/cm") (thermCondVal "0.012 w/cm-degC")) ("L5_SIG2" (layerType "CONDUCTOR") (material "COPPER") (thickness "  1.250000 mil") (width "4.00 MIL") (dielectricConstant "4.500000") (lossTangent "0.035") (etchFactor "90.000000") (elecCondVal "595900.000000 mho/cm") (thermCondVal "0.012 w/cm-degC") (signalDieConstant "4.000000") (signalLossTangent "0.035")) ("" (layerType "DIELECTRIC") (material "FR-4") (thickness "  3.000000 mil") (dielectricConstant "4.500000") (lossTangent "0.035") (etchFactor "0.000000") (elecCondVal "0 mho/cm") (thermCondVal "0 w/cm-degC")) ("L6_GND3" (layerType "PLANE") (material "COPPER") (isShield t) (thickness "  1.250000 mil") (dielectricConstant "4.500000") (lossTangent "0.035") (etchFactor "90.000000") (elecCondVal "595900.000000 mho/cm") (thermCondVal "0 w/cm-degC")) ("" (layerType "DIELECTRIC") (material "FR-4") (thickness "  4.500000 mil") (dielectricConstant "4.100000") (lossTangent "0.035") (etchFactor "0.000000") (elecCondVal "0 mho/cm") (thermCondVal "0.012 w/cm-degC")) ("L7_PWR1-SIG" (layerType "PLANE") (material "COPPER") (isShield t) (thickness "  2.610000 mil") (dielectricConstant "4.500000") (lossTangent "0.035") (etchFactor "90.000000") (elecCondVal "595900.000000 mho/cm") (thermCondVal "0.012 w/cm-degC")) ("" (layerType "DIELECTRIC") (material "FR-4") (thickness "  3.100000 mil") (dielectricConstant "4.500000") (lossTangent "0.035") (etchFactor "0.000000") (elecCondVal "0 mho/cm") (thermCondVal "0 w/cm-degC")) ("L8_GND_TEMP" (layerType "PLANE") (material "COPPER") (isShield t) (thickness "  1.250000 mil") (dielectricConstant "4.500000") (lossTangent "0.035") (etchFactor "90.000000") (elecCondVal "595900.000000 mho/cm") (thermCondVal "0 w/cm-degC")) ("" (layerType "DIELECTRIC") (material "FR-4") (thickness "  3.030000 mil") (dielectricConstant "4.500000") (lossTangent "0.035") (etchFactor "0.000000") (elecCondVal "0 mho/cm") (thermCondVal "0 w/cm-degC")) ("L9_SIG_TEMP" (layerType "CONDUCTOR") (material "COPPER") (thickness "  1.250000 mil") (width "3.52 MIL") (dielectricConstant "4.500000") (lossTangent "0.035") (etchFactor "90.000000") (elecCondVal "595900.000000 mho/cm") (thermCondVal "0 w/cm-degC") (signalDieConstant "4.500000") (signalLossTangent "0.035")) ("" (layerType "DIELECTRIC") (material "FR-4") (thickness "  5.000000 mil") (dielectricConstant "4.500000") (lossTangent "0.035") (etchFactor "0.000000") (elecCondVal "0 mho/cm") (thermCondVal "0 w/cm-degC")) ("L10_SIG_TEMP" (layerType "CONDUCTOR") (material "COPPER") (thickness "  1.250000 mil") (width "3.52 MIL") (dielectricConstant "4.500000") (lossTangent "0.035") (etchFactor "90.000000") (elecCondVal "595900.000000 mho/cm") (thermCondVal "0 w/cm-degC") (signalDieConstant "4.500000") (signalLossTangent "0.035")) ("" (layerType "DIELECTRIC") (material "FR-4") (thickness "  3.030000 mil") (dielectricConstant "4.500000") (lossTangent "0.035") (etchFactor "0.000000") (elecCondVal "0 mho/cm") (thermCondVal "0 w/cm-degC")) ("L11_GND_TEMP" (layerType "PLANE") (material "COPPER") (isShield t) (thickness "  1.250000 mil") (dielectricConstant "4.500000") (lossTangent "0.035") (etchFactor "90.000000") (elecCondVal "595900.000000 mho/cm") (thermCondVal "0 w/cm-degC")) ("" (layerType "DIELECTRIC") (material "FR-4") (thickness "  3.100000 mil") (dielectricConstant "4.000000") (lossTangent "0.035") (etchFactor "0.000000") (elecCondVal "0 mho/cm") (thermCondVal "0.012 w/cm-degC")) ("L12_PWR2-SIG" (layerType "PLANE") (material "COPPER") (isShield t) (thickness "  2.610000 mil") (dielectricConstant "4.500000") (lossTangent "0.035") (etchFactor "90.000000") (elecCondVal "595900.000000 mho/cm") (thermCondVal "0.012 w/cm-degC")) ("" (layerType "DIELECTRIC") (material "FR-4") (thickness "  4.500000 mil") (dielectricConstant "4.500000") (lossTangent "0.035") (etchFactor "0.000000") (elecCondVal "0 mho/cm") (thermCondVal "0 w/cm-degC")) ("L13_GND4" (layerType "PLANE") (material "COPPER") (isShield t) (thickness "  1.250000 mil") (dielectricConstant "4.500000") (lossTangent "0.035") (etchFactor "90.000000") (elecCondVal "595900.000000 mho/cm") (thermCondVal "0 w/cm-degC")) ("" (layerType "DIELECTRIC") (material "FR-4") (thickness "  3.000000 mil") (dielectricConstant "4.100000") (lossTangent "0.035") (etchFactor "0.000000") (elecCondVal "0 mho/cm") (thermCondVal "0.012 w/cm-degC")) ("L14_SIG3" (layerType "CONDUCTOR") (material "COPPER") (thickness "  1.250000 mil") (width "4.00 MIL") (dielectricConstant "4.500000") (lossTangent "0.035") (etchFactor "90.000000") (elecCondVal "595900.000000 mho/cm") (thermCondVal "0.012 w/cm-degC") (signalDieConstant "4.100000") (signalLossTangent "0.035")) ("" (layerType "DIELECTRIC") (material "FR-4") (thickness "  9.000000 mil") (dielectricConstant "4.500000") (lossTangent "0.035") (etchFactor "0.000000") (elecCondVal "0 mho/cm") (thermCondVal "0 w/cm-degC")) ("L15_GND5" (layerType "PLANE") (material "COPPER") (isShield t) (thickness "  1.250000 mil") (dielectricConstant "4.500000") (lossTangent "0.035") (etchFactor "90.000000") (elecCondVal "595900.000000 mho/cm") (thermCondVal "0 w/cm-degC")) ("" (layerType "DIELECTRIC") (material "FR-4") (thickness "  3.000000 mil") (dielectricConstant "4.500000") (lossTangent "0.035") (etchFactor "0.000000") (elecCondVal "0 mho/cm") (thermCondVal "0.012 w/cm-degC")) ("L16_SIG4" (layerType "CONDUCTOR") (material "COPPER") (thickness "  1.250000 mil") (width "4.00 MIL") (dielectricConstant "4.500000") (lossTangent "0.035") (etchFactor "90.000000") (elecCondVal "595900.000000 mho/cm") (thermCondVal "0.012 w/cm-degC") (signalDieConstant "4.500000") (signalLossTangent "0.035")) ("" (layerType "DIELECTRIC") (material "FR-4") (thickness "  9.000000 mil") (dielectricConstant "4.500000") (lossTangent "0.035") (etchFactor "0.000000") (elecCondVal "0 mho/cm") (thermCondVal "0 w/cm-degC")) ("L17_GND6" (layerType "PLANE") (material "COPPER") (isShield t) (thickness "  1.250000 mil") (dielectricConstant "4.500000") (lossTangent "0.035") (etchFactor "90.000000") (elecCondVal "595900.000000 mho/cm") (thermCondVal "0.012 w/cm-degC")) ("" (layerType "DIELECTRIC") (material "FR-4") (thickness "  2.670000 mil") (dielectricConstant "4.500000") (lossTangent "0.035") (etchFactor "0.000000") (elecCondVal "0 mho/cm") (thermCondVal "0.012 w/cm-degC")) ("BOTTOM" (layerType "CONDUCTOR") (material "COPPER") (thickness "  2.100000 mil") (width "4.00 MIL") (dielectricConstant "4.500000") (lossTangent "0") (etchFactor "70.000000") (elecCondVal "595900.000000 mho/cm") (thermCondVal "0 w/cm-degC") (signalDieConstant "3.800000") (signalLossTangent "0.035")) ("" (layerType "DIELECTRIC") (material "CONFORMAL_COAT") (thickness "0.5 mil") (dielectricConstant "3.800000") (lossTangent "0.035") (etchFactor "0.000000") (elecCondVal "0 mho/cm") (thermCondVal "0.012 w/cm-degC")) ("" (layerType "SURFACE") (material "AIR") (thickness "0 mil") (dielectricConstant "1.000000") (lossTangent "0") (etchFactor "0.000000") (elecCondVal "0 mho/cm") (thermCondVal "0 w/cm-degC"))))) (Props (DesUnits "mils 2") (LayerStack ("DIELECTRIC" "DIELECTRIC" "BOTTOM" "DIELECTRIC" "L17_GND6" "DIELECTRIC" "L16_SIG4" "DIELECTRIC" "L15_GND5" "DIELECTRIC" "L14_SIG3" "DIELECTRIC" "L13_GND4" "DIELECTRIC" "L12_PWR2-SIG" "DIELECTRIC" "L11_GND_TEMP" "DIELECTRIC" "L10_SIG_TEMP" "DIELECTRIC" "L9_SIG_TEMP" "DIELECTRIC" "L8_GND_TEMP" "DIELECTRIC" "L7_PWR1-SIG" "DIELECTRIC" "L6_GND3" "DIELECTRIC" "L5_SIG2" "DIELECTRIC" "L4_GND2" "DIELECTRIC" "L3_SIG1" "DIELECTRIC" "L2_GND1" "DIELECTRIC" "TOP" "DIELECTRIC" "DIELECTRIC")) (Revision "16.600")) (Params (DiffInput ((temperature "27") (bufferModelNonInverting "CDSDefaultInput_2p5v") (bufferModelInverting "CDSDefaultInput_2p5v") (threshInputHighMin "1.7 V") (threshInputHighTyp "1.7  V") (threshInputHighMax "1.7  V") (threshInputLowMin "0.7  V") (threshInputLowTyp "0.7  V") (threshInputLowMax "0.7  V") (mappingTagNonInverting nil) (mappingTagInverting nil) (cycle "1"))) (Resistor ((resistance "50 ohm") (orientation "0"))) (DiffOutputPkg ((temperature "27") (bufferModelNonInverting "CDSDefaultOutput_2p5v") (bufferModelInverting "CDSDefaultOutput_2p5v") (stimuli nil) (offsets nil) (state "tristate") (cycle "1") (termMap nil) (setup "0.9e-09") (hold "0.4e-09") (rise nil) (fall nil) (threshOutputHighMin "2.375  V") (threshOutputHighTyp "2.5  V") (threshOutputHighMax "2.625  V") (threshOutputLowMin "1.275  V") (threshOutputLowTyp "1.7  V") (threshOutputLowMax "1.985  V") (mappingTagNonInverting nil) (mappingTagInverting nil) (spice nil))) (DiffOutput ((temperature "27") (bufferModelNonInverting "CDSDefaultOutput_2p5v") (bufferModelInverting "CDSDefaultOutput_2p5v") (stimuli nil) (offsets nil) (state "tristate") (cycle "1") (termMap nil) (setup "0.9e-09") (hold "0.4e-09") (rise nil) (fall nil) (threshOutputHighMin "2.375  V") (threshOutputHighTyp "2.5  V") (threshOutputHighMax "2.625  V") (threshOutputLowMin "1.275  V") (threshOutputLowTyp "1.7  V") (threshOutputLowMax "1.985  V") (mappingTagNonInverting nil) (mappingTagInverting nil) (spice nil))) (Inductor ((inductance "5 nH") (orientation "0"))) (Capacitor ((capacitance "10 pF") (orientation "0"))) (DiffIOPkg ((temperature "27") (bufferModelNonInverting "CDSDefaultIO_2p5v") (bufferModelInverting "CDSDefaultIO_2p5v") (stimuli nil) (offsets nil) (state "tristate") (cycle "1") (termMap nil) (setup "0.9e-09") (hold "0.4e-09") (rise nil) (fall nil) (threshInputHighMin "1.7 V") (threshInputHighTyp "1.7  V") (threshInputHighMax "1.7  V") (threshInputLowMin "0.7  V") (threshInputLowTyp "0.7  V") (threshInputLowMax "0.7 ") (threshOutputHighMin "2.365  V") (threshOutputHighTyp "2.5  V") (threshOutputHighMax "2.625  V") (threshOutputLowMin "1.275  V") (threshOutputLowTyp "1.7  V") (threshOutputLowMax "1.985  V") (mappingTagNonInverting nil) (mappingTagInverting nil) (spice nil))) (Source ((voltage "5 V"))) (DiffIO ((temperature "27") (bufferModelNonInverting "CDSDefaultIO_2p5v") (bufferModelInverting "CDSDefaultIO_2p5v") (stimuli nil) (offsets nil) (state "tristate") (cycle "1") (termMap nil) (setup "0.9e-09") (hold "0.4e-09") (rise nil) (fall nil) (threshInputHighMin "1.7 V") (threshInputHighTyp "1.7  V") (threshInputHighMax "1.7  V") (threshInputLowMin "0.7  V") (threshInputLowTyp "0.7  V") (threshInputLowMax "0.7 ") (threshOutputHighMin "2.365  V") (threshOutputHighTyp "2.5  V") (threshOutputHighMax "2.625  V") (threshOutputLowMin "1.275  V") (threshOutputLowTyp "1.7  V") (threshOutputLowMax "1.985  V") (mappingTagNonInverting nil) (mappingTagInverting nil) (spice nil))) (RLGC (length("1000 mil"))) (DiffInputPkg ((temperature "27") (bufferModelNonInverting "CDSDefaultInput_2p5v") (bufferModelInverting "CDSDefaultInput_2p5v") (threshInputHighMin "1.7 V") (threshInputHighTyp "1.7  V") (threshInputHighMax "1.7  V") (threshInputLowMin "0.7  V") (threshInputLowTyp "0.7  V") (threshInputLowMax "0.7  V") (mappingTagNonInverting nil) (mappingTagInverting nil) (cycle "1"))) (IbisInput ((temperature "27") (bufferModel "CDSDefaultInput_2p5v") (cycle "1") (LEFDEFPinName nil) (LEFDEFPinType nil) (mappingTag nil))) (Diode ((cutoffVoltage "0.7 V"))) (idlCircuit ((allDrivers "active") (ftsMode '("Typ")) (rcvrSelect "all") (simMode "Reflection") (tlineDelayMode "time") (userRevision "1.0") (autoSolve "On"))) (CPW ((d1Thickness "10 mil") (d1Constant "4.5") (d1LossTangent "0.035") (d2Thickness "0.72 mil") (d2Constant "1") (d2LossTangent "0") (d3Thickness "0.0") (d3Constant "1") (d3LossTangent "0") length("1000 mil") (spacing "5 mil") (spacing2 "5 mil") (spacing3 "5 mil") (spacing4 "5 mil") (spacing5 "5 mil") (traceConductivity "595900 mho/cm") (traceGeometry "cpwms") (traceLayerName "") (traceThickness "0.72 mil") (traceType "single") (traceWidth "5.0 mil") (traceWidth2 "5.0 mil") (traceWidth3 "5.0 mil") (traceWidth4 "5.0 mil") (traceWidth5 "5.0 mil") (traceWidth6 "5.0 mil") (offset "0 mil") (traceCount "1") (impedance nil))) (DualClampTerm ((cutoffVoltageUp "0.7 V") (cutoffVoltageDown "0.7 V") (voltageUp "5 V") (voltageDown "0 V") (maxDelay "0.1 ns"))) (ESpiceDevice nil) (HiClampTerm ((cutoffVoltage "0.7 V") (voltage "5 V") (maxDelay "0.1 ns"))) (IbisOutput ((temperature "27") (bufferModel "CDSDefaultOutput_2p5v") (stimuli nil) (offsets nil) (state "tristate") (cycle "1") (termMap nil) (setup "2.0e-09") (hold "1.0e-09") (rise nil) (fall nil) (macroType nil) (voltage nil) (spice nil) (LEFDEFPinName nil) (LEFDEFPinType nil) (mappingTag nil))) (sync ((syncFreq "100e6") (syncInitState "1") (syncPattern "10") (syncEdgeSwitch "rise"))) (IbisIO ((temperature "27") (bufferModel "CDSDefaultIO_2p5v") (stimuli nil) (offsets nil) (state "tristate") (cycle "1") (termMap nil) (setup "2.0e-09") (hold "1.0e-09") (rise nil) (fall nil) (macroType nil) (voltage nil) (spice nil) (LEFDEFPinName nil) (LEFDEFPinType nil) (mappingTag nil))) (RCTerm ((resistance "50 ohm") (capacitance "20 pF") (voltage "5 V") (maxDelay "0.1 ns"))) (TLine ((diffImpedance "100ohm") (diffVelocity "1.4142e+08M/s") (impedance "60ohm") length("2800 mil") (propDelay "0.5 ns") (velocity "5600 mil/ns") (traceCount "1") (traceGeometry "Microstrip") (impedanceMin nil) (impedanceMax nil) (lengthMin nil) (lengthMax nil) (propDelayMin nil) (propDelayMax nil) (impedanceSweepCount nil) (propDelaySweepCount nil) (velocitySweepCount nil) (lengthSweepCount nil) (matchSetName nil))) (LowClampTerm ((cutoffVoltage "0.7 V") (voltage "0 V") (maxDelay "0.1 ns"))) (Connector nil) (ShuntTerm ((resistance "50 ohm") (voltage "5 V") (maxDelay "0.1 ns"))) (IbisIO_OpenPullDown ((temperature "27") (bufferModel "CDSDefaultIO_2p5v") (stimuli nil) (offsets nil) (state "tristate") (cycle "1") (termMap nil) (setup "2.0e-09") (hold "1.0e-09") (rise nil) (fall nil) (macroType nil) (voltage nil) (spice nil) (LEFDEFPinName nil) (LEFDEFPinType nil) (mappingTag nil))) (clocked ((clockRise "1e-09") (clockFall "1e-09") (clockFreq "100e6") (clockInitState "0") (clockDutyCycle "0.5") (clockJitter "0"))) (TheveninTerm ((resistanceUp "180 ohm") (resistanceDown "270 ohm") (voltageUp "5 V") (voltageDown "0 V") (maxDelay "0.1 ns"))) (IbisIO_OpenPullUp ((temperature "27") (bufferModel "CDSDefaultIO_2p5v") (stimuli nil) (offsets nil) (state "tristate") (cycle "1") (termMap nil) (setup "2.0e-09") (hold "1.0e-09") (rise nil) (fall nil) (macroType nil) (voltage nil) (spice nil) (LEFDEFPinName nil) (LEFDEFPinType nil) (mappingTag nil))) (CPWSL ((d1Thickness "10 mil") (d1Constant "4.5") (d1LossTangent "0.035") (d2Thickness "0.72 mil") (d2Constant "4.5") (d2LossTangent "0.035") (d3Thickness "10 mil") (d3Constant "4.5") (d3LossTangent "0.035") length("1000 mil") (spacing "5 mil") (spacing2 "5 mil") (spacing3 "5 mil") (spacing4 "5 mil") (spacing5 "5 mil") (traceConductivity "595900 mho/cm") (traceGeometry "cpwms") (traceLayerName "") (traceThickness "0.72 mil") (traceType "single") (traceWidth "5.0 mil") (traceWidth2 "5.0 mil") (traceWidth3 "5.0 mil") (traceWidth4 "5.0 mil") (traceWidth5 "5.0 mil") (traceWidth6 "5.0 mil") (offset "0 mil") (traceCount "1") (impedance nil))) (IbisOutput_OpenPullUp ((temperature "27") (bufferModel "CDSDefaultOutput_2p5v") (stimuli nil) (offsets nil) (state "tristate") (cycle "1") (termMap nil) (setup "2.0e-09") (hold "1.0e-09") (rise nil) (fall nil) (macroType nil) (voltage nil) (spice nil) (LEFDEFPinName nil) (LEFDEFPinType nil) (mappingTag nil))) (CPWMS ((d1Thickness "10 mil") (d1Constant "4.5") (d1LossTangent "0.035") (d2Thickness "0.72 mil") (d2Constant "4.5") (d2LossTangent "0.035") (d3Thickness "0.0") (d3Constant "1") (d3LossTangent "0") length("1000 mil") (spacing "5 mil") (spacing2 "5 mil") (spacing3 "5 mil") (spacing4 "5 mil") (spacing5 "5 mil") (traceConductivity "595900 mho/cm") (traceGeometry "cpwms") (traceLayerName "") (traceThickness "0.72 mil") (traceType "single") (traceWidth "5.0 mil") (traceWidth2 "5.0 mil") (traceWidth3 "5.0 mil") (traceWidth4 "5.0 mil") (traceWidth5 "5.0 mil") (traceWidth6 "5.0 mil") (offset "0 mil") (traceCount "1") (impedance nil))) (periodic ((periodicFreq "100e6") (periodicPattern "10") (periodicJitter "0"))) (IbisInputPkg ((temperature "27") (bufferModel "CDSDefaultInput_2p5v") (cycle "1") (LEFDEFPinName nil) (LEFDEFPinType nil) (mappingTag nil))) (IbisIOMacro ((temperature "27") (bufferModel "CDSDefaultIO_2p5v") (stimuli nil) (offsets nil) (state "tristate") (cycle "1") (termMap nil) (setup "2.0e-09") (hold "1.0e-09") (rise nil) (fall nil) (macroType nil) (voltage nil) (spice nil) (LEFDEFPinName nil) (LEFDEFPinType nil) (mappingTag nil))) (CurrentProbe nil) (IbisOutputPkg ((temperature "27") (bufferModel "CDSDefaultOutput_2p5v") (stimuli nil) (offsets nil) (state "tristate") (cycle "1") (termMap nil) (setup "2.0e-09") (hold "1.0e-09") (rise nil) (fall nil) (macroType nil) (voltage nil) (spice nil) (LEFDEFPinName nil) (LEFDEFPinType nil) (mappingTag nil))) (IbisIOPkg ((temperature "27") (bufferModel "CDSDefaultIO_2p5v") (stimuli nil) (offsets nil) (state "tristate") (cycle "1") (termMap nil) (setup "2.0e-09") (hold "1.0e-09") (rise nil) (fall nil) (macroType nil) (voltage nil) (spice nil) (LEFDEFPinName nil) (LEFDEFPinType nil) (mappingTag nil))) (SeriesTerm ((resistance "22 ohm") (maxDelay "0.1 ns"))) (Trace ((d1Thickness "10 mil") (d1Constant "4.5") (d1LossTangent "0.035") (d2Thickness "10 mil") (d2Constant "4.5") (d2LossTangent "0.035") (d3Thickness "0.0") (d3Constant "1.0") (d3LossTangent "0") length("1000 mil") (spacing "5 mil") (spacing2 "5 mil") (spacing3 "5 mil") (spacing4 "5 mil") (spacing5 "5 mil") (traceConductivity "595900 mho/cm") (traceGeometry "microstrip") (traceLayerName "") (traceThickness "0.72 mil") (traceType "single") (traceWidth "5.0 mil") (traceWidth2 "5.0 mil") (traceWidth3 "5.0 mil") (traceWidth4 "5.0 mil") (traceWidth5 "5.0 mil") (traceWidth6 "5.0 mil") (offset "0 mil") (traceCount "1") (impedance nil))) (async ((asyncTimePoints "") (asyncInitState "1"))) (Cable (length("1 m"))) (Via ((model "Unknown") (viaOutputFormat "Unknown") (viaPadstack nil) (viaTopLayer nil) (viaBottomLayer nil) (viaIsPower nil) (viaIsGround nil)))))
				)
				( objectStatus "RMII_TX_NEW" )
			)
			( electricalCSet "@crescent_city_bb_fab1_lib.crescent_city_bb_fab1(sch_1):\RMII_BMC_PCH_SPRNGVLLE_TXD0\"
				( pinPairRef "RMII_TX:U9F4.A10:U7C1.AL1" )
				( pinPairRef "RMII_TX:U9F4.A10:R1T28.1" )
				( attribute "TOPOLOGY_TEMPLATE_REVISION" "1.0"
					( Origin gBackEnd )
				)
				( topologyData 25412
(SKIDL (Circuits ("MAIN" (Parts ("CRESCENT_CITY_180_20141223_Q.@@U47.A10" IbisOutputPkg (xy (5498 4235)) (refDes "U9F4") (model "Unknown") (Props (_SXDesignName "CRESCENT_CITY_180_20141223_Q") (brdx "17587.29 MIL") (brdy "771.76 MIL") (bufferModel "CDSDefaultOutput_2p5v") (cycle "1") (hold "1.0e-09") (mappingTag "") (offsets ("4" "0")) (setup "2.0e-09") (state "tristate") (stimuli ("4" "local2")) (temperature "27") (termMap ("4" "Data"))) (Terms ("CRESCENT_CITY_180_20141223_Q.X1758729Y77176L2LRATS" "A10"))) ("CRESCENT_CITY_180_20141223_Q.@@U22.AL1" IbisIOPkg (xy (5566 4240)) (refDes "U7C1") (model "Unknown") (Props (_SXDesignName "CRESCENT_CITY_180_20141223_Q") (brdx "15275 MIL") (brdy "3682.87 MIL") (bufferModel "CDSDefaultIO_2p5v") (cycle "1") (hold "1.0e-09") (mappingTag "") (offsets ("4" "0") ("5" "0")) (setup "2.0e-09") (state "tristate") (stimuli ("5" "local4") ("4" "local3")) (temperature "27") (termMap ("4" "Data") ("5" "Enable"))) (Terms ("CRESCENT_CITY_180_20141223_Q.X1527500Y368287L2LRATS" "AL1"))) ("CRESCENT_CITY_180_20141223_Q.@@EU46.9" IbisInputPkg (xy (5550 4227)) (refDes "EU9E1") (model "Unknown") (Props (_SXDesignName "CRESCENT_CITY_180_20141223_Q") (brdx "19352 MIL") (brdy "1774.84 MIL") (bufferModel "CDSDefaultInput_2p5v") (mappingTag "") (temperature "27")) (Terms ("CRESCENT_CITY_180_20141223_Q.X1935200Y177484L2LRATS" "9"))) ("CRESCENT_CITY_180_20141223_Q.@@R3478.2.1" Resistor (xy (5521 4235)) (mirror x) (refDes "R1T28") (value "22 Ohm") (Props (_SXDesignName "CRESCENT_CITY_180_20141223_Q")) (Terms ("CRESCENT_CITY_180_20141223_Q.X1943000Y180000L2LRATS" "2") ("CRESCENT_CITY_180_20141223_Q.X1946500Y180000L2LRATS" "1"))) ("CRESCENT_CITY_180_20141223_Q.@@R3439.2.1" Resistor (xy (5497 4228)) (mirror x) (refDes "R1R4") (value "10000 Ohm") (Props (_SXDesignName "CRESCENT_CITY_180_20141223_Q")) (Terms ("CRESCENT_CITY_180_20141223_Q.X1946500Y180000L28LRATS" "2") ("CRESCENT_CITY_180_20141223_Q.X1943000Y180000L28RATS" "1"))) ("CRESCENT_CITY_180_20141223_Q.@@R3439.1_SOURCE" Source (xy (5484 4228)) (refDes "P3V3_STBY") (value "3.3 V") (Props (_SXDesignName "CRESCENT_CITY_180_20141223_Q")) (Terms ("CRESCENT_CITY_180_20141223_Q.X1943000Y180000L28RATS" "1"))) ("CRESCENT_CITY_180_20141223_Q.T@@RATS@@U22.AL1@@EU46.9" TLine (xy (5551 4235)) (mirror x) (refDes "TL5") (Props (_SXDesignName "CRESCENT_CITY_180_20141223_Q") (impedance "60 ohm") length("5985.04 MIL") (propDelay "1.07495 ns") (traceCount "1") (traceGeometry "Microstrip") (velocity "5567.72 mil/ns")) (Terms ("CRESCENT_CITY_180_20141223_Q.X1527500Y368287L2LRATS" "1") ("CRESCENT_CITY_180_20141223_Q.X1935200Y177484L2LRATS" "2"))) ("CRESCENT_CITY_180_20141223_Q.T@@RATS@@R3478.1@@R3439.2" TLine (xy (5512 4228)) (mirror x) (refDes "TL6") (Props (_SXDesignName "CRESCENT_CITY_180_20141223_Q") (impedance "48.412 ohm") (propDelay "1.79607e-006 ns") (traceCount "1") (traceGeometry "Microstrip")) (Terms ("CRESCENT_CITY_180_20141223_Q.X1946500Y180000L2LRATS" "1") ("CRESCENT_CITY_180_20141223_Q.X1946500Y180000L28LRATS" "2"))) ("CRESCENT_CITY_180_20141223_Q.T@@RATS@@R3478.1@@U47.A10" TLine (xy (5506 4235)) (mirror x) (refDes "TL7") (Props (_SXDesignName "CRESCENT_CITY_180_20141223_Q") (impedance "49.728 ohm") length("2905.95 MIL") (propDelay "0.52193 ns") (traceCount "1") (traceGeometry "Microstrip") (velocity "5567.72 mil/ns")) (Terms ("CRESCENT_CITY_180_20141223_Q.X1946500Y180000L2LRATS" "1") ("CRESCENT_CITY_180_20141223_Q.X1758729Y77176L2LRATS" "2"))) ("CRESCENT_CITY_180_20141223_Q.T@@RATS@@EU46.9@@R3478.2" TLine (xy (5536 4235)) (mirror x) (refDes "TL8") (Props (_SXDesignName "CRESCENT_CITY_180_20141223_Q") (impedance "48.412 ohm") length("103.16 MIL") (propDelay "0.01853 ns") (traceCount "1") (traceGeometry "Microstrip") (velocity "5567.2 mil/ns")) (Terms ("CRESCENT_CITY_180_20141223_Q.X1935200Y177484L2LRATS" "1") ("CRESCENT_CITY_180_20141223_Q.X1943000Y180000L2LRATS" "2")))) (Nodes ("CRESCENT_CITY_180_20141223_Q.X1527500Y368287L2LRATS" (terms "CRESCENT_CITY_180_20141223_Q.T@@RATS@@U22.AL1@@EU46.9.1" "CRESCENT_CITY_180_20141223_Q.@@U22.AL1.1")) ("CRESCENT_CITY_180_20141223_Q.X1946500Y180000L2LRATS" (terms "CRESCENT_CITY_180_20141223_Q.T@@RATS@@R3478.1@@U47.A10.1" "CRESCENT_CITY_180_20141223_Q.T@@RATS@@R3478.1@@R3439.2.1" "CRESCENT_CITY_180_20141223_Q.@@R3478.2.1.2")) ("CRESCENT_CITY_180_20141223_Q.X1946500Y180000L28LRATS" (terms "CRESCENT_CITY_180_20141223_Q.T@@RATS@@R3478.1@@R3439.2.2" "CRESCENT_CITY_180_20141223_Q.@@R3439.2.1.1")) ("CRESCENT_CITY_180_20141223_Q.X1935200Y177484L2LRATS" (terms "CRESCENT_CITY_180_20141223_Q.T@@RATS@@EU46.9@@R3478.2.1" "CRESCENT_CITY_180_20141223_Q.T@@RATS@@U22.AL1@@EU46.9.2" "CRESCENT_CITY_180_20141223_Q.@@EU46.9.1")) ("CRESCENT_CITY_180_20141223_Q.X1943000Y180000L2LRATS" (terms "CRESCENT_CITY_180_20141223_Q.T@@RATS@@EU46.9@@R3478.2.2" "CRESCENT_CITY_180_20141223_Q.@@R3478.2.1.1")) ("CRESCENT_CITY_180_20141223_Q.X1943000Y180000L28RATS" (terms "CRESCENT_CITY_180_20141223_Q.@@R3439.1_SOURCE.1" "CRESCENT_CITY_180_20141223_Q.@@R3439.2.1.2")) ("CRESCENT_CITY_180_20141223_Q.X1758729Y77176L2LRATS" (terms "CRESCENT_CITY_180_20141223_Q.T@@RATS@@R3478.1@@U47.A10.2" "CRESCENT_CITY_180_20141223_Q.@@U47.A10.1"))) (Ports) (Stimuli ("local2" (scope local) (stimType periodic) (Props (periodicFreq "5e+007") (periodicJitter "0") (periodicPattern "1"))) ("local3" (scope local) (stimType periodic) (Props (periodicFreq "5e+007") (periodicJitter "0") (periodicPattern "1"))) ("local4" (scope local) (stimType periodic) (Props (periodicFreq "5e+007") (periodicJitter "0") (periodicPattern "1")))) (Notes) (Constraints ("DELAY_RULE" ("CRESCENT_CITY_180_20141223_Q U47.A10" "CRESCENT_CITY_180_20141223_Q U22.AL1" "LENGTH" "0.2032" "LENGTH" "0.3556") ("CRESCENT_CITY_180_20141223_Q U47.A10" "CRESCENT_CITY_180_20141223_Q R3478.1" "LENGTH" "" "LENGTH" "0.0127"))) (MeasurementSets ("EMI" ("EMIStatus" status("on")) ("PeakEmission" status("on")) ("PeakFrequency" status("on")) ("PulseFreq" status("on")) ("RiseTime" status("on")) ("VoltageSwing" status("on"))) ("Reflection" ("BufferDelayFall" status("off")) ("BufferDelayRise" status("off")) ("EyeHeight" status("off")) ("EyeJitter" status("off")) ("EyeWidth" status("off")) ("FirstIncidentFall" status("off")) ("FirstIncidentRise" status("off")) ("Glitch" status("on")) ("GlitchFall" status("off")) ("GlitchRise" status("off")) ("Monotonic" status("on")) ("MonotonicFall" status("off")) ("MonotonicRise" status("off")) ("NoiseMargin" status("on")) ("NoiseMarginHigh" status("off")) ("NoiseMarginLow" status("off")) ("OvershootHigh" status("on")) ("OvershootLow" status("on")) ("PropDelay" status("on")) ("SettleDelay" status("on")) ("SettleDelayFall" status("off")) ("SettleDelayRise" status("off")) ("SwitchDelay" status("on")) ("SwitchDelayFall" status("off")) ("SwitchDelayRise" status("off"))) ("Crosstalk" ("Crosstalk" status("on"))) ("Custom")) (VectorSets) (Props (XnetName "RMII_BMC_PCH_SPRNGVLLE_TXD0") (allDrivers "active") (customSimType "Reflection") (ftsMode ("Typ")) (rcvrSelect "all") (tlineDelayMode "time") (userRevision "1.0")))) (Subckts) (CrossSections ("CRESCENT_CITY_180_20141223_Q" (Props (SXDesignName "CRESCENT_CITY_180_20141223_Q")) (Layers ("" (layerType "SURFACE") (material "AIR") (thickness "0 mil") (dielectricConstant "1.000000") (lossTangent "0") (etchFactor "0.000000") (elecCondVal "0 mho/cm") (thermCondVal "0 w/cm-degC")) ("" (layerType "DIELECTRIC") (material "CONFORMAL_COAT") (thickness "0.5 mil") (dielectricConstant "3.800000") (lossTangent "0.035") (etchFactor "0.000000") (elecCondVal "0 mho/cm") (thermCondVal "0.012 w/cm-degC")) ("TOP" (layerType "CONDUCTOR") (material "COPPER") (thickness "  2.100000 mil") (width "4.00 MIL") (dielectricConstant "4.500000") (lossTangent "0") (etchFactor "70.000000") (elecCondVal "595900.000000 mho/cm") (thermCondVal "0 w/cm-degC") (signalDieConstant "3.800000") (signalLossTangent "0.035")) ("" (layerType "DIELECTRIC") (material "FR-4") (thickness "  2.670000 mil") (dielectricConstant "4.000000") (lossTangent "0.035") (etchFactor "0.000000") (elecCondVal "0 mho/cm") (thermCondVal "0.012 w/cm-degC")) ("L2_GND1" (layerType "PLANE") (material "COPPER") (isShield t) (thickness "  1.250000 mil") (dielectricConstant "4.500000") (lossTangent "0.035") (etchFactor "90.000000") (elecCondVal "595900.000000 mho/cm") (thermCondVal "0.012 w/cm-degC")) ("" (layerType "DIELECTRIC") (material "FR-4") (thickness "  9.000000 mil") (dielectricConstant "4.100000") (lossTangent "0.035") (etchFactor "0.000000") (elecCondVal "0 mho/cm") (thermCondVal "0.012 w/cm-degC")) ("L3_SIG1" (layerType "CONDUCTOR") (material "COPPER") (thickness "  1.250000 mil") (width "4.00 MIL") (dielectricConstant "4.500000") (lossTangent "0.035") (etchFactor "90.000000") (elecCondVal "595900.000000 mho/cm") (thermCondVal "0.012 w/cm-degC") (signalDieConstant "4.100000") (signalLossTangent "0.035")) ("" (layerType "DIELECTRIC") (material "FR-4") (thickness "  3.000000 mil") (dielectricConstant "4.500000") (lossTangent "0.035") (etchFactor "0.000000") (elecCondVal "0 mho/cm") (thermCondVal "0 w/cm-degC")) ("L4_GND2" (layerType "PLANE") (material "COPPER") (isShield t) (thickness "  1.250000 mil") (dielectricConstant "4.500000") (lossTangent "0.035") (etchFactor "90.000000") (elecCondVal "595900.000000 mho/cm") (thermCondVal "0 w/cm-degC")) ("" (layerType "DIELECTRIC") (material "FR-4") (thickness "  9.000000 mil") (dielectricConstant "4.000000") (lossTangent "0.035") (etchFactor "0.000000") (elecCondVal "0 mho/cm") (thermCondVal "0.012 w/cm-degC")) ("L5_SIG2" (layerType "CONDUCTOR") (material "COPPER") (thickness "  1.250000 mil") (width "4.00 MIL") (dielectricConstant "4.500000") (lossTangent "0.035") (etchFactor "90.000000") (elecCondVal "595900.000000 mho/cm") (thermCondVal "0.012 w/cm-degC") (signalDieConstant "4.000000") (signalLossTangent "0.035")) ("" (layerType "DIELECTRIC") (material "FR-4") (thickness "  3.000000 mil") (dielectricConstant "4.500000") (lossTangent "0.035") (etchFactor "0.000000") (elecCondVal "0 mho/cm") (thermCondVal "0 w/cm-degC")) ("L6_GND3" (layerType "PLANE") (material "COPPER") (isShield t) (thickness "  1.250000 mil") (dielectricConstant "4.500000") (lossTangent "0.035") (etchFactor "90.000000") (elecCondVal "595900.000000 mho/cm") (thermCondVal "0 w/cm-degC")) ("" (layerType "DIELECTRIC") (material "FR-4") (thickness "  4.500000 mil") (dielectricConstant "4.100000") (lossTangent "0.035") (etchFactor "0.000000") (elecCondVal "0 mho/cm") (thermCondVal "0.012 w/cm-degC")) ("L7_PWR1-SIG" (layerType "PLANE") (material "COPPER") (isShield t) (thickness "  2.400000 mil") (dielectricConstant "4.500000") (lossTangent "0.035") (etchFactor "90.000000") (elecCondVal "595900.000000 mho/cm") (thermCondVal "0.012 w/cm-degC")) ("" (layerType "DIELECTRIC") (material "FR-4") (thickness "  4.600000 mil") (dielectricConstant "4.000000") (lossTangent "0.035") (etchFactor "0.000000") (elecCondVal "0 mho/cm") (thermCondVal "0.012 w/cm-degC")) ("L8_PWR2-SIG" (layerType "PLANE") (material "COPPER") (isShield t) (thickness "  2.400000 mil") (dielectricConstant "4.500000") (lossTangent "0.035") (etchFactor "90.000000") (elecCondVal "595900.000000 mho/cm") (thermCondVal "0.012 w/cm-degC")) ("" (layerType "DIELECTRIC") (material "FR-4") (thickness "  4.500000 mil") (dielectricConstant "4.500000") (lossTangent "0.035") (etchFactor "0.000000") (elecCondVal "0 mho/cm") (thermCondVal "0 w/cm-degC")) ("L9_GND4" (layerType "PLANE") (material "COPPER") (isShield t) (thickness "  1.250000 mil") (dielectricConstant "4.500000") (lossTangent "0.035") (etchFactor "90.000000") (elecCondVal "595900.000000 mho/cm") (thermCondVal "0 w/cm-degC")) ("" (layerType "DIELECTRIC") (material "FR-4") (thickness "  3.000000 mil") (dielectricConstant "4.100000") (lossTangent "0.035") (etchFactor "0.000000") (elecCondVal "0 mho/cm") (thermCondVal "0.012 w/cm-degC")) ("L10_SIG3" (layerType "CONDUCTOR") (material "COPPER") (thickness "  1.250000 mil") (width "4.00 MIL") (dielectricConstant "4.500000") (lossTangent "0.035") (etchFactor "90.000000") (elecCondVal "595900.000000 mho/cm") (thermCondVal "0.012 w/cm-degC") (signalDieConstant "4.100000") (signalLossTangent "0.035")) ("" (layerType "DIELECTRIC") (material "FR-4") (thickness "  9.000000 mil") (dielectricConstant "4.500000") (lossTangent "0.035") (etchFactor "0.000000") (elecCondVal "0 mho/cm") (thermCondVal "0 w/cm-degC")) ("L11_GND5" (layerType "PLANE") (material "COPPER") (isShield t) (thickness "  1.250000 mil") (dielectricConstant "4.500000") (lossTangent "0.035") (etchFactor "90.000000") (elecCondVal "595900.000000 mho/cm") (thermCondVal "0 w/cm-degC")) ("" (layerType "DIELECTRIC") (material "FR-4") (thickness "  3.000000 mil") (dielectricConstant "4.500000") (lossTangent "0.035") (etchFactor "0.000000") (elecCondVal "0 mho/cm") (thermCondVal "0.012 w/cm-degC")) ("L12_SIG4" (layerType "CONDUCTOR") (material "COPPER") (thickness "  1.250000 mil") (width "4.00 MIL") (dielectricConstant "4.500000") (lossTangent "0.035") (etchFactor "90.000000") (elecCondVal "595900.000000 mho/cm") (thermCondVal "0.012 w/cm-degC") (signalDieConstant "4.500000") (signalLossTangent "0.035")) ("" (layerType "DIELECTRIC") (material "FR-4") (thickness "  9.000000 mil") (dielectricConstant "4.500000") (lossTangent "0.035") (etchFactor "0.000000") (elecCondVal "0 mho/cm") (thermCondVal "0 w/cm-degC")) ("L13_GND6" (layerType "PLANE") (material "COPPER") (isShield t) (thickness "  1.250000 mil") (dielectricConstant "4.500000") (lossTangent "0.035") (etchFactor "90.000000") (elecCondVal "595900.000000 mho/cm") (thermCondVal "0.012 w/cm-degC")) ("" (layerType "DIELECTRIC") (material "FR-4") (thickness "  2.670000 mil") (dielectricConstant "4.500000") (lossTangent "0.035") (etchFactor "0.000000") (elecCondVal "0 mho/cm") (thermCondVal "0.012 w/cm-degC")) ("BOTTOM" (layerType "CONDUCTOR") (material "COPPER") (thickness "  2.100000 mil") (width "4.00 MIL") (dielectricConstant "4.500000") (lossTangent "0") (etchFactor "70.000000") (elecCondVal "595900.000000 mho/cm") (thermCondVal "0 w/cm-degC") (signalDieConstant "3.800000") (signalLossTangent "0.035")) ("" (layerType "DIELECTRIC") (material "CONFORMAL_COAT") (thickness "0.5 mil") (dielectricConstant "3.800000") (lossTangent "0.035") (etchFactor "0.000000") (elecCondVal "0 mho/cm") (thermCondVal "0.012 w/cm-degC")) ("" (layerType "SURFACE") (material "AIR") (thickness "0 mil") (dielectricConstant "1.000000") (lossTangent "0") (etchFactor "0.000000") (elecCondVal "0 mho/cm") (thermCondVal "0 w/cm-degC"))))) (Props (DesUnits "mils 2") (LayerStack ("DIELECTRIC" "DIELECTRIC" "BOTTOM" "DIELECTRIC" "L13_GND6" "DIELECTRIC" "L12_SIG4" "DIELECTRIC" "L11_GND5" "DIELECTRIC" "L10_SIG3" "DIELECTRIC" "L9_GND4" "DIELECTRIC" "L8_PWR2-SIG" "DIELECTRIC" "L7_PWR1-SIG" "DIELECTRIC" "L6_GND3" "DIELECTRIC" "L5_SIG2" "DIELECTRIC" "L4_GND2" "DIELECTRIC" "L3_SIG1" "DIELECTRIC" "L2_GND1" "DIELECTRIC" "TOP" "DIELECTRIC" "DIELECTRIC")) (Revision "16.600")) (Params (IbisIOPkg ((temperature "27") (bufferModel "CDSDefaultIO_2p5v") (stimuli nil) (offsets nil) (state "tristate") (cycle "1") (termMap nil) (setup "2.0e-09") (hold "1.0e-09") (rise nil) (fall nil) (macroType nil) (voltage nil) (spice nil) (LEFDEFPinName nil) (LEFDEFPinType nil) (mappingTag nil))) (IbisIOMacro ((temperature "27") (bufferModel "CDSDefaultIO_2p5v") (stimuli nil) (offsets nil) (state "tristate") (cycle "1") (termMap nil) (setup "2.0e-09") (hold "1.0e-09") (rise nil) (fall nil) (macroType nil) (voltage nil) (spice nil) (LEFDEFPinName nil) (LEFDEFPinType nil) (mappingTag nil))) (IbisInputPkg ((temperature "27") (bufferModel "CDSDefaultInput_2p5v") (cycle "1") (LEFDEFPinName nil) (LEFDEFPinType nil) (mappingTag nil))) (IbisOutputPkg ((temperature "27") (bufferModel "CDSDefaultOutput_2p5v") (stimuli nil) (offsets nil) (state "tristate") (cycle "1") (termMap nil) (setup "2.0e-09") (hold "1.0e-09") (rise nil) (fall nil) (macroType nil) (voltage nil) (spice nil) (LEFDEFPinName nil) (LEFDEFPinType nil) (mappingTag nil))) (periodic ((periodicFreq "100e6") (periodicPattern "10") (periodicJitter "0"))) (IbisIO_OpenPullUp ((temperature "27") (bufferModel "CDSDefaultIO_2p5v") (stimuli nil) (offsets nil) (state "tristate") (cycle "1") (termMap nil) (setup "2.0e-09") (hold "1.0e-09") (rise nil) (fall nil) (macroType nil) (voltage nil) (spice nil) (LEFDEFPinName nil) (LEFDEFPinType nil) (mappingTag nil))) (clocked ((clockRise "1e-09") (clockFall "1e-09") (clockFreq "100e6") (clockInitState "0") (clockDutyCycle "0.5") (clockJitter "0"))) (IbisIO ((temperature "27") (bufferModel "CDSDefaultIO_2p5v") (stimuli nil) (offsets nil) (state "tristate") (cycle "1") (termMap nil) (setup "2.0e-09") (hold "1.0e-09") (rise nil) (fall nil) (macroType nil) (voltage nil) (spice nil) (LEFDEFPinName nil) (LEFDEFPinType nil) (mappingTag nil))) (IbisIO_OpenPullDown ((temperature "27") (bufferModel "CDSDefaultIO_2p5v") (stimuli nil) (offsets nil) (state "tristate") (cycle "1") (termMap nil) (setup "2.0e-09") (hold "1.0e-09") (rise nil) (fall nil) (macroType nil) (voltage nil) (spice nil) (LEFDEFPinName nil) (LEFDEFPinType nil) (mappingTag nil))) (IbisOutput ((temperature "27") (bufferModel "CDSDefaultOutput_2p5v") (stimuli nil) (offsets nil) (state "tristate") (cycle "1") (termMap nil) (setup "2.0e-09") (hold "1.0e-09") (rise nil) (fall nil) (macroType nil) (voltage nil) (spice nil) (LEFDEFPinName nil) (LEFDEFPinType nil) (mappingTag nil))) (async ((asyncTimePoints "") (asyncInitState "1"))) (TLine ((diffImpedance "100ohm") (diffVelocity "1.4142e+08M/s") (impedance "60ohm") length("2800 mil") (propDelay "0.5 ns") (velocity "5600 mil/ns") (traceCount "1") (traceGeometry "Microstrip") (impedanceMin nil) (impedanceMax nil) (lengthMin nil) (lengthMax nil) (propDelayMin nil) (propDelayMax nil) (impedanceSweepCount nil) (propDelaySweepCount nil) (velocitySweepCount nil) (lengthSweepCount nil) (matchSetName nil))) (IbisInput ((temperature "27") (bufferModel "CDSDefaultInput_2p5v") (cycle "1") (LEFDEFPinName nil) (LEFDEFPinType nil) (mappingTag nil))) (SeriesTerm ((resistance "22 ohm") (maxDelay "0.1 ns"))) (Connector nil) (CurrentProbe nil) (IbisOutput_OpenPullUp ((temperature "27") (bufferModel "CDSDefaultOutput_2p5v") (stimuli nil) (offsets nil) (state "tristate") (cycle "1") (termMap nil) (setup "2.0e-09") (hold "1.0e-09") (rise nil) (fall nil) (macroType nil) (voltage nil) (spice nil) (LEFDEFPinName nil) (LEFDEFPinType nil) (mappingTag nil))) (sync ((syncFreq "100e6") (syncInitState "1") (syncPattern "10") (syncEdgeSwitch "rise"))) (DiffInputPkg ((temperature "27") (bufferModelNonInverting "CDSDefaultInput_2p5v") (bufferModelInverting "CDSDefaultInput_2p5v") (threshInputHighMin "1.7 V") (threshInputHighTyp "1.7  V") (threshInputHighMax "1.7  V") (threshInputLowMin "0.7  V") (threshInputLowTyp "0.7  V") (threshInputLowMax "0.7  V") (mappingTagNonInverting nil) (mappingTagInverting nil) (cycle "1"))) (idlCircuit ((allDrivers "active") (ftsMode '("Typ")) (rcvrSelect "all") (simMode "Reflection") (tlineDelayMode "time") (userRevision "1.0") (autoSolve "On"))) (Trace ((d1Thickness "10 mil") (d1Constant "4.5") (d1LossTangent "0.035") (d2Thickness "10 mil") (d2Constant "4.5") (d2LossTangent "0.035") (d3Thickness "0.0") (d3Constant "1.0") (d3LossTangent "0") length("1000 mil") (spacing "5 mil") (spacing2 "5 mil") (spacing3 "5 mil") (spacing4 "5 mil") (spacing5 "5 mil") (traceConductivity "595900 mho/cm") (traceGeometry "microstrip") (traceLayerName "") (traceThickness "0.72 mil") (traceType "single") (traceWidth "5.0 mil") (traceWidth2 "5.0 mil") (traceWidth3 "5.0 mil") (traceWidth4 "5.0 mil") (traceWidth5 "5.0 mil") (traceWidth6 "5.0 mil") (offset "0 mil") (traceCount "1") (impedance nil))) (DiffOutput ((temperature "27") (bufferModelNonInverting "CDSDefaultOutput_2p5v") (bufferModelInverting "CDSDefaultOutput_2p5v") (stimuli nil) (offsets nil) (state "tristate") (cycle "1") (termMap nil) (setup "0.9e-09") (hold "0.4e-09") (rise nil) (fall nil) (threshOutputHighMin "2.375  V") (threshOutputHighTyp "2.5  V") (threshOutputHighMax "2.625  V") (threshOutputLowMin "1.275  V") (threshOutputLowTyp "1.7  V") (threshOutputLowMax "1.985  V") (mappingTagNonInverting nil) (mappingTagInverting nil) (spice nil))) (HiClampTerm ((cutoffVoltage "0.7 V") (voltage "5 V") (maxDelay "0.1 ns"))) (Via ((model "Unknown") (viaOutputFormat "Unknown") (viaPadstack nil) (viaTopLayer nil) (viaBottomLayer nil) (viaIsPower nil) (viaIsGround nil))) (Resistor ((resistance "50 ohm") (orientation "0"))) (LowClampTerm ((cutoffVoltage "0.7 V") (voltage "0 V") (maxDelay "0.1 ns"))) (DiffOutputPkg ((temperature "27") (bufferModelNonInverting "CDSDefaultOutput_2p5v") (bufferModelInverting "CDSDefaultOutput_2p5v") (stimuli nil) (offsets nil) (state "tristate") (cycle "1") (termMap nil) (setup "0.9e-09") (hold "0.4e-09") (rise nil) (fall nil) (threshOutputHighMin "2.375  V") (threshOutputHighTyp "2.5  V") (threshOutputHighMax "2.625  V") (threshOutputLowMin "1.275  V") (threshOutputLowTyp "1.7  V") (threshOutputLowMax "1.985  V") (mappingTagNonInverting nil) (mappingTagInverting nil) (spice nil))) (RCTerm ((resistance "50 ohm") (capacitance "20 pF") (voltage "5 V") (maxDelay "0.1 ns"))) (DiffIO ((temperature "27") (bufferModelNonInverting "CDSDefaultIO_2p5v") (bufferModelInverting "CDSDefaultIO_2p5v") (stimuli nil) (offsets nil) (state "tristate") (cycle "1") (termMap nil) (setup "0.9e-09") (hold "0.4e-09") (rise nil) (fall nil) (threshInputHighMin "1.7 V") (threshInputHighTyp "1.7  V") (threshInputHighMax "1.7  V") (threshInputLowMin "0.7  V") (threshInputLowTyp "0.7  V") (threshInputLowMax "0.7 ") (threshOutputHighMin "2.365  V") (threshOutputHighTyp "2.5  V") (threshOutputHighMax "2.625  V") (threshOutputLowMin "1.275  V") (threshOutputLowTyp "1.7  V") (threshOutputLowMax "1.985  V") (mappingTagNonInverting nil) (mappingTagInverting nil) (spice nil))) (TheveninTerm ((resistanceUp "180 ohm") (resistanceDown "270 ohm") (voltageUp "5 V") (voltageDown "0 V") (maxDelay "0.1 ns"))) (DiffIOPkg ((temperature "27") (bufferModelNonInverting "CDSDefaultIO_2p5v") (bufferModelInverting "CDSDefaultIO_2p5v") (stimuli nil) (offsets nil) (state "tristate") (cycle "1") (termMap nil) (setup "0.9e-09") (hold "0.4e-09") (rise nil) (fall nil) (threshInputHighMin "1.7 V") (threshInputHighTyp "1.7  V") (threshInputHighMax "1.7  V") (threshInputLowMin "0.7  V") (threshInputLowTyp "0.7  V") (threshInputLowMax "0.7 ") (threshOutputHighMin "2.365  V") (threshOutputHighTyp "2.5  V") (threshOutputHighMax "2.625  V") (threshOutputLowMin "1.275  V") (threshOutputLowTyp "1.7  V") (threshOutputLowMax "1.985  V") (mappingTagNonInverting nil) (mappingTagInverting nil) (spice nil))) (Source ((voltage "5 V"))) (ShuntTerm ((resistance "50 ohm") (voltage "5 V") (maxDelay "0.1 ns"))) (RLGC (length("1000 mil"))) (Capacitor ((capacitance "10 pF") (orientation "0"))) (DiffInput ((temperature "27") (bufferModelNonInverting "CDSDefaultInput_2p5v") (bufferModelInverting "CDSDefaultInput_2p5v") (threshInputHighMin "1.7 V") (threshInputHighTyp "1.7  V") (threshInputHighMax "1.7  V") (threshInputLowMin "0.7  V") (threshInputLowTyp "0.7  V") (threshInputLowMax "0.7  V") (mappingTagNonInverting nil) (mappingTagInverting nil) (cycle "1"))) (Inductor ((inductance "5 nH") (orientation "0"))) (Cable (length("1 m"))) (CPWSL ((d1Thickness "10 mil") (d1Constant "4.5") (d1LossTangent "0.035") (d2Thickness "0.72 mil") (d2Constant "4.5") (d2LossTangent "0.035") (d3Thickness "10 mil") (d3Constant "4.5") (d3LossTangent "0.035") length("1000 mil") (spacing "5 mil") (spacing2 "5 mil") (spacing3 "5 mil") (spacing4 "5 mil") (spacing5 "5 mil") (traceConductivity "595900 mho/cm") (traceGeometry "cpwms") (traceLayerName "") (traceThickness "0.72 mil") (traceType "single") (traceWidth "5.0 mil") (traceWidth2 "5.0 mil") (traceWidth3 "5.0 mil") (traceWidth4 "5.0 mil") (traceWidth5 "5.0 mil") (traceWidth6 "5.0 mil") (offset "0 mil") (traceCount "1") (impedance nil))) (CPWMS ((d1Thickness "10 mil") (d1Constant "4.5") (d1LossTangent "0.035") (d2Thickness "0.72 mil") (d2Constant "4.5") (d2LossTangent "0.035") (d3Thickness "0.0") (d3Constant "1") (d3LossTangent "0") length("1000 mil") (spacing "5 mil") (spacing2 "5 mil") (spacing3 "5 mil") (spacing4 "5 mil") (spacing5 "5 mil") (traceConductivity "595900 mho/cm") (traceGeometry "cpwms") (traceLayerName "") (traceThickness "0.72 mil") (traceType "single") (traceWidth "5.0 mil") (traceWidth2 "5.0 mil") (traceWidth3 "5.0 mil") (traceWidth4 "5.0 mil") (traceWidth5 "5.0 mil") (traceWidth6 "5.0 mil") (offset "0 mil") (traceCount "1") (impedance nil))) (Diode ((cutoffVoltage "0.7 V"))) (CPW ((d1Thickness "10 mil") (d1Constant "4.5") (d1LossTangent "0.035") (d2Thickness "0.72 mil") (d2Constant "1") (d2LossTangent "0") (d3Thickness "0.0") (d3Constant "1") (d3LossTangent "0") length("1000 mil") (spacing "5 mil") (spacing2 "5 mil") (spacing3 "5 mil") (spacing4 "5 mil") (spacing5 "5 mil") (traceConductivity "595900 mho/cm") (traceGeometry "cpwms") (traceLayerName "") (traceThickness "0.72 mil") (traceType "single") (traceWidth "5.0 mil") (traceWidth2 "5.0 mil") (traceWidth3 "5.0 mil") (traceWidth4 "5.0 mil") (traceWidth5 "5.0 mil") (traceWidth6 "5.0 mil") (offset "0 mil") (traceCount "1") (impedance nil))) (DualClampTerm ((cutoffVoltageUp "0.7 V") (cutoffVoltageDown "0.7 V") (voltageUp "5 V") (voltageDown "0 V") (maxDelay "0.1 ns"))) (ESpiceDevice nil)))
				)
				( objectStatus "RMII_TX" )
			)
			( electricalCSet "@crescent_city_bb_fab1_lib.crescent_city_bb_fab1(sch_1):\RMII_RX\"
				( pinPairRef "RMII_RX:U9F4.A9:U7C1.AM2" )
				( attribute "TOPOLOGY_TEMPLATE_REVISION" "1.0"
					( Origin gBackEnd )
				)
				( topologyData 25276
(SKIDL (Circuits ("MAIN" (Parts ("CRESCENT_CITY_180_20141223_Q.@@U22.AM2" IbisIOPkg (xy (5548 4240)) (refDes "U7C1") (model "Unknown") (Props (_SXDesignName "CRESCENT_CITY_180_20141223_Q") (brdx "15294.69 MIL") (brdy "3699.21 MIL") (bufferModel "CDSDefaultIO_2p5v") (cycle "1") (hold "1.0e-09") (mappingTag "") (offsets ("4" "0") ("5" "0")) (setup "2.0e-09") (state "tristate") (stimuli ("4" "local14") ("5" "local15")) (temperature "27") (termMap ("4" "Data") ("5" "Enable"))) (Terms ("CRESCENT_CITY_180_20141223_Q.X1529469Y369921L2LRATS" "AM2"))) ("CRESCENT_CITY_180_20141223_Q.@@EU46.6" IbisOutputPkg (xy (5498 4235)) (refDes "EU9E1") (model "Unknown") (Props (_SXDesignName "CRESCENT_CITY_180_20141223_Q") (brdx "19352 MIL") (brdy "1715.79 MIL") (bufferModel "CDSDefaultOutput_2p5v") (cycle "1") (hold "1.0e-09") (mappingTag "") (offsets ("4" "0")) (setup "2.0e-09") (state "tristate") (stimuli ("4" "local16")) (temperature "27") (termMap ("4" "Data"))) (Terms ("CRESCENT_CITY_180_20141223_Q.X1935200Y171579L2LRATS" "6"))) ("CRESCENT_CITY_180_20141223_Q.@@U47.A9" IbisInputPkg (xy (5538 4227)) (refDes "U9F4") (model "Unknown") (Props (_SXDesignName "CRESCENT_CITY_180_20141223_Q") (brdx "17587.29 MIL") (brdy "740.26 MIL") (bufferModel "CDSDefaultInput_2p5v") (mappingTag "") (temperature "27")) (Terms ("CRESCENT_CITY_180_20141223_Q.X1758729Y74026L2LRATS" "A9"))) ("CRESCENT_CITY_180_20141223_Q.T@@RATS@@U47.A9@@U22.AM2" TLine (xy (5539 4235)) (refDes "TL15") (Props (_SXDesignName "CRESCENT_CITY_180_20141223_Q") (impedance "60 ohm") length("5251.57 MIL") (propDelay "0.943214 ns") (traceCount "1") (traceGeometry "Microstrip") (velocity "5567.76 mil/ns")) (Terms ("CRESCENT_CITY_180_20141223_Q.X1758729Y74026L2LRATS" "1") ("CRESCENT_CITY_180_20141223_Q.X1529469Y369921L2LRATS" "2"))) ("CRESCENT_CITY_180_20141223_Q.T@@RATS@@R3476.1@@EU46.6" TLine (xy (5506 4235)) (mirror x) (refDes "TL16") (Props (_SXDesignName "CRESCENT_CITY_180_20141223_Q") (impedance "48.412 ohm") length("82.21 MIL") (propDelay "0.01477 ns") (traceCount "1") (traceGeometry "Microstrip") (velocity "5566.02 mil/ns")) (Terms ("CRESCENT_CITY_180_20141223_Q.X1943000Y172000L2LRATS" "1") ("CRESCENT_CITY_180_20141223_Q.X1935200Y171579L2LRATS" "2"))) ("CRESCENT_CITY_180_20141223_Q.T@@RATS@@R3476.2@@U47.A9" TLine (xy (5530 4235)) (refDes "TL17") (Props (_SXDesignName "CRESCENT_CITY_180_20141223_Q") (impedance "49.728 ohm") length("2857.45 MIL") (propDelay "0.51322 ns") (traceCount "1") (traceGeometry "Microstrip") (velocity "5567.68 mil/ns")) (Terms ("CRESCENT_CITY_180_20141223_Q.X1946500Y172000L2LRATS" "1") ("CRESCENT_CITY_180_20141223_Q.X1758729Y74026L2LRATS" "2"))) ("CRESCENT_CITY_180_20141223_Q.T@@RATS@@R3476.2@@R3437.2" TLine (xy (5527 4228)) (mirror x) (refDes "TL18") (Props (_SXDesignName "CRESCENT_CITY_180_20141223_Q") (impedance "48.412 ohm") (propDelay "1.79607e-006 ns") (traceCount "1") (traceGeometry "Microstrip")) (Terms ("CRESCENT_CITY_180_20141223_Q.X1946500Y172000L2LRATS" "1") ("CRESCENT_CITY_180_20141223_Q.X1946500Y172000L28LRATS" "2"))) ("CRESCENT_CITY_180_20141223_Q.@@R3476.1.2" Resistor (xy (5521 4235)) (refDes "R9E17") (value "22 Ohm") (Props (_SXDesignName "CRESCENT_CITY_180_20141223_Q")) (Terms ("CRESCENT_CITY_180_20141223_Q.X1943000Y172000L2LRATS" "1") ("CRESCENT_CITY_180_20141223_Q.X1946500Y172000L2LRATS" "2"))) ("CRESCENT_CITY_180_20141223_Q.@@R3437.1_SOURCE" Source (xy (5499 4228)) (refDes "P3V3_STBY") (value "3.3 V") (Props (_SXDesignName "CRESCENT_CITY_180_20141223_Q")) (Terms ("CRESCENT_CITY_180_20141223_Q.X1943000Y172000L28RATS" "1"))) ("CRESCENT_CITY_180_20141223_Q.@@R3437.2.1" Resistor (xy (5512 4228)) (mirror x) (refDes "R1R10") (value "10000 Ohm") (Props (_SXDesignName "CRESCENT_CITY_180_20141223_Q")) (Terms ("CRESCENT_CITY_180_20141223_Q.X1946500Y172000L28LRATS" "2") ("CRESCENT_CITY_180_20141223_Q.X1943000Y172000L28RATS" "1")))) (Nodes ("CRESCENT_CITY_180_20141223_Q.X1946500Y172000L28LRATS" (terms "CRESCENT_CITY_180_20141223_Q.@@R3437.2.1.1" "CRESCENT_CITY_180_20141223_Q.T@@RATS@@R3476.2@@R3437.2.2")) ("CRESCENT_CITY_180_20141223_Q.X1943000Y172000L2LRATS" (terms "CRESCENT_CITY_180_20141223_Q.@@R3476.1.2.1" "CRESCENT_CITY_180_20141223_Q.T@@RATS@@R3476.1@@EU46.6.1")) ("CRESCENT_CITY_180_20141223_Q.X1758729Y74026L2LRATS" (terms "CRESCENT_CITY_180_20141223_Q.T@@RATS@@R3476.2@@U47.A9.2" "CRESCENT_CITY_180_20141223_Q.T@@RATS@@U47.A9@@U22.AM2.1" "CRESCENT_CITY_180_20141223_Q.@@U47.A9.1")) ("CRESCENT_CITY_180_20141223_Q.X1529469Y369921L2LRATS" (terms "CRESCENT_CITY_180_20141223_Q.T@@RATS@@U47.A9@@U22.AM2.2" "CRESCENT_CITY_180_20141223_Q.@@U22.AM2.1")) ("CRESCENT_CITY_180_20141223_Q.X1946500Y172000L2LRATS" (terms "CRESCENT_CITY_180_20141223_Q.@@R3476.1.2.2" "CRESCENT_CITY_180_20141223_Q.T@@RATS@@R3476.2@@R3437.2.1" "CRESCENT_CITY_180_20141223_Q.T@@RATS@@R3476.2@@U47.A9.1")) ("CRESCENT_CITY_180_20141223_Q.X1943000Y172000L28RATS" (terms "CRESCENT_CITY_180_20141223_Q.@@R3437.2.1.2" "CRESCENT_CITY_180_20141223_Q.@@R3437.1_SOURCE.1")) ("CRESCENT_CITY_180_20141223_Q.X1935200Y171579L2LRATS" (terms "CRESCENT_CITY_180_20141223_Q.T@@RATS@@R3476.1@@EU46.6.2" "CRESCENT_CITY_180_20141223_Q.@@EU46.6.1"))) (Ports) (Stimuli ("local15" (scope local) (stimType periodic) (Props (periodicFreq "5e+007") (periodicJitter "0") (periodicPattern "1"))) ("local14" (scope local) (stimType periodic) (Props (periodicFreq "5e+007") (periodicJitter "0") (periodicPattern "1"))) ("local16" (scope local) (stimType periodic) (Props (periodicFreq "5e+007") (periodicJitter "0") (periodicPattern "1")))) (Notes) (Constraints ("DELAY_RULE" ("CRESCENT_CITY_180_20141223_Q U47.A9" "CRESCENT_CITY_180_20141223_Q U22.AM2" "LENGTH" "0.2032" "LENGTH" "0.3556"))) (MeasurementSets ("EMI" ("EMIStatus" status("on")) ("PeakEmission" status("on")) ("PeakFrequency" status("on")) ("PulseFreq" status("on")) ("RiseTime" status("on")) ("VoltageSwing" status("on"))) ("Reflection" ("BufferDelayFall" status("off")) ("BufferDelayRise" status("off")) ("EyeHeight" status("off")) ("EyeJitter" status("off")) ("EyeWidth" status("off")) ("FirstIncidentFall" status("off")) ("FirstIncidentRise" status("off")) ("Glitch" status("on")) ("GlitchFall" status("off")) ("GlitchRise" status("off")) ("Monotonic" status("on")) ("MonotonicFall" status("off")) ("MonotonicRise" status("off")) ("NoiseMargin" status("on")) ("NoiseMarginHigh" status("off")) ("NoiseMarginLow" status("off")) ("OvershootHigh" status("on")) ("OvershootLow" status("on")) ("PropDelay" status("on")) ("SettleDelay" status("on")) ("SettleDelayFall" status("off")) ("SettleDelayRise" status("off")) ("SwitchDelay" status("on")) ("SwitchDelayFall" status("off")) ("SwitchDelayRise" status("off"))) ("Crosstalk" ("Crosstalk" status("on"))) ("Custom")) (VectorSets) (Props (XnetName "RMII_SPRNGVLLE_BMC_PCH_RXD0") (allDrivers "active") (customSimType "Reflection") (ftsMode ("Typ")) (rcvrSelect "all") (tlineDelayMode "time") (userRevision "1.0")))) (Subckts) (CrossSections ("CRESCENT_CITY_180_20141223_Q" (Props (SXDesignName "CRESCENT_CITY_180_20141223_Q")) (Layers ("" (layerType "SURFACE") (material "AIR") (thickness "0 mil") (dielectricConstant "1.000000") (lossTangent "0") (etchFactor "0.000000") (elecCondVal "0 mho/cm") (thermCondVal "0 w/cm-degC")) ("" (layerType "DIELECTRIC") (material "CONFORMAL_COAT") (thickness "0.5 mil") (dielectricConstant "3.800000") (lossTangent "0.035") (etchFactor "0.000000") (elecCondVal "0 mho/cm") (thermCondVal "0.012 w/cm-degC")) ("TOP" (layerType "CONDUCTOR") (material "COPPER") (thickness "  2.100000 mil") (width "4.00 MIL") (dielectricConstant "4.500000") (lossTangent "0") (etchFactor "70.000000") (elecCondVal "595900.000000 mho/cm") (thermCondVal "0 w/cm-degC") (signalDieConstant "3.800000") (signalLossTangent "0.035")) ("" (layerType "DIELECTRIC") (material "FR-4") (thickness "  2.670000 mil") (dielectricConstant "4.000000") (lossTangent "0.035") (etchFactor "0.000000") (elecCondVal "0 mho/cm") (thermCondVal "0.012 w/cm-degC")) ("L2_GND1" (layerType "PLANE") (material "COPPER") (isShield t) (thickness "  1.250000 mil") (dielectricConstant "4.500000") (lossTangent "0.035") (etchFactor "90.000000") (elecCondVal "595900.000000 mho/cm") (thermCondVal "0.012 w/cm-degC")) ("" (layerType "DIELECTRIC") (material "FR-4") (thickness "  9.000000 mil") (dielectricConstant "4.100000") (lossTangent "0.035") (etchFactor "0.000000") (elecCondVal "0 mho/cm") (thermCondVal "0.012 w/cm-degC")) ("L3_SIG1" (layerType "CONDUCTOR") (material "COPPER") (thickness "  1.250000 mil") (width "4.00 MIL") (dielectricConstant "4.500000") (lossTangent "0.035") (etchFactor "90.000000") (elecCondVal "595900.000000 mho/cm") (thermCondVal "0.012 w/cm-degC") (signalDieConstant "4.100000") (signalLossTangent "0.035")) ("" (layerType "DIELECTRIC") (material "FR-4") (thickness "  3.000000 mil") (dielectricConstant "4.500000") (lossTangent "0.035") (etchFactor "0.000000") (elecCondVal "0 mho/cm") (thermCondVal "0 w/cm-degC")) ("L4_GND2" (layerType "PLANE") (material "COPPER") (isShield t) (thickness "  1.250000 mil") (dielectricConstant "4.500000") (lossTangent "0.035") (etchFactor "90.000000") (elecCondVal "595900.000000 mho/cm") (thermCondVal "0 w/cm-degC")) ("" (layerType "DIELECTRIC") (material "FR-4") (thickness "  9.000000 mil") (dielectricConstant "4.000000") (lossTangent "0.035") (etchFactor "0.000000") (elecCondVal "0 mho/cm") (thermCondVal "0.012 w/cm-degC")) ("L5_SIG2" (layerType "CONDUCTOR") (material "COPPER") (thickness "  1.250000 mil") (width "4.00 MIL") (dielectricConstant "4.500000") (lossTangent "0.035") (etchFactor "90.000000") (elecCondVal "595900.000000 mho/cm") (thermCondVal "0.012 w/cm-degC") (signalDieConstant "4.000000") (signalLossTangent "0.035")) ("" (layerType "DIELECTRIC") (material "FR-4") (thickness "  3.000000 mil") (dielectricConstant "4.500000") (lossTangent "0.035") (etchFactor "0.000000") (elecCondVal "0 mho/cm") (thermCondVal "0 w/cm-degC")) ("L6_GND3" (layerType "PLANE") (material "COPPER") (isShield t) (thickness "  1.250000 mil") (dielectricConstant "4.500000") (lossTangent "0.035") (etchFactor "90.000000") (elecCondVal "595900.000000 mho/cm") (thermCondVal "0 w/cm-degC")) ("" (layerType "DIELECTRIC") (material "FR-4") (thickness "  4.500000 mil") (dielectricConstant "4.100000") (lossTangent "0.035") (etchFactor "0.000000") (elecCondVal "0 mho/cm") (thermCondVal "0.012 w/cm-degC")) ("L7_PWR1-SIG" (layerType "PLANE") (material "COPPER") (isShield t) (thickness "  2.400000 mil") (dielectricConstant "4.500000") (lossTangent "0.035") (etchFactor "90.000000") (elecCondVal "595900.000000 mho/cm") (thermCondVal "0.012 w/cm-degC")) ("" (layerType "DIELECTRIC") (material "FR-4") (thickness "  4.600000 mil") (dielectricConstant "4.000000") (lossTangent "0.035") (etchFactor "0.000000") (elecCondVal "0 mho/cm") (thermCondVal "0.012 w/cm-degC")) ("L8_PWR2-SIG" (layerType "PLANE") (material "COPPER") (isShield t) (thickness "  2.400000 mil") (dielectricConstant "4.500000") (lossTangent "0.035") (etchFactor "90.000000") (elecCondVal "595900.000000 mho/cm") (thermCondVal "0.012 w/cm-degC")) ("" (layerType "DIELECTRIC") (material "FR-4") (thickness "  4.500000 mil") (dielectricConstant "4.500000") (lossTangent "0.035") (etchFactor "0.000000") (elecCondVal "0 mho/cm") (thermCondVal "0 w/cm-degC")) ("L9_GND4" (layerType "PLANE") (material "COPPER") (isShield t) (thickness "  1.250000 mil") (dielectricConstant "4.500000") (lossTangent "0.035") (etchFactor "90.000000") (elecCondVal "595900.000000 mho/cm") (thermCondVal "0 w/cm-degC")) ("" (layerType "DIELECTRIC") (material "FR-4") (thickness "  3.000000 mil") (dielectricConstant "4.100000") (lossTangent "0.035") (etchFactor "0.000000") (elecCondVal "0 mho/cm") (thermCondVal "0.012 w/cm-degC")) ("L10_SIG3" (layerType "CONDUCTOR") (material "COPPER") (thickness "  1.250000 mil") (width "4.00 MIL") (dielectricConstant "4.500000") (lossTangent "0.035") (etchFactor "90.000000") (elecCondVal "595900.000000 mho/cm") (thermCondVal "0.012 w/cm-degC") (signalDieConstant "4.100000") (signalLossTangent "0.035")) ("" (layerType "DIELECTRIC") (material "FR-4") (thickness "  9.000000 mil") (dielectricConstant "4.500000") (lossTangent "0.035") (etchFactor "0.000000") (elecCondVal "0 mho/cm") (thermCondVal "0 w/cm-degC")) ("L11_GND5" (layerType "PLANE") (material "COPPER") (isShield t) (thickness "  1.250000 mil") (dielectricConstant "4.500000") (lossTangent "0.035") (etchFactor "90.000000") (elecCondVal "595900.000000 mho/cm") (thermCondVal "0 w/cm-degC")) ("" (layerType "DIELECTRIC") (material "FR-4") (thickness "  3.000000 mil") (dielectricConstant "4.500000") (lossTangent "0.035") (etchFactor "0.000000") (elecCondVal "0 mho/cm") (thermCondVal "0.012 w/cm-degC")) ("L12_SIG4" (layerType "CONDUCTOR") (material "COPPER") (thickness "  1.250000 mil") (width "4.00 MIL") (dielectricConstant "4.500000") (lossTangent "0.035") (etchFactor "90.000000") (elecCondVal "595900.000000 mho/cm") (thermCondVal "0.012 w/cm-degC") (signalDieConstant "4.500000") (signalLossTangent "0.035")) ("" (layerType "DIELECTRIC") (material "FR-4") (thickness "  9.000000 mil") (dielectricConstant "4.500000") (lossTangent "0.035") (etchFactor "0.000000") (elecCondVal "0 mho/cm") (thermCondVal "0 w/cm-degC")) ("L13_GND6" (layerType "PLANE") (material "COPPER") (isShield t) (thickness "  1.250000 mil") (dielectricConstant "4.500000") (lossTangent "0.035") (etchFactor "90.000000") (elecCondVal "595900.000000 mho/cm") (thermCondVal "0.012 w/cm-degC")) ("" (layerType "DIELECTRIC") (material "FR-4") (thickness "  2.670000 mil") (dielectricConstant "4.500000") (lossTangent "0.035") (etchFactor "0.000000") (elecCondVal "0 mho/cm") (thermCondVal "0.012 w/cm-degC")) ("BOTTOM" (layerType "CONDUCTOR") (material "COPPER") (thickness "  2.100000 mil") (width "4.00 MIL") (dielectricConstant "4.500000") (lossTangent "0") (etchFactor "70.000000") (elecCondVal "595900.000000 mho/cm") (thermCondVal "0 w/cm-degC") (signalDieConstant "3.800000") (signalLossTangent "0.035")) ("" (layerType "DIELECTRIC") (material "CONFORMAL_COAT") (thickness "0.5 mil") (dielectricConstant "3.800000") (lossTangent "0.035") (etchFactor "0.000000") (elecCondVal "0 mho/cm") (thermCondVal "0.012 w/cm-degC")) ("" (layerType "SURFACE") (material "AIR") (thickness "0 mil") (dielectricConstant "1.000000") (lossTangent "0") (etchFactor "0.000000") (elecCondVal "0 mho/cm") (thermCondVal "0 w/cm-degC"))))) (Props (DesUnits "mils 2") (LayerStack ("DIELECTRIC" "DIELECTRIC" "BOTTOM" "DIELECTRIC" "L13_GND6" "DIELECTRIC" "L12_SIG4" "DIELECTRIC" "L11_GND5" "DIELECTRIC" "L10_SIG3" "DIELECTRIC" "L9_GND4" "DIELECTRIC" "L8_PWR2-SIG" "DIELECTRIC" "L7_PWR1-SIG" "DIELECTRIC" "L6_GND3" "DIELECTRIC" "L5_SIG2" "DIELECTRIC" "L4_GND2" "DIELECTRIC" "L3_SIG1" "DIELECTRIC" "L2_GND1" "DIELECTRIC" "TOP" "DIELECTRIC" "DIELECTRIC")) (Revision "16.600")) (Params (IbisIOPkg ((temperature "27") (bufferModel "CDSDefaultIO_2p5v") (stimuli nil) (offsets nil) (state "tristate") (cycle "1") (termMap nil) (setup "2.0e-09") (hold "1.0e-09") (rise nil) (fall nil) (macroType nil) (voltage nil) (spice nil) (LEFDEFPinName nil) (LEFDEFPinType nil) (mappingTag nil))) (IbisIOMacro ((temperature "27") (bufferModel "CDSDefaultIO_2p5v") (stimuli nil) (offsets nil) (state "tristate") (cycle "1") (termMap nil) (setup "2.0e-09") (hold "1.0e-09") (rise nil) (fall nil) (macroType nil) (voltage nil) (spice nil) (LEFDEFPinName nil) (LEFDEFPinType nil) (mappingTag nil))) (IbisInputPkg ((temperature "27") (bufferModel "CDSDefaultInput_2p5v") (cycle "1") (LEFDEFPinName nil) (LEFDEFPinType nil) (mappingTag nil))) (IbisOutputPkg ((temperature "27") (bufferModel "CDSDefaultOutput_2p5v") (stimuli nil) (offsets nil) (state "tristate") (cycle "1") (termMap nil) (setup "2.0e-09") (hold "1.0e-09") (rise nil) (fall nil) (macroType nil) (voltage nil) (spice nil) (LEFDEFPinName nil) (LEFDEFPinType nil) (mappingTag nil))) (periodic ((periodicFreq "100e6") (periodicPattern "10") (periodicJitter "0"))) (IbisIO_OpenPullUp ((temperature "27") (bufferModel "CDSDefaultIO_2p5v") (stimuli nil) (offsets nil) (state "tristate") (cycle "1") (termMap nil) (setup "2.0e-09") (hold "1.0e-09") (rise nil) (fall nil) (macroType nil) (voltage nil) (spice nil) (LEFDEFPinName nil) (LEFDEFPinType nil) (mappingTag nil))) (clocked ((clockRise "1e-09") (clockFall "1e-09") (clockFreq "100e6") (clockInitState "0") (clockDutyCycle "0.5") (clockJitter "0"))) (IbisIO ((temperature "27") (bufferModel "CDSDefaultIO_2p5v") (stimuli nil) (offsets nil) (state "tristate") (cycle "1") (termMap nil) (setup "2.0e-09") (hold "1.0e-09") (rise nil) (fall nil) (macroType nil) (voltage nil) (spice nil) (LEFDEFPinName nil) (LEFDEFPinType nil) (mappingTag nil))) (IbisIO_OpenPullDown ((temperature "27") (bufferModel "CDSDefaultIO_2p5v") (stimuli nil) (offsets nil) (state "tristate") (cycle "1") (termMap nil) (setup "2.0e-09") (hold "1.0e-09") (rise nil) (fall nil) (macroType nil) (voltage nil) (spice nil) (LEFDEFPinName nil) (LEFDEFPinType nil) (mappingTag nil))) (IbisOutput ((temperature "27") (bufferModel "CDSDefaultOutput_2p5v") (stimuli nil) (offsets nil) (state "tristate") (cycle "1") (termMap nil) (setup "2.0e-09") (hold "1.0e-09") (rise nil) (fall nil) (macroType nil) (voltage nil) (spice nil) (LEFDEFPinName nil) (LEFDEFPinType nil) (mappingTag nil))) (async ((asyncTimePoints "") (asyncInitState "1"))) (TLine ((diffImpedance "100ohm") (diffVelocity "1.4142e+08M/s") (impedance "60ohm") length("2800 mil") (propDelay "0.5 ns") (velocity "5600 mil/ns") (traceCount "1") (traceGeometry "Microstrip") (impedanceMin nil) (impedanceMax nil) (lengthMin nil) (lengthMax nil) (propDelayMin nil) (propDelayMax nil) (impedanceSweepCount nil) (propDelaySweepCount nil) (velocitySweepCount nil) (lengthSweepCount nil) (matchSetName nil))) (IbisInput ((temperature "27") (bufferModel "CDSDefaultInput_2p5v") (cycle "1") (LEFDEFPinName nil) (LEFDEFPinType nil) (mappingTag nil))) (SeriesTerm ((resistance "22 ohm") (maxDelay "0.1 ns"))) (Connector nil) (CurrentProbe nil) (IbisOutput_OpenPullUp ((temperature "27") (bufferModel "CDSDefaultOutput_2p5v") (stimuli nil) (offsets nil) (state "tristate") (cycle "1") (termMap nil) (setup "2.0e-09") (hold "1.0e-09") (rise nil) (fall nil) (macroType nil) (voltage nil) (spice nil) (LEFDEFPinName nil) (LEFDEFPinType nil) (mappingTag nil))) (sync ((syncFreq "100e6") (syncInitState "1") (syncPattern "10") (syncEdgeSwitch "rise"))) (DiffInputPkg ((temperature "27") (bufferModelNonInverting "CDSDefaultInput_2p5v") (bufferModelInverting "CDSDefaultInput_2p5v") (threshInputHighMin "1.7 V") (threshInputHighTyp "1.7  V") (threshInputHighMax "1.7  V") (threshInputLowMin "0.7  V") (threshInputLowTyp "0.7  V") (threshInputLowMax "0.7  V") (mappingTagNonInverting nil) (mappingTagInverting nil) (cycle "1"))) (idlCircuit ((allDrivers "active") (ftsMode '("Typ")) (rcvrSelect "all") (simMode "Reflection") (tlineDelayMode "time") (userRevision "1.0") (autoSolve "On"))) (Trace ((d1Thickness "10 mil") (d1Constant "4.5") (d1LossTangent "0.035") (d2Thickness "10 mil") (d2Constant "4.5") (d2LossTangent "0.035") (d3Thickness "0.0") (d3Constant "1.0") (d3LossTangent "0") length("1000 mil") (spacing "5 mil") (spacing2 "5 mil") (spacing3 "5 mil") (spacing4 "5 mil") (spacing5 "5 mil") (traceConductivity "595900 mho/cm") (traceGeometry "microstrip") (traceLayerName "") (traceThickness "0.72 mil") (traceType "single") (traceWidth "5.0 mil") (traceWidth2 "5.0 mil") (traceWidth3 "5.0 mil") (traceWidth4 "5.0 mil") (traceWidth5 "5.0 mil") (traceWidth6 "5.0 mil") (offset "0 mil") (traceCount "1") (impedance nil))) (DiffOutput ((temperature "27") (bufferModelNonInverting "CDSDefaultOutput_2p5v") (bufferModelInverting "CDSDefaultOutput_2p5v") (stimuli nil) (offsets nil) (state "tristate") (cycle "1") (termMap nil) (setup "0.9e-09") (hold "0.4e-09") (rise nil) (fall nil) (threshOutputHighMin "2.375  V") (threshOutputHighTyp "2.5  V") (threshOutputHighMax "2.625  V") (threshOutputLowMin "1.275  V") (threshOutputLowTyp "1.7  V") (threshOutputLowMax "1.985  V") (mappingTagNonInverting nil) (mappingTagInverting nil) (spice nil))) (HiClampTerm ((cutoffVoltage "0.7 V") (voltage "5 V") (maxDelay "0.1 ns"))) (Via ((model "Unknown") (viaOutputFormat "Unknown") (viaPadstack nil) (viaTopLayer nil) (viaBottomLayer nil) (viaIsPower nil) (viaIsGround nil))) (Resistor ((resistance "50 ohm") (orientation "0"))) (LowClampTerm ((cutoffVoltage "0.7 V") (voltage "0 V") (maxDelay "0.1 ns"))) (DiffOutputPkg ((temperature "27") (bufferModelNonInverting "CDSDefaultOutput_2p5v") (bufferModelInverting "CDSDefaultOutput_2p5v") (stimuli nil) (offsets nil) (state "tristate") (cycle "1") (termMap nil) (setup "0.9e-09") (hold "0.4e-09") (rise nil) (fall nil) (threshOutputHighMin "2.375  V") (threshOutputHighTyp "2.5  V") (threshOutputHighMax "2.625  V") (threshOutputLowMin "1.275  V") (threshOutputLowTyp "1.7  V") (threshOutputLowMax "1.985  V") (mappingTagNonInverting nil) (mappingTagInverting nil) (spice nil))) (RCTerm ((resistance "50 ohm") (capacitance "20 pF") (voltage "5 V") (maxDelay "0.1 ns"))) (DiffIO ((temperature "27") (bufferModelNonInverting "CDSDefaultIO_2p5v") (bufferModelInverting "CDSDefaultIO_2p5v") (stimuli nil) (offsets nil) (state "tristate") (cycle "1") (termMap nil) (setup "0.9e-09") (hold "0.4e-09") (rise nil) (fall nil) (threshInputHighMin "1.7 V") (threshInputHighTyp "1.7  V") (threshInputHighMax "1.7  V") (threshInputLowMin "0.7  V") (threshInputLowTyp "0.7  V") (threshInputLowMax "0.7 ") (threshOutputHighMin "2.365  V") (threshOutputHighTyp "2.5  V") (threshOutputHighMax "2.625  V") (threshOutputLowMin "1.275  V") (threshOutputLowTyp "1.7  V") (threshOutputLowMax "1.985  V") (mappingTagNonInverting nil) (mappingTagInverting nil) (spice nil))) (TheveninTerm ((resistanceUp "180 ohm") (resistanceDown "270 ohm") (voltageUp "5 V") (voltageDown "0 V") (maxDelay "0.1 ns"))) (DiffIOPkg ((temperature "27") (bufferModelNonInverting "CDSDefaultIO_2p5v") (bufferModelInverting "CDSDefaultIO_2p5v") (stimuli nil) (offsets nil) (state "tristate") (cycle "1") (termMap nil) (setup "0.9e-09") (hold "0.4e-09") (rise nil) (fall nil) (threshInputHighMin "1.7 V") (threshInputHighTyp "1.7  V") (threshInputHighMax "1.7  V") (threshInputLowMin "0.7  V") (threshInputLowTyp "0.7  V") (threshInputLowMax "0.7 ") (threshOutputHighMin "2.365  V") (threshOutputHighTyp "2.5  V") (threshOutputHighMax "2.625  V") (threshOutputLowMin "1.275  V") (threshOutputLowTyp "1.7  V") (threshOutputLowMax "1.985  V") (mappingTagNonInverting nil) (mappingTagInverting nil) (spice nil))) (Source ((voltage "5 V"))) (ShuntTerm ((resistance "50 ohm") (voltage "5 V") (maxDelay "0.1 ns"))) (RLGC (length("1000 mil"))) (Capacitor ((capacitance "10 pF") (orientation "0"))) (DiffInput ((temperature "27") (bufferModelNonInverting "CDSDefaultInput_2p5v") (bufferModelInverting "CDSDefaultInput_2p5v") (threshInputHighMin "1.7 V") (threshInputHighTyp "1.7  V") (threshInputHighMax "1.7  V") (threshInputLowMin "0.7  V") (threshInputLowTyp "0.7  V") (threshInputLowMax "0.7  V") (mappingTagNonInverting nil) (mappingTagInverting nil) (cycle "1"))) (Inductor ((inductance "5 nH") (orientation "0"))) (Cable (length("1 m"))) (CPWSL ((d1Thickness "10 mil") (d1Constant "4.5") (d1LossTangent "0.035") (d2Thickness "0.72 mil") (d2Constant "4.5") (d2LossTangent "0.035") (d3Thickness "10 mil") (d3Constant "4.5") (d3LossTangent "0.035") length("1000 mil") (spacing "5 mil") (spacing2 "5 mil") (spacing3 "5 mil") (spacing4 "5 mil") (spacing5 "5 mil") (traceConductivity "595900 mho/cm") (traceGeometry "cpwms") (traceLayerName "") (traceThickness "0.72 mil") (traceType "single") (traceWidth "5.0 mil") (traceWidth2 "5.0 mil") (traceWidth3 "5.0 mil") (traceWidth4 "5.0 mil") (traceWidth5 "5.0 mil") (traceWidth6 "5.0 mil") (offset "0 mil") (traceCount "1") (impedance nil))) (CPWMS ((d1Thickness "10 mil") (d1Constant "4.5") (d1LossTangent "0.035") (d2Thickness "0.72 mil") (d2Constant "4.5") (d2LossTangent "0.035") (d3Thickness "0.0") (d3Constant "1") (d3LossTangent "0") length("1000 mil") (spacing "5 mil") (spacing2 "5 mil") (spacing3 "5 mil") (spacing4 "5 mil") (spacing5 "5 mil") (traceConductivity "595900 mho/cm") (traceGeometry "cpwms") (traceLayerName "") (traceThickness "0.72 mil") (traceType "single") (traceWidth "5.0 mil") (traceWidth2 "5.0 mil") (traceWidth3 "5.0 mil") (traceWidth4 "5.0 mil") (traceWidth5 "5.0 mil") (traceWidth6 "5.0 mil") (offset "0 mil") (traceCount "1") (impedance nil))) (Diode ((cutoffVoltage "0.7 V"))) (CPW ((d1Thickness "10 mil") (d1Constant "4.5") (d1LossTangent "0.035") (d2Thickness "0.72 mil") (d2Constant "1") (d2LossTangent "0") (d3Thickness "0.0") (d3Constant "1") (d3LossTangent "0") length("1000 mil") (spacing "5 mil") (spacing2 "5 mil") (spacing3 "5 mil") (spacing4 "5 mil") (spacing5 "5 mil") (traceConductivity "595900 mho/cm") (traceGeometry "cpwms") (traceLayerName "") (traceThickness "0.72 mil") (traceType "single") (traceWidth "5.0 mil") (traceWidth2 "5.0 mil") (traceWidth3 "5.0 mil") (traceWidth4 "5.0 mil") (traceWidth5 "5.0 mil") (traceWidth6 "5.0 mil") (offset "0 mil") (traceCount "1") (impedance nil))) (DualClampTerm ((cutoffVoltageUp "0.7 V") (cutoffVoltageDown "0.7 V") (voltageUp "5 V") (voltageDown "0 V") (maxDelay "0.1 ns"))) (ESpiceDevice nil)))
				)
				( objectStatus "RMII_RX" )
			)
			( electricalCSet "@crescent_city_bb_fab1_lib.crescent_city_bb_fab1(sch_1):\RMII_SPRNGVLLE_BMC_PCH_RXD0\"
				( pinPairRef "RMII_SPRNGVLLE_BMC_PCH_RXD0:EU9E1.6:R9E17.1" )
				( pinPairRef "RMII_SPRNGVLLE_BMC_PCH_RXD0:R3P3.2:U7C1.AL1" )
				( pinPairRef "RMII_SPRNGVLLE_BMC_PCH_RXD0:U9F4.A9:EU9E1.6" )
				( pinPairRef "RMII_SPRNGVLLE_BMC_PCH_RXD0:U9F4.A9:U7C1.AL1" )
				( attribute "TOPOLOGY_TEMPLATE_REVISION" "1.0"
					( Origin gBackEnd )
				)
				( topologyData 27680
(SKIDL (Circuits ("MAIN" (Parts ("CONSTRAINTS_CRESCENT_CITY_610_20150219_B.@@U22.AL1" IbisIOPkg (xy (5547 4218)) (refDes "U7C1") (model "Unknown") (Props (_SXDesignName "CONSTRAINTS_CRESCENT_CITY_610_20150219_B") (brdx "15275 MIL") (brdy "3682.87 MIL") (bufferModel "CDSDefaultIO_2p5v") (cycle "1") (hold "1.0e-09") (mappingTag "") (offsets ("4" "0") ("5" "0")) (setup "2.0e-09") (state "tristate") (stimuli ("4" "local0") ("5" "local1")) (temperature "27") (termMap ("4" "Data") ("5" "Enable"))) (Terms ("CONSTRAINTS_CRESCENT_CITY_610_20150219_B.X1527500Y368287L2LRATS" "AL1"))) ("CONSTRAINTS_CRESCENT_CITY_610_20150219_B.@@EU46.6" IbisOutputPkg (xy (5498 4235)) (refDes "EU9E1") (model "Unknown") (Props (_SXDesignName "CONSTRAINTS_CRESCENT_CITY_610_20150219_B") (brdx "19352 MIL") (brdy "1715.79 MIL") (bufferModel "CDSDefaultOutput_2p5v") (cycle "1") (hold "1.0e-09") (mappingTag "") (offsets ("4" "0")) (setup "2.0e-09") (state "tristate") (stimuli ("4" "local2")) (temperature "27") (termMap ("4" "Data"))) (Terms ("CONSTRAINTS_CRESCENT_CITY_610_20150219_B.X1935200Y171579L2LRATS" "6"))) ("CONSTRAINTS_CRESCENT_CITY_610_20150219_B.@@U47.A9" IbisInputPkg (xy (5552 4235)) (refDes "U9F4") (model "Unknown") (Props (_SXDesignName "CONSTRAINTS_CRESCENT_CITY_610_20150219_B") (brdx "17587.29 MIL") (brdy "740.26 MIL") (bufferModel "CDSDefaultInput_2p5v") (mappingTag "") (temperature "27")) (Terms ("CONSTRAINTS_CRESCENT_CITY_610_20150219_B.X1758729Y74026L2LRATS" "A9"))) ("CONSTRAINTS_CRESCENT_CITY_610_20150219_B.@@R3437.1.2" Resistor (xy (5503.0 4228.5)) (refDes "R1R10") (value "10000 Ohm") (Props (_SXDesignName "CONSTRAINTS_CRESCENT_CITY_610_20150219_B")) (Terms ("CONSTRAINTS_CRESCENT_CITY_610_20150219_B.X1943000Y172000L28RATS" "1") ("CONSTRAINTS_CRESCENT_CITY_610_20150219_B.X1946500Y172000L28LRATS" "2"))) ("CONSTRAINTS_CRESCENT_CITY_610_20150219_B.T@@RATS@@U47.A9@@R3476.2" TLine (xy (5530 4235)) (mirror x) (refDes "TL1") (Props (_SXDesignName "CONSTRAINTS_CRESCENT_CITY_610_20150219_B") (impedance "49.728 ohm") length("2857.45 MIL") (propDelay "0.51322 ns") (traceCount "1") (traceGeometry "Microstrip") (velocity "5567.68 mil/ns")) (Terms ("CONSTRAINTS_CRESCENT_CITY_610_20150219_B.X1758729Y74026L2LRATS" "1") ("CONSTRAINTS_CRESCENT_CITY_610_20150219_B.X1946500Y172000L2LRATS" "2"))) ("CONSTRAINTS_CRESCENT_CITY_610_20150219_B.@@R3476.1.2" Resistor (xy (5520.5 4235.0)) (refDes "R9E17") (value "22 Ohm") (Props (_SXDesignName "CONSTRAINTS_CRESCENT_CITY_610_20150219_B")) (Terms ("CONSTRAINTS_CRESCENT_CITY_610_20150219_B.X1943000Y172000L2LRATS" "1") ("CONSTRAINTS_CRESCENT_CITY_610_20150219_B.X1946500Y172000L2LRATS" "2"))) ("CONSTRAINTS_CRESCENT_CITY_610_20150219_B.T@@RATS@@R3476.1@@EU46.6" TLine (xy (5506 4235)) (mirror x) (refDes "TL2") (Props (_SXDesignName "CONSTRAINTS_CRESCENT_CITY_610_20150219_B") (impedance "48.412 ohm") length("82.21 MIL") (propDelay "0.01477 ns") (traceCount "1") (traceGeometry "Microstrip") (velocity "5566.02 mil/ns")) (Terms ("CONSTRAINTS_CRESCENT_CITY_610_20150219_B.X1943000Y172000L2LRATS" "1") ("CONSTRAINTS_CRESCENT_CITY_610_20150219_B.X1935200Y171579L2LRATS" "2"))) ("CONSTRAINTS_CRESCENT_CITY_610_20150219_B.T@@RATS@@U47.A9@@R615.1" TLine (xy (5547.0 4227.0)) (mirror x) (refDes "TL3") (Props (_SXDesignName "CONSTRAINTS_CRESCENT_CITY_610_20150219_B") (impedance "60 ohm") length("5183.03 MIL") (propDelay "0.930908 ns") (traceCount "1") (traceGeometry "Microstrip") (velocity "5567.72 mil/ns")) (Terms ("CONSTRAINTS_CRESCENT_CITY_610_20150219_B.X1758729Y74026L2LRATS" "1") ("CONSTRAINTS_CRESCENT_CITY_610_20150219_B.X1526000Y359600L28LRATS" "2"))) ("CONSTRAINTS_CRESCENT_CITY_610_20150219_B.T@@RATS@@U22.AL1@@R615.2" TLine (xy (5532 4213)) (mirror x) (refDes "TL4") (Props (_SXDesignName "CONSTRAINTS_CRESCENT_CITY_610_20150219_B") (impedance "60 ohm") length("66.87 MIL") (propDelay "0.0120103 ns") (traceCount "1") (traceGeometry "Microstrip") (velocity "5567.87 mil/ns")) (Terms ("CONSTRAINTS_CRESCENT_CITY_610_20150219_B.X1527500Y368287L2LRATS" "1") ("CONSTRAINTS_CRESCENT_CITY_610_20150219_B.X1526000Y363100L28LRATS" "2"))) ("CONSTRAINTS_CRESCENT_CITY_610_20150219_B.@@R615.2.1" Resistor (xy (5531.0 4227.0)) (refDes "R3P3") (value "1 Ohm") (Props (_SXDesignName "CONSTRAINTS_CRESCENT_CITY_610_20150219_B")) (Terms ("CONSTRAINTS_CRESCENT_CITY_610_20150219_B.X1526000Y363100L28LRATS" "2") ("CONSTRAINTS_CRESCENT_CITY_610_20150219_B.X1526000Y359600L28LRATS" "1"))) ("CONSTRAINTS_CRESCENT_CITY_610_20150219_B.T@@RATS@@R3476.2@@R3437.2" TLine (xy (5520.5 4228.5)) (mirror x) (refDes "TL5") (Props (_SXDesignName "CONSTRAINTS_CRESCENT_CITY_610_20150219_B") (impedance "48.412 ohm") (propDelay "1.79607e-006 ns") (traceCount "1") (traceGeometry "Microstrip")) (Terms ("CONSTRAINTS_CRESCENT_CITY_610_20150219_B.X1946500Y172000L2LRATS" "1") ("CONSTRAINTS_CRESCENT_CITY_610_20150219_B.X1946500Y172000L28LRATS" "2"))) ("CONSTRAINTS_CRESCENT_CITY_610_20150219_B.@@R3437.1_SOURCE" Source (xy (5496.5 4228.5)) (refDes "P3V3_STBY") (value "3.3 V") (Props (_SXDesignName "CONSTRAINTS_CRESCENT_CITY_610_20150219_B")) (Terms ("CONSTRAINTS_CRESCENT_CITY_610_20150219_B.X1943000Y172000L28RATS" "1")))) (Nodes ("CONSTRAINTS_CRESCENT_CITY_610_20150219_B.X1946500Y172000L2LRATS" (terms "CONSTRAINTS_CRESCENT_CITY_610_20150219_B.T@@RATS@@R3476.2@@R3437.2.1" "CONSTRAINTS_CRESCENT_CITY_610_20150219_B.@@R3476.1.2.2" "CONSTRAINTS_CRESCENT_CITY_610_20150219_B.T@@RATS@@U47.A9@@R3476.2.2")) ("CONSTRAINTS_CRESCENT_CITY_610_20150219_B.X1943000Y172000L2LRATS" (terms "CONSTRAINTS_CRESCENT_CITY_610_20150219_B.T@@RATS@@R3476.1@@EU46.6.1" "CONSTRAINTS_CRESCENT_CITY_610_20150219_B.@@R3476.1.2.1")) ("CONSTRAINTS_CRESCENT_CITY_610_20150219_B.X1943000Y172000L28RATS" (terms "CONSTRAINTS_CRESCENT_CITY_610_20150219_B.@@R3437.1_SOURCE.1" "CONSTRAINTS_CRESCENT_CITY_610_20150219_B.@@R3437.1.2.1")) ("CONSTRAINTS_CRESCENT_CITY_610_20150219_B.X1527500Y368287L2LRATS" (terms "CONSTRAINTS_CRESCENT_CITY_610_20150219_B.T@@RATS@@U22.AL1@@R615.2.1" "CONSTRAINTS_CRESCENT_CITY_610_20150219_B.@@U22.AL1.1")) ("CONSTRAINTS_CRESCENT_CITY_610_20150219_B.X1526000Y363100L28LRATS" (terms "CONSTRAINTS_CRESCENT_CITY_610_20150219_B.@@R615.2.1.1" "CONSTRAINTS_CRESCENT_CITY_610_20150219_B.T@@RATS@@U22.AL1@@R615.2.2")) ("CONSTRAINTS_CRESCENT_CITY_610_20150219_B.X1526000Y359600L28LRATS" (terms "CONSTRAINTS_CRESCENT_CITY_610_20150219_B.@@R615.2.1.2" "CONSTRAINTS_CRESCENT_CITY_610_20150219_B.T@@RATS@@U47.A9@@R615.1.2")) ("CONSTRAINTS_CRESCENT_CITY_610_20150219_B.X1946500Y172000L28LRATS" (terms "CONSTRAINTS_CRESCENT_CITY_610_20150219_B.T@@RATS@@R3476.2@@R3437.2.2" "CONSTRAINTS_CRESCENT_CITY_610_20150219_B.@@R3437.1.2.2")) ("CONSTRAINTS_CRESCENT_CITY_610_20150219_B.X1935200Y171579L2LRATS" (terms "CONSTRAINTS_CRESCENT_CITY_610_20150219_B.T@@RATS@@R3476.1@@EU46.6.2" "CONSTRAINTS_CRESCENT_CITY_610_20150219_B.@@EU46.6.1")) ("CONSTRAINTS_CRESCENT_CITY_610_20150219_B.X1758729Y74026L2LRATS" (terms "CONSTRAINTS_CRESCENT_CITY_610_20150219_B.T@@RATS@@U47.A9@@R615.1.1" "CONSTRAINTS_CRESCENT_CITY_610_20150219_B.T@@RATS@@U47.A9@@R3476.2.1" "CONSTRAINTS_CRESCENT_CITY_610_20150219_B.@@U47.A9.1"))) (Ports) (Stimuli ("local2" (scope local) (stimType periodic) (Props (periodicFreq "5e+007") (periodicJitter "0") (periodicPattern "1"))) ("local0" (scope local) (stimType periodic) (Props (periodicFreq "5e+007") (periodicJitter "0") (periodicPattern "1"))) ("local1" (scope local) (stimType periodic) (Props (periodicFreq "5e+007") (periodicJitter "0") (periodicPattern "1")))) (Notes) (Constraints ("DELAY_RULE" ("CONSTRAINTS_CRESCENT_CITY_610_20150219_B EU46.6" "CONSTRAINTS_CRESCENT_CITY_610_20150219_B R3476.1" "LENGTH" "0" "LENGTH" "0.0127") ("CONSTRAINTS_CRESCENT_CITY_610_20150219_B R615.2" "CONSTRAINTS_CRESCENT_CITY_610_20150219_B U22.AL1" "LENGTH" "0" "LENGTH" "0.0127") ("CONSTRAINTS_CRESCENT_CITY_610_20150219_B U47.A9" "CONSTRAINTS_CRESCENT_CITY_610_20150219_B EU46.6" "LENGTH" "0.0254" "LENGTH" "0.2032") ("CONSTRAINTS_CRESCENT_CITY_610_20150219_B U47.A9" "CONSTRAINTS_CRESCENT_CITY_610_20150219_B U22.AL1" "LENGTH" "0.0254" "LENGTH" "0.2032"))) (MeasurementSets ("EMI" ("EMIStatus" status("on")) ("PeakEmission" status("on")) ("PeakFrequency" status("on")) ("PulseFreq" status("on")) ("RiseTime" status("on")) ("VoltageSwing" status("on"))) ("Reflection" ("BufferDelayFall" status("off")) ("BufferDelayRise" status("off")) ("EyeHeight" status("off")) ("EyeJitter" status("off")) ("EyeWidth" status("off")) ("FirstIncidentFall" status("off")) ("FirstIncidentRise" status("off")) ("Glitch" status("on")) ("GlitchFall" status("off")) ("GlitchRise" status("off")) ("Monotonic" status("on")) ("MonotonicFall" status("off")) ("MonotonicRise" status("off")) ("NoiseMargin" status("on")) ("NoiseMarginHigh" status("off")) ("NoiseMarginLow" status("off")) ("OvershootHigh" status("on")) ("OvershootLow" status("on")) ("PropDelay" status("on")) ("SettleDelay" status("on")) ("SettleDelayFall" status("off")) ("SettleDelayRise" status("off")) ("SwitchDelay" status("on")) ("SwitchDelayFall" status("off")) ("SwitchDelayRise" status("off"))) ("Crosstalk" ("Crosstalk" status("on"))) ("Custom")) (VectorSets) (Props (XnetName "RMII_SPRNGVLLE_BMC_PCH_RXD0") (allDrivers "active") (customSimType "Reflection") (ftsMode ("Typ")) (rcvrSelect "all") (tlineDelayMode "time") (userRevision "1.0")))) (Subckts) (CrossSections ("CONSTRAINTS_CRESCENT_CITY_610_20150219_B" (Props (SXDesignName "CONSTRAINTS_CRESCENT_CITY_610_20150219_B")) (Layers ("" (layerType "SURFACE") (material "AIR") (thickness "0 mil") (dielectricConstant "1.000000") (lossTangent "0") (etchFactor "0.000000") (elecCondVal "0 mho/cm") (thermCondVal "0 w/cm-degC")) ("" (layerType "DIELECTRIC") (material "CONFORMAL_COAT") (thickness "0.5 mil") (dielectricConstant "3.800000") (lossTangent "0.035") (etchFactor "0.000000") (elecCondVal "0 mho/cm") (thermCondVal "0.012 w/cm-degC")) ("TOP" (layerType "CONDUCTOR") (material "COPPER") (thickness "  2.100000 mil") (width "4.00 MIL") (dielectricConstant "4.500000") (lossTangent "0") (etchFactor "70.000000") (elecCondVal "595900.000000 mho/cm") (thermCondVal "0 w/cm-degC") (signalDieConstant "3.800000") (signalLossTangent "0.035")) ("" (layerType "DIELECTRIC") (material "FR-4") (thickness "  2.670000 mil") (dielectricConstant "4.000000") (lossTangent "0.035") (etchFactor "0.000000") (elecCondVal "0 mho/cm") (thermCondVal "0.012 w/cm-degC")) ("L2_GND1" (layerType "PLANE") (material "COPPER") (isShield t) (thickness "  1.250000 mil") (dielectricConstant "4.500000") (lossTangent "0.035") (etchFactor "90.000000") (elecCondVal "595900.000000 mho/cm") (thermCondVal "0.012 w/cm-degC")) ("" (layerType "DIELECTRIC") (material "FR-4") (thickness "  9.000000 mil") (dielectricConstant "4.100000") (lossTangent "0.035") (etchFactor "0.000000") (elecCondVal "0 mho/cm") (thermCondVal "0.012 w/cm-degC")) ("L3_SIG1" (layerType "CONDUCTOR") (material "COPPER") (thickness "  1.250000 mil") (width "4.00 MIL") (dielectricConstant "4.500000") (lossTangent "0.035") (etchFactor "90.000000") (elecCondVal "595900.000000 mho/cm") (thermCondVal "0.012 w/cm-degC") (signalDieConstant "4.100000") (signalLossTangent "0.035")) ("" (layerType "DIELECTRIC") (material "FR-4") (thickness "  3.000000 mil") (dielectricConstant "4.500000") (lossTangent "0.035") (etchFactor "0.000000") (elecCondVal "0 mho/cm") (thermCondVal "0 w/cm-degC")) ("L4_GND2" (layerType "PLANE") (material "COPPER") (isShield t) (thickness "  1.250000 mil") (dielectricConstant "4.500000") (lossTangent "0.035") (etchFactor "90.000000") (elecCondVal "595900.000000 mho/cm") (thermCondVal "0 w/cm-degC")) ("" (layerType "DIELECTRIC") (material "FR-4") (thickness "  9.000000 mil") (dielectricConstant "4.000000") (lossTangent "0.035") (etchFactor "0.000000") (elecCondVal "0 mho/cm") (thermCondVal "0.012 w/cm-degC")) ("L5_SIG2" (layerType "CONDUCTOR") (material "COPPER") (thickness "  1.250000 mil") (width "4.00 MIL") (dielectricConstant "4.500000") (lossTangent "0.035") (etchFactor "90.000000") (elecCondVal "595900.000000 mho/cm") (thermCondVal "0.012 w/cm-degC") (signalDieConstant "4.000000") (signalLossTangent "0.035")) ("" (layerType "DIELECTRIC") (material "FR-4") (thickness "  3.000000 mil") (dielectricConstant "4.500000") (lossTangent "0.035") (etchFactor "0.000000") (elecCondVal "0 mho/cm") (thermCondVal "0 w/cm-degC")) ("L6_GND3" (layerType "PLANE") (material "COPPER") (isShield t) (thickness "  1.250000 mil") (dielectricConstant "4.500000") (lossTangent "0.035") (etchFactor "90.000000") (elecCondVal "595900.000000 mho/cm") (thermCondVal "0 w/cm-degC")) ("" (layerType "DIELECTRIC") (material "FR-4") (thickness "  4.500000 mil") (dielectricConstant "4.100000") (lossTangent "0.035") (etchFactor "0.000000") (elecCondVal "0 mho/cm") (thermCondVal "0.012 w/cm-degC")) ("L7_PWR1-SIG" (layerType "PLANE") (material "COPPER") (isShield t) (thickness "  2.400000 mil") (dielectricConstant "4.500000") (lossTangent "0.035") (etchFactor "90.000000") (elecCondVal "595900.000000 mho/cm") (thermCondVal "0.012 w/cm-degC")) ("" (layerType "DIELECTRIC") (material "FR-4") (thickness "  4.600000 mil") (dielectricConstant "4.000000") (lossTangent "0.035") (etchFactor "0.000000") (elecCondVal "0 mho/cm") (thermCondVal "0.012 w/cm-degC")) ("L8_PWR2-SIG" (layerType "PLANE") (material "COPPER") (isShield t) (thickness "  2.400000 mil") (dielectricConstant "4.500000") (lossTangent "0.035") (etchFactor "90.000000") (elecCondVal "595900.000000 mho/cm") (thermCondVal "0.012 w/cm-degC")) ("" (layerType "DIELECTRIC") (material "FR-4") (thickness "  4.500000 mil") (dielectricConstant "4.500000") (lossTangent "0.035") (etchFactor "0.000000") (elecCondVal "0 mho/cm") (thermCondVal "0 w/cm-degC")) ("L9_GND4" (layerType "PLANE") (material "COPPER") (isShield t) (thickness "  1.250000 mil") (dielectricConstant "4.500000") (lossTangent "0.035") (etchFactor "90.000000") (elecCondVal "595900.000000 mho/cm") (thermCondVal "0 w/cm-degC")) ("" (layerType "DIELECTRIC") (material "FR-4") (thickness "  3.000000 mil") (dielectricConstant "4.100000") (lossTangent "0.035") (etchFactor "0.000000") (elecCondVal "0 mho/cm") (thermCondVal "0.012 w/cm-degC")) ("L10_SIG3" (layerType "CONDUCTOR") (material "COPPER") (thickness "  1.250000 mil") (width "4.00 MIL") (dielectricConstant "4.500000") (lossTangent "0.035") (etchFactor "90.000000") (elecCondVal "595900.000000 mho/cm") (thermCondVal "0.012 w/cm-degC") (signalDieConstant "4.100000") (signalLossTangent "0.035")) ("" (layerType "DIELECTRIC") (material "FR-4") (thickness "  9.000000 mil") (dielectricConstant "4.500000") (lossTangent "0.035") (etchFactor "0.000000") (elecCondVal "0 mho/cm") (thermCondVal "0 w/cm-degC")) ("L11_GND5" (layerType "PLANE") (material "COPPER") (isShield t) (thickness "  1.250000 mil") (dielectricConstant "4.500000") (lossTangent "0.035") (etchFactor "90.000000") (elecCondVal "595900.000000 mho/cm") (thermCondVal "0 w/cm-degC")) ("" (layerType "DIELECTRIC") (material "FR-4") (thickness "  3.000000 mil") (dielectricConstant "4.500000") (lossTangent "0.035") (etchFactor "0.000000") (elecCondVal "0 mho/cm") (thermCondVal "0.012 w/cm-degC")) ("L12_SIG4" (layerType "CONDUCTOR") (material "COPPER") (thickness "  1.250000 mil") (width "4.00 MIL") (dielectricConstant "4.500000") (lossTangent "0.035") (etchFactor "90.000000") (elecCondVal "595900.000000 mho/cm") (thermCondVal "0.012 w/cm-degC") (signalDieConstant "4.500000") (signalLossTangent "0.035")) ("" (layerType "DIELECTRIC") (material "FR-4") (thickness "  9.000000 mil") (dielectricConstant "4.500000") (lossTangent "0.035") (etchFactor "0.000000") (elecCondVal "0 mho/cm") (thermCondVal "0 w/cm-degC")) ("L13_GND6" (layerType "PLANE") (material "COPPER") (isShield t) (thickness "  1.250000 mil") (dielectricConstant "4.500000") (lossTangent "0.035") (etchFactor "90.000000") (elecCondVal "595900.000000 mho/cm") (thermCondVal "0.012 w/cm-degC")) ("" (layerType "DIELECTRIC") (material "FR-4") (thickness "  2.670000 mil") (dielectricConstant "4.500000") (lossTangent "0.035") (etchFactor "0.000000") (elecCondVal "0 mho/cm") (thermCondVal "0.012 w/cm-degC")) ("BOTTOM" (layerType "CONDUCTOR") (material "COPPER") (thickness "  2.100000 mil") (width "4.00 MIL") (dielectricConstant "4.500000") (lossTangent "0") (etchFactor "70.000000") (elecCondVal "595900.000000 mho/cm") (thermCondVal "0 w/cm-degC") (signalDieConstant "3.800000") (signalLossTangent "0.035")) ("" (layerType "DIELECTRIC") (material "CONFORMAL_COAT") (thickness "0.5 mil") (dielectricConstant "3.800000") (lossTangent "0.035") (etchFactor "0.000000") (elecCondVal "0 mho/cm") (thermCondVal "0.012 w/cm-degC")) ("" (layerType "SURFACE") (material "AIR") (thickness "0 mil") (dielectricConstant "1.000000") (lossTangent "0") (etchFactor "0.000000") (elecCondVal "0 mho/cm") (thermCondVal "0 w/cm-degC"))))) (Props (DesUnits "mils 2") (LayerStack ("DIELECTRIC" "DIELECTRIC" "BOTTOM" "DIELECTRIC" "L13_GND6" "DIELECTRIC" "L12_SIG4" "DIELECTRIC" "L11_GND5" "DIELECTRIC" "L10_SIG3" "DIELECTRIC" "L9_GND4" "DIELECTRIC" "L8_PWR2-SIG" "DIELECTRIC" "L7_PWR1-SIG" "DIELECTRIC" "L6_GND3" "DIELECTRIC" "L5_SIG2" "DIELECTRIC" "L4_GND2" "DIELECTRIC" "L3_SIG1" "DIELECTRIC" "L2_GND1" "DIELECTRIC" "TOP" "DIELECTRIC" "DIELECTRIC")) (Revision "16.600")) (Params (Trace ((d1Thickness "10 mil") (d1Constant "4.5") (d1LossTangent "0.035") (d2Thickness "10 mil") (d2Constant "4.5") (d2LossTangent "0.035") (d3Thickness "0.0") (d3Constant "1.0") (d3LossTangent "0") length("1000 mil") (spacing "5 mil") (spacing2 "5 mil") (spacing3 "5 mil") (spacing4 "5 mil") (spacing5 "5 mil") (traceConductivity "595900 mho/cm") (traceGeometry "microstrip") (traceLayerName "") (traceThickness "0.72 mil") (traceType "single") (traceWidth "5.0 mil") (traceWidth2 "5.0 mil") (traceWidth3 "5.0 mil") (traceWidth4 "5.0 mil") (traceWidth5 "5.0 mil") (traceWidth6 "5.0 mil") (offset "0 mil") (traceCount "1") (impedance nil))) (Cable (length("1 m"))) (Via ((model "Unknown") (viaOutputFormat "Unknown") (viaPadstack nil) (viaTopLayer nil) (viaBottomLayer nil) (viaIsPower nil) (viaIsGround nil))) (TLine ((diffImpedance "100ohm") (diffVelocity "1.4142e+08M/s") (impedance "60ohm") length("2800 mil") (propDelay "0.5 ns") (velocity "5600 mil/ns") (traceCount "1") (traceGeometry "Microstrip") (impedanceMin nil) (impedanceMax nil) (lengthMin nil) (lengthMax nil) (propDelayMin nil) (propDelayMax nil) (impedanceSweepCount nil) (propDelaySweepCount nil) (velocitySweepCount nil) (lengthSweepCount nil) (matchSetName nil))) (async ((asyncTimePoints "") (asyncInitState "1"))) (DualClampTerm ((cutoffVoltageUp "0.7 V") (cutoffVoltageDown "0.7 V") (voltageUp "5 V") (voltageDown "0 V") (maxDelay "0.1 ns"))) (Diode ((cutoffVoltage "0.7 V"))) (RCTerm ((resistance "50 ohm") (capacitance "20 pF") (voltage "5 V") (maxDelay "0.1 ns"))) (TheveninTerm ((resistanceUp "180 ohm") (resistanceDown "270 ohm") (voltageUp "5 V") (voltageDown "0 V") (maxDelay "0.1 ns"))) (ShuntTerm ((resistance "50 ohm") (voltage "5 V") (maxDelay "0.1 ns"))) (SeriesTerm ((resistance "22 ohm") (maxDelay "0.1 ns"))) (Connector nil) (CurrentProbe nil) (HiClampTerm ((cutoffVoltage "0.7 V") (voltage "5 V") (maxDelay "0.1 ns"))) (LowClampTerm ((cutoffVoltage "0.7 V") (voltage "0 V") (maxDelay "0.1 ns"))) (CPW ((d1Thickness "10 mil") (d1Constant "4.5") (d1LossTangent "0.035") (d2Thickness "0.72 mil") (d2Constant "1") (d2LossTangent "0") (d3Thickness "0.0") (d3Constant "1") (d3LossTangent "0") length("1000 mil") (spacing "5 mil") (spacing2 "5 mil") (spacing3 "5 mil") (spacing4 "5 mil") (spacing5 "5 mil") (traceConductivity "595900 mho/cm") (traceGeometry "cpwms") (traceLayerName "") (traceThickness "0.72 mil") (traceType "single") (traceWidth "5.0 mil") (traceWidth2 "5.0 mil") (traceWidth3 "5.0 mil") (traceWidth4 "5.0 mil") (traceWidth5 "5.0 mil") (traceWidth6 "5.0 mil") (offset "0 mil") (traceCount "1") (impedance nil))) (sync ((syncFreq "100e6") (syncInitState "1") (syncPattern "10") (syncEdgeSwitch "rise"))) (DiffInput ((temperature "27") (bufferModelNonInverting "CDSDefaultInput_2p5v") (bufferModelInverting "CDSDefaultInput_2p5v") (threshInputHighMin "1.7 V") (threshInputHighTyp "1.7  V") (threshInputHighMax "1.7  V") (threshInputLowMin "0.7  V") (threshInputLowTyp "0.7  V") (threshInputLowMax "0.7  V") (mappingTagNonInverting nil) (mappingTagInverting nil) (cycle "1"))) (DiffOutputPkg ((temperature "27") (bufferModelNonInverting "CDSDefaultOutput_2p5v") (bufferModelInverting "CDSDefaultOutput_2p5v") (stimuli nil) (offsets nil) (state "tristate") (cycle "1") (termMap nil) (setup "0.9e-09") (hold "0.4e-09") (rise nil) (fall nil) (threshOutputHighMin "2.375  V") (threshOutputHighTyp "2.5  V") (threshOutputHighMax "2.625  V") (threshOutputLowMin "1.275  V") (threshOutputLowTyp "1.7  V") (threshOutputLowMax "1.985  V") (mappingTagNonInverting nil) (mappingTagInverting nil) (spice nil))) (CPWMS ((d1Thickness "10 mil") (d1Constant "4.5") (d1LossTangent "0.035") (d2Thickness "0.72 mil") (d2Constant "4.5") (d2LossTangent "0.035") (d3Thickness "0.0") (d3Constant "1") (d3LossTangent "0") length("1000 mil") (spacing "5 mil") (spacing2 "5 mil") (spacing3 "5 mil") (spacing4 "5 mil") (spacing5 "5 mil") (traceConductivity "595900 mho/cm") (traceGeometry "cpwms") (traceLayerName "") (traceThickness "0.72 mil") (traceType "single") (traceWidth "5.0 mil") (traceWidth2 "5.0 mil") (traceWidth3 "5.0 mil") (traceWidth4 "5.0 mil") (traceWidth5 "5.0 mil") (traceWidth6 "5.0 mil") (offset "0 mil") (traceCount "1") (impedance nil))) (DiffOutput ((temperature "27") (bufferModelNonInverting "CDSDefaultOutput_2p5v") (bufferModelInverting "CDSDefaultOutput_2p5v") (stimuli nil) (offsets nil) (state "tristate") (cycle "1") (termMap nil) (setup "0.9e-09") (hold "0.4e-09") (rise nil) (fall nil) (threshOutputHighMin "2.375  V") (threshOutputHighTyp "2.5  V") (threshOutputHighMax "2.625  V") (threshOutputLowMin "1.275  V") (threshOutputLowTyp "1.7  V") (threshOutputLowMax "1.985  V") (mappingTagNonInverting nil) (mappingTagInverting nil) (spice nil))) (CPWSL ((d1Thickness "10 mil") (d1Constant "4.5") (d1LossTangent "0.035") (d2Thickness "0.72 mil") (d2Constant "4.5") (d2LossTangent "0.035") (d3Thickness "10 mil") (d3Constant "4.5") (d3LossTangent "0.035") length("1000 mil") (spacing "5 mil") (spacing2 "5 mil") (spacing3 "5 mil") (spacing4 "5 mil") (spacing5 "5 mil") (traceConductivity "595900 mho/cm") (traceGeometry "cpwms") (traceLayerName "") (traceThickness "0.72 mil") (traceType "single") (traceWidth "5.0 mil") (traceWidth2 "5.0 mil") (traceWidth3 "5.0 mil") (traceWidth4 "5.0 mil") (traceWidth5 "5.0 mil") (traceWidth6 "5.0 mil") (offset "0 mil") (traceCount "1") (impedance nil))) (DiffIOPkg ((temperature "27") (bufferModelNonInverting "CDSDefaultIO_2p5v") (bufferModelInverting "CDSDefaultIO_2p5v") (stimuli nil) (offsets nil) (state "tristate") (cycle "1") (termMap nil) (setup "0.9e-09") (hold "0.4e-09") (rise nil) (fall nil) (threshInputHighMin "1.7 V") (threshInputHighTyp "1.7  V") (threshInputHighMax "1.7  V") (threshInputLowMin "0.7  V") (threshInputLowTyp "0.7  V") (threshInputLowMax "0.7 ") (threshOutputHighMin "2.365  V") (threshOutputHighTyp "2.5  V") (threshOutputHighMax "2.625  V") (threshOutputLowMin "1.275  V") (threshOutputLowTyp "1.7  V") (threshOutputLowMax "1.985  V") (mappingTagNonInverting nil) (mappingTagInverting nil) (spice nil))) (DiffIO ((temperature "27") (bufferModelNonInverting "CDSDefaultIO_2p5v") (bufferModelInverting "CDSDefaultIO_2p5v") (stimuli nil) (offsets nil) (state "tristate") (cycle "1") (termMap nil) (setup "0.9e-09") (hold "0.4e-09") (rise nil) (fall nil) (threshInputHighMin "1.7 V") (threshInputHighTyp "1.7  V") (threshInputHighMax "1.7  V") (threshInputLowMin "0.7  V") (threshInputLowTyp "0.7  V") (threshInputLowMax "0.7 ") (threshOutputHighMin "2.365  V") (threshOutputHighTyp "2.5  V") (threshOutputHighMax "2.625  V") (threshOutputLowMin "1.275  V") (threshOutputLowTyp "1.7  V") (threshOutputLowMax "1.985  V") (mappingTagNonInverting nil) (mappingTagInverting nil) (spice nil))) (Resistor ((resistance "50 ohm") (orientation "0"))) (IbisIO_OpenPullDown ((temperature "27") (bufferModel "CDSDefaultIO_2p5v") (stimuli nil) (offsets nil) (state "tristate") (cycle "1") (termMap nil) (setup "2.0e-09") (hold "1.0e-09") (rise nil) (fall nil) (macroType nil) (voltage nil) (spice nil) (LEFDEFPinName nil) (LEFDEFPinType nil) (mappingTag nil))) (idlCircuit ((allDrivers "active") (ftsMode '("Typ")) (rcvrSelect "all") (simMode "Reflection") (tlineDelayMode "time") (userRevision "1.0") (autoSolve "On"))) (IbisInput ((temperature "27") (bufferModel "CDSDefaultInput_2p5v") (cycle "1") (LEFDEFPinName nil) (LEFDEFPinType nil) (mappingTag nil))) (IbisInputPkg ((temperature "27") (bufferModel "CDSDefaultInput_2p5v") (cycle "1") (LEFDEFPinName nil) (LEFDEFPinType nil) (mappingTag nil))) (IbisIO_OpenPullUp ((temperature "27") (bufferModel "CDSDefaultIO_2p5v") (stimuli nil) (offsets nil) (state "tristate") (cycle "1") (termMap nil) (setup "2.0e-09") (hold "1.0e-09") (rise nil) (fall nil) (macroType nil) (voltage nil) (spice nil) (LEFDEFPinName nil) (LEFDEFPinType nil) (mappingTag nil))) (Capacitor ((capacitance "10 pF") (orientation "0"))) (Inductor ((inductance "5 nH") (orientation "0"))) (IbisIOMacro ((temperature "27") (bufferModel "CDSDefaultIO_2p5v") (stimuli nil) (offsets nil) (state "tristate") (cycle "1") (termMap nil) (setup "2.0e-09") (hold "1.0e-09") (rise nil) (fall nil) (macroType nil) (voltage nil) (spice nil) (LEFDEFPinName nil) (LEFDEFPinType nil) (mappingTag nil))) (IbisOutput_OpenPullUp ((temperature "27") (bufferModel "CDSDefaultOutput_2p5v") (stimuli nil) (offsets nil) (state "tristate") (cycle "1") (termMap nil) (setup "2.0e-09") (hold "1.0e-09") (rise nil) (fall nil) (macroType nil) (voltage nil) (spice nil) (LEFDEFPinName nil) (LEFDEFPinType nil) (mappingTag nil))) (IbisIOPkg ((temperature "27") (bufferModel "CDSDefaultIO_2p5v") (stimuli nil) (offsets nil) (state "tristate") (cycle "1") (termMap nil) (setup "2.0e-09") (hold "1.0e-09") (rise nil) (fall nil) (macroType nil) (voltage nil) (spice nil) (LEFDEFPinName nil) (LEFDEFPinType nil) (mappingTag nil))) (RLGC (length("1000 mil"))) (ESpiceDevice nil) (IbisOutputPkg ((temperature "27") (bufferModel "CDSDefaultOutput_2p5v") (stimuli nil) (offsets nil) (state "tristate") (cycle "1") (termMap nil) (setup "2.0e-09") (hold "1.0e-09") (rise nil) (fall nil) (macroType nil) (voltage nil) (spice nil) (LEFDEFPinName nil) (LEFDEFPinType nil) (mappingTag nil))) (IbisIO ((temperature "27") (bufferModel "CDSDefaultIO_2p5v") (stimuli nil) (offsets nil) (state "tristate") (cycle "1") (termMap nil) (setup "2.0e-09") (hold "1.0e-09") (rise nil) (fall nil) (macroType nil) (voltage nil) (spice nil) (LEFDEFPinName nil) (LEFDEFPinType nil) (mappingTag nil))) (periodic ((periodicFreq "100e6") (periodicPattern "10") (periodicJitter "0"))) (clocked ((clockRise "1e-09") (clockFall "1e-09") (clockFreq "100e6") (clockInitState "0") (clockDutyCycle "0.5") (clockJitter "0"))) (DiffInputPkg ((temperature "27") (bufferModelNonInverting "CDSDefaultInput_2p5v") (bufferModelInverting "CDSDefaultInput_2p5v") (threshInputHighMin "1.7 V") (threshInputHighTyp "1.7  V") (threshInputHighMax "1.7  V") (threshInputLowMin "0.7  V") (threshInputLowTyp "0.7  V") (threshInputLowMax "0.7  V") (mappingTagNonInverting nil) (mappingTagInverting nil) (cycle "1"))) (IbisOutput ((temperature "27") (bufferModel "CDSDefaultOutput_2p5v") (stimuli nil) (offsets nil) (state "tristate") (cycle "1") (termMap nil) (setup "2.0e-09") (hold "1.0e-09") (rise nil) (fall nil) (macroType nil) (voltage nil) (spice nil) (LEFDEFPinName nil) (LEFDEFPinType nil) (mappingTag nil))) (Source ((voltage "5 V")))))
				)
				( objectStatus "RMII_SPRNGVLLE_BMC_PCH_RXD0" )
			)
			( electricalCSet "@crescent_city_bb_fab1_lib.crescent_city_bb_fab1(sch_1):\RMII_RX_1\"
				( pinPairRef "RMII_RX_1:U9F4.C8:U7C1.AH2" )
				( attribute "TOPOLOGY_TEMPLATE_REVISION" "1.0"
					( Origin gBackEnd )
				)
				( topologyData 23358
(SKIDL (Circuits ("MAIN" (Parts ("CRESCENT_CITY_180_20141223_Q.@@U47.C8" IbisInputPkg (xy (5505 4222)) (refDes "U9F4") (model "Unknown") (Props (_SXDesignName "CRESCENT_CITY_180_20141223_Q") (brdx "17650.28 MIL") (brdy "708.76 MIL") (bufferModel "CDSDefaultInput_2p5v") (mappingTag "") (temperature "27")) (Terms ("CRESCENT_CITY_180_20141223_Q.X1765028Y70876L2LRATS" "C8"))) ("CRESCENT_CITY_180_20141223_Q.@@U22.AH2" IbisIOPkg (xy (5502 4240)) (refDes "U7C1") (model "Unknown") (Props (_SXDesignName "CRESCENT_CITY_180_20141223_Q") (brdx "15215.94 MIL") (brdy "3699.21 MIL") (bufferModel "CDSDefaultIO_2p5v") (cycle "1") (hold "1.0e-09") (mappingTag "") (offsets ("4" "0") ("5" "0")) (setup "2.0e-09") (state "tristate") (stimuli ("5" "local31") ("4" "local30")) (temperature "27") (termMap ("4" "Data") ("5" "Enable"))) (Terms ("CRESCENT_CITY_180_20141223_Q.X1521594Y369921L2LRATS" "AH2"))) ("CRESCENT_CITY_180_20141223_Q.@@R2394.2.1" Resistor (xy (5488 4229)) (mirror x) (refDes "R7D13") (value "1 Ohm") (Props (_SXDesignName "CRESCENT_CITY_180_20141223_Q")) (Terms ("CRESCENT_CITY_180_20141223_Q.X1527000Y349000L2LRATS" "2") ("CRESCENT_CITY_180_20141223_Q.X1527000Y345500L2RATS" "1"))) ("CRESCENT_CITY_180_20141223_Q.@@R2394.1_SOURCE" Source (xy (5475 4229)) (refDes "P3V3_STBY") (value "3.3 V") (Props (_SXDesignName "CRESCENT_CITY_180_20141223_Q")) (Terms ("CRESCENT_CITY_180_20141223_Q.X1527000Y345500L2RATS" "1"))) ("CRESCENT_CITY_180_20141223_Q.T@@RATS@@R2394.2@@U47.C8" TLine (xy (5497 4222)) (refDes "TL19") (Props (_SXDesignName "CRESCENT_CITY_180_20141223_Q") (impedance "60 ohm") length("5161.54 MIL") (propDelay "0.927044 ns") (traceCount "1") (traceGeometry "Microstrip") (velocity "5567.76 mil/ns")) (Terms ("CRESCENT_CITY_180_20141223_Q.X1527000Y349000L2LRATS" "1") ("CRESCENT_CITY_180_20141223_Q.X1765028Y70876L2LRATS" "2"))) ("CRESCENT_CITY_180_20141223_Q.T@@RATS@@R2394.2@@U22.AH2" TLine (xy (5497 4229)) (refDes "TL20") (Props (_SXDesignName "CRESCENT_CITY_180_20141223_Q") (impedance "52.449 ohm") length("263.27 MIL") (propDelay "0.04729 ns") (traceCount "1") (traceGeometry "Microstrip") (velocity "5567.13 mil/ns")) (Terms ("CRESCENT_CITY_180_20141223_Q.X1527000Y349000L2LRATS" "1") ("CRESCENT_CITY_180_20141223_Q.X1521594Y369921L2LRATS" "2")))) (Nodes ("CRESCENT_CITY_180_20141223_Q.X1527000Y345500L2RATS" (terms "CRESCENT_CITY_180_20141223_Q.@@R2394.1_SOURCE.1" "CRESCENT_CITY_180_20141223_Q.@@R2394.2.1.2")) ("CRESCENT_CITY_180_20141223_Q.X1521594Y369921L2LRATS" (terms "CRESCENT_CITY_180_20141223_Q.T@@RATS@@R2394.2@@U22.AH2.2" "CRESCENT_CITY_180_20141223_Q.@@U22.AH2.1")) ("CRESCENT_CITY_180_20141223_Q.X1527000Y349000L2LRATS" (terms "CRESCENT_CITY_180_20141223_Q.T@@RATS@@R2394.2@@U22.AH2.1" "CRESCENT_CITY_180_20141223_Q.T@@RATS@@R2394.2@@U47.C8.1" "CRESCENT_CITY_180_20141223_Q.@@R2394.2.1.1")) ("CRESCENT_CITY_180_20141223_Q.X1765028Y70876L2LRATS" (terms "CRESCENT_CITY_180_20141223_Q.T@@RATS@@R2394.2@@U47.C8.2" "CRESCENT_CITY_180_20141223_Q.@@U47.C8.1"))) (Ports) (Stimuli ("local30" (scope local) (stimType periodic) (Props (periodicFreq "5e+007") (periodicJitter "0") (periodicPattern "1"))) ("local15" (scope local) (stimType periodic) (Props (periodicFreq "5e+007") (periodicJitter "0") (periodicPattern "1"))) ("local14" (scope local) (stimType periodic) (Props (periodicFreq "5e+007") (periodicJitter "0") (periodicPattern "1"))) ("local16" (scope local) (stimType periodic) (Props (periodicFreq "5e+007") (periodicJitter "0") (periodicPattern "1"))) ("local31" (scope local) (stimType periodic) (Props (periodicFreq "5e+007") (periodicJitter "0") (periodicPattern "1")))) (Notes) (Constraints ("DELAY_RULE" ("CRESCENT_CITY_180_20141223_Q U47.C8" "CRESCENT_CITY_180_20141223_Q U22.AH2" "LENGTH" "0.2032" "LENGTH" "0.3556"))) (MeasurementSets ("EMI" ("EMIStatus" status("on")) ("PeakEmission" status("on")) ("PeakFrequency" status("on")) ("PulseFreq" status("on")) ("RiseTime" status("on")) ("VoltageSwing" status("on"))) ("Reflection" ("BufferDelayFall" status("off")) ("BufferDelayRise" status("off")) ("EyeHeight" status("off")) ("EyeJitter" status("off")) ("EyeWidth" status("off")) ("FirstIncidentFall" status("off")) ("FirstIncidentRise" status("off")) ("Glitch" status("on")) ("GlitchFall" status("off")) ("GlitchRise" status("off")) ("Monotonic" status("on")) ("MonotonicFall" status("off")) ("MonotonicRise" status("off")) ("NoiseMargin" status("on")) ("NoiseMarginHigh" status("off")) ("NoiseMarginLow" status("off")) ("OvershootHigh" status("on")) ("OvershootLow" status("on")) ("PropDelay" status("on")) ("SettleDelay" status("on")) ("SettleDelayFall" status("off")) ("SettleDelayRise" status("off")) ("SwitchDelay" status("on")) ("SwitchDelayFall" status("off")) ("SwitchDelayRise" status("off"))) ("Crosstalk" ("Crosstalk" status("on"))) ("Custom")) (VectorSets) (Props (XnetName "RMII_BMC_PCH_SPRNGVLLE_RXER") (allDrivers "active") (customSimType "Reflection") (ftsMode ("Typ")) (rcvrSelect "all") (tlineDelayMode "time") (userRevision "1.0")))) (Subckts) (CrossSections ("CRESCENT_CITY_180_20141223_Q" (Props (SXDesignName "CRESCENT_CITY_180_20141223_Q")) (Layers ("" (layerType "SURFACE") (material "AIR") (thickness "0 mil") (dielectricConstant "1.000000") (lossTangent "0") (etchFactor "0.000000") (elecCondVal "0 mho/cm") (thermCondVal "0 w/cm-degC")) ("" (layerType "DIELECTRIC") (material "CONFORMAL_COAT") (thickness "0.5 mil") (dielectricConstant "3.800000") (lossTangent "0.035") (etchFactor "0.000000") (elecCondVal "0 mho/cm") (thermCondVal "0.012 w/cm-degC")) ("TOP" (layerType "CONDUCTOR") (material "COPPER") (thickness "  2.100000 mil") (width "4.00 MIL") (dielectricConstant "4.500000") (lossTangent "0") (etchFactor "70.000000") (elecCondVal "595900.000000 mho/cm") (thermCondVal "0 w/cm-degC") (signalDieConstant "3.800000") (signalLossTangent "0.035")) ("" (layerType "DIELECTRIC") (material "FR-4") (thickness "  2.670000 mil") (dielectricConstant "4.000000") (lossTangent "0.035") (etchFactor "0.000000") (elecCondVal "0 mho/cm") (thermCondVal "0.012 w/cm-degC")) ("L2_GND1" (layerType "PLANE") (material "COPPER") (isShield t) (thickness "  1.250000 mil") (dielectricConstant "4.500000") (lossTangent "0.035") (etchFactor "90.000000") (elecCondVal "595900.000000 mho/cm") (thermCondVal "0.012 w/cm-degC")) ("" (layerType "DIELECTRIC") (material "FR-4") (thickness "  9.000000 mil") (dielectricConstant "4.100000") (lossTangent "0.035") (etchFactor "0.000000") (elecCondVal "0 mho/cm") (thermCondVal "0.012 w/cm-degC")) ("L3_SIG1" (layerType "CONDUCTOR") (material "COPPER") (thickness "  1.250000 mil") (width "4.00 MIL") (dielectricConstant "4.500000") (lossTangent "0.035") (etchFactor "90.000000") (elecCondVal "595900.000000 mho/cm") (thermCondVal "0.012 w/cm-degC") (signalDieConstant "4.100000") (signalLossTangent "0.035")) ("" (layerType "DIELECTRIC") (material "FR-4") (thickness "  3.000000 mil") (dielectricConstant "4.500000") (lossTangent "0.035") (etchFactor "0.000000") (elecCondVal "0 mho/cm") (thermCondVal "0 w/cm-degC")) ("L4_GND2" (layerType "PLANE") (material "COPPER") (isShield t) (thickness "  1.250000 mil") (dielectricConstant "4.500000") (lossTangent "0.035") (etchFactor "90.000000") (elecCondVal "595900.000000 mho/cm") (thermCondVal "0 w/cm-degC")) ("" (layerType "DIELECTRIC") (material "FR-4") (thickness "  9.000000 mil") (dielectricConstant "4.000000") (lossTangent "0.035") (etchFactor "0.000000") (elecCondVal "0 mho/cm") (thermCondVal "0.012 w/cm-degC")) ("L5_SIG2" (layerType "CONDUCTOR") (material "COPPER") (thickness "  1.250000 mil") (width "4.00 MIL") (dielectricConstant "4.500000") (lossTangent "0.035") (etchFactor "90.000000") (elecCondVal "595900.000000 mho/cm") (thermCondVal "0.012 w/cm-degC") (signalDieConstant "4.000000") (signalLossTangent "0.035")) ("" (layerType "DIELECTRIC") (material "FR-4") (thickness "  3.000000 mil") (dielectricConstant "4.500000") (lossTangent "0.035") (etchFactor "0.000000") (elecCondVal "0 mho/cm") (thermCondVal "0 w/cm-degC")) ("L6_GND3" (layerType "PLANE") (material "COPPER") (isShield t) (thickness "  1.250000 mil") (dielectricConstant "4.500000") (lossTangent "0.035") (etchFactor "90.000000") (elecCondVal "595900.000000 mho/cm") (thermCondVal "0 w/cm-degC")) ("" (layerType "DIELECTRIC") (material "FR-4") (thickness "  4.500000 mil") (dielectricConstant "4.100000") (lossTangent "0.035") (etchFactor "0.000000") (elecCondVal "0 mho/cm") (thermCondVal "0.012 w/cm-degC")) ("L7_PWR1-SIG" (layerType "PLANE") (material "COPPER") (isShield t) (thickness "  2.400000 mil") (dielectricConstant "4.500000") (lossTangent "0.035") (etchFactor "90.000000") (elecCondVal "595900.000000 mho/cm") (thermCondVal "0.012 w/cm-degC")) ("" (layerType "DIELECTRIC") (material "FR-4") (thickness "  4.600000 mil") (dielectricConstant "4.000000") (lossTangent "0.035") (etchFactor "0.000000") (elecCondVal "0 mho/cm") (thermCondVal "0.012 w/cm-degC")) ("L8_PWR2-SIG" (layerType "PLANE") (material "COPPER") (isShield t) (thickness "  2.400000 mil") (dielectricConstant "4.500000") (lossTangent "0.035") (etchFactor "90.000000") (elecCondVal "595900.000000 mho/cm") (thermCondVal "0.012 w/cm-degC")) ("" (layerType "DIELECTRIC") (material "FR-4") (thickness "  4.500000 mil") (dielectricConstant "4.500000") (lossTangent "0.035") (etchFactor "0.000000") (elecCondVal "0 mho/cm") (thermCondVal "0 w/cm-degC")) ("L9_GND4" (layerType "PLANE") (material "COPPER") (isShield t) (thickness "  1.250000 mil") (dielectricConstant "4.500000") (lossTangent "0.035") (etchFactor "90.000000") (elecCondVal "595900.000000 mho/cm") (thermCondVal "0 w/cm-degC")) ("" (layerType "DIELECTRIC") (material "FR-4") (thickness "  3.000000 mil") (dielectricConstant "4.100000") (lossTangent "0.035") (etchFactor "0.000000") (elecCondVal "0 mho/cm") (thermCondVal "0.012 w/cm-degC")) ("L10_SIG3" (layerType "CONDUCTOR") (material "COPPER") (thickness "  1.250000 mil") (width "4.00 MIL") (dielectricConstant "4.500000") (lossTangent "0.035") (etchFactor "90.000000") (elecCondVal "595900.000000 mho/cm") (thermCondVal "0.012 w/cm-degC") (signalDieConstant "4.100000") (signalLossTangent "0.035")) ("" (layerType "DIELECTRIC") (material "FR-4") (thickness "  9.000000 mil") (dielectricConstant "4.500000") (lossTangent "0.035") (etchFactor "0.000000") (elecCondVal "0 mho/cm") (thermCondVal "0 w/cm-degC")) ("L11_GND5" (layerType "PLANE") (material "COPPER") (isShield t) (thickness "  1.250000 mil") (dielectricConstant "4.500000") (lossTangent "0.035") (etchFactor "90.000000") (elecCondVal "595900.000000 mho/cm") (thermCondVal "0 w/cm-degC")) ("" (layerType "DIELECTRIC") (material "FR-4") (thickness "  3.000000 mil") (dielectricConstant "4.500000") (lossTangent "0.035") (etchFactor "0.000000") (elecCondVal "0 mho/cm") (thermCondVal "0.012 w/cm-degC")) ("L12_SIG4" (layerType "CONDUCTOR") (material "COPPER") (thickness "  1.250000 mil") (width "4.00 MIL") (dielectricConstant "4.500000") (lossTangent "0.035") (etchFactor "90.000000") (elecCondVal "595900.000000 mho/cm") (thermCondVal "0.012 w/cm-degC") (signalDieConstant "4.500000") (signalLossTangent "0.035")) ("" (layerType "DIELECTRIC") (material "FR-4") (thickness "  9.000000 mil") (dielectricConstant "4.500000") (lossTangent "0.035") (etchFactor "0.000000") (elecCondVal "0 mho/cm") (thermCondVal "0 w/cm-degC")) ("L13_GND6" (layerType "PLANE") (material "COPPER") (isShield t) (thickness "  1.250000 mil") (dielectricConstant "4.500000") (lossTangent "0.035") (etchFactor "90.000000") (elecCondVal "595900.000000 mho/cm") (thermCondVal "0.012 w/cm-degC")) ("" (layerType "DIELECTRIC") (material "FR-4") (thickness "  2.670000 mil") (dielectricConstant "4.500000") (lossTangent "0.035") (etchFactor "0.000000") (elecCondVal "0 mho/cm") (thermCondVal "0.012 w/cm-degC")) ("BOTTOM" (layerType "CONDUCTOR") (material "COPPER") (thickness "  2.100000 mil") (width "4.00 MIL") (dielectricConstant "4.500000") (lossTangent "0") (etchFactor "70.000000") (elecCondVal "595900.000000 mho/cm") (thermCondVal "0 w/cm-degC") (signalDieConstant "3.800000") (signalLossTangent "0.035")) ("" (layerType "DIELECTRIC") (material "CONFORMAL_COAT") (thickness "0.5 mil") (dielectricConstant "3.800000") (lossTangent "0.035") (etchFactor "0.000000") (elecCondVal "0 mho/cm") (thermCondVal "0.012 w/cm-degC")) ("" (layerType "SURFACE") (material "AIR") (thickness "0 mil") (dielectricConstant "1.000000") (lossTangent "0") (etchFactor "0.000000") (elecCondVal "0 mho/cm") (thermCondVal "0 w/cm-degC"))))) (Props (DesUnits "mils 2") (LayerStack ("DIELECTRIC" "DIELECTRIC" "BOTTOM" "DIELECTRIC" "L13_GND6" "DIELECTRIC" "L12_SIG4" "DIELECTRIC" "L11_GND5" "DIELECTRIC" "L10_SIG3" "DIELECTRIC" "L9_GND4" "DIELECTRIC" "L8_PWR2-SIG" "DIELECTRIC" "L7_PWR1-SIG" "DIELECTRIC" "L6_GND3" "DIELECTRIC" "L5_SIG2" "DIELECTRIC" "L4_GND2" "DIELECTRIC" "L3_SIG1" "DIELECTRIC" "L2_GND1" "DIELECTRIC" "TOP" "DIELECTRIC" "DIELECTRIC")) (Revision "16.600")) (Params (IbisIOPkg ((temperature "27") (bufferModel "CDSDefaultIO_2p5v") (stimuli nil) (offsets nil) (state "tristate") (cycle "1") (termMap nil) (setup "2.0e-09") (hold "1.0e-09") (rise nil) (fall nil) (macroType nil) (voltage nil) (spice nil) (LEFDEFPinName nil) (LEFDEFPinType nil) (mappingTag nil))) (IbisIOMacro ((temperature "27") (bufferModel "CDSDefaultIO_2p5v") (stimuli nil) (offsets nil) (state "tristate") (cycle "1") (termMap nil) (setup "2.0e-09") (hold "1.0e-09") (rise nil) (fall nil) (macroType nil) (voltage nil) (spice nil) (LEFDEFPinName nil) (LEFDEFPinType nil) (mappingTag nil))) (IbisInputPkg ((temperature "27") (bufferModel "CDSDefaultInput_2p5v") (cycle "1") (LEFDEFPinName nil) (LEFDEFPinType nil) (mappingTag nil))) (IbisOutputPkg ((temperature "27") (bufferModel "CDSDefaultOutput_2p5v") (stimuli nil) (offsets nil) (state "tristate") (cycle "1") (termMap nil) (setup "2.0e-09") (hold "1.0e-09") (rise nil) (fall nil) (macroType nil) (voltage nil) (spice nil) (LEFDEFPinName nil) (LEFDEFPinType nil) (mappingTag nil))) (periodic ((periodicFreq "100e6") (periodicPattern "10") (periodicJitter "0"))) (IbisIO_OpenPullUp ((temperature "27") (bufferModel "CDSDefaultIO_2p5v") (stimuli nil) (offsets nil) (state "tristate") (cycle "1") (termMap nil) (setup "2.0e-09") (hold "1.0e-09") (rise nil) (fall nil) (macroType nil) (voltage nil) (spice nil) (LEFDEFPinName nil) (LEFDEFPinType nil) (mappingTag nil))) (clocked ((clockRise "1e-09") (clockFall "1e-09") (clockFreq "100e6") (clockInitState "0") (clockDutyCycle "0.5") (clockJitter "0"))) (IbisIO ((temperature "27") (bufferModel "CDSDefaultIO_2p5v") (stimuli nil) (offsets nil) (state "tristate") (cycle "1") (termMap nil) (setup "2.0e-09") (hold "1.0e-09") (rise nil) (fall nil) (macroType nil) (voltage nil) (spice nil) (LEFDEFPinName nil) (LEFDEFPinType nil) (mappingTag nil))) (IbisIO_OpenPullDown ((temperature "27") (bufferModel "CDSDefaultIO_2p5v") (stimuli nil) (offsets nil) (state "tristate") (cycle "1") (termMap nil) (setup "2.0e-09") (hold "1.0e-09") (rise nil) (fall nil) (macroType nil) (voltage nil) (spice nil) (LEFDEFPinName nil) (LEFDEFPinType nil) (mappingTag nil))) (IbisOutput ((temperature "27") (bufferModel "CDSDefaultOutput_2p5v") (stimuli nil) (offsets nil) (state "tristate") (cycle "1") (termMap nil) (setup "2.0e-09") (hold "1.0e-09") (rise nil) (fall nil) (macroType nil) (voltage nil) (spice nil) (LEFDEFPinName nil) (LEFDEFPinType nil) (mappingTag nil))) (async ((asyncTimePoints "") (asyncInitState "1"))) (TLine ((diffImpedance "100ohm") (diffVelocity "1.4142e+08M/s") (impedance "60ohm") length("2800 mil") (propDelay "0.5 ns") (velocity "5600 mil/ns") (traceCount "1") (traceGeometry "Microstrip") (impedanceMin nil) (impedanceMax nil) (lengthMin nil) (lengthMax nil) (propDelayMin nil) (propDelayMax nil) (impedanceSweepCount nil) (propDelaySweepCount nil) (velocitySweepCount nil) (lengthSweepCount nil) (matchSetName nil))) (IbisInput ((temperature "27") (bufferModel "CDSDefaultInput_2p5v") (cycle "1") (LEFDEFPinName nil) (LEFDEFPinType nil) (mappingTag nil))) (SeriesTerm ((resistance "22 ohm") (maxDelay "0.1 ns"))) (Connector nil) (CurrentProbe nil) (IbisOutput_OpenPullUp ((temperature "27") (bufferModel "CDSDefaultOutput_2p5v") (stimuli nil) (offsets nil) (state "tristate") (cycle "1") (termMap nil) (setup "2.0e-09") (hold "1.0e-09") (rise nil) (fall nil) (macroType nil) (voltage nil) (spice nil) (LEFDEFPinName nil) (LEFDEFPinType nil) (mappingTag nil))) (sync ((syncFreq "100e6") (syncInitState "1") (syncPattern "10") (syncEdgeSwitch "rise"))) (DiffInputPkg ((temperature "27") (bufferModelNonInverting "CDSDefaultInput_2p5v") (bufferModelInverting "CDSDefaultInput_2p5v") (threshInputHighMin "1.7 V") (threshInputHighTyp "1.7  V") (threshInputHighMax "1.7  V") (threshInputLowMin "0.7  V") (threshInputLowTyp "0.7  V") (threshInputLowMax "0.7  V") (mappingTagNonInverting nil) (mappingTagInverting nil) (cycle "1"))) (idlCircuit ((allDrivers "active") (ftsMode '("Typ")) (rcvrSelect "all") (simMode "Reflection") (tlineDelayMode "time") (userRevision "1.0") (autoSolve "On"))) (Trace ((d1Thickness "10 mil") (d1Constant "4.5") (d1LossTangent "0.035") (d2Thickness "10 mil") (d2Constant "4.5") (d2LossTangent "0.035") (d3Thickness "0.0") (d3Constant "1.0") (d3LossTangent "0") length("1000 mil") (spacing "5 mil") (spacing2 "5 mil") (spacing3 "5 mil") (spacing4 "5 mil") (spacing5 "5 mil") (traceConductivity "595900 mho/cm") (traceGeometry "microstrip") (traceLayerName "") (traceThickness "0.72 mil") (traceType "single") (traceWidth "5.0 mil") (traceWidth2 "5.0 mil") (traceWidth3 "5.0 mil") (traceWidth4 "5.0 mil") (traceWidth5 "5.0 mil") (traceWidth6 "5.0 mil") (offset "0 mil") (traceCount "1") (impedance nil))) (DiffOutput ((temperature "27") (bufferModelNonInverting "CDSDefaultOutput_2p5v") (bufferModelInverting "CDSDefaultOutput_2p5v") (stimuli nil) (offsets nil) (state "tristate") (cycle "1") (termMap nil) (setup "0.9e-09") (hold "0.4e-09") (rise nil) (fall nil) (threshOutputHighMin "2.375  V") (threshOutputHighTyp "2.5  V") (threshOutputHighMax "2.625  V") (threshOutputLowMin "1.275  V") (threshOutputLowTyp "1.7  V") (threshOutputLowMax "1.985  V") (mappingTagNonInverting nil) (mappingTagInverting nil) (spice nil))) (HiClampTerm ((cutoffVoltage "0.7 V") (voltage "5 V") (maxDelay "0.1 ns"))) (Via ((model "Unknown") (viaOutputFormat "Unknown") (viaPadstack nil) (viaTopLayer nil) (viaBottomLayer nil) (viaIsPower nil) (viaIsGround nil))) (Resistor ((resistance "50 ohm") (orientation "0"))) (LowClampTerm ((cutoffVoltage "0.7 V") (voltage "0 V") (maxDelay "0.1 ns"))) (DiffOutputPkg ((temperature "27") (bufferModelNonInverting "CDSDefaultOutput_2p5v") (bufferModelInverting "CDSDefaultOutput_2p5v") (stimuli nil) (offsets nil) (state "tristate") (cycle "1") (termMap nil) (setup "0.9e-09") (hold "0.4e-09") (rise nil) (fall nil) (threshOutputHighMin "2.375  V") (threshOutputHighTyp "2.5  V") (threshOutputHighMax "2.625  V") (threshOutputLowMin "1.275  V") (threshOutputLowTyp "1.7  V") (threshOutputLowMax "1.985  V") (mappingTagNonInverting nil) (mappingTagInverting nil) (spice nil))) (RCTerm ((resistance "50 ohm") (capacitance "20 pF") (voltage "5 V") (maxDelay "0.1 ns"))) (DiffIO ((temperature "27") (bufferModelNonInverting "CDSDefaultIO_2p5v") (bufferModelInverting "CDSDefaultIO_2p5v") (stimuli nil) (offsets nil) (state "tristate") (cycle "1") (termMap nil) (setup "0.9e-09") (hold "0.4e-09") (rise nil) (fall nil) (threshInputHighMin "1.7 V") (threshInputHighTyp "1.7  V") (threshInputHighMax "1.7  V") (threshInputLowMin "0.7  V") (threshInputLowTyp "0.7  V") (threshInputLowMax "0.7 ") (threshOutputHighMin "2.365  V") (threshOutputHighTyp "2.5  V") (threshOutputHighMax "2.625  V") (threshOutputLowMin "1.275  V") (threshOutputLowTyp "1.7  V") (threshOutputLowMax "1.985  V") (mappingTagNonInverting nil) (mappingTagInverting nil) (spice nil))) (TheveninTerm ((resistanceUp "180 ohm") (resistanceDown "270 ohm") (voltageUp "5 V") (voltageDown "0 V") (maxDelay "0.1 ns"))) (DiffIOPkg ((temperature "27") (bufferModelNonInverting "CDSDefaultIO_2p5v") (bufferModelInverting "CDSDefaultIO_2p5v") (stimuli nil) (offsets nil) (state "tristate") (cycle "1") (termMap nil) (setup "0.9e-09") (hold "0.4e-09") (rise nil) (fall nil) (threshInputHighMin "1.7 V") (threshInputHighTyp "1.7  V") (threshInputHighMax "1.7  V") (threshInputLowMin "0.7  V") (threshInputLowTyp "0.7  V") (threshInputLowMax "0.7 ") (threshOutputHighMin "2.365  V") (threshOutputHighTyp "2.5  V") (threshOutputHighMax "2.625  V") (threshOutputLowMin "1.275  V") (threshOutputLowTyp "1.7  V") (threshOutputLowMax "1.985  V") (mappingTagNonInverting nil) (mappingTagInverting nil) (spice nil))) (Source ((voltage "5 V"))) (ShuntTerm ((resistance "50 ohm") (voltage "5 V") (maxDelay "0.1 ns"))) (RLGC (length("1000 mil"))) (Capacitor ((capacitance "10 pF") (orientation "0"))) (DiffInput ((temperature "27") (bufferModelNonInverting "CDSDefaultInput_2p5v") (bufferModelInverting "CDSDefaultInput_2p5v") (threshInputHighMin "1.7 V") (threshInputHighTyp "1.7  V") (threshInputHighMax "1.7  V") (threshInputLowMin "0.7  V") (threshInputLowTyp "0.7  V") (threshInputLowMax "0.7  V") (mappingTagNonInverting nil) (mappingTagInverting nil) (cycle "1"))) (Inductor ((inductance "5 nH") (orientation "0"))) (Cable (length("1 m"))) (CPWSL ((d1Thickness "10 mil") (d1Constant "4.5") (d1LossTangent "0.035") (d2Thickness "0.72 mil") (d2Constant "4.5") (d2LossTangent "0.035") (d3Thickness "10 mil") (d3Constant "4.5") (d3LossTangent "0.035") length("1000 mil") (spacing "5 mil") (spacing2 "5 mil") (spacing3 "5 mil") (spacing4 "5 mil") (spacing5 "5 mil") (traceConductivity "595900 mho/cm") (traceGeometry "cpwms") (traceLayerName "") (traceThickness "0.72 mil") (traceType "single") (traceWidth "5.0 mil") (traceWidth2 "5.0 mil") (traceWidth3 "5.0 mil") (traceWidth4 "5.0 mil") (traceWidth5 "5.0 mil") (traceWidth6 "5.0 mil") (offset "0 mil") (traceCount "1") (impedance nil))) (CPWMS ((d1Thickness "10 mil") (d1Constant "4.5") (d1LossTangent "0.035") (d2Thickness "0.72 mil") (d2Constant "4.5") (d2LossTangent "0.035") (d3Thickness "0.0") (d3Constant "1") (d3LossTangent "0") length("1000 mil") (spacing "5 mil") (spacing2 "5 mil") (spacing3 "5 mil") (spacing4 "5 mil") (spacing5 "5 mil") (traceConductivity "595900 mho/cm") (traceGeometry "cpwms") (traceLayerName "") (traceThickness "0.72 mil") (traceType "single") (traceWidth "5.0 mil") (traceWidth2 "5.0 mil") (traceWidth3 "5.0 mil") (traceWidth4 "5.0 mil") (traceWidth5 "5.0 mil") (traceWidth6 "5.0 mil") (offset "0 mil") (traceCount "1") (impedance nil))) (Diode ((cutoffVoltage "0.7 V"))) (CPW ((d1Thickness "10 mil") (d1Constant "4.5") (d1LossTangent "0.035") (d2Thickness "0.72 mil") (d2Constant "1") (d2LossTangent "0") (d3Thickness "0.0") (d3Constant "1") (d3LossTangent "0") length("1000 mil") (spacing "5 mil") (spacing2 "5 mil") (spacing3 "5 mil") (spacing4 "5 mil") (spacing5 "5 mil") (traceConductivity "595900 mho/cm") (traceGeometry "cpwms") (traceLayerName "") (traceThickness "0.72 mil") (traceType "single") (traceWidth "5.0 mil") (traceWidth2 "5.0 mil") (traceWidth3 "5.0 mil") (traceWidth4 "5.0 mil") (traceWidth5 "5.0 mil") (traceWidth6 "5.0 mil") (offset "0 mil") (traceCount "1") (impedance nil))) (DualClampTerm ((cutoffVoltageUp "0.7 V") (cutoffVoltageDown "0.7 V") (voltageUp "5 V") (voltageDown "0 V") (maxDelay "0.1 ns"))) (ESpiceDevice nil)))
				)
				( objectStatus "RMII_RX_1" )
			)
			( electricalCSet "@crescent_city_bb_fab1_lib.crescent_city_bb_fab1(sch_1):\FIVR\"
				( pinPairRef "FIVR:U5D1.AU14:U7D2.3" )
				( attribute "TOPOLOGY_TEMPLATE_REVISION" "1.0"
					( Origin gBackEnd )
				)
				( topologyData 21918
(SKIDL (Circuits ("MAIN" (Parts ("CRESCENT_CITY_176_20141216_Q.@@U41.3" IbisIOPkg (xy (5521 4240)) (refDes "U7D2") (model "Unknown") (Props (_SXDesignName "CRESCENT_CITY_176_20141216_Q") (brdx "14352.76 MIL") (brdy "2655.87 MIL") (bufferModel "CDSDefaultIO_2p5v") (cycle "1") (hold "1.0e-09") (mappingTag "") (offsets ("4" "0") ("5" "0")) (setup "2.0e-09") (state "tristate") (stimuli ("4" "local117") ("5" "local118")) (temperature "27") (termMap ("4" "Data") ("5" "Enable"))) (Terms ("CRESCENT_CITY_176_20141216_Q.X1435276Y265587L2LRATS" "3"))) ("CRESCENT_CITY_176_20141216_Q.@@U36.AU14" IbisOutputPkg (xy (5498 4235)) (refDes "U5D1") (model "Unknown") (Props (_SXDesignName "CRESCENT_CITY_176_20141216_Q") (brdx "11657.1 MIL") (brdy "2727.47 MIL") (bufferModel "CDSDefaultOutput_2p5v") (cycle "1") (hold "1.0e-09") (mappingTag "") (offsets ("4" "0")) (setup "2.0e-09") (state "tristate") (stimuli ("4" "local119")) (temperature "27") (termMap ("4" "Data"))) (Terms ("CRESCENT_CITY_176_20141216_Q.X1165710Y272747L2LRATS" "AU14"))) ("CRESCENT_CITY_176_20141216_Q.T@@RATS@@U41.3@@U36.AU14" TLine (xy (5506 4235)) (mirror x) (refDes "TL82") (Props (_SXDesignName "CRESCENT_CITY_176_20141216_Q") (impedance "60 ohm") length("2767.25 MIL") (propDelay "0.497019 ns") (traceCount "1") (traceGeometry "Microstrip") (velocity "5567.72 mil/ns")) (Terms ("CRESCENT_CITY_176_20141216_Q.X1435276Y265587L2LRATS" "1") ("CRESCENT_CITY_176_20141216_Q.X1165710Y272747L2LRATS" "2")))) (Nodes ("CRESCENT_CITY_176_20141216_Q.X1435276Y265587L2LRATS" (terms "CRESCENT_CITY_176_20141216_Q.T@@RATS@@U41.3@@U36.AU14.1" "CRESCENT_CITY_176_20141216_Q.@@U41.3.1")) ("CRESCENT_CITY_176_20141216_Q.X1165710Y272747L2LRATS" (terms "CRESCENT_CITY_176_20141216_Q.T@@RATS@@U41.3@@U36.AU14.2" "CRESCENT_CITY_176_20141216_Q.@@U36.AU14.1"))) (Ports) (Stimuli ("local117" (scope local) (stimType periodic) (Props (periodicFreq "5e+007") (periodicJitter "0") (periodicPattern "1"))) ("local119" (scope local) (stimType periodic) (Props (periodicFreq "5e+007") (periodicJitter "0") (periodicPattern "1"))) ("local118" (scope local) (stimType periodic) (Props (periodicFreq "5e+007") (periodicJitter "0") (periodicPattern "1")))) (Notes) (Constraints ("DELAY_RULE" ("CRESCENT_CITY_176_20141216_Q U36.AU14" "CRESCENT_CITY_176_20141216_Q U41.3" "LENGTH" "" "LENGTH" "0.3302"))) (MeasurementSets ("EMI" ("EMIStatus" status("on")) ("PeakEmission" status("on")) ("PeakFrequency" status("on")) ("PulseFreq" status("on")) ("RiseTime" status("on")) ("VoltageSwing" status("on"))) ("Reflection" ("BufferDelayFall" status("off")) ("BufferDelayRise" status("off")) ("EyeHeight" status("off")) ("EyeJitter" status("off")) ("EyeWidth" status("off")) ("FirstIncidentFall" status("off")) ("FirstIncidentRise" status("off")) ("Glitch" status("on")) ("GlitchFall" status("off")) ("GlitchRise" status("off")) ("Monotonic" status("on")) ("MonotonicFall" status("off")) ("MonotonicRise" status("off")) ("NoiseMargin" status("on")) ("NoiseMarginHigh" status("off")) ("NoiseMarginLow" status("off")) ("OvershootHigh" status("on")) ("OvershootLow" status("on")) ("PropDelay" status("on")) ("SettleDelay" status("on")) ("SettleDelayFall" status("off")) ("SettleDelayRise" status("off")) ("SwitchDelay" status("on")) ("SwitchDelayFall" status("off")) ("SwitchDelayRise" status("off"))) ("Crosstalk" ("Crosstalk" status("on"))) ("Custom")) (VectorSets) (Props (XnetName "H_CPU0_FIVR_FAULT_G") (allDrivers "active") (customSimType "Reflection") (ftsMode ("Typ")) (rcvrSelect "all") (tlineDelayMode "time") (userRevision "1.0")))) (Subckts) (CrossSections ("CRESCENT_CITY_176_20141216_Q" (Props (SXDesignName "CRESCENT_CITY_176_20141216_Q")) (Layers ("" (layerType "SURFACE") (material "AIR") (thickness "0 mil") (dielectricConstant "1.000000") (lossTangent "0") (etchFactor "0.000000") (elecCondVal "0 mho/cm") (thermCondVal "0 w/cm-degC")) ("" (layerType "DIELECTRIC") (material "CONFORMAL_COAT") (thickness "0.5 mil") (dielectricConstant "3.800000") (lossTangent "0.035") (etchFactor "0.000000") (elecCondVal "0 mho/cm") (thermCondVal "0.012 w/cm-degC")) ("TOP" (layerType "CONDUCTOR") (material "COPPER") (thickness "  2.100000 mil") (width "4.00 MIL") (dielectricConstant "4.500000") (lossTangent "0") (etchFactor "70.000000") (elecCondVal "595900.000000 mho/cm") (thermCondVal "0 w/cm-degC") (signalDieConstant "3.800000") (signalLossTangent "0.035")) ("" (layerType "DIELECTRIC") (material "FR-4") (thickness "  2.670000 mil") (dielectricConstant "4.000000") (lossTangent "0.035") (etchFactor "0.000000") (elecCondVal "0 mho/cm") (thermCondVal "0.012 w/cm-degC")) ("L2_GND1" (layerType "PLANE") (material "COPPER") (isShield t) (thickness "  1.250000 mil") (dielectricConstant "4.500000") (lossTangent "0.035") (etchFactor "90.000000") (elecCondVal "595900.000000 mho/cm") (thermCondVal "0.012 w/cm-degC")) ("" (layerType "DIELECTRIC") (material "FR-4") (thickness "  9.000000 mil") (dielectricConstant "4.100000") (lossTangent "0.035") (etchFactor "0.000000") (elecCondVal "0 mho/cm") (thermCondVal "0.012 w/cm-degC")) ("L3_SIG1" (layerType "CONDUCTOR") (material "COPPER") (thickness "  1.250000 mil") (width "4.00 MIL") (dielectricConstant "4.500000") (lossTangent "0.035") (etchFactor "90.000000") (elecCondVal "595900.000000 mho/cm") (thermCondVal "0.012 w/cm-degC") (signalDieConstant "4.100000") (signalLossTangent "0.035")) ("" (layerType "DIELECTRIC") (material "FR-4") (thickness "  3.000000 mil") (dielectricConstant "4.500000") (lossTangent "0.035") (etchFactor "0.000000") (elecCondVal "0 mho/cm") (thermCondVal "0 w/cm-degC")) ("L4_GND2" (layerType "PLANE") (material "COPPER") (isShield t) (thickness "  1.250000 mil") (dielectricConstant "4.500000") (lossTangent "0.035") (etchFactor "90.000000") (elecCondVal "595900.000000 mho/cm") (thermCondVal "0 w/cm-degC")) ("" (layerType "DIELECTRIC") (material "FR-4") (thickness "  9.000000 mil") (dielectricConstant "4.000000") (lossTangent "0.035") (etchFactor "0.000000") (elecCondVal "0 mho/cm") (thermCondVal "0.012 w/cm-degC")) ("L5_SIG2" (layerType "CONDUCTOR") (material "COPPER") (thickness "  1.250000 mil") (width "4.00 MIL") (dielectricConstant "4.500000") (lossTangent "0.035") (etchFactor "90.000000") (elecCondVal "595900.000000 mho/cm") (thermCondVal "0.012 w/cm-degC") (signalDieConstant "4.000000") (signalLossTangent "0.035")) ("" (layerType "DIELECTRIC") (material "FR-4") (thickness "  3.000000 mil") (dielectricConstant "4.500000") (lossTangent "0.035") (etchFactor "0.000000") (elecCondVal "0 mho/cm") (thermCondVal "0 w/cm-degC")) ("L6_GND3" (layerType "PLANE") (material "COPPER") (isShield t) (thickness "  1.250000 mil") (dielectricConstant "4.500000") (lossTangent "0.035") (etchFactor "90.000000") (elecCondVal "595900.000000 mho/cm") (thermCondVal "0 w/cm-degC")) ("" (layerType "DIELECTRIC") (material "FR-4") (thickness "  4.500000 mil") (dielectricConstant "4.100000") (lossTangent "0.035") (etchFactor "0.000000") (elecCondVal "0 mho/cm") (thermCondVal "0.012 w/cm-degC")) ("L7_PWR1-SIG" (layerType "PLANE") (material "COPPER") (isShield t) (thickness "  2.400000 mil") (dielectricConstant "4.500000") (lossTangent "0.035") (etchFactor "90.000000") (elecCondVal "595900.000000 mho/cm") (thermCondVal "0.012 w/cm-degC")) ("" (layerType "DIELECTRIC") (material "FR-4") (thickness "  4.600000 mil") (dielectricConstant "4.000000") (lossTangent "0.035") (etchFactor "0.000000") (elecCondVal "0 mho/cm") (thermCondVal "0.012 w/cm-degC")) ("L8_PWR2-SIG" (layerType "PLANE") (material "COPPER") (isShield t) (thickness "  2.400000 mil") (dielectricConstant "4.500000") (lossTangent "0.035") (etchFactor "90.000000") (elecCondVal "595900.000000 mho/cm") (thermCondVal "0.012 w/cm-degC")) ("" (layerType "DIELECTRIC") (material "FR-4") (thickness "  4.500000 mil") (dielectricConstant "4.500000") (lossTangent "0.035") (etchFactor "0.000000") (elecCondVal "0 mho/cm") (thermCondVal "0 w/cm-degC")) ("L9_GND4" (layerType "PLANE") (material "COPPER") (isShield t) (thickness "  1.250000 mil") (dielectricConstant "4.500000") (lossTangent "0.035") (etchFactor "90.000000") (elecCondVal "595900.000000 mho/cm") (thermCondVal "0 w/cm-degC")) ("" (layerType "DIELECTRIC") (material "FR-4") (thickness "  3.000000 mil") (dielectricConstant "4.100000") (lossTangent "0.035") (etchFactor "0.000000") (elecCondVal "0 mho/cm") (thermCondVal "0.012 w/cm-degC")) ("L10_SIG3" (layerType "CONDUCTOR") (material "COPPER") (thickness "  1.250000 mil") (width "4.00 MIL") (dielectricConstant "4.500000") (lossTangent "0.035") (etchFactor "90.000000") (elecCondVal "595900.000000 mho/cm") (thermCondVal "0.012 w/cm-degC") (signalDieConstant "4.100000") (signalLossTangent "0.035")) ("" (layerType "DIELECTRIC") (material "FR-4") (thickness "  9.000000 mil") (dielectricConstant "4.500000") (lossTangent "0.035") (etchFactor "0.000000") (elecCondVal "0 mho/cm") (thermCondVal "0 w/cm-degC")) ("L11_GND5" (layerType "PLANE") (material "COPPER") (isShield t) (thickness "  1.250000 mil") (dielectricConstant "4.500000") (lossTangent "0.035") (etchFactor "90.000000") (elecCondVal "595900.000000 mho/cm") (thermCondVal "0 w/cm-degC")) ("" (layerType "DIELECTRIC") (material "FR-4") (thickness "  3.000000 mil") (dielectricConstant "4.500000") (lossTangent "0.035") (etchFactor "0.000000") (elecCondVal "0 mho/cm") (thermCondVal "0.012 w/cm-degC")) ("L12_SIG4" (layerType "CONDUCTOR") (material "COPPER") (thickness "  1.250000 mil") (width "4.00 MIL") (dielectricConstant "4.500000") (lossTangent "0.035") (etchFactor "90.000000") (elecCondVal "595900.000000 mho/cm") (thermCondVal "0.012 w/cm-degC") (signalDieConstant "4.500000") (signalLossTangent "0.035")) ("" (layerType "DIELECTRIC") (material "FR-4") (thickness "  9.000000 mil") (dielectricConstant "4.500000") (lossTangent "0.035") (etchFactor "0.000000") (elecCondVal "0 mho/cm") (thermCondVal "0 w/cm-degC")) ("L13_GND6" (layerType "PLANE") (material "COPPER") (isShield t) (thickness "  1.250000 mil") (dielectricConstant "4.500000") (lossTangent "0.035") (etchFactor "90.000000") (elecCondVal "595900.000000 mho/cm") (thermCondVal "0.012 w/cm-degC")) ("" (layerType "DIELECTRIC") (material "FR-4") (thickness "  2.670000 mil") (dielectricConstant "4.500000") (lossTangent "0.035") (etchFactor "0.000000") (elecCondVal "0 mho/cm") (thermCondVal "0.012 w/cm-degC")) ("BOTTOM" (layerType "CONDUCTOR") (material "COPPER") (thickness "  2.100000 mil") (width "4.00 MIL") (dielectricConstant "4.500000") (lossTangent "0") (etchFactor "70.000000") (elecCondVal "595900.000000 mho/cm") (thermCondVal "0 w/cm-degC") (signalDieConstant "3.800000") (signalLossTangent "0.035")) ("" (layerType "DIELECTRIC") (material "CONFORMAL_COAT") (thickness "0.5 mil") (dielectricConstant "3.800000") (lossTangent "0.035") (etchFactor "0.000000") (elecCondVal "0 mho/cm") (thermCondVal "0.012 w/cm-degC")) ("" (layerType "SURFACE") (material "AIR") (thickness "0 mil") (dielectricConstant "1.000000") (lossTangent "0") (etchFactor "0.000000") (elecCondVal "0 mho/cm") (thermCondVal "0 w/cm-degC"))))) (Props (DesUnits "mils 2") (LayerStack ("DIELECTRIC" "DIELECTRIC" "BOTTOM" "DIELECTRIC" "L13_GND6" "DIELECTRIC" "L12_SIG4" "DIELECTRIC" "L11_GND5" "DIELECTRIC" "L10_SIG3" "DIELECTRIC" "L9_GND4" "DIELECTRIC" "L8_PWR2-SIG" "DIELECTRIC" "L7_PWR1-SIG" "DIELECTRIC" "L6_GND3" "DIELECTRIC" "L5_SIG2" "DIELECTRIC" "L4_GND2" "DIELECTRIC" "L3_SIG1" "DIELECTRIC" "L2_GND1" "DIELECTRIC" "TOP" "DIELECTRIC" "DIELECTRIC")) (Revision "16.600")) (Params (Via ((model "Unknown") (viaOutputFormat "Unknown") (viaPadstack nil) (viaTopLayer nil) (viaBottomLayer nil) (viaIsPower nil) (viaIsGround nil))) (IbisIOMacro ((temperature "27") (bufferModel "CDSDefaultIO_2p5v") (stimuli nil) (offsets nil) (state "tristate") (cycle "1") (termMap nil) (setup "2.0e-09") (hold "1.0e-09") (rise nil) (fall nil) (macroType nil) (voltage nil) (spice nil) (LEFDEFPinName nil) (LEFDEFPinType nil) (mappingTag nil))) (DiffInputPkg ((temperature "27") (bufferModelNonInverting "CDSDefaultInput_2p5v") (bufferModelInverting "CDSDefaultInput_2p5v") (threshInputHighMin "1.7 V") (threshInputHighTyp "1.7  V") (threshInputHighMax "1.7  V") (threshInputLowMin "0.7  V") (threshInputLowTyp "0.7  V") (threshInputLowMax "0.7  V") (mappingTagNonInverting nil) (mappingTagInverting nil) (cycle "1"))) (DiffIO ((temperature "27") (bufferModelNonInverting "CDSDefaultIO_2p5v") (bufferModelInverting "CDSDefaultIO_2p5v") (stimuli nil) (offsets nil) (state "tristate") (cycle "1") (termMap nil) (setup "0.9e-09") (hold "0.4e-09") (rise nil) (fall nil) (threshInputHighMin "1.7 V") (threshInputHighTyp "1.7  V") (threshInputHighMax "1.7  V") (threshInputLowMin "0.7  V") (threshInputLowTyp "0.7  V") (threshInputLowMax "0.7 ") (threshOutputHighMin "2.365  V") (threshOutputHighTyp "2.5  V") (threshOutputHighMax "2.625  V") (threshOutputLowMin "1.275  V") (threshOutputLowTyp "1.7  V") (threshOutputLowMax "1.985  V") (mappingTagNonInverting nil) (mappingTagInverting nil) (spice nil))) (Trace ((d1Thickness "10 mil") (d1Constant "4.5") (d1LossTangent "0.035") (d2Thickness "10 mil") (d2Constant "4.5") (d2LossTangent "0.035") (d3Thickness "0.0") (d3Constant "1.0") (d3LossTangent "0") length("1000 mil") (spacing "5 mil") (spacing2 "5 mil") (spacing3 "5 mil") (spacing4 "5 mil") (spacing5 "5 mil") (traceConductivity "595900 mho/cm") (traceGeometry "microstrip") (traceLayerName "") (traceThickness "0.72 mil") (traceType "single") (traceWidth "5.0 mil") (traceWidth2 "5.0 mil") (traceWidth3 "5.0 mil") (traceWidth4 "5.0 mil") (traceWidth5 "5.0 mil") (traceWidth6 "5.0 mil") (offset "0 mil") (traceCount "1") (impedance nil))) (sync ((syncFreq "100e6") (syncInitState "1") (syncPattern "10") (syncEdgeSwitch "rise"))) (DiffOutputPkg ((temperature "27") (bufferModelNonInverting "CDSDefaultOutput_2p5v") (bufferModelInverting "CDSDefaultOutput_2p5v") (stimuli nil) (offsets nil) (state "tristate") (cycle "1") (termMap nil) (setup "0.9e-09") (hold "0.4e-09") (rise nil) (fall nil) (threshOutputHighMin "2.375  V") (threshOutputHighTyp "2.5  V") (threshOutputHighMax "2.625  V") (threshOutputLowMin "1.275  V") (threshOutputLowTyp "1.7  V") (threshOutputLowMax "1.985  V") (mappingTagNonInverting nil) (mappingTagInverting nil) (spice nil))) (DiffOutput ((temperature "27") (bufferModelNonInverting "CDSDefaultOutput_2p5v") (bufferModelInverting "CDSDefaultOutput_2p5v") (stimuli nil) (offsets nil) (state "tristate") (cycle "1") (termMap nil) (setup "0.9e-09") (hold "0.4e-09") (rise nil) (fall nil) (threshOutputHighMin "2.375  V") (threshOutputHighTyp "2.5  V") (threshOutputHighMax "2.625  V") (threshOutputLowMin "1.275  V") (threshOutputLowTyp "1.7  V") (threshOutputLowMax "1.985  V") (mappingTagNonInverting nil) (mappingTagInverting nil) (spice nil))) (IbisOutputPkg ((temperature "27") (bufferModel "CDSDefaultOutput_2p5v") (stimuli nil) (offsets nil) (state "tristate") (cycle "1") (termMap nil) (setup "2.0e-09") (hold "1.0e-09") (rise nil) (fall nil) (macroType nil) (voltage nil) (spice nil) (LEFDEFPinName nil) (LEFDEFPinType nil) (mappingTag nil))) (DiffIOPkg ((temperature "27") (bufferModelNonInverting "CDSDefaultIO_2p5v") (bufferModelInverting "CDSDefaultIO_2p5v") (stimuli nil) (offsets nil) (state "tristate") (cycle "1") (termMap nil) (setup "0.9e-09") (hold "0.4e-09") (rise nil) (fall nil) (threshInputHighMin "1.7 V") (threshInputHighTyp "1.7  V") (threshInputHighMax "1.7  V") (threshInputLowMin "0.7  V") (threshInputLowTyp "0.7  V") (threshInputLowMax "0.7 ") (threshOutputHighMin "2.365  V") (threshOutputHighTyp "2.5  V") (threshOutputHighMax "2.625  V") (threshOutputLowMin "1.275  V") (threshOutputLowTyp "1.7  V") (threshOutputLowMax "1.985  V") (mappingTagNonInverting nil) (mappingTagInverting nil) (spice nil))) (IbisIOPkg ((temperature "27") (bufferModel "CDSDefaultIO_2p5v") (stimuli nil) (offsets nil) (state "tristate") (cycle "1") (termMap nil) (setup "2.0e-09") (hold "1.0e-09") (rise nil) (fall nil) (macroType nil) (voltage nil) (spice nil) (LEFDEFPinName nil) (LEFDEFPinType nil) (mappingTag nil))) (CurrentProbe nil) (DiffInput ((temperature "27") (bufferModelNonInverting "CDSDefaultInput_2p5v") (bufferModelInverting "CDSDefaultInput_2p5v") (threshInputHighMin "1.7 V") (threshInputHighTyp "1.7  V") (threshInputHighMax "1.7  V") (threshInputLowMin "0.7  V") (threshInputLowTyp "0.7  V") (threshInputLowMax "0.7  V") (mappingTagNonInverting nil) (mappingTagInverting nil) (cycle "1"))) (IbisInputPkg ((temperature "27") (bufferModel "CDSDefaultInput_2p5v") (cycle "1") (LEFDEFPinName nil) (LEFDEFPinType nil) (mappingTag nil))) (idlCircuit ((allDrivers "active") (ftsMode '("Typ")) (rcvrSelect "all") (simMode "Reflection") (tlineDelayMode "time") (userRevision "1.0") (autoSolve "On"))) (SeriesTerm ((resistance "22 ohm") (maxDelay "0.1 ns"))) (RLGC (length("1000 mil"))) (periodic ((periodicFreq "100e6") (periodicPattern "10") (periodicJitter "0"))) (Resistor ((resistance "50 ohm") (orientation "0"))) (async ((asyncTimePoints "") (asyncInitState "1"))) (Capacitor ((capacitance "10 pF") (orientation "0"))) (Inductor ((inductance "5 nH") (orientation "0"))) (clocked ((clockRise "1e-09") (clockFall "1e-09") (clockFreq "100e6") (clockInitState "0") (clockDutyCycle "0.5") (clockJitter "0"))) (TLine ((diffImpedance "100ohm") (diffVelocity "1.4142e+08M/s") (impedance "60ohm") length("2800 mil") (propDelay "0.5 ns") (velocity "5600 mil/ns") (traceCount "1") (traceGeometry "Microstrip") (impedanceMin nil) (impedanceMax nil) (lengthMin nil) (lengthMax nil) (propDelayMin nil) (propDelayMax nil) (impedanceSweepCount nil) (propDelaySweepCount nil) (velocitySweepCount nil) (lengthSweepCount nil) (matchSetName nil))) (Cable (length("1 m"))) (DualClampTerm ((cutoffVoltageUp "0.7 V") (cutoffVoltageDown "0.7 V") (voltageUp "5 V") (voltageDown "0 V") (maxDelay "0.1 ns"))) (LowClampTerm ((cutoffVoltage "0.7 V") (voltage "0 V") (maxDelay "0.1 ns"))) (HiClampTerm ((cutoffVoltage "0.7 V") (voltage "5 V") (maxDelay "0.1 ns"))) (RCTerm ((resistance "50 ohm") (capacitance "20 pF") (voltage "5 V") (maxDelay "0.1 ns"))) (IbisOutput ((temperature "27") (bufferModel "CDSDefaultOutput_2p5v") (stimuli nil) (offsets nil) (state "tristate") (cycle "1") (termMap nil) (setup "2.0e-09") (hold "1.0e-09") (rise nil) (fall nil) (macroType nil) (voltage nil) (spice nil) (LEFDEFPinName nil) (LEFDEFPinType nil) (mappingTag nil))) (IbisIO ((temperature "27") (bufferModel "CDSDefaultIO_2p5v") (stimuli nil) (offsets nil) (state "tristate") (cycle "1") (termMap nil) (setup "2.0e-09") (hold "1.0e-09") (rise nil) (fall nil) (macroType nil) (voltage nil) (spice nil) (LEFDEFPinName nil) (LEFDEFPinType nil) (mappingTag nil))) (Diode ((cutoffVoltage "0.7 V"))) (IbisInput ((temperature "27") (bufferModel "CDSDefaultInput_2p5v") (cycle "1") (LEFDEFPinName nil) (LEFDEFPinType nil) (mappingTag nil))) (ESpiceDevice nil) (CPW ((d1Thickness "10 mil") (d1Constant "4.5") (d1LossTangent "0.035") (d2Thickness "0.72 mil") (d2Constant "1") (d2LossTangent "0") (d3Thickness "0.0") (d3Constant "1") (d3LossTangent "0") length("1000 mil") (spacing "5 mil") (spacing2 "5 mil") (spacing3 "5 mil") (spacing4 "5 mil") (spacing5 "5 mil") (traceConductivity "595900 mho/cm") (traceGeometry "cpwms") (traceLayerName "") (traceThickness "0.72 mil") (traceType "single") (traceWidth "5.0 mil") (traceWidth2 "5.0 mil") (traceWidth3 "5.0 mil") (traceWidth4 "5.0 mil") (traceWidth5 "5.0 mil") (traceWidth6 "5.0 mil") (offset "0 mil") (traceCount "1") (impedance nil))) (IbisOutput_OpenPullUp ((temperature "27") (bufferModel "CDSDefaultOutput_2p5v") (stimuli nil) (offsets nil) (state "tristate") (cycle "1") (termMap nil) (setup "2.0e-09") (hold "1.0e-09") (rise nil) (fall nil) (macroType nil) (voltage nil) (spice nil) (LEFDEFPinName nil) (LEFDEFPinType nil) (mappingTag nil))) (CPWMS ((d1Thickness "10 mil") (d1Constant "4.5") (d1LossTangent "0.035") (d2Thickness "0.72 mil") (d2Constant "4.5") (d2LossTangent "0.035") (d3Thickness "0.0") (d3Constant "1") (d3LossTangent "0") length("1000 mil") (spacing "5 mil") (spacing2 "5 mil") (spacing3 "5 mil") (spacing4 "5 mil") (spacing5 "5 mil") (traceConductivity "595900 mho/cm") (traceGeometry "cpwms") (traceLayerName "") (traceThickness "0.72 mil") (traceType "single") (traceWidth "5.0 mil") (traceWidth2 "5.0 mil") (traceWidth3 "5.0 mil") (traceWidth4 "5.0 mil") (traceWidth5 "5.0 mil") (traceWidth6 "5.0 mil") (offset "0 mil") (traceCount "1") (impedance nil))) (IbisIO_OpenPullDown ((temperature "27") (bufferModel "CDSDefaultIO_2p5v") (stimuli nil) (offsets nil) (state "tristate") (cycle "1") (termMap nil) (setup "2.0e-09") (hold "1.0e-09") (rise nil) (fall nil) (macroType nil) (voltage nil) (spice nil) (LEFDEFPinName nil) (LEFDEFPinType nil) (mappingTag nil))) (Connector nil) (CPWSL ((d1Thickness "10 mil") (d1Constant "4.5") (d1LossTangent "0.035") (d2Thickness "0.72 mil") (d2Constant "4.5") (d2LossTangent "0.035") (d3Thickness "10 mil") (d3Constant "4.5") (d3LossTangent "0.035") length("1000 mil") (spacing "5 mil") (spacing2 "5 mil") (spacing3 "5 mil") (spacing4 "5 mil") (spacing5 "5 mil") (traceConductivity "595900 mho/cm") (traceGeometry "cpwms") (traceLayerName "") (traceThickness "0.72 mil") (traceType "single") (traceWidth "5.0 mil") (traceWidth2 "5.0 mil") (traceWidth3 "5.0 mil") (traceWidth4 "5.0 mil") (traceWidth5 "5.0 mil") (traceWidth6 "5.0 mil") (offset "0 mil") (traceCount "1") (impedance nil))) (IbisIO_OpenPullUp ((temperature "27") (bufferModel "CDSDefaultIO_2p5v") (stimuli nil) (offsets nil) (state "tristate") (cycle "1") (termMap nil) (setup "2.0e-09") (hold "1.0e-09") (rise nil) (fall nil) (macroType nil) (voltage nil) (spice nil) (LEFDEFPinName nil) (LEFDEFPinType nil) (mappingTag nil))) (TheveninTerm ((resistanceUp "180 ohm") (resistanceDown "270 ohm") (voltageUp "5 V") (voltageDown "0 V") (maxDelay "0.1 ns"))) (ShuntTerm ((resistance "50 ohm") (voltage "5 V") (maxDelay "0.1 ns"))) (Source ((voltage "5 V")))))
				)
				( objectStatus "FIVR" )
			)
			( electricalCSet "@crescent_city_bb_fab1_lib.crescent_city_bb_fab1(sch_1):\PCIE_CO_SATA\"
				( groupRef "PCIE_CO_SATA:MG_PCIE_L0" )
				( groupRef "PCIE_CO_SATA:MG_PCIE_L1" )
				( groupRef "PCIE_CO_SATA:MG_PCIE_ALL0" )
				( pinPairRef "PCIE_CO_SATA:J8F1.41:C8F15.2" )
				( pinPairRef "PCIE_CO_SATA:U7C1.BA71:C8F15.1" )
				( pinPairRef "PCIE_CO_SATA:J8F1.41:U7C1.BA71" )
				( attribute "RATSNEST_SCHEDULE" "TEMPLATE"
					( Status sLocked )
					( Origin gBackEnd )
				)
				( attribute "TOPOLOGY_TEMPLATE_REVISION" "1.0"
					( Origin gBackEnd )
				)
				( topologyData 26819
(SKIDL (Circuits ("MAIN" (Parts ("CRESCENT_CITY_178_20141217_B.@@U22.BB63" IbisIOPkg (xy (5536 4222)) (refDes "U7C1") (model "Unknown") (Props (_SXDesignName "CRESCENT_CITY_178_20141217_B") (brdx "15479.75 MIL") (brdy "4798.2 MIL") (bufferModel "CDSDefaultIO_2p5v") (cycle "1") (hold "1.0e-09") (mappingTag "") (offsets ("4" "0") ("5" "0")) (setup "2.0e-09") (state "tristate") (stimuli ("4" "local25") ("5" "local26")) (temperature "27") (termMap ("4" "Data") ("5" "Enable"))) (Terms ("CRESCENT_CITY_178_20141217_B.X1547975Y479820L2LRATS" "BB63"))) ("CRESCENT_CITY_178_20141217_B.@@J104.41" IbisIOPkg (xy (5522.0 4243.0)) (refDes "J8F1") (model "Unknown") (Props (_SXDesignName "CRESCENT_CITY_178_20141217_B") (brdx "16243.11 MIL") (brdy "1231.14 MIL") (bufferModel "CDSDefaultIO_2p5v") (cycle "1") (hold "1.0e-09") (mappingTag "") (offsets ("4" "0") ("5" "0")) (setup "2.0e-09") (state "tristate") (stimuli ("4" "local27") ("5" "local28")) (temperature "27") (termMap ("4" "Data") ("5" "Enable"))) (Terms ("CRESCENT_CITY_178_20141217_B.X1624311Y123114L2LRATS" "41"))) ("CRESCENT_CITY_178_20141217_B.@@U22.BA71" IbisIOPkg (xy (5502.0 4243.0)) (refDes "U7C1") (model "Unknown") (Props (_SXDesignName "CRESCENT_CITY_178_20141217_B") (brdx "15452.17 MIL") (brdy "4950.79 MIL") (bufferModel "CDSDefaultIO_2p5v") (cycle "1") (hold "1.0e-09") (mappingTag "") (offsets ("4" "0") ("5" "0")) (setup "2.0e-09") (state "tristate") (stimuli ("4" "local29") ("5" "local30")) (temperature "27") (termMap ("4" "Data") ("5" "Enable"))) (Terms ("CRESCENT_CITY_178_20141217_B.X1545217Y495079L2LRATS" "BA71"))) ("CRESCENT_CITY_178_20141217_B.@@C3036.1.2" Capacitor (xy (5518.0 4217.0)) (mirror x) (refDes "C8F15") (value "1e+012 pF") (Props (_SXDesignName "CRESCENT_CITY_178_20141217_B")) (Terms ("CRESCENT_CITY_178_20141217_B.X1614300Y117250L2LRATS" "1") ("idlNode_36" "2"))) ("CRESCENT_CITY_178_20141217_B.T@@RATS@@R2791.1@@U22.BA71" TLine (xy (5497.0 4234.0)) (refDes "TL10") (Props (_SXDesignName "CRESCENT_CITY_178_20141217_B") (impedance "52.449 ohm") length("4399.13 MIL") (propDelay "0.79011 ns") (traceCount "1") (traceGeometry "Microstrip") (velocity "5567.72 mil/ns")) (Terms ("CRESCENT_CITY_178_20141217_B.X1607300Y117250L2LRATS" "1") ("CRESCENT_CITY_178_20141217_B.X1545217Y495079L2LRATS" "2"))) ("CRESCENT_CITY_178_20141217_B.T@@RATS@@C3036.2@@J104.41" TLine (xy (5517.0 4232.0)) (refDes "TL11") (Props (_SXDesignName "CRESCENT_CITY_178_20141217_B") (impedance "47.169 ohm") length("193.75 MIL") (propDelay "0.0348 ns") (traceCount "1") (traceGeometry "Microstrip") (velocity "5567.52 mil/ns")) (Terms ("idlNode_40" "1") ("CRESCENT_CITY_178_20141217_B.X1624311Y123114L2LRATS" "2"))) ("CRESCENT_CITY_178_20141217_B.T@@RATS@@U22.BB63@@C3036.1" TLine (xy (5527.0 4217.0)) (mirror x) (refDes "TL12") (Props (_SXDesignName "CRESCENT_CITY_178_20141217_B") (impedance "47.169 ohm") length("4288.94 MIL") (propDelay "0.77032 ns") (traceCount "1") (traceGeometry "Microstrip") (velocity "5567.76 mil/ns")) (Terms ("CRESCENT_CITY_178_20141217_B.X1547975Y479820L2LRATS" "1") ("CRESCENT_CITY_178_20141217_B.X1614300Y117250L2LRATS" "2"))) ("CRESCENT_CITY_178_20141217_B.@@R2791.1.2" Resistor (xy (5497.0 4229.0)) (refDes "R8F21") (value "2.2e-007 Ohm") (Props (_SXDesignName "CRESCENT_CITY_178_20141217_B")) (Terms ("CRESCENT_CITY_178_20141217_B.X1607300Y117250L2LRATS" "1") ("idlNode_44" "2"))) ("idlPart_20" TLine (xy (5505.5 4229.0)) (refDes "TL13") (Props (_SXDesignName "CRESCENT_CITY_178_20141217_B") (impedance "47.169 ohm") length("193.75 MIL") (propDelay "0.0348 ns") (traceCount "1") (traceGeometry "Microstrip") (velocity "5567.52 mil/ns")) (Terms ("idlNode_44" "1") ("idlNode_40" "2"))) ("idlPart_22" TLine (xy (5510.5 4217.0)) (refDes "TL14") (Props (_SXDesignName "CRESCENT_CITY_178_20141217_B") (impedance "47.169 ohm") length("193.75 MIL") (propDelay "0.0348 ns") (traceCount "1") (traceGeometry "Microstrip") (velocity "5567.52 mil/ns")) (Terms ("idlNode_40" "1") ("idlNode_36" "2")))) (Nodes ("CRESCENT_CITY_178_20141217_B.X1624311Y123114L2LRATS" (terms "CRESCENT_CITY_178_20141217_B.T@@RATS@@C3036.2@@J104.41.2" "CRESCENT_CITY_178_20141217_B.@@J104.41.1")) ("CRESCENT_CITY_178_20141217_B.X1614300Y117250L2LRATS" (terms "CRESCENT_CITY_178_20141217_B.T@@RATS@@U22.BB63@@C3036.1.2" "CRESCENT_CITY_178_20141217_B.@@C3036.1.2.1")) ("CRESCENT_CITY_178_20141217_B.X1607300Y117250L2LRATS" (terms "CRESCENT_CITY_178_20141217_B.@@R2791.1.2.1" "CRESCENT_CITY_178_20141217_B.T@@RATS@@R2791.1@@U22.BA71.1")) ("idlNode_40" (terms "idlPart_22.1" "idlPart_20.2" "CRESCENT_CITY_178_20141217_B.T@@RATS@@C3036.2@@J104.41.1") (tee "CRESCENT_CITY_178_20141217_B NET.T.1")) ("CRESCENT_CITY_178_20141217_B.X1547975Y479820L2LRATS" (terms "CRESCENT_CITY_178_20141217_B.T@@RATS@@U22.BB63@@C3036.1.1" "CRESCENT_CITY_178_20141217_B.@@U22.BB63.1")) ("idlNode_44" (terms "idlPart_20.1" "CRESCENT_CITY_178_20141217_B.@@R2791.1.2.2")) ("CRESCENT_CITY_178_20141217_B.X1545217Y495079L2LRATS" (terms "CRESCENT_CITY_178_20141217_B.T@@RATS@@R2791.1@@U22.BA71.2" "CRESCENT_CITY_178_20141217_B.@@U22.BA71.1")) ("idlNode_36" (terms "idlPart_22.2" "CRESCENT_CITY_178_20141217_B.@@C3036.1.2.2"))) (Ports) (Stimuli ("local2" (scope local) (stimType periodic) (Props (periodicFreq "5e+007") (periodicJitter "0") (periodicPattern "1"))) ("local25" (scope local) (stimType periodic) (Props (periodicFreq "5e+007") (periodicJitter "0") (periodicPattern "1"))) ("local30" (scope local) (stimType periodic) (Props (periodicFreq "5e+007") (periodicJitter "0") (periodicPattern "1"))) ("local132" (scope local) (stimType periodic) (Props (periodicFreq "5e+007") (periodicJitter "0") (periodicPattern "1"))) ("local29" (scope local) (stimType periodic) (Props (periodicFreq "5e+007") (periodicJitter "0") (periodicPattern "1"))) ("local131" (scope local) (stimType periodic) (Props (periodicFreq "5e+007") (periodicJitter "0") (periodicPattern "1"))) ("local0" (scope local) (stimType periodic) (Props (periodicFreq "5e+007") (periodicJitter "0") (periodicPattern "1"))) ("local27" (scope local) (stimType periodic) (Props (periodicFreq "5e+007") (periodicJitter "0") (periodicPattern "1"))) ("local1" (scope local) (stimType periodic) (Props (periodicFreq "5e+007") (periodicJitter "0") (periodicPattern "1"))) ("local26" (scope local) (stimType periodic) (Props (periodicFreq "5e+007") (periodicJitter "0") (periodicPattern "1"))) ("local28" (scope local) (stimType periodic) (Props (periodicFreq "5e+007") (periodicJitter "0") (periodicPattern "1")))) (Notes) (Constraints ("DELAY_RULE" ("CRESCENT_CITY_178_20141217_B J104.41" "CRESCENT_CITY_178_20141217_B U22.BA71" "LENGTH" "" "LENGTH" "0.4064")) ("RATSNEST_SCHEDULE" "TEMPLATE") ("RELATIVE_PROPAGATION_DELAY" ("TMP" "CRESCENT_CITY_178_20141217_B J104.41" "CRESCENT_CITY_178_20141217_B U22.BB63" "LOCAL" "LENGTH" "0.000127" "DELAY" "") ("TMP" "CRESCENT_CITY_178_20141217_B J104.41" "CRESCENT_CITY_178_20141217_B U22.BA71" "LOCAL" "LENGTH" "0.000127" "DELAY" "") ("MG_PCIE_LOCAL" "CRESCENT_CITY_178_20141217_B U22.BA71" "CRESCENT_CITY_178_20141217_B C3036.1" "LOCAL" "LENGTH" "0.000127" "DELAY" "") ("MG_PCIE_LOCAL" "CRESCENT_CITY_178_20141217_B J104.41" "CRESCENT_CITY_178_20141217_B C3036.2" "LOCAL" "LENGTH" "0.000127" "DELAY" ""))) (MeasurementSets ("EMI" ("EMIStatus" status("on")) ("PeakEmission" status("on")) ("PeakFrequency" status("on")) ("PulseFreq" status("on")) ("RiseTime" status("on")) ("VoltageSwing" status("on"))) ("Reflection" ("BufferDelayFall" status("off")) ("BufferDelayRise" status("off")) ("EyeHeight" status("off")) ("EyeJitter" status("off")) ("EyeWidth" status("off")) ("FirstIncidentFall" status("off")) ("FirstIncidentRise" status("off")) ("Glitch" status("on")) ("GlitchFall" status("off")) ("GlitchRise" status("off")) ("Monotonic" status("on")) ("MonotonicFall" status("off")) ("MonotonicRise" status("off")) ("NoiseMargin" status("on")) ("NoiseMarginHigh" status("off")) ("NoiseMarginLow" status("off")) ("OvershootHigh" status("on")) ("OvershootLow" status("on")) ("PropDelay" status("on")) ("SettleDelay" status("on")) ("SettleDelayFall" status("off")) ("SettleDelayRise" status("off")) ("SwitchDelay" status("on")) ("SwitchDelayFall" status("off")) ("SwitchDelayRise" status("off"))) ("Crosstalk" ("Crosstalk" status("on"))) ("Custom")) (VectorSets) (Props (XnetName "P3E_PCH_RX_0_DN") (allDrivers "active") (customSimType "Reflection") (ftsMode ("Typ")) (rcvrSelect "all") (tlineDelayMode "time") (userRevision "1.0")))) (Subckts) (CrossSections ("CRESCENT_CITY_178_20141217_B" (Props (SXDesignName "CRESCENT_CITY_178_20141217_B")) (Layers ("" (layerType "SURFACE") (material "AIR") (thickness "0 mil") (dielectricConstant "1.000000") (lossTangent "0") (etchFactor "0.000000") (elecCondVal "0 mho/cm") (thermCondVal "0 w/cm-degC")) ("" (layerType "DIELECTRIC") (material "CONFORMAL_COAT") (thickness "0.5 mil") (dielectricConstant "3.800000") (lossTangent "0.035") (etchFactor "0.000000") (elecCondVal "0 mho/cm") (thermCondVal "0.012 w/cm-degC")) ("TOP" (layerType "CONDUCTOR") (material "COPPER") (thickness "  2.100000 mil") (width "4.00 MIL") (dielectricConstant "4.500000") (lossTangent "0") (etchFactor "70.000000") (elecCondVal "595900.000000 mho/cm") (thermCondVal "0 w/cm-degC") (signalDieConstant "3.800000") (signalLossTangent "0.035")) ("" (layerType "DIELECTRIC") (material "FR-4") (thickness "  2.670000 mil") (dielectricConstant "4.000000") (lossTangent "0.035") (etchFactor "0.000000") (elecCondVal "0 mho/cm") (thermCondVal "0.012 w/cm-degC")) ("L2_GND1" (layerType "PLANE") (material "COPPER") (isShield t) (thickness "  1.250000 mil") (dielectricConstant "4.500000") (lossTangent "0.035") (etchFactor "90.000000") (elecCondVal "595900.000000 mho/cm") (thermCondVal "0.012 w/cm-degC")) ("" (layerType "DIELECTRIC") (material "FR-4") (thickness "  9.000000 mil") (dielectricConstant "4.100000") (lossTangent "0.035") (etchFactor "0.000000") (elecCondVal "0 mho/cm") (thermCondVal "0.012 w/cm-degC")) ("L3_SIG1" (layerType "CONDUCTOR") (material "COPPER") (thickness "  1.250000 mil") (width "4.00 MIL") (dielectricConstant "4.500000") (lossTangent "0.035") (etchFactor "90.000000") (elecCondVal "595900.000000 mho/cm") (thermCondVal "0.012 w/cm-degC") (signalDieConstant "4.100000") (signalLossTangent "0.035")) ("" (layerType "DIELECTRIC") (material "FR-4") (thickness "  3.000000 mil") (dielectricConstant "4.500000") (lossTangent "0.035") (etchFactor "0.000000") (elecCondVal "0 mho/cm") (thermCondVal "0 w/cm-degC")) ("L4_GND2" (layerType "PLANE") (material "COPPER") (isShield t) (thickness "  1.250000 mil") (dielectricConstant "4.500000") (lossTangent "0.035") (etchFactor "90.000000") (elecCondVal "595900.000000 mho/cm") (thermCondVal "0 w/cm-degC")) ("" (layerType "DIELECTRIC") (material "FR-4") (thickness "  9.000000 mil") (dielectricConstant "4.000000") (lossTangent "0.035") (etchFactor "0.000000") (elecCondVal "0 mho/cm") (thermCondVal "0.012 w/cm-degC")) ("L5_SIG2" (layerType "CONDUCTOR") (material "COPPER") (thickness "  1.250000 mil") (width "4.00 MIL") (dielectricConstant "4.500000") (lossTangent "0.035") (etchFactor "90.000000") (elecCondVal "595900.000000 mho/cm") (thermCondVal "0.012 w/cm-degC") (signalDieConstant "4.000000") (signalLossTangent "0.035")) ("" (layerType "DIELECTRIC") (material "FR-4") (thickness "  3.000000 mil") (dielectricConstant "4.500000") (lossTangent "0.035") (etchFactor "0.000000") (elecCondVal "0 mho/cm") (thermCondVal "0 w/cm-degC")) ("L6_GND3" (layerType "PLANE") (material "COPPER") (isShield t) (thickness "  1.250000 mil") (dielectricConstant "4.500000") (lossTangent "0.035") (etchFactor "90.000000") (elecCondVal "595900.000000 mho/cm") (thermCondVal "0 w/cm-degC")) ("" (layerType "DIELECTRIC") (material "FR-4") (thickness "  4.500000 mil") (dielectricConstant "4.100000") (lossTangent "0.035") (etchFactor "0.000000") (elecCondVal "0 mho/cm") (thermCondVal "0.012 w/cm-degC")) ("L7_PWR1-SIG" (layerType "PLANE") (material "COPPER") (isShield t) (thickness "  2.400000 mil") (dielectricConstant "4.500000") (lossTangent "0.035") (etchFactor "90.000000") (elecCondVal "595900.000000 mho/cm") (thermCondVal "0.012 w/cm-degC")) ("" (layerType "DIELECTRIC") (material "FR-4") (thickness "  4.600000 mil") (dielectricConstant "4.000000") (lossTangent "0.035") (etchFactor "0.000000") (elecCondVal "0 mho/cm") (thermCondVal "0.012 w/cm-degC")) ("L8_PWR2-SIG" (layerType "PLANE") (material "COPPER") (isShield t) (thickness "  2.400000 mil") (dielectricConstant "4.500000") (lossTangent "0.035") (etchFactor "90.000000") (elecCondVal "595900.000000 mho/cm") (thermCondVal "0.012 w/cm-degC")) ("" (layerType "DIELECTRIC") (material "FR-4") (thickness "  4.500000 mil") (dielectricConstant "4.500000") (lossTangent "0.035") (etchFactor "0.000000") (elecCondVal "0 mho/cm") (thermCondVal "0 w/cm-degC")) ("L9_GND4" (layerType "PLANE") (material "COPPER") (isShield t) (thickness "  1.250000 mil") (dielectricConstant "4.500000") (lossTangent "0.035") (etchFactor "90.000000") (elecCondVal "595900.000000 mho/cm") (thermCondVal "0 w/cm-degC")) ("" (layerType "DIELECTRIC") (material "FR-4") (thickness "  3.000000 mil") (dielectricConstant "4.100000") (lossTangent "0.035") (etchFactor "0.000000") (elecCondVal "0 mho/cm") (thermCondVal "0.012 w/cm-degC")) ("L10_SIG3" (layerType "CONDUCTOR") (material "COPPER") (thickness "  1.250000 mil") (width "4.00 MIL") (dielectricConstant "4.500000") (lossTangent "0.035") (etchFactor "90.000000") (elecCondVal "595900.000000 mho/cm") (thermCondVal "0.012 w/cm-degC") (signalDieConstant "4.100000") (signalLossTangent "0.035")) ("" (layerType "DIELECTRIC") (material "FR-4") (thickness "  9.000000 mil") (dielectricConstant "4.500000") (lossTangent "0.035") (etchFactor "0.000000") (elecCondVal "0 mho/cm") (thermCondVal "0 w/cm-degC")) ("L11_GND5" (layerType "PLANE") (material "COPPER") (isShield t) (thickness "  1.250000 mil") (dielectricConstant "4.500000") (lossTangent "0.035") (etchFactor "90.000000") (elecCondVal "595900.000000 mho/cm") (thermCondVal "0 w/cm-degC")) ("" (layerType "DIELECTRIC") (material "FR-4") (thickness "  3.000000 mil") (dielectricConstant "4.500000") (lossTangent "0.035") (etchFactor "0.000000") (elecCondVal "0 mho/cm") (thermCondVal "0.012 w/cm-degC")) ("L12_SIG4" (layerType "CONDUCTOR") (material "COPPER") (thickness "  1.250000 mil") (width "4.00 MIL") (dielectricConstant "4.500000") (lossTangent "0.035") (etchFactor "90.000000") (elecCondVal "595900.000000 mho/cm") (thermCondVal "0.012 w/cm-degC") (signalDieConstant "4.500000") (signalLossTangent "0.035")) ("" (layerType "DIELECTRIC") (material "FR-4") (thickness "  9.000000 mil") (dielectricConstant "4.500000") (lossTangent "0.035") (etchFactor "0.000000") (elecCondVal "0 mho/cm") (thermCondVal "0 w/cm-degC")) ("L13_GND6" (layerType "PLANE") (material "COPPER") (isShield t) (thickness "  1.250000 mil") (dielectricConstant "4.500000") (lossTangent "0.035") (etchFactor "90.000000") (elecCondVal "595900.000000 mho/cm") (thermCondVal "0.012 w/cm-degC")) ("" (layerType "DIELECTRIC") (material "FR-4") (thickness "  2.670000 mil") (dielectricConstant "4.500000") (lossTangent "0.035") (etchFactor "0.000000") (elecCondVal "0 mho/cm") (thermCondVal "0.012 w/cm-degC")) ("BOTTOM" (layerType "CONDUCTOR") (material "COPPER") (thickness "  2.100000 mil") (width "4.00 MIL") (dielectricConstant "4.500000") (lossTangent "0") (etchFactor "70.000000") (elecCondVal "595900.000000 mho/cm") (thermCondVal "0 w/cm-degC") (signalDieConstant "3.800000") (signalLossTangent "0.035")) ("" (layerType "DIELECTRIC") (material "CONFORMAL_COAT") (thickness "0.5 mil") (dielectricConstant "3.800000") (lossTangent "0.035") (etchFactor "0.000000") (elecCondVal "0 mho/cm") (thermCondVal "0.012 w/cm-degC")) ("" (layerType "SURFACE") (material "AIR") (thickness "0 mil") (dielectricConstant "1.000000") (lossTangent "0") (etchFactor "0.000000") (elecCondVal "0 mho/cm") (thermCondVal "0 w/cm-degC"))))) (Props (DesUnits "mils 2") (LayerStack ("DIELECTRIC" "DIELECTRIC" "BOTTOM" "DIELECTRIC" "L13_GND6" "DIELECTRIC" "L12_SIG4" "DIELECTRIC" "L11_GND5" "DIELECTRIC" "L10_SIG3" "DIELECTRIC" "L9_GND4" "DIELECTRIC" "L8_PWR2-SIG" "DIELECTRIC" "L7_PWR1-SIG" "DIELECTRIC" "L6_GND3" "DIELECTRIC" "L5_SIG2" "DIELECTRIC" "L4_GND2" "DIELECTRIC" "L3_SIG1" "DIELECTRIC" "L2_GND1" "DIELECTRIC" "TOP" "DIELECTRIC" "DIELECTRIC")) (Revision "16.600")) (Params (Source ((voltage "5 V"))) (Inductor ((inductance "5 nH") (orientation "0"))) (IbisIO_OpenPullDown ((temperature "27") (bufferModel "CDSDefaultIO_2p5v") (stimuli nil) (offsets nil) (state "tristate") (cycle "1") (termMap nil) (setup "2.0e-09") (hold "1.0e-09") (rise nil) (fall nil) (macroType nil) (voltage nil) (spice nil) (LEFDEFPinName nil) (LEFDEFPinType nil) (mappingTag nil))) (DiffInputPkg ((temperature "27") (bufferModelNonInverting "CDSDefaultInput_2p5v") (bufferModelInverting "CDSDefaultInput_2p5v") (threshInputHighMin "1.7 V") (threshInputHighTyp "1.7  V") (threshInputHighMax "1.7  V") (threshInputLowMin "0.7  V") (threshInputLowTyp "0.7  V") (threshInputLowMax "0.7  V") (mappingTagNonInverting nil) (mappingTagInverting nil) (cycle "1"))) (IbisIO ((temperature "27") (bufferModel "CDSDefaultIO_2p5v") (stimuli nil) (offsets nil) (state "tristate") (cycle "1") (termMap nil) (setup "2.0e-09") (hold "1.0e-09") (rise nil) (fall nil) (macroType nil) (voltage nil) (spice nil) (LEFDEFPinName nil) (LEFDEFPinType nil) (mappingTag nil))) (Trace ((d1Thickness "10 mil") (d1Constant "4.5") (d1LossTangent "0.035") (d2Thickness "10 mil") (d2Constant "4.5") (d2LossTangent "0.035") (d3Thickness "0.0") (d3Constant "1.0") (d3LossTangent "0") length("1000 mil") (spacing "5 mil") (spacing2 "5 mil") (spacing3 "5 mil") (spacing4 "5 mil") (spacing5 "5 mil") (traceConductivity "595900 mho/cm") (traceGeometry "microstrip") (traceLayerName "") (traceThickness "0.72 mil") (traceType "single") (traceWidth "5.0 mil") (traceWidth2 "5.0 mil") (traceWidth3 "5.0 mil") (traceWidth4 "5.0 mil") (traceWidth5 "5.0 mil") (traceWidth6 "5.0 mil") (offset "0 mil") (traceCount "1") (impedance nil))) (IbisIOMacro ((temperature "27") (bufferModel "CDSDefaultIO_2p5v") (stimuli nil) (offsets nil) (state "tristate") (cycle "1") (termMap nil) (setup "2.0e-09") (hold "1.0e-09") (rise nil) (fall nil) (macroType nil) (voltage nil) (spice nil) (LEFDEFPinName nil) (LEFDEFPinType nil) (mappingTag nil))) (Cable (length("1 m"))) (Capacitor ((capacitance "10 pF") (orientation "0"))) (Via ((model "Unknown") (viaOutputFormat "Unknown") (viaPadstack nil) (viaTopLayer nil) (viaBottomLayer nil) (viaIsPower nil) (viaIsGround nil))) (Resistor ((resistance "50 ohm") (orientation "0"))) (IbisOutputPkg ((temperature "27") (bufferModel "CDSDefaultOutput_2p5v") (stimuli nil) (offsets nil) (state "tristate") (cycle "1") (termMap nil) (setup "2.0e-09") (hold "1.0e-09") (rise nil) (fall nil) (macroType nil) (voltage nil) (spice nil) (LEFDEFPinName nil) (LEFDEFPinType nil) (mappingTag nil))) (IbisOutput_OpenPullUp ((temperature "27") (bufferModel "CDSDefaultOutput_2p5v") (stimuli nil) (offsets nil) (state "tristate") (cycle "1") (termMap nil) (setup "2.0e-09") (hold "1.0e-09") (rise nil) (fall nil) (macroType nil) (voltage nil) (spice nil) (LEFDEFPinName nil) (LEFDEFPinType nil) (mappingTag nil))) (IbisIOPkg ((temperature "27") (bufferModel "CDSDefaultIO_2p5v") (stimuli nil) (offsets nil) (state "tristate") (cycle "1") (termMap nil) (setup "2.0e-09") (hold "1.0e-09") (rise nil) (fall nil) (macroType nil) (voltage nil) (spice nil) (LEFDEFPinName nil) (LEFDEFPinType nil) (mappingTag nil))) (IbisIO_OpenPullUp ((temperature "27") (bufferModel "CDSDefaultIO_2p5v") (stimuli nil) (offsets nil) (state "tristate") (cycle "1") (termMap nil) (setup "2.0e-09") (hold "1.0e-09") (rise nil) (fall nil) (macroType nil) (voltage nil) (spice nil) (LEFDEFPinName nil) (LEFDEFPinType nil) (mappingTag nil))) (ESpiceDevice nil) (IbisInputPkg ((temperature "27") (bufferModel "CDSDefaultInput_2p5v") (cycle "1") (LEFDEFPinName nil) (LEFDEFPinType nil) (mappingTag nil))) (IbisInput ((temperature "27") (bufferModel "CDSDefaultInput_2p5v") (cycle "1") (LEFDEFPinName nil) (LEFDEFPinType nil) (mappingTag nil))) (TLine ((diffImpedance "100ohm") (diffVelocity "1.4142e+08M/s") (impedance "60ohm") length("2800 mil") (propDelay "0.5 ns") (velocity "5600 mil/ns") (traceCount "1") (traceGeometry "Microstrip") (impedanceMin nil) (impedanceMax nil) (lengthMin nil) (lengthMax nil) (propDelayMin nil) (propDelayMax nil) (impedanceSweepCount nil) (propDelaySweepCount nil) (velocitySweepCount nil) (lengthSweepCount nil) (matchSetName nil))) (periodic ((periodicFreq "100e6") (periodicPattern "10") (periodicJitter "0"))) (clocked ((clockRise "1e-09") (clockFall "1e-09") (clockFreq "100e6") (clockInitState "0") (clockDutyCycle "0.5") (clockJitter "0"))) (RLGC (length("1000 mil"))) (DiffInput ((temperature "27") (bufferModelNonInverting "CDSDefaultInput_2p5v") (bufferModelInverting "CDSDefaultInput_2p5v") (threshInputHighMin "1.7 V") (threshInputHighTyp "1.7  V") (threshInputHighMax "1.7  V") (threshInputLowMin "0.7  V") (threshInputLowTyp "0.7  V") (threshInputLowMax "0.7  V") (mappingTagNonInverting nil) (mappingTagInverting nil) (cycle "1"))) (async ((asyncTimePoints "") (asyncInitState "1"))) (idlCircuit ((allDrivers "active") (ftsMode '("Typ")) (rcvrSelect "all") (simMode "Reflection") (tlineDelayMode "time") (userRevision "1.0") (autoSolve "On"))) (DiffIO ((temperature "27") (bufferModelNonInverting "CDSDefaultIO_2p5v") (bufferModelInverting "CDSDefaultIO_2p5v") (stimuli nil) (offsets nil) (state "tristate") (cycle "1") (termMap nil) (setup "0.9e-09") (hold "0.4e-09") (rise nil) (fall nil) (threshInputHighMin "1.7 V") (threshInputHighTyp "1.7  V") (threshInputHighMax "1.7  V") (threshInputLowMin "0.7  V") (threshInputLowTyp "0.7  V") (threshInputLowMax "0.7 ") (threshOutputHighMin "2.365  V") (threshOutputHighTyp "2.5  V") (threshOutputHighMax "2.625  V") (threshOutputLowMin "1.275  V") (threshOutputLowTyp "1.7  V") (threshOutputLowMax "1.985  V") (mappingTagNonInverting nil) (mappingTagInverting nil) (spice nil))) (DiffOutput ((temperature "27") (bufferModelNonInverting "CDSDefaultOutput_2p5v") (bufferModelInverting "CDSDefaultOutput_2p5v") (stimuli nil) (offsets nil) (state "tristate") (cycle "1") (termMap nil) (setup "0.9e-09") (hold "0.4e-09") (rise nil) (fall nil) (threshOutputHighMin "2.375  V") (threshOutputHighTyp "2.5  V") (threshOutputHighMax "2.625  V") (threshOutputLowMin "1.275  V") (threshOutputLowTyp "1.7  V") (threshOutputLowMax "1.985  V") (mappingTagNonInverting nil) (mappingTagInverting nil) (spice nil))) (DiffIOPkg ((temperature "27") (bufferModelNonInverting "CDSDefaultIO_2p5v") (bufferModelInverting "CDSDefaultIO_2p5v") (stimuli nil) (offsets nil) (state "tristate") (cycle "1") (termMap nil) (setup "0.9e-09") (hold "0.4e-09") (rise nil) (fall nil) (threshInputHighMin "1.7 V") (threshInputHighTyp "1.7  V") (threshInputHighMax "1.7  V") (threshInputLowMin "0.7  V") (threshInputLowTyp "0.7  V") (threshInputLowMax "0.7 ") (threshOutputHighMin "2.365  V") (threshOutputHighTyp "2.5  V") (threshOutputHighMax "2.625  V") (threshOutputLowMin "1.275  V") (threshOutputLowTyp "1.7  V") (threshOutputLowMax "1.985  V") (mappingTagNonInverting nil) (mappingTagInverting nil) (spice nil))) (sync ((syncFreq "100e6") (syncInitState "1") (syncPattern "10") (syncEdgeSwitch "rise"))) (SeriesTerm ((resistance "22 ohm") (maxDelay "0.1 ns"))) (DiffOutputPkg ((temperature "27") (bufferModelNonInverting "CDSDefaultOutput_2p5v") (bufferModelInverting "CDSDefaultOutput_2p5v") (stimuli nil) (offsets nil) (state "tristate") (cycle "1") (termMap nil) (setup "0.9e-09") (hold "0.4e-09") (rise nil) (fall nil) (threshOutputHighMin "2.375  V") (threshOutputHighTyp "2.5  V") (threshOutputHighMax "2.625  V") (threshOutputLowMin "1.275  V") (threshOutputLowTyp "1.7  V") (threshOutputLowMax "1.985  V") (mappingTagNonInverting nil) (mappingTagInverting nil) (spice nil))) (IbisOutput ((temperature "27") (bufferModel "CDSDefaultOutput_2p5v") (stimuli nil) (offsets nil) (state "tristate") (cycle "1") (termMap nil) (setup "2.0e-09") (hold "1.0e-09") (rise nil) (fall nil) (macroType nil) (voltage nil) (spice nil) (LEFDEFPinName nil) (LEFDEFPinType nil) (mappingTag nil))) (CPW ((d1Thickness "10 mil") (d1Constant "4.5") (d1LossTangent "0.035") (d2Thickness "0.72 mil") (d2Constant "1") (d2LossTangent "0") (d3Thickness "0.0") (d3Constant "1") (d3LossTangent "0") length("1000 mil") (spacing "5 mil") (spacing2 "5 mil") (spacing3 "5 mil") (spacing4 "5 mil") (spacing5 "5 mil") (traceConductivity "595900 mho/cm") (traceGeometry "cpwms") (traceLayerName "") (traceThickness "0.72 mil") (traceType "single") (traceWidth "5.0 mil") (traceWidth2 "5.0 mil") (traceWidth3 "5.0 mil") (traceWidth4 "5.0 mil") (traceWidth5 "5.0 mil") (traceWidth6 "5.0 mil") (offset "0 mil") (traceCount "1") (impedance nil))) (CPWMS ((d1Thickness "10 mil") (d1Constant "4.5") (d1LossTangent "0.035") (d2Thickness "0.72 mil") (d2Constant "4.5") (d2LossTangent "0.035") (d3Thickness "0.0") (d3Constant "1") (d3LossTangent "0") length("1000 mil") (spacing "5 mil") (spacing2 "5 mil") (spacing3 "5 mil") (spacing4 "5 mil") (spacing5 "5 mil") (traceConductivity "595900 mho/cm") (traceGeometry "cpwms") (traceLayerName "") (traceThickness "0.72 mil") (traceType "single") (traceWidth "5.0 mil") (traceWidth2 "5.0 mil") (traceWidth3 "5.0 mil") (traceWidth4 "5.0 mil") (traceWidth5 "5.0 mil") (traceWidth6 "5.0 mil") (offset "0 mil") (traceCount "1") (impedance nil))) (CurrentProbe nil) (CPWSL ((d1Thickness "10 mil") (d1Constant "4.5") (d1LossTangent "0.035") (d2Thickness "0.72 mil") (d2Constant "4.5") (d2LossTangent "0.035") (d3Thickness "10 mil") (d3Constant "4.5") (d3LossTangent "0.035") length("1000 mil") (spacing "5 mil") (spacing2 "5 mil") (spacing3 "5 mil") (spacing4 "5 mil") (spacing5 "5 mil") (traceConductivity "595900 mho/cm") (traceGeometry "cpwms") (traceLayerName "") (traceThickness "0.72 mil") (traceType "single") (traceWidth "5.0 mil") (traceWidth2 "5.0 mil") (traceWidth3 "5.0 mil") (traceWidth4 "5.0 mil") (traceWidth5 "5.0 mil") (traceWidth6 "5.0 mil") (offset "0 mil") (traceCount "1") (impedance nil))) (ShuntTerm ((resistance "50 ohm") (voltage "5 V") (maxDelay "0.1 ns"))) (TheveninTerm ((resistanceUp "180 ohm") (resistanceDown "270 ohm") (voltageUp "5 V") (voltageDown "0 V") (maxDelay "0.1 ns"))) (Connector nil) (RCTerm ((resistance "50 ohm") (capacitance "20 pF") (voltage "5 V") (maxDelay "0.1 ns"))) (LowClampTerm ((cutoffVoltage "0.7 V") (voltage "0 V") (maxDelay "0.1 ns"))) (HiClampTerm ((cutoffVoltage "0.7 V") (voltage "5 V") (maxDelay "0.1 ns"))) (DualClampTerm ((cutoffVoltageUp "0.7 V") (cutoffVoltageDown "0.7 V") (voltageUp "5 V") (voltageDown "0 V") (maxDelay "0.1 ns"))) (Diode ((cutoffVoltage "0.7 V")))))
				)
				( objectStatus "PCIE_CO_SATA" )
			)
			( electricalCSet "@crescent_city_bb_fab1_lib.crescent_city_bb_fab1(sch_1):\SVID_PCH_CORE_PVNN_AUX_VID_0\"
				( attribute "TOPOLOGY_TEMPLATE_REVISION" "1.0"
					( Origin gBackEnd )
				)
				( topologyData 22398
(SKIDL (Circuits ("MAIN" (Parts ("CRESCENT_CITY_195_20150128_Q.@@U22.BL7" IbisIOPkg (xy (5522 4240)) (refDes "U7C1") (model "Unknown") (Props (_SXDesignName "CRESCENT_CITY_195_20150128_Q") (brdx "15635.75 MIL") (brdy "3784.2 MIL") (bufferModel "CDSDefaultIO_2p5v") (cycle "1") (hold "1.0e-09") (mappingTag "") (offsets ("4" "0") ("5" "0")) (setup "2.0e-09") (state "tristate") (stimuli ("4" "local102") ("5" "local103")) (temperature "27") (termMap ("4" "Data") ("5" "Enable"))) (Terms ("CRESCENT_CITY_195_20150128_Q.X1563575Y378420L2LRATS" "BL7"))) ("CRESCENT_CITY_195_20150128_Q.@@EU67.13" IbisIOPkg (xy (5502 4240)) (refDes "EU8A1") (model "Unknown") (Props (_SXDesignName "CRESCENT_CITY_195_20150128_Q") (brdx "15699.5 MIL") (brdy "6073.37 MIL") (bufferModel "CDSDefaultIO_2p5v") (cycle "1") (hold "1.0e-09") (mappingTag "") (offsets ("4" "0") ("5" "0")) (setup "2.0e-09") (state "tristate") (stimuli ("4" "local104") ("5" "local105")) (temperature "27") (termMap ("4" "Data") ("5" "Enable"))) (Terms ("CRESCENT_CITY_195_20150128_Q.X1569950Y607337L2LRATS" "13"))) ("CRESCENT_CITY_195_20150128_Q.T@@RATS@@EU67.13@@U22.BL7" TLine (xy (5513 4235)) (refDes "TL165") (Props (_SXDesignName "CRESCENT_CITY_195_20150128_Q") (impedance "60 ohm") length("2352.92 MIL") (propDelay "0.422601 ns") (traceCount "1") (traceGeometry "Microstrip") (velocity "5567.72 mil/ns")) (Terms ("CRESCENT_CITY_195_20150128_Q.X1569950Y607337L2LRATS" "1") ("CRESCENT_CITY_195_20150128_Q.X1563575Y378420L2LRATS" "2")))) (Nodes ("CRESCENT_CITY_195_20150128_Q.X1569950Y607337L2LRATS" (terms "CRESCENT_CITY_195_20150128_Q.T@@RATS@@EU67.13@@U22.BL7.1" "CRESCENT_CITY_195_20150128_Q.@@EU67.13.1")) ("CRESCENT_CITY_195_20150128_Q.X1563575Y378420L2LRATS" (terms "CRESCENT_CITY_195_20150128_Q.T@@RATS@@EU67.13@@U22.BL7.2" "CRESCENT_CITY_195_20150128_Q.@@U22.BL7.1"))) (Ports) (Stimuli ("local103" (scope local) (stimType periodic) (Props (periodicFreq "5e+007") (periodicJitter "0") (periodicPattern "1"))) ("local105" (scope local) (stimType periodic) (Props (periodicFreq "5e+007") (periodicJitter "0") (periodicPattern "1"))) ("local102" (scope local) (stimType periodic) (Props (periodicFreq "5e+007") (periodicJitter "0") (periodicPattern "1"))) ("local104" (scope local) (stimType periodic) (Props (periodicFreq "5e+007") (periodicJitter "0") (periodicPattern "1")))) (Notes) (Constraints) (MeasurementSets ("EMI" ("EMIStatus" status("on")) ("PeakEmission" status("on")) ("PeakFrequency" status("on")) ("PulseFreq" status("on")) ("RiseTime" status("on")) ("VoltageSwing" status("on"))) ("Reflection" ("BufferDelayFall" status("off")) ("BufferDelayRise" status("off")) ("EyeHeight" status("off")) ("EyeJitter" status("off")) ("EyeWidth" status("off")) ("FirstIncidentFall" status("off")) ("FirstIncidentRise" status("off")) ("Glitch" status("on")) ("GlitchFall" status("off")) ("GlitchRise" status("off")) ("Monotonic" status("on")) ("MonotonicFall" status("off")) ("MonotonicRise" status("off")) ("NoiseMargin" status("on")) ("NoiseMarginHigh" status("off")) ("NoiseMarginLow" status("off")) ("OvershootHigh" status("on")) ("OvershootLow" status("on")) ("PropDelay" status("on")) ("SettleDelay" status("on")) ("SettleDelayFall" status("off")) ("SettleDelayRise" status("off")) ("SwitchDelay" status("on")) ("SwitchDelayFall" status("off")) ("SwitchDelayRise" status("off"))) ("Crosstalk" ("Crosstalk" status("on"))) ("Custom")) (VectorSets) (Props (XnetName "SVID_PCH_CORE_PVNN_AUX_VID_0") (allDrivers "active") (customSimType "Reflection") (ftsMode ("Typ")) (rcvrSelect "all") (tlineDelayMode "time") (userRevision "1.0")))) (Subckts) (CrossSections ("CRESCENT_CITY_195_20150128_Q" (Props (SXDesignName "CRESCENT_CITY_195_20150128_Q")) (Layers ("" (layerType "SURFACE") (material "AIR") (thickness "0 mil") (dielectricConstant "1.000000") (lossTangent "0") (etchFactor "0.000000") (elecCondVal "0 mho/cm") (thermCondVal "0 w/cm-degC")) ("" (layerType "DIELECTRIC") (material "CONFORMAL_COAT") (thickness "0.5 mil") (dielectricConstant "3.800000") (lossTangent "0.035") (etchFactor "0.000000") (elecCondVal "0 mho/cm") (thermCondVal "0.012 w/cm-degC")) ("TOP" (layerType "CONDUCTOR") (material "COPPER") (thickness "  2.100000 mil") (width "4.00 MIL") (dielectricConstant "4.500000") (lossTangent "0") (etchFactor "70.000000") (elecCondVal "595900.000000 mho/cm") (thermCondVal "0 w/cm-degC") (signalDieConstant "3.800000") (signalLossTangent "0.035")) ("" (layerType "DIELECTRIC") (material "FR-4") (thickness "  2.670000 mil") (dielectricConstant "4.000000") (lossTangent "0.035") (etchFactor "0.000000") (elecCondVal "0 mho/cm") (thermCondVal "0.012 w/cm-degC")) ("L2_GND1" (layerType "PLANE") (material "COPPER") (isShield t) (thickness "  1.250000 mil") (dielectricConstant "4.500000") (lossTangent "0.035") (etchFactor "90.000000") (elecCondVal "595900.000000 mho/cm") (thermCondVal "0.012 w/cm-degC")) ("" (layerType "DIELECTRIC") (material "FR-4") (thickness "  9.000000 mil") (dielectricConstant "4.100000") (lossTangent "0.035") (etchFactor "0.000000") (elecCondVal "0 mho/cm") (thermCondVal "0.012 w/cm-degC")) ("L3_SIG1" (layerType "CONDUCTOR") (material "COPPER") (thickness "  1.250000 mil") (width "4.00 MIL") (dielectricConstant "4.500000") (lossTangent "0.035") (etchFactor "90.000000") (elecCondVal "595900.000000 mho/cm") (thermCondVal "0.012 w/cm-degC") (signalDieConstant "4.100000") (signalLossTangent "0.035")) ("" (layerType "DIELECTRIC") (material "FR-4") (thickness "  3.000000 mil") (dielectricConstant "4.500000") (lossTangent "0.035") (etchFactor "0.000000") (elecCondVal "0 mho/cm") (thermCondVal "0 w/cm-degC")) ("L4_GND2" (layerType "PLANE") (material "COPPER") (isShield t) (thickness "  1.250000 mil") (dielectricConstant "4.500000") (lossTangent "0.035") (etchFactor "90.000000") (elecCondVal "595900.000000 mho/cm") (thermCondVal "0 w/cm-degC")) ("" (layerType "DIELECTRIC") (material "FR-4") (thickness "  9.000000 mil") (dielectricConstant "4.000000") (lossTangent "0.035") (etchFactor "0.000000") (elecCondVal "0 mho/cm") (thermCondVal "0.012 w/cm-degC")) ("L5_SIG2" (layerType "CONDUCTOR") (material "COPPER") (thickness "  1.250000 mil") (width "4.00 MIL") (dielectricConstant "4.500000") (lossTangent "0.035") (etchFactor "90.000000") (elecCondVal "595900.000000 mho/cm") (thermCondVal "0.012 w/cm-degC") (signalDieConstant "4.000000") (signalLossTangent "0.035")) ("" (layerType "DIELECTRIC") (material "FR-4") (thickness "  3.000000 mil") (dielectricConstant "4.500000") (lossTangent "0.035") (etchFactor "0.000000") (elecCondVal "0 mho/cm") (thermCondVal "0 w/cm-degC")) ("L6_GND3" (layerType "PLANE") (material "COPPER") (isShield t) (thickness "  1.250000 mil") (dielectricConstant "4.500000") (lossTangent "0.035") (etchFactor "90.000000") (elecCondVal "595900.000000 mho/cm") (thermCondVal "0 w/cm-degC")) ("" (layerType "DIELECTRIC") (material "FR-4") (thickness "  4.500000 mil") (dielectricConstant "4.100000") (lossTangent "0.035") (etchFactor "0.000000") (elecCondVal "0 mho/cm") (thermCondVal "0.012 w/cm-degC")) ("L7_PWR1-SIG" (layerType "PLANE") (material "COPPER") (isShield t) (thickness "  2.400000 mil") (dielectricConstant "4.500000") (lossTangent "0.035") (etchFactor "90.000000") (elecCondVal "595900.000000 mho/cm") (thermCondVal "0.012 w/cm-degC")) ("" (layerType "DIELECTRIC") (material "FR-4") (thickness "  4.600000 mil") (dielectricConstant "4.000000") (lossTangent "0.035") (etchFactor "0.000000") (elecCondVal "0 mho/cm") (thermCondVal "0.012 w/cm-degC")) ("L8_PWR2-SIG" (layerType "PLANE") (material "COPPER") (isShield t) (thickness "  2.400000 mil") (dielectricConstant "4.500000") (lossTangent "0.035") (etchFactor "90.000000") (elecCondVal "595900.000000 mho/cm") (thermCondVal "0.012 w/cm-degC")) ("" (layerType "DIELECTRIC") (material "FR-4") (thickness "  8.000000 mil") (dielectricConstant "4.500000") (lossTangent "0.035") (etchFactor "0.000000") (elecCondVal "0 mho/cm") (thermCondVal "0 w/cm-degC")) ("" (layerType "DIELECTRIC") (material "FR-4") (thickness "  8.000000 mil") (dielectricConstant "4.500000") (lossTangent "0.035") (etchFactor "0.000000") (elecCondVal "0 mho/cm") (thermCondVal "0 w/cm-degC")) ("" (layerType "DIELECTRIC") (material "FR-4") (thickness "  4.500000 mil") (dielectricConstant "4.500000") (lossTangent "0.035") (etchFactor "0.000000") (elecCondVal "0 mho/cm") (thermCondVal "0 w/cm-degC")) ("L9_GND4" (layerType "PLANE") (material "COPPER") (isShield t) (thickness "  1.250000 mil") (dielectricConstant "4.500000") (lossTangent "0.035") (etchFactor "90.000000") (elecCondVal "595900.000000 mho/cm") (thermCondVal "0 w/cm-degC")) ("" (layerType "DIELECTRIC") (material "FR-4") (thickness "  3.000000 mil") (dielectricConstant "4.100000") (lossTangent "0.035") (etchFactor "0.000000") (elecCondVal "0 mho/cm") (thermCondVal "0.012 w/cm-degC")) ("L10_SIG3" (layerType "CONDUCTOR") (material "COPPER") (thickness "  1.250000 mil") (width "4.00 MIL") (dielectricConstant "4.500000") (lossTangent "0.035") (etchFactor "90.000000") (elecCondVal "595900.000000 mho/cm") (thermCondVal "0.012 w/cm-degC") (signalDieConstant "4.100000") (signalLossTangent "0.035")) ("" (layerType "DIELECTRIC") (material "FR-4") (thickness "  9.000000 mil") (dielectricConstant "4.500000") (lossTangent "0.035") (etchFactor "0.000000") (elecCondVal "0 mho/cm") (thermCondVal "0 w/cm-degC")) ("L11_GND5" (layerType "PLANE") (material "COPPER") (isShield t) (thickness "  1.250000 mil") (dielectricConstant "4.500000") (lossTangent "0.035") (etchFactor "90.000000") (elecCondVal "595900.000000 mho/cm") (thermCondVal "0 w/cm-degC")) ("" (layerType "DIELECTRIC") (material "FR-4") (thickness "  3.000000 mil") (dielectricConstant "4.500000") (lossTangent "0.035") (etchFactor "0.000000") (elecCondVal "0 mho/cm") (thermCondVal "0.012 w/cm-degC")) ("L12_SIG4" (layerType "CONDUCTOR") (material "COPPER") (thickness "  1.250000 mil") (width "4.00 MIL") (dielectricConstant "4.500000") (lossTangent "0.035") (etchFactor "90.000000") (elecCondVal "595900.000000 mho/cm") (thermCondVal "0.012 w/cm-degC") (signalDieConstant "4.500000") (signalLossTangent "0.035")) ("" (layerType "DIELECTRIC") (material "FR-4") (thickness "  9.000000 mil") (dielectricConstant "4.500000") (lossTangent "0.035") (etchFactor "0.000000") (elecCondVal "0 mho/cm") (thermCondVal "0 w/cm-degC")) ("L13_GND6" (layerType "PLANE") (material "COPPER") (isShield t) (thickness "  1.250000 mil") (dielectricConstant "4.500000") (lossTangent "0.035") (etchFactor "90.000000") (elecCondVal "595900.000000 mho/cm") (thermCondVal "0.012 w/cm-degC")) ("" (layerType "DIELECTRIC") (material "FR-4") (thickness "  2.670000 mil") (dielectricConstant "4.500000") (lossTangent "0.035") (etchFactor "0.000000") (elecCondVal "0 mho/cm") (thermCondVal "0.012 w/cm-degC")) ("BOTTOM" (layerType "CONDUCTOR") (material "COPPER") (thickness "  2.100000 mil") (width "4.00 MIL") (dielectricConstant "4.500000") (lossTangent "0") (etchFactor "70.000000") (elecCondVal "595900.000000 mho/cm") (thermCondVal "0 w/cm-degC") (signalDieConstant "3.800000") (signalLossTangent "0.035")) ("" (layerType "DIELECTRIC") (material "CONFORMAL_COAT") (thickness "0.5 mil") (dielectricConstant "3.800000") (lossTangent "0.035") (etchFactor "0.000000") (elecCondVal "0 mho/cm") (thermCondVal "0.012 w/cm-degC")) ("" (layerType "SURFACE") (material "AIR") (thickness "0 mil") (dielectricConstant "1.000000") (lossTangent "0") (etchFactor "0.000000") (elecCondVal "0 mho/cm") (thermCondVal "0 w/cm-degC"))))) (Props (DesUnits "mils 2") (LayerStack ("DIELECTRIC" "DIELECTRIC" "BOTTOM" "DIELECTRIC" "L13_GND6" "DIELECTRIC" "L12_SIG4" "DIELECTRIC" "L11_GND5" "DIELECTRIC" "L10_SIG3" "DIELECTRIC" "L9_GND4" "DIELECTRIC" "DIELECTRIC" "DIELECTRIC" "L8_PWR2-SIG" "DIELECTRIC" "L7_PWR1-SIG" "DIELECTRIC" "L6_GND3" "DIELECTRIC" "L5_SIG2" "DIELECTRIC" "L4_GND2" "DIELECTRIC" "L3_SIG1" "DIELECTRIC" "L2_GND1" "DIELECTRIC" "TOP" "DIELECTRIC" "DIELECTRIC")) (Revision "16.600")) (Params (DiffOutputPkg ((temperature "27") (bufferModelNonInverting "CDSDefaultOutput_2p5v") (bufferModelInverting "CDSDefaultOutput_2p5v") (stimuli nil) (offsets nil) (state "tristate") (cycle "1") (termMap nil) (setup "0.9e-09") (hold "0.4e-09") (rise nil) (fall nil) (threshOutputHighMin "2.375  V") (threshOutputHighTyp "2.5  V") (threshOutputHighMax "2.625  V") (threshOutputLowMin "1.275  V") (threshOutputLowTyp "1.7  V") (threshOutputLowMax "1.985  V") (mappingTagNonInverting nil) (mappingTagInverting nil) (spice nil))) (HiClampTerm ((cutoffVoltage "0.7 V") (voltage "5 V") (maxDelay "0.1 ns"))) (LowClampTerm ((cutoffVoltage "0.7 V") (voltage "0 V") (maxDelay "0.1 ns"))) (DiffOutput ((temperature "27") (bufferModelNonInverting "CDSDefaultOutput_2p5v") (bufferModelInverting "CDSDefaultOutput_2p5v") (stimuli nil) (offsets nil) (state "tristate") (cycle "1") (termMap nil) (setup "0.9e-09") (hold "0.4e-09") (rise nil) (fall nil) (threshOutputHighMin "2.375  V") (threshOutputHighTyp "2.5  V") (threshOutputHighMax "2.625  V") (threshOutputLowMin "1.275  V") (threshOutputLowTyp "1.7  V") (threshOutputLowMax "1.985  V") (mappingTagNonInverting nil) (mappingTagInverting nil) (spice nil))) (Via ((model "Unknown") (viaOutputFormat "Unknown") (viaPadstack nil) (viaTopLayer nil) (viaBottomLayer nil) (viaIsPower nil) (viaIsGround nil))) (Resistor ((resistance "50 ohm") (orientation "0"))) (RCTerm ((resistance "50 ohm") (capacitance "20 pF") (voltage "5 V") (maxDelay "0.1 ns"))) (DiffIOPkg ((temperature "27") (bufferModelNonInverting "CDSDefaultIO_2p5v") (bufferModelInverting "CDSDefaultIO_2p5v") (stimuli nil) (offsets nil) (state "tristate") (cycle "1") (termMap nil) (setup "0.9e-09") (hold "0.4e-09") (rise nil) (fall nil) (threshInputHighMin "1.7 V") (threshInputHighTyp "1.7  V") (threshInputHighMax "1.7  V") (threshInputLowMin "0.7  V") (threshInputLowTyp "0.7  V") (threshInputLowMax "0.7 ") (threshOutputHighMin "2.365  V") (threshOutputHighTyp "2.5  V") (threshOutputHighMax "2.625  V") (threshOutputLowMin "1.275  V") (threshOutputLowTyp "1.7  V") (threshOutputLowMax "1.985  V") (mappingTagNonInverting nil) (mappingTagInverting nil) (spice nil))) (Trace ((d1Thickness "10 mil") (d1Constant "4.5") (d1LossTangent "0.035") (d2Thickness "10 mil") (d2Constant "4.5") (d2LossTangent "0.035") (d3Thickness "0.0") (d3Constant "1.0") (d3LossTangent "0") length("1000 mil") (spacing "5 mil") (spacing2 "5 mil") (spacing3 "5 mil") (spacing4 "5 mil") (spacing5 "5 mil") (traceConductivity "595900 mho/cm") (traceGeometry "microstrip") (traceLayerName "") (traceThickness "0.72 mil") (traceType "single") (traceWidth "5.0 mil") (traceWidth2 "5.0 mil") (traceWidth3 "5.0 mil") (traceWidth4 "5.0 mil") (traceWidth5 "5.0 mil") (traceWidth6 "5.0 mil") (offset "0 mil") (traceCount "1") (impedance nil))) (TheveninTerm ((resistanceUp "180 ohm") (resistanceDown "270 ohm") (voltageUp "5 V") (voltageDown "0 V") (maxDelay "0.1 ns"))) (DiffIO ((temperature "27") (bufferModelNonInverting "CDSDefaultIO_2p5v") (bufferModelInverting "CDSDefaultIO_2p5v") (stimuli nil) (offsets nil) (state "tristate") (cycle "1") (termMap nil) (setup "0.9e-09") (hold "0.4e-09") (rise nil) (fall nil) (threshInputHighMin "1.7 V") (threshInputHighTyp "1.7  V") (threshInputHighMax "1.7  V") (threshInputLowMin "0.7  V") (threshInputLowTyp "0.7  V") (threshInputLowMax "0.7 ") (threshOutputHighMin "2.365  V") (threshOutputHighTyp "2.5  V") (threshOutputHighMax "2.625  V") (threshOutputLowMin "1.275  V") (threshOutputLowTyp "1.7  V") (threshOutputLowMax "1.985  V") (mappingTagNonInverting nil) (mappingTagInverting nil) (spice nil))) (ShuntTerm ((resistance "50 ohm") (voltage "5 V") (maxDelay "0.1 ns"))) (Inductor ((inductance "5 nH") (orientation "0"))) (Capacitor ((capacitance "10 pF") (orientation "0"))) (RLGC (length("1000 mil"))) (Source ((voltage "5 V"))) (DiffInput ((temperature "27") (bufferModelNonInverting "CDSDefaultInput_2p5v") (bufferModelInverting "CDSDefaultInput_2p5v") (threshInputHighMin "1.7 V") (threshInputHighTyp "1.7  V") (threshInputHighMax "1.7  V") (threshInputLowMin "0.7  V") (threshInputLowTyp "0.7  V") (threshInputLowMax "0.7  V") (mappingTagNonInverting nil) (mappingTagInverting nil) (cycle "1"))) (Cable (length("1 m"))) (CPWSL ((d1Thickness "10 mil") (d1Constant "4.5") (d1LossTangent "0.035") (d2Thickness "0.72 mil") (d2Constant "4.5") (d2LossTangent "0.035") (d3Thickness "10 mil") (d3Constant "4.5") (d3LossTangent "0.035") length("1000 mil") (spacing "5 mil") (spacing2 "5 mil") (spacing3 "5 mil") (spacing4 "5 mil") (spacing5 "5 mil") (traceConductivity "595900 mho/cm") (traceGeometry "cpwms") (traceLayerName "") (traceThickness "0.72 mil") (traceType "single") (traceWidth "5.0 mil") (traceWidth2 "5.0 mil") (traceWidth3 "5.0 mil") (traceWidth4 "5.0 mil") (traceWidth5 "5.0 mil") (traceWidth6 "5.0 mil") (offset "0 mil") (traceCount "1") (impedance nil))) (ESpiceDevice nil) (CPWMS ((d1Thickness "10 mil") (d1Constant "4.5") (d1LossTangent "0.035") (d2Thickness "0.72 mil") (d2Constant "4.5") (d2LossTangent "0.035") (d3Thickness "0.0") (d3Constant "1") (d3LossTangent "0") length("1000 mil") (spacing "5 mil") (spacing2 "5 mil") (spacing3 "5 mil") (spacing4 "5 mil") (spacing5 "5 mil") (traceConductivity "595900 mho/cm") (traceGeometry "cpwms") (traceLayerName "") (traceThickness "0.72 mil") (traceType "single") (traceWidth "5.0 mil") (traceWidth2 "5.0 mil") (traceWidth3 "5.0 mil") (traceWidth4 "5.0 mil") (traceWidth5 "5.0 mil") (traceWidth6 "5.0 mil") (offset "0 mil") (traceCount "1") (impedance nil))) (Diode ((cutoffVoltage "0.7 V"))) (CPW ((d1Thickness "10 mil") (d1Constant "4.5") (d1LossTangent "0.035") (d2Thickness "0.72 mil") (d2Constant "1") (d2LossTangent "0") (d3Thickness "0.0") (d3Constant "1") (d3LossTangent "0") length("1000 mil") (spacing "5 mil") (spacing2 "5 mil") (spacing3 "5 mil") (spacing4 "5 mil") (spacing5 "5 mil") (traceConductivity "595900 mho/cm") (traceGeometry "cpwms") (traceLayerName "") (traceThickness "0.72 mil") (traceType "single") (traceWidth "5.0 mil") (traceWidth2 "5.0 mil") (traceWidth3 "5.0 mil") (traceWidth4 "5.0 mil") (traceWidth5 "5.0 mil") (traceWidth6 "5.0 mil") (offset "0 mil") (traceCount "1") (impedance nil))) (DualClampTerm ((cutoffVoltageUp "0.7 V") (cutoffVoltageDown "0.7 V") (voltageUp "5 V") (voltageDown "0 V") (maxDelay "0.1 ns"))) (IbisOutputPkg ((temperature "27") (bufferModel "CDSDefaultOutput_2p5v") (stimuli nil) (offsets nil) (state "tristate") (cycle "1") (termMap nil) (setup "2.0e-09") (hold "1.0e-09") (rise nil) (fall nil) (macroType nil) (voltage nil) (spice nil) (LEFDEFPinName nil) (LEFDEFPinType nil) (mappingTag nil))) (IbisIO_OpenPullDown ((temperature "27") (bufferModel "CDSDefaultIO_2p5v") (stimuli nil) (offsets nil) (state "tristate") (cycle "1") (termMap nil) (setup "2.0e-09") (hold "1.0e-09") (rise nil) (fall nil) (macroType nil) (voltage nil) (spice nil) (LEFDEFPinName nil) (LEFDEFPinType nil) (mappingTag nil))) (IbisInputPkg ((temperature "27") (bufferModel "CDSDefaultInput_2p5v") (cycle "1") (LEFDEFPinName nil) (LEFDEFPinType nil) (mappingTag nil))) (IbisIOMacro ((temperature "27") (bufferModel "CDSDefaultIO_2p5v") (stimuli nil) (offsets nil) (state "tristate") (cycle "1") (termMap nil) (setup "2.0e-09") (hold "1.0e-09") (rise nil) (fall nil) (macroType nil) (voltage nil) (spice nil) (LEFDEFPinName nil) (LEFDEFPinType nil) (mappingTag nil))) (IbisIO_OpenPullUp ((temperature "27") (bufferModel "CDSDefaultIO_2p5v") (stimuli nil) (offsets nil) (state "tristate") (cycle "1") (termMap nil) (setup "2.0e-09") (hold "1.0e-09") (rise nil) (fall nil) (macroType nil) (voltage nil) (spice nil) (LEFDEFPinName nil) (LEFDEFPinType nil) (mappingTag nil))) (IbisIOPkg ((temperature "27") (bufferModel "CDSDefaultIO_2p5v") (stimuli nil) (offsets nil) (state "tristate") (cycle "1") (termMap nil) (setup "2.0e-09") (hold "1.0e-09") (rise nil) (fall nil) (macroType nil) (voltage nil) (spice nil) (LEFDEFPinName nil) (LEFDEFPinType nil) (mappingTag nil))) (clocked ((clockRise "1e-09") (clockFall "1e-09") (clockFreq "100e6") (clockInitState "0") (clockDutyCycle "0.5") (clockJitter "0"))) (periodic ((periodicFreq "100e6") (periodicPattern "10") (periodicJitter "0"))) (IbisIO ((temperature "27") (bufferModel "CDSDefaultIO_2p5v") (stimuli nil) (offsets nil) (state "tristate") (cycle "1") (termMap nil) (setup "2.0e-09") (hold "1.0e-09") (rise nil) (fall nil) (macroType nil) (voltage nil) (spice nil) (LEFDEFPinName nil) (LEFDEFPinType nil) (mappingTag nil))) (async ((asyncTimePoints "") (asyncInitState "1"))) (IbisOutput ((temperature "27") (bufferModel "CDSDefaultOutput_2p5v") (stimuli nil) (offsets nil) (state "tristate") (cycle "1") (termMap nil) (setup "2.0e-09") (hold "1.0e-09") (rise nil) (fall nil) (macroType nil) (voltage nil) (spice nil) (LEFDEFPinName nil) (LEFDEFPinType nil) (mappingTag nil))) (TLine ((diffImpedance "100ohm") (diffVelocity "1.4142e+08M/s") (impedance "60ohm") length("2800 mil") (propDelay "0.5 ns") (velocity "5600 mil/ns") (traceCount "1") (traceGeometry "Microstrip") (impedanceMin nil) (impedanceMax nil) (lengthMin nil) (lengthMax nil) (propDelayMin nil) (propDelayMax nil) (impedanceSweepCount nil) (propDelaySweepCount nil) (velocitySweepCount nil) (lengthSweepCount nil) (matchSetName nil))) (CurrentProbe nil) (IbisInput ((temperature "27") (bufferModel "CDSDefaultInput_2p5v") (cycle "1") (LEFDEFPinName nil) (LEFDEFPinType nil) (mappingTag nil))) (SeriesTerm ((resistance "22 ohm") (maxDelay "0.1 ns"))) (Connector nil) (sync ((syncFreq "100e6") (syncInitState "1") (syncPattern "10") (syncEdgeSwitch "rise"))) (IbisOutput_OpenPullUp ((temperature "27") (bufferModel "CDSDefaultOutput_2p5v") (stimuli nil) (offsets nil) (state "tristate") (cycle "1") (termMap nil) (setup "2.0e-09") (hold "1.0e-09") (rise nil) (fall nil) (macroType nil) (voltage nil) (spice nil) (LEFDEFPinName nil) (LEFDEFPinType nil) (mappingTag nil))) (DiffInputPkg ((temperature "27") (bufferModelNonInverting "CDSDefaultInput_2p5v") (bufferModelInverting "CDSDefaultInput_2p5v") (threshInputHighMin "1.7 V") (threshInputHighTyp "1.7  V") (threshInputHighMax "1.7  V") (threshInputLowMin "0.7  V") (threshInputLowTyp "0.7  V") (threshInputLowMax "0.7  V") (mappingTagNonInverting nil) (mappingTagInverting nil) (cycle "1"))) (idlCircuit ((allDrivers "active") (ftsMode '("Typ")) (rcvrSelect "all") (simMode "Reflection") (tlineDelayMode "time") (userRevision "1.0") (autoSolve "On")))))
				)
				( objectStatus "SVID_PCH_CORE_PVNN_AUX_VID_0" )
			)
			( electricalCSet "@crescent_city_bb_fab1_lib.crescent_city_bb_fab1(sch_1):\CLK_100M_OTHERS\"
				( attribute "DIFFP_GATHER_CONTROL" "IGNORE"
					( Origin gBackEnd )
				)
				( attribute "DIFFP_UNCOUPLED_LENGTH" "350.00"
					( Origin gBackEnd )
				)
				( attribute "DIFFP_COUPLED_PLUS" "0.50"
					( Origin gBackEnd )
				)
				( attribute "DIFFP_COUPLED_MINUS" "0.50"
					( Origin gBackEnd )
				)
				( attribute "DIFFP_PHASE_TOL" "10 mil"
					( Units "uPhaseTol" "ns" 1.000000)
					( Origin gBackEnd )
				)
				( attribute "TOPOLOGY_TEMPLATE_REVISION" "1.0"
					( Origin gBackEnd )
				)
				( topologyData 24288
(SKIDL (Circuits ("MAIN" (Parts ("CRESCENT_CITY_623_20150314_B.@@U22.J33" IbisIOPkg (xy (5528 4240)) (refDes "U7C1") (model "Unknown") (Props (_SXDesignName "CRESCENT_CITY_623_20150314_B") (brdx "14894.75 MIL") (brdy "4257.4 MIL") (bufferModel "CDSDefaultIO_2p5v") (cycle "1") (hold "1.0e-09") (mappingTag "") (offsets ("4" "0") ("5" "0")) (setup "2.0e-09") (state "tristate") (stimuli ("4" "local0") ("5" "local1")) (temperature "27") (termMap ("4" "Data") ("5" "Enable"))) (Terms ("CRESCENT_CITY_623_20150314_B.X1489475Y425740L2LRATS" "J33"))) ("CRESCENT_CITY_623_20150314_B.@@J73.35" IbisIOPkg (xy (5502 4240)) (refDes "J8G1") (model "Unknown") (Props (_SXDesignName "CRESCENT_CITY_623_20150314_B") (brdx "16961.35 MIL") (brdy "306.76 MIL") (bufferModel "CDSDefaultIO_2p5v") (cycle "1") (hold "1.0e-09") (mappingTag "") (offsets ("4" "0") ("5" "0")) (setup "2.0e-09") (state "tristate") (stimuli ("4" "local2") ("5" "local3")) (temperature "27") (termMap ("4" "Data") ("5" "Enable"))) (Terms ("CRESCENT_CITY_623_20150314_B.X1696135Y30676L2LRATS" "35"))) ("CRESCENT_CITY_623_20150314_B.T@@RATS@@U22.J33@@J73.35" TLine (xy (5513 4235)) (mirror x) (refDes "TL1") (Props (_SXDesignName "CRESCENT_CITY_623_20150314_B") (impedance "47.169 ohm") length("6017.24 MIL") (propDelay "1.08074 ns") (traceCount "1") (traceGeometry "Microstrip") (velocity "5567.72 mil/ns")) (Terms ("CRESCENT_CITY_623_20150314_B.X1489475Y425740L2LRATS" "1") ("CRESCENT_CITY_623_20150314_B.X1696135Y30676L2LRATS" "2")))) (Nodes ("CRESCENT_CITY_623_20150314_B.X1696135Y30676L2LRATS" (terms "CRESCENT_CITY_623_20150314_B.T@@RATS@@U22.J33@@J73.35.2" "CRESCENT_CITY_623_20150314_B.@@J73.35.1")) ("CRESCENT_CITY_623_20150314_B.X1489475Y425740L2LRATS" (terms "CRESCENT_CITY_623_20150314_B.T@@RATS@@U22.J33@@J73.35.1" "CRESCENT_CITY_623_20150314_B.@@U22.J33.1"))) (Ports) (Stimuli ("local2" (scope local) (stimType periodic) (Props (periodicFreq "5e+007") (periodicJitter "0") (periodicPattern "1"))) ("local0" (scope local) (stimType periodic) (Props (periodicFreq "5e+007") (periodicJitter "0") (periodicPattern "1"))) ("local1" (scope local) (stimType periodic) (Props (periodicFreq "5e+007") (periodicJitter "0") (periodicPattern "1"))) ("local3" (scope local) (stimType periodic) (Props (periodicFreq "5e+007") (periodicJitter "0") (periodicPattern "1")))) (Notes) (Constraints ("DP_GATHER_CONTROL" "IGNORE") ("DP_MAX_UNCOUPLED_LENGTH" "0.000254") ("DP_PHASE_TOLERANCE" ("LENGTH" "0.000254")) ("RELATIVE_PROPAGATION_DELAY" ("MG_CLK_G2-BCLK" "CRESCENT_CITY_623_20150314_B U22.J33" "CRESCENT_CITY_623_20150314_B J73.35" "GLOBAL" "LENGTH" "0.127" "LENGTH" "0.12639"))) (MeasurementSets ("EMI" ("EMIStatus" status("on")) ("PeakEmission" status("on")) ("PeakFrequency" status("on")) ("PulseFreq" status("on")) ("RiseTime" status("on")) ("VoltageSwing" status("on"))) ("Reflection" ("BufferDelayFall" status("off")) ("BufferDelayRise" status("off")) ("EyeHeight" status("off")) ("EyeJitter" status("off")) ("EyeWidth" status("off")) ("FirstIncidentFall" status("off")) ("FirstIncidentRise" status("off")) ("Glitch" status("on")) ("GlitchFall" status("off")) ("GlitchRise" status("off")) ("Monotonic" status("on")) ("MonotonicFall" status("off")) ("MonotonicRise" status("off")) ("NoiseMargin" status("on")) ("NoiseMarginHigh" status("off")) ("NoiseMarginLow" status("off")) ("OvershootHigh" status("on")) ("OvershootLow" status("on")) ("PropDelay" status("on")) ("SettleDelay" status("on")) ("SettleDelayFall" status("off")) ("SettleDelayRise" status("off")) ("SwitchDelay" status("on")) ("SwitchDelayFall" status("off")) ("SwitchDelayRise" status("off"))) ("Crosstalk" ("Crosstalk" status("on"))) ("Custom")) (VectorSets) (Props (XnetName "CLK_100M_PCH_SLOTX24_S0_DN") (allDrivers "active") (customSimType "Reflection") (ftsMode ("Typ")) (rcvrSelect "all") (tlineDelayMode "time") (userRevision "1.0")))) (Subckts) (CrossSections ("CRESCENT_CITY_623_20150314_B" (Props (SXDesignName "CRESCENT_CITY_623_20150314_B")) (Layers ("" (layerType "SURFACE") (material "AIR") (thickness "0 mil") (dielectricConstant "1.000000") (lossTangent "0") (etchFactor "0.000000") (elecCondVal "0 mho/cm") (thermCondVal "0 w/cm-degC")) ("" (layerType "DIELECTRIC") (material "CONFORMAL_COAT") (thickness "0.5 mil") (dielectricConstant "3.800000") (lossTangent "0.035") (etchFactor "0.000000") (elecCondVal "0 mho/cm") (thermCondVal "0.012 w/cm-degC")) ("TOP" (layerType "CONDUCTOR") (material "COPPER") (thickness "  2.100000 mil") (width "4.00 MIL") (dielectricConstant "4.500000") (lossTangent "0") (etchFactor "70.000000") (elecCondVal "595900.000000 mho/cm") (thermCondVal "0 w/cm-degC") (signalDieConstant "3.800000") (signalLossTangent "0.035")) ("" (layerType "DIELECTRIC") (material "FR-4") (thickness "  2.670000 mil") (dielectricConstant "4.000000") (lossTangent "0.035") (etchFactor "0.000000") (elecCondVal "0 mho/cm") (thermCondVal "0.012 w/cm-degC")) ("L2_GND1" (layerType "PLANE") (material "COPPER") (isShield t) (thickness "  1.250000 mil") (dielectricConstant "4.500000") (lossTangent "0.035") (etchFactor "90.000000") (elecCondVal "595900.000000 mho/cm") (thermCondVal "0.012 w/cm-degC")) ("" (layerType "DIELECTRIC") (material "FR-4") (thickness "  9.000000 mil") (dielectricConstant "4.100000") (lossTangent "0.035") (etchFactor "0.000000") (elecCondVal "0 mho/cm") (thermCondVal "0.012 w/cm-degC")) ("L3_SIG1" (layerType "CONDUCTOR") (material "COPPER") (thickness "  1.250000 mil") (width "4.00 MIL") (dielectricConstant "4.500000") (lossTangent "0.035") (etchFactor "90.000000") (elecCondVal "595900.000000 mho/cm") (thermCondVal "0.012 w/cm-degC") (signalDieConstant "4.100000") (signalLossTangent "0.035")) ("" (layerType "DIELECTRIC") (material "FR-4") (thickness "  3.000000 mil") (dielectricConstant "4.500000") (lossTangent "0.035") (etchFactor "0.000000") (elecCondVal "0 mho/cm") (thermCondVal "0 w/cm-degC")) ("L4_GND2" (layerType "PLANE") (material "COPPER") (isShield t) (thickness "  1.250000 mil") (dielectricConstant "4.500000") (lossTangent "0.035") (etchFactor "90.000000") (elecCondVal "595900.000000 mho/cm") (thermCondVal "0 w/cm-degC")) ("" (layerType "DIELECTRIC") (material "FR-4") (thickness "  9.000000 mil") (dielectricConstant "4.000000") (lossTangent "0.035") (etchFactor "0.000000") (elecCondVal "0 mho/cm") (thermCondVal "0.012 w/cm-degC")) ("L5_SIG2" (layerType "CONDUCTOR") (material "COPPER") (thickness "  1.250000 mil") (width "4.00 MIL") (dielectricConstant "4.500000") (lossTangent "0.035") (etchFactor "90.000000") (elecCondVal "595900.000000 mho/cm") (thermCondVal "0.012 w/cm-degC") (signalDieConstant "4.000000") (signalLossTangent "0.035")) ("" (layerType "DIELECTRIC") (material "FR-4") (thickness "  3.000000 mil") (dielectricConstant "4.500000") (lossTangent "0.035") (etchFactor "0.000000") (elecCondVal "0 mho/cm") (thermCondVal "0 w/cm-degC")) ("L6_GND3" (layerType "PLANE") (material "COPPER") (isShield t) (thickness "  1.250000 mil") (dielectricConstant "4.500000") (lossTangent "0.035") (etchFactor "90.000000") (elecCondVal "595900.000000 mho/cm") (thermCondVal "0 w/cm-degC")) ("" (layerType "DIELECTRIC") (material "FR-4") (thickness "  4.500000 mil") (dielectricConstant "4.100000") (lossTangent "0.035") (etchFactor "0.000000") (elecCondVal "0 mho/cm") (thermCondVal "0.012 w/cm-degC")) ("L7_PWR1-SIG" (layerType "PLANE") (material "COPPER") (isShield t) (thickness "  2.610000 mil") (dielectricConstant "4.500000") (lossTangent "0.035") (etchFactor "90.000000") (elecCondVal "595900.000000 mho/cm") (thermCondVal "0.012 w/cm-degC")) ("" (layerType "DIELECTRIC") (material "FR-4") (thickness "  3.100000 mil") (dielectricConstant "4.500000") (lossTangent "0.035") (etchFactor "0.000000") (elecCondVal "0 mho/cm") (thermCondVal "0 w/cm-degC")) ("L8_GND_TEMP" (layerType "PLANE") (material "COPPER") (isShield t) (thickness "  1.250000 mil") (dielectricConstant "4.500000") (lossTangent "0.035") (etchFactor "90.000000") (elecCondVal "595900.000000 mho/cm") (thermCondVal "0 w/cm-degC")) ("" (layerType "DIELECTRIC") (material "FR-4") (thickness "  3.030000 mil") (dielectricConstant "4.500000") (lossTangent "0.035") (etchFactor "0.000000") (elecCondVal "0 mho/cm") (thermCondVal "0 w/cm-degC")) ("L9_SIG_TEMP" (layerType "CONDUCTOR") (material "COPPER") (thickness "  1.250000 mil") (width "3.52 MIL") (dielectricConstant "4.500000") (lossTangent "0.035") (etchFactor "90.000000") (elecCondVal "595900.000000 mho/cm") (thermCondVal "0 w/cm-degC") (signalDieConstant "4.500000") (signalLossTangent "0.035")) ("" (layerType "DIELECTRIC") (material "FR-4") (thickness "  5.000000 mil") (dielectricConstant "4.500000") (lossTangent "0.035") (etchFactor "0.000000") (elecCondVal "0 mho/cm") (thermCondVal "0 w/cm-degC")) ("L10_SIG_TEMP" (layerType "CONDUCTOR") (material "COPPER") (thickness "  1.250000 mil") (width "3.52 MIL") (dielectricConstant "4.500000") (lossTangent "0.035") (etchFactor "90.000000") (elecCondVal "595900.000000 mho/cm") (thermCondVal "0 w/cm-degC") (signalDieConstant "4.500000") (signalLossTangent "0.035")) ("" (layerType "DIELECTRIC") (material "FR-4") (thickness "  3.030000 mil") (dielectricConstant "4.500000") (lossTangent "0.035") (etchFactor "0.000000") (elecCondVal "0 mho/cm") (thermCondVal "0 w/cm-degC")) ("L11_GND_TEMP" (layerType "PLANE") (material "COPPER") (isShield t) (thickness "  1.250000 mil") (dielectricConstant "4.500000") (lossTangent "0.035") (etchFactor "90.000000") (elecCondVal "595900.000000 mho/cm") (thermCondVal "0 w/cm-degC")) ("" (layerType "DIELECTRIC") (material "FR-4") (thickness "  3.100000 mil") (dielectricConstant "4.000000") (lossTangent "0.035") (etchFactor "0.000000") (elecCondVal "0 mho/cm") (thermCondVal "0.012 w/cm-degC")) ("L12_PWR2-SIG" (layerType "PLANE") (material "COPPER") (isShield t) (thickness "  2.610000 mil") (dielectricConstant "4.500000") (lossTangent "0.035") (etchFactor "90.000000") (elecCondVal "595900.000000 mho/cm") (thermCondVal "0.012 w/cm-degC")) ("" (layerType "DIELECTRIC") (material "FR-4") (thickness "  4.500000 mil") (dielectricConstant "4.500000") (lossTangent "0.035") (etchFactor "0.000000") (elecCondVal "0 mho/cm") (thermCondVal "0 w/cm-degC")) ("L13_GND4" (layerType "PLANE") (material "COPPER") (isShield t) (thickness "  1.250000 mil") (dielectricConstant "4.500000") (lossTangent "0.035") (etchFactor "90.000000") (elecCondVal "595900.000000 mho/cm") (thermCondVal "0 w/cm-degC")) ("" (layerType "DIELECTRIC") (material "FR-4") (thickness "  3.000000 mil") (dielectricConstant "4.100000") (lossTangent "0.035") (etchFactor "0.000000") (elecCondVal "0 mho/cm") (thermCondVal "0.012 w/cm-degC")) ("L14_SIG3" (layerType "CONDUCTOR") (material "COPPER") (thickness "  1.250000 mil") (width "4.00 MIL") (dielectricConstant "4.500000") (lossTangent "0.035") (etchFactor "90.000000") (elecCondVal "595900.000000 mho/cm") (thermCondVal "0.012 w/cm-degC") (signalDieConstant "4.100000") (signalLossTangent "0.035")) ("" (layerType "DIELECTRIC") (material "FR-4") (thickness "  9.000000 mil") (dielectricConstant "4.500000") (lossTangent "0.035") (etchFactor "0.000000") (elecCondVal "0 mho/cm") (thermCondVal "0 w/cm-degC")) ("L15_GND5" (layerType "PLANE") (material "COPPER") (isShield t) (thickness "  1.250000 mil") (dielectricConstant "4.500000") (lossTangent "0.035") (etchFactor "90.000000") (elecCondVal "595900.000000 mho/cm") (thermCondVal "0 w/cm-degC")) ("" (layerType "DIELECTRIC") (material "FR-4") (thickness "  3.000000 mil") (dielectricConstant "4.500000") (lossTangent "0.035") (etchFactor "0.000000") (elecCondVal "0 mho/cm") (thermCondVal "0.012 w/cm-degC")) ("L16_SIG4" (layerType "CONDUCTOR") (material "COPPER") (thickness "  1.250000 mil") (width "4.00 MIL") (dielectricConstant "4.500000") (lossTangent "0.035") (etchFactor "90.000000") (elecCondVal "595900.000000 mho/cm") (thermCondVal "0.012 w/cm-degC") (signalDieConstant "4.500000") (signalLossTangent "0.035")) ("" (layerType "DIELECTRIC") (material "FR-4") (thickness "  9.000000 mil") (dielectricConstant "4.500000") (lossTangent "0.035") (etchFactor "0.000000") (elecCondVal "0 mho/cm") (thermCondVal "0 w/cm-degC")) ("L17_GND6" (layerType "PLANE") (material "COPPER") (isShield t) (thickness "  1.250000 mil") (dielectricConstant "4.500000") (lossTangent "0.035") (etchFactor "90.000000") (elecCondVal "595900.000000 mho/cm") (thermCondVal "0.012 w/cm-degC")) ("" (layerType "DIELECTRIC") (material "FR-4") (thickness "  2.670000 mil") (dielectricConstant "4.500000") (lossTangent "0.035") (etchFactor "0.000000") (elecCondVal "0 mho/cm") (thermCondVal "0.012 w/cm-degC")) ("BOTTOM" (layerType "CONDUCTOR") (material "COPPER") (thickness "  2.100000 mil") (width "4.00 MIL") (dielectricConstant "4.500000") (lossTangent "0") (etchFactor "70.000000") (elecCondVal "595900.000000 mho/cm") (thermCondVal "0 w/cm-degC") (signalDieConstant "3.800000") (signalLossTangent "0.035")) ("" (layerType "DIELECTRIC") (material "CONFORMAL_COAT") (thickness "0.5 mil") (dielectricConstant "3.800000") (lossTangent "0.035") (etchFactor "0.000000") (elecCondVal "0 mho/cm") (thermCondVal "0.012 w/cm-degC")) ("" (layerType "SURFACE") (material "AIR") (thickness "0 mil") (dielectricConstant "1.000000") (lossTangent "0") (etchFactor "0.000000") (elecCondVal "0 mho/cm") (thermCondVal "0 w/cm-degC"))))) (Props (DesUnits "mils 2") (LayerStack ("DIELECTRIC" "DIELECTRIC" "BOTTOM" "DIELECTRIC" "L17_GND6" "DIELECTRIC" "L16_SIG4" "DIELECTRIC" "L15_GND5" "DIELECTRIC" "L14_SIG3" "DIELECTRIC" "L13_GND4" "DIELECTRIC" "L12_PWR2-SIG" "DIELECTRIC" "L11_GND_TEMP" "DIELECTRIC" "L10_SIG_TEMP" "DIELECTRIC" "L9_SIG_TEMP" "DIELECTRIC" "L8_GND_TEMP" "DIELECTRIC" "L7_PWR1-SIG" "DIELECTRIC" "L6_GND3" "DIELECTRIC" "L5_SIG2" "DIELECTRIC" "L4_GND2" "DIELECTRIC" "L3_SIG1" "DIELECTRIC" "L2_GND1" "DIELECTRIC" "TOP" "DIELECTRIC" "DIELECTRIC")) (Revision "16.600")) (Params (RLGC (length("1000 mil"))) (DiffIO ((temperature "27") (bufferModelNonInverting "CDSDefaultIO_2p5v") (bufferModelInverting "CDSDefaultIO_2p5v") (stimuli nil) (offsets nil) (state "tristate") (cycle "1") (termMap nil) (setup "0.9e-09") (hold "0.4e-09") (rise nil) (fall nil) (threshInputHighMin "1.7 V") (threshInputHighTyp "1.7  V") (threshInputHighMax "1.7  V") (threshInputLowMin "0.7  V") (threshInputLowTyp "0.7  V") (threshInputLowMax "0.7 ") (threshOutputHighMin "2.365  V") (threshOutputHighTyp "2.5  V") (threshOutputHighMax "2.625  V") (threshOutputLowMin "1.275  V") (threshOutputLowTyp "1.7  V") (threshOutputLowMax "1.985  V") (mappingTagNonInverting nil) (mappingTagInverting nil) (spice nil))) (Source ((voltage "5 V"))) (DiffIOPkg ((temperature "27") (bufferModelNonInverting "CDSDefaultIO_2p5v") (bufferModelInverting "CDSDefaultIO_2p5v") (stimuli nil) (offsets nil) (state "tristate") (cycle "1") (termMap nil) (setup "0.9e-09") (hold "0.4e-09") (rise nil) (fall nil) (threshInputHighMin "1.7 V") (threshInputHighTyp "1.7  V") (threshInputHighMax "1.7  V") (threshInputLowMin "0.7  V") (threshInputLowTyp "0.7  V") (threshInputLowMax "0.7 ") (threshOutputHighMin "2.365  V") (threshOutputHighTyp "2.5  V") (threshOutputHighMax "2.625  V") (threshOutputLowMin "1.275  V") (threshOutputLowTyp "1.7  V") (threshOutputLowMax "1.985  V") (mappingTagNonInverting nil) (mappingTagInverting nil) (spice nil))) (Inductor ((inductance "5 nH") (orientation "0"))) (DiffOutput ((temperature "27") (bufferModelNonInverting "CDSDefaultOutput_2p5v") (bufferModelInverting "CDSDefaultOutput_2p5v") (stimuli nil) (offsets nil) (state "tristate") (cycle "1") (termMap nil) (setup "0.9e-09") (hold "0.4e-09") (rise nil) (fall nil) (threshOutputHighMin "2.375  V") (threshOutputHighTyp "2.5  V") (threshOutputHighMax "2.625  V") (threshOutputLowMin "1.275  V") (threshOutputLowTyp "1.7  V") (threshOutputLowMax "1.985  V") (mappingTagNonInverting nil) (mappingTagInverting nil) (spice nil))) (Capacitor ((capacitance "10 pF") (orientation "0"))) (DiffOutputPkg ((temperature "27") (bufferModelNonInverting "CDSDefaultOutput_2p5v") (bufferModelInverting "CDSDefaultOutput_2p5v") (stimuli nil) (offsets nil) (state "tristate") (cycle "1") (termMap nil) (setup "0.9e-09") (hold "0.4e-09") (rise nil) (fall nil) (threshOutputHighMin "2.375  V") (threshOutputHighTyp "2.5  V") (threshOutputHighMax "2.625  V") (threshOutputLowMin "1.275  V") (threshOutputLowTyp "1.7  V") (threshOutputLowMax "1.985  V") (mappingTagNonInverting nil) (mappingTagInverting nil) (spice nil))) (IbisOutput ((temperature "27") (bufferModel "CDSDefaultOutput_2p5v") (stimuli nil) (offsets nil) (state "tristate") (cycle "1") (termMap nil) (setup "2.0e-09") (hold "1.0e-09") (rise nil) (fall nil) (macroType nil) (voltage nil) (spice nil) (LEFDEFPinName nil) (LEFDEFPinType nil) (mappingTag nil))) (IbisIO ((temperature "27") (bufferModel "CDSDefaultIO_2p5v") (stimuli nil) (offsets nil) (state "tristate") (cycle "1") (termMap nil) (setup "2.0e-09") (hold "1.0e-09") (rise nil) (fall nil) (macroType nil) (voltage nil) (spice nil) (LEFDEFPinName nil) (LEFDEFPinType nil) (mappingTag nil))) (CPWMS ((d1Thickness "10 mil") (d1Constant "4.5") (d1LossTangent "0.035") (d2Thickness "0.72 mil") (d2Constant "4.5") (d2LossTangent "0.035") (d3Thickness "0.0") (d3Constant "1") (d3LossTangent "0") length("1000 mil") (spacing "5 mil") (spacing2 "5 mil") (spacing3 "5 mil") (spacing4 "5 mil") (spacing5 "5 mil") (traceConductivity "595900 mho/cm") (traceGeometry "cpwms") (traceLayerName "") (traceThickness "0.72 mil") (traceType "single") (traceWidth "5.0 mil") (traceWidth2 "5.0 mil") (traceWidth3 "5.0 mil") (traceWidth4 "5.0 mil") (traceWidth5 "5.0 mil") (traceWidth6 "5.0 mil") (offset "0 mil") (traceCount "1") (impedance nil))) (CPW ((d1Thickness "10 mil") (d1Constant "4.5") (d1LossTangent "0.035") (d2Thickness "0.72 mil") (d2Constant "1") (d2LossTangent "0") (d3Thickness "0.0") (d3Constant "1") (d3LossTangent "0") length("1000 mil") (spacing "5 mil") (spacing2 "5 mil") (spacing3 "5 mil") (spacing4 "5 mil") (spacing5 "5 mil") (traceConductivity "595900 mho/cm") (traceGeometry "cpwms") (traceLayerName "") (traceThickness "0.72 mil") (traceType "single") (traceWidth "5.0 mil") (traceWidth2 "5.0 mil") (traceWidth3 "5.0 mil") (traceWidth4 "5.0 mil") (traceWidth5 "5.0 mil") (traceWidth6 "5.0 mil") (offset "0 mil") (traceCount "1") (impedance nil))) (Resistor ((resistance "50 ohm") (orientation "0"))) (async ((asyncTimePoints "") (asyncInitState "1"))) (DiffInput ((temperature "27") (bufferModelNonInverting "CDSDefaultInput_2p5v") (bufferModelInverting "CDSDefaultInput_2p5v") (threshInputHighMin "1.7 V") (threshInputHighTyp "1.7  V") (threshInputHighMax "1.7  V") (threshInputLowMin "0.7  V") (threshInputLowTyp "0.7  V") (threshInputLowMax "0.7  V") (mappingTagNonInverting nil) (mappingTagInverting nil) (cycle "1"))) (Cable (length("1 m"))) (CPWSL ((d1Thickness "10 mil") (d1Constant "4.5") (d1LossTangent "0.035") (d2Thickness "0.72 mil") (d2Constant "4.5") (d2LossTangent "0.035") (d3Thickness "10 mil") (d3Constant "4.5") (d3LossTangent "0.035") length("1000 mil") (spacing "5 mil") (spacing2 "5 mil") (spacing3 "5 mil") (spacing4 "5 mil") (spacing5 "5 mil") (traceConductivity "595900 mho/cm") (traceGeometry "cpwms") (traceLayerName "") (traceThickness "0.72 mil") (traceType "single") (traceWidth "5.0 mil") (traceWidth2 "5.0 mil") (traceWidth3 "5.0 mil") (traceWidth4 "5.0 mil") (traceWidth5 "5.0 mil") (traceWidth6 "5.0 mil") (offset "0 mil") (traceCount "1") (impedance nil))) (Trace ((d1Thickness "10 mil") (d1Constant "4.5") (d1LossTangent "0.035") (d2Thickness "10 mil") (d2Constant "4.5") (d2LossTangent "0.035") (d3Thickness "0.0") (d3Constant "1.0") (d3LossTangent "0") length("1000 mil") (spacing "5 mil") (spacing2 "5 mil") (spacing3 "5 mil") (spacing4 "5 mil") (spacing5 "5 mil") (traceConductivity "595900 mho/cm") (traceGeometry "microstrip") (traceLayerName "") (traceThickness "0.72 mil") (traceType "single") (traceWidth "5.0 mil") (traceWidth2 "5.0 mil") (traceWidth3 "5.0 mil") (traceWidth4 "5.0 mil") (traceWidth5 "5.0 mil") (traceWidth6 "5.0 mil") (offset "0 mil") (traceCount "1") (impedance nil))) (Via ((model "Unknown") (viaOutputFormat "Unknown") (viaPadstack nil) (viaTopLayer nil) (viaBottomLayer nil) (viaIsPower nil) (viaIsGround nil))) (Connector nil) (IbisOutput_OpenPullUp ((temperature "27") (bufferModel "CDSDefaultOutput_2p5v") (stimuli nil) (offsets nil) (state "tristate") (cycle "1") (termMap nil) (setup "2.0e-09") (hold "1.0e-09") (rise nil) (fall nil) (macroType nil) (voltage nil) (spice nil) (LEFDEFPinName nil) (LEFDEFPinType nil) (mappingTag nil))) (TLine ((diffImpedance "100ohm") (diffVelocity "1.4142e+08M/s") (impedance "60ohm") length("2800 mil") (propDelay "0.5 ns") (velocity "5600 mil/ns") (traceCount "1") (traceGeometry "Microstrip") (impedanceMin nil) (impedanceMax nil) (lengthMin nil) (lengthMax nil) (propDelayMin nil) (propDelayMax nil) (impedanceSweepCount nil) (propDelaySweepCount nil) (velocitySweepCount nil) (lengthSweepCount nil) (matchSetName nil))) (sync ((syncFreq "100e6") (syncInitState "1") (syncPattern "10") (syncEdgeSwitch "rise"))) (idlCircuit ((allDrivers "active") (ftsMode '("Typ")) (rcvrSelect "all") (simMode "Reflection") (tlineDelayMode "time") (userRevision "1.0") (autoSolve "On"))) (IbisInputPkg ((temperature "27") (bufferModel "CDSDefaultInput_2p5v") (cycle "1") (LEFDEFPinName nil) (LEFDEFPinType nil) (mappingTag nil))) (IbisOutputPkg ((temperature "27") (bufferModel "CDSDefaultOutput_2p5v") (stimuli nil) (offsets nil) (state "tristate") (cycle "1") (termMap nil) (setup "2.0e-09") (hold "1.0e-09") (rise nil) (fall nil) (macroType nil) (voltage nil) (spice nil) (LEFDEFPinName nil) (LEFDEFPinType nil) (mappingTag nil))) (IbisIOPkg ((temperature "27") (bufferModel "CDSDefaultIO_2p5v") (stimuli nil) (offsets nil) (state "tristate") (cycle "1") (termMap nil) (setup "2.0e-09") (hold "1.0e-09") (rise nil) (fall nil) (macroType nil) (voltage nil) (spice nil) (LEFDEFPinName nil) (LEFDEFPinType nil) (mappingTag nil))) (IbisIOMacro ((temperature "27") (bufferModel "CDSDefaultIO_2p5v") (stimuli nil) (offsets nil) (state "tristate") (cycle "1") (termMap nil) (setup "2.0e-09") (hold "1.0e-09") (rise nil) (fall nil) (macroType nil) (voltage nil) (spice nil) (LEFDEFPinName nil) (LEFDEFPinType nil) (mappingTag nil))) (CurrentProbe nil) (DiffInputPkg ((temperature "27") (bufferModelNonInverting "CDSDefaultInput_2p5v") (bufferModelInverting "CDSDefaultInput_2p5v") (threshInputHighMin "1.7 V") (threshInputHighTyp "1.7  V") (threshInputHighMax "1.7  V") (threshInputLowMin "0.7  V") (threshInputLowTyp "0.7  V") (threshInputLowMax "0.7  V") (mappingTagNonInverting nil) (mappingTagInverting nil) (cycle "1"))) (Diode ((cutoffVoltage "0.7 V"))) (HiClampTerm ((cutoffVoltage "0.7 V") (voltage "5 V") (maxDelay "0.1 ns"))) (DualClampTerm ((cutoffVoltageUp "0.7 V") (cutoffVoltageDown "0.7 V") (voltageUp "5 V") (voltageDown "0 V") (maxDelay "0.1 ns"))) (RCTerm ((resistance "50 ohm") (capacitance "20 pF") (voltage "5 V") (maxDelay "0.1 ns"))) (LowClampTerm ((cutoffVoltage "0.7 V") (voltage "0 V") (maxDelay "0.1 ns"))) (ShuntTerm ((resistance "50 ohm") (voltage "5 V") (maxDelay "0.1 ns"))) (SeriesTerm ((resistance "22 ohm") (maxDelay "0.1 ns"))) (periodic ((periodicFreq "100e6") (periodicPattern "10") (periodicJitter "0"))) (IbisIO_OpenPullDown ((temperature "27") (bufferModel "CDSDefaultIO_2p5v") (stimuli nil) (offsets nil) (state "tristate") (cycle "1") (termMap nil) (setup "2.0e-09") (hold "1.0e-09") (rise nil) (fall nil) (macroType nil) (voltage nil) (spice nil) (LEFDEFPinName nil) (LEFDEFPinType nil) (mappingTag nil))) (IbisIO_OpenPullUp ((temperature "27") (bufferModel "CDSDefaultIO_2p5v") (stimuli nil) (offsets nil) (state "tristate") (cycle "1") (termMap nil) (setup "2.0e-09") (hold "1.0e-09") (rise nil) (fall nil) (macroType nil) (voltage nil) (spice nil) (LEFDEFPinName nil) (LEFDEFPinType nil) (mappingTag nil))) (TheveninTerm ((resistanceUp "180 ohm") (resistanceDown "270 ohm") (voltageUp "5 V") (voltageDown "0 V") (maxDelay "0.1 ns"))) (clocked ((clockRise "1e-09") (clockFall "1e-09") (clockFreq "100e6") (clockInitState "0") (clockDutyCycle "0.5") (clockJitter "0"))) (ESpiceDevice nil) (IbisInput ((temperature "27") (bufferModel "CDSDefaultInput_2p5v") (cycle "1") (LEFDEFPinName nil) (LEFDEFPinType nil) (mappingTag nil)))))
				)
				( objectStatus "CLK_100M_OTHERS" )
			)
			( electricalCSet "@crescent_city_bb_fab1_lib.crescent_city_bb_fab1(sch_1):\CLK_100M_PCH_SLOT\"
				( groupRef "CLK_100M_MEZZ_&_SLOT:MG_CLK_G2-BCLK" )
				( pinPairRef "CLK_100M_MEZZ_&_SLOT:U7C1.J33:J8G1.35" )
				( attribute "DIFFP_GATHER_CONTROL" "IGNORE"
					( Origin gBackEnd )
				)
				( attribute "DIFFP_UNCOUPLED_LENGTH" "250.00"
					( Origin gBackEnd )
				)
				( attribute "DIFFP_COUPLED_PLUS" "7.00"
					( Origin gBackEnd )
				)
				( attribute "DIFFP_COUPLED_MINUS" "0.50"
					( Origin gBackEnd )
				)
				( attribute "DIFFP_PHASE_TOL" "10 mil"
					( Units "uPhaseTol" "ns" 1.000000)
					( Origin gBackEnd )
				)
				( attribute "TOPOLOGY_TEMPLATE_REVISION" "1.0"
					( Origin gBackEnd )
				)
				( topologyData 24288
(SKIDL (Circuits ("MAIN" (Parts ("CRESCENT_CITY_623_20150314_B.@@U22.J33" IbisIOPkg (xy (5528 4240)) (refDes "U7C1") (model "Unknown") (Props (_SXDesignName "CRESCENT_CITY_623_20150314_B") (brdx "14894.75 MIL") (brdy "4257.4 MIL") (bufferModel "CDSDefaultIO_2p5v") (cycle "1") (hold "1.0e-09") (mappingTag "") (offsets ("4" "0") ("5" "0")) (setup "2.0e-09") (state "tristate") (stimuli ("4" "local0") ("5" "local1")) (temperature "27") (termMap ("4" "Data") ("5" "Enable"))) (Terms ("CRESCENT_CITY_623_20150314_B.X1489475Y425740L2LRATS" "J33"))) ("CRESCENT_CITY_623_20150314_B.@@J73.35" IbisIOPkg (xy (5502 4240)) (refDes "J8G1") (model "Unknown") (Props (_SXDesignName "CRESCENT_CITY_623_20150314_B") (brdx "16961.35 MIL") (brdy "306.76 MIL") (bufferModel "CDSDefaultIO_2p5v") (cycle "1") (hold "1.0e-09") (mappingTag "") (offsets ("4" "0") ("5" "0")) (setup "2.0e-09") (state "tristate") (stimuli ("4" "local2") ("5" "local3")) (temperature "27") (termMap ("4" "Data") ("5" "Enable"))) (Terms ("CRESCENT_CITY_623_20150314_B.X1696135Y30676L2LRATS" "35"))) ("CRESCENT_CITY_623_20150314_B.T@@RATS@@U22.J33@@J73.35" TLine (xy (5513 4235)) (mirror x) (refDes "TL1") (Props (_SXDesignName "CRESCENT_CITY_623_20150314_B") (impedance "47.169 ohm") length("6017.24 MIL") (propDelay "1.08074 ns") (traceCount "1") (traceGeometry "Microstrip") (velocity "5567.72 mil/ns")) (Terms ("CRESCENT_CITY_623_20150314_B.X1489475Y425740L2LRATS" "1") ("CRESCENT_CITY_623_20150314_B.X1696135Y30676L2LRATS" "2")))) (Nodes ("CRESCENT_CITY_623_20150314_B.X1696135Y30676L2LRATS" (terms "CRESCENT_CITY_623_20150314_B.T@@RATS@@U22.J33@@J73.35.2" "CRESCENT_CITY_623_20150314_B.@@J73.35.1")) ("CRESCENT_CITY_623_20150314_B.X1489475Y425740L2LRATS" (terms "CRESCENT_CITY_623_20150314_B.T@@RATS@@U22.J33@@J73.35.1" "CRESCENT_CITY_623_20150314_B.@@U22.J33.1"))) (Ports) (Stimuli ("local2" (scope local) (stimType periodic) (Props (periodicFreq "5e+007") (periodicJitter "0") (periodicPattern "1"))) ("local0" (scope local) (stimType periodic) (Props (periodicFreq "5e+007") (periodicJitter "0") (periodicPattern "1"))) ("local1" (scope local) (stimType periodic) (Props (periodicFreq "5e+007") (periodicJitter "0") (periodicPattern "1"))) ("local3" (scope local) (stimType periodic) (Props (periodicFreq "5e+007") (periodicJitter "0") (periodicPattern "1")))) (Notes) (Constraints ("DP_GATHER_CONTROL" "IGNORE") ("DP_MAX_UNCOUPLED_LENGTH" "0.000254") ("DP_PHASE_TOLERANCE" ("LENGTH" "0.000254")) ("RELATIVE_PROPAGATION_DELAY" ("MG_CLK_G2-BCLK" "CRESCENT_CITY_623_20150314_B U22.J33" "CRESCENT_CITY_623_20150314_B J73.35" "GLOBAL" "LENGTH" "0.127" "LENGTH" "0.12639"))) (MeasurementSets ("EMI" ("EMIStatus" status("on")) ("PeakEmission" status("on")) ("PeakFrequency" status("on")) ("PulseFreq" status("on")) ("RiseTime" status("on")) ("VoltageSwing" status("on"))) ("Reflection" ("BufferDelayFall" status("off")) ("BufferDelayRise" status("off")) ("EyeHeight" status("off")) ("EyeJitter" status("off")) ("EyeWidth" status("off")) ("FirstIncidentFall" status("off")) ("FirstIncidentRise" status("off")) ("Glitch" status("on")) ("GlitchFall" status("off")) ("GlitchRise" status("off")) ("Monotonic" status("on")) ("MonotonicFall" status("off")) ("MonotonicRise" status("off")) ("NoiseMargin" status("on")) ("NoiseMarginHigh" status("off")) ("NoiseMarginLow" status("off")) ("OvershootHigh" status("on")) ("OvershootLow" status("on")) ("PropDelay" status("on")) ("SettleDelay" status("on")) ("SettleDelayFall" status("off")) ("SettleDelayRise" status("off")) ("SwitchDelay" status("on")) ("SwitchDelayFall" status("off")) ("SwitchDelayRise" status("off"))) ("Crosstalk" ("Crosstalk" status("on"))) ("Custom")) (VectorSets) (Props (XnetName "CLK_100M_PCH_SLOTX24_S0_DN") (allDrivers "active") (customSimType "Reflection") (ftsMode ("Typ")) (rcvrSelect "all") (tlineDelayMode "time") (userRevision "1.0")))) (Subckts) (CrossSections ("CRESCENT_CITY_623_20150314_B" (Props (SXDesignName "CRESCENT_CITY_623_20150314_B")) (Layers ("" (layerType "SURFACE") (material "AIR") (thickness "0 mil") (dielectricConstant "1.000000") (lossTangent "0") (etchFactor "0.000000") (elecCondVal "0 mho/cm") (thermCondVal "0 w/cm-degC")) ("" (layerType "DIELECTRIC") (material "CONFORMAL_COAT") (thickness "0.5 mil") (dielectricConstant "3.800000") (lossTangent "0.035") (etchFactor "0.000000") (elecCondVal "0 mho/cm") (thermCondVal "0.012 w/cm-degC")) ("TOP" (layerType "CONDUCTOR") (material "COPPER") (thickness "  2.100000 mil") (width "4.00 MIL") (dielectricConstant "4.500000") (lossTangent "0") (etchFactor "70.000000") (elecCondVal "595900.000000 mho/cm") (thermCondVal "0 w/cm-degC") (signalDieConstant "3.800000") (signalLossTangent "0.035")) ("" (layerType "DIELECTRIC") (material "FR-4") (thickness "  2.670000 mil") (dielectricConstant "4.000000") (lossTangent "0.035") (etchFactor "0.000000") (elecCondVal "0 mho/cm") (thermCondVal "0.012 w/cm-degC")) ("L2_GND1" (layerType "PLANE") (material "COPPER") (isShield t) (thickness "  1.250000 mil") (dielectricConstant "4.500000") (lossTangent "0.035") (etchFactor "90.000000") (elecCondVal "595900.000000 mho/cm") (thermCondVal "0.012 w/cm-degC")) ("" (layerType "DIELECTRIC") (material "FR-4") (thickness "  9.000000 mil") (dielectricConstant "4.100000") (lossTangent "0.035") (etchFactor "0.000000") (elecCondVal "0 mho/cm") (thermCondVal "0.012 w/cm-degC")) ("L3_SIG1" (layerType "CONDUCTOR") (material "COPPER") (thickness "  1.250000 mil") (width "4.00 MIL") (dielectricConstant "4.500000") (lossTangent "0.035") (etchFactor "90.000000") (elecCondVal "595900.000000 mho/cm") (thermCondVal "0.012 w/cm-degC") (signalDieConstant "4.100000") (signalLossTangent "0.035")) ("" (layerType "DIELECTRIC") (material "FR-4") (thickness "  3.000000 mil") (dielectricConstant "4.500000") (lossTangent "0.035") (etchFactor "0.000000") (elecCondVal "0 mho/cm") (thermCondVal "0 w/cm-degC")) ("L4_GND2" (layerType "PLANE") (material "COPPER") (isShield t) (thickness "  1.250000 mil") (dielectricConstant "4.500000") (lossTangent "0.035") (etchFactor "90.000000") (elecCondVal "595900.000000 mho/cm") (thermCondVal "0 w/cm-degC")) ("" (layerType "DIELECTRIC") (material "FR-4") (thickness "  9.000000 mil") (dielectricConstant "4.000000") (lossTangent "0.035") (etchFactor "0.000000") (elecCondVal "0 mho/cm") (thermCondVal "0.012 w/cm-degC")) ("L5_SIG2" (layerType "CONDUCTOR") (material "COPPER") (thickness "  1.250000 mil") (width "4.00 MIL") (dielectricConstant "4.500000") (lossTangent "0.035") (etchFactor "90.000000") (elecCondVal "595900.000000 mho/cm") (thermCondVal "0.012 w/cm-degC") (signalDieConstant "4.000000") (signalLossTangent "0.035")) ("" (layerType "DIELECTRIC") (material "FR-4") (thickness "  3.000000 mil") (dielectricConstant "4.500000") (lossTangent "0.035") (etchFactor "0.000000") (elecCondVal "0 mho/cm") (thermCondVal "0 w/cm-degC")) ("L6_GND3" (layerType "PLANE") (material "COPPER") (isShield t) (thickness "  1.250000 mil") (dielectricConstant "4.500000") (lossTangent "0.035") (etchFactor "90.000000") (elecCondVal "595900.000000 mho/cm") (thermCondVal "0 w/cm-degC")) ("" (layerType "DIELECTRIC") (material "FR-4") (thickness "  4.500000 mil") (dielectricConstant "4.100000") (lossTangent "0.035") (etchFactor "0.000000") (elecCondVal "0 mho/cm") (thermCondVal "0.012 w/cm-degC")) ("L7_PWR1-SIG" (layerType "PLANE") (material "COPPER") (isShield t) (thickness "  2.610000 mil") (dielectricConstant "4.500000") (lossTangent "0.035") (etchFactor "90.000000") (elecCondVal "595900.000000 mho/cm") (thermCondVal "0.012 w/cm-degC")) ("" (layerType "DIELECTRIC") (material "FR-4") (thickness "  3.100000 mil") (dielectricConstant "4.500000") (lossTangent "0.035") (etchFactor "0.000000") (elecCondVal "0 mho/cm") (thermCondVal "0 w/cm-degC")) ("L8_GND_TEMP" (layerType "PLANE") (material "COPPER") (isShield t) (thickness "  1.250000 mil") (dielectricConstant "4.500000") (lossTangent "0.035") (etchFactor "90.000000") (elecCondVal "595900.000000 mho/cm") (thermCondVal "0 w/cm-degC")) ("" (layerType "DIELECTRIC") (material "FR-4") (thickness "  3.030000 mil") (dielectricConstant "4.500000") (lossTangent "0.035") (etchFactor "0.000000") (elecCondVal "0 mho/cm") (thermCondVal "0 w/cm-degC")) ("L9_SIG_TEMP" (layerType "CONDUCTOR") (material "COPPER") (thickness "  1.250000 mil") (width "3.52 MIL") (dielectricConstant "4.500000") (lossTangent "0.035") (etchFactor "90.000000") (elecCondVal "595900.000000 mho/cm") (thermCondVal "0 w/cm-degC") (signalDieConstant "4.500000") (signalLossTangent "0.035")) ("" (layerType "DIELECTRIC") (material "FR-4") (thickness "  5.000000 mil") (dielectricConstant "4.500000") (lossTangent "0.035") (etchFactor "0.000000") (elecCondVal "0 mho/cm") (thermCondVal "0 w/cm-degC")) ("L10_SIG_TEMP" (layerType "CONDUCTOR") (material "COPPER") (thickness "  1.250000 mil") (width "3.52 MIL") (dielectricConstant "4.500000") (lossTangent "0.035") (etchFactor "90.000000") (elecCondVal "595900.000000 mho/cm") (thermCondVal "0 w/cm-degC") (signalDieConstant "4.500000") (signalLossTangent "0.035")) ("" (layerType "DIELECTRIC") (material "FR-4") (thickness "  3.030000 mil") (dielectricConstant "4.500000") (lossTangent "0.035") (etchFactor "0.000000") (elecCondVal "0 mho/cm") (thermCondVal "0 w/cm-degC")) ("L11_GND_TEMP" (layerType "PLANE") (material "COPPER") (isShield t) (thickness "  1.250000 mil") (dielectricConstant "4.500000") (lossTangent "0.035") (etchFactor "90.000000") (elecCondVal "595900.000000 mho/cm") (thermCondVal "0 w/cm-degC")) ("" (layerType "DIELECTRIC") (material "FR-4") (thickness "  3.100000 mil") (dielectricConstant "4.000000") (lossTangent "0.035") (etchFactor "0.000000") (elecCondVal "0 mho/cm") (thermCondVal "0.012 w/cm-degC")) ("L12_PWR2-SIG" (layerType "PLANE") (material "COPPER") (isShield t) (thickness "  2.610000 mil") (dielectricConstant "4.500000") (lossTangent "0.035") (etchFactor "90.000000") (elecCondVal "595900.000000 mho/cm") (thermCondVal "0.012 w/cm-degC")) ("" (layerType "DIELECTRIC") (material "FR-4") (thickness "  4.500000 mil") (dielectricConstant "4.500000") (lossTangent "0.035") (etchFactor "0.000000") (elecCondVal "0 mho/cm") (thermCondVal "0 w/cm-degC")) ("L13_GND4" (layerType "PLANE") (material "COPPER") (isShield t) (thickness "  1.250000 mil") (dielectricConstant "4.500000") (lossTangent "0.035") (etchFactor "90.000000") (elecCondVal "595900.000000 mho/cm") (thermCondVal "0 w/cm-degC")) ("" (layerType "DIELECTRIC") (material "FR-4") (thickness "  3.000000 mil") (dielectricConstant "4.100000") (lossTangent "0.035") (etchFactor "0.000000") (elecCondVal "0 mho/cm") (thermCondVal "0.012 w/cm-degC")) ("L14_SIG3" (layerType "CONDUCTOR") (material "COPPER") (thickness "  1.250000 mil") (width "4.00 MIL") (dielectricConstant "4.500000") (lossTangent "0.035") (etchFactor "90.000000") (elecCondVal "595900.000000 mho/cm") (thermCondVal "0.012 w/cm-degC") (signalDieConstant "4.100000") (signalLossTangent "0.035")) ("" (layerType "DIELECTRIC") (material "FR-4") (thickness "  9.000000 mil") (dielectricConstant "4.500000") (lossTangent "0.035") (etchFactor "0.000000") (elecCondVal "0 mho/cm") (thermCondVal "0 w/cm-degC")) ("L15_GND5" (layerType "PLANE") (material "COPPER") (isShield t) (thickness "  1.250000 mil") (dielectricConstant "4.500000") (lossTangent "0.035") (etchFactor "90.000000") (elecCondVal "595900.000000 mho/cm") (thermCondVal "0 w/cm-degC")) ("" (layerType "DIELECTRIC") (material "FR-4") (thickness "  3.000000 mil") (dielectricConstant "4.500000") (lossTangent "0.035") (etchFactor "0.000000") (elecCondVal "0 mho/cm") (thermCondVal "0.012 w/cm-degC")) ("L16_SIG4" (layerType "CONDUCTOR") (material "COPPER") (thickness "  1.250000 mil") (width "4.00 MIL") (dielectricConstant "4.500000") (lossTangent "0.035") (etchFactor "90.000000") (elecCondVal "595900.000000 mho/cm") (thermCondVal "0.012 w/cm-degC") (signalDieConstant "4.500000") (signalLossTangent "0.035")) ("" (layerType "DIELECTRIC") (material "FR-4") (thickness "  9.000000 mil") (dielectricConstant "4.500000") (lossTangent "0.035") (etchFactor "0.000000") (elecCondVal "0 mho/cm") (thermCondVal "0 w/cm-degC")) ("L17_GND6" (layerType "PLANE") (material "COPPER") (isShield t) (thickness "  1.250000 mil") (dielectricConstant "4.500000") (lossTangent "0.035") (etchFactor "90.000000") (elecCondVal "595900.000000 mho/cm") (thermCondVal "0.012 w/cm-degC")) ("" (layerType "DIELECTRIC") (material "FR-4") (thickness "  2.670000 mil") (dielectricConstant "4.500000") (lossTangent "0.035") (etchFactor "0.000000") (elecCondVal "0 mho/cm") (thermCondVal "0.012 w/cm-degC")) ("BOTTOM" (layerType "CONDUCTOR") (material "COPPER") (thickness "  2.100000 mil") (width "4.00 MIL") (dielectricConstant "4.500000") (lossTangent "0") (etchFactor "70.000000") (elecCondVal "595900.000000 mho/cm") (thermCondVal "0 w/cm-degC") (signalDieConstant "3.800000") (signalLossTangent "0.035")) ("" (layerType "DIELECTRIC") (material "CONFORMAL_COAT") (thickness "0.5 mil") (dielectricConstant "3.800000") (lossTangent "0.035") (etchFactor "0.000000") (elecCondVal "0 mho/cm") (thermCondVal "0.012 w/cm-degC")) ("" (layerType "SURFACE") (material "AIR") (thickness "0 mil") (dielectricConstant "1.000000") (lossTangent "0") (etchFactor "0.000000") (elecCondVal "0 mho/cm") (thermCondVal "0 w/cm-degC"))))) (Props (DesUnits "mils 2") (LayerStack ("DIELECTRIC" "DIELECTRIC" "BOTTOM" "DIELECTRIC" "L17_GND6" "DIELECTRIC" "L16_SIG4" "DIELECTRIC" "L15_GND5" "DIELECTRIC" "L14_SIG3" "DIELECTRIC" "L13_GND4" "DIELECTRIC" "L12_PWR2-SIG" "DIELECTRIC" "L11_GND_TEMP" "DIELECTRIC" "L10_SIG_TEMP" "DIELECTRIC" "L9_SIG_TEMP" "DIELECTRIC" "L8_GND_TEMP" "DIELECTRIC" "L7_PWR1-SIG" "DIELECTRIC" "L6_GND3" "DIELECTRIC" "L5_SIG2" "DIELECTRIC" "L4_GND2" "DIELECTRIC" "L3_SIG1" "DIELECTRIC" "L2_GND1" "DIELECTRIC" "TOP" "DIELECTRIC" "DIELECTRIC")) (Revision "16.600")) (Params (RLGC (length("1000 mil"))) (DiffIO ((temperature "27") (bufferModelNonInverting "CDSDefaultIO_2p5v") (bufferModelInverting "CDSDefaultIO_2p5v") (stimuli nil) (offsets nil) (state "tristate") (cycle "1") (termMap nil) (setup "0.9e-09") (hold "0.4e-09") (rise nil) (fall nil) (threshInputHighMin "1.7 V") (threshInputHighTyp "1.7  V") (threshInputHighMax "1.7  V") (threshInputLowMin "0.7  V") (threshInputLowTyp "0.7  V") (threshInputLowMax "0.7 ") (threshOutputHighMin "2.365  V") (threshOutputHighTyp "2.5  V") (threshOutputHighMax "2.625  V") (threshOutputLowMin "1.275  V") (threshOutputLowTyp "1.7  V") (threshOutputLowMax "1.985  V") (mappingTagNonInverting nil) (mappingTagInverting nil) (spice nil))) (Source ((voltage "5 V"))) (DiffIOPkg ((temperature "27") (bufferModelNonInverting "CDSDefaultIO_2p5v") (bufferModelInverting "CDSDefaultIO_2p5v") (stimuli nil) (offsets nil) (state "tristate") (cycle "1") (termMap nil) (setup "0.9e-09") (hold "0.4e-09") (rise nil) (fall nil) (threshInputHighMin "1.7 V") (threshInputHighTyp "1.7  V") (threshInputHighMax "1.7  V") (threshInputLowMin "0.7  V") (threshInputLowTyp "0.7  V") (threshInputLowMax "0.7 ") (threshOutputHighMin "2.365  V") (threshOutputHighTyp "2.5  V") (threshOutputHighMax "2.625  V") (threshOutputLowMin "1.275  V") (threshOutputLowTyp "1.7  V") (threshOutputLowMax "1.985  V") (mappingTagNonInverting nil) (mappingTagInverting nil) (spice nil))) (Inductor ((inductance "5 nH") (orientation "0"))) (DiffOutput ((temperature "27") (bufferModelNonInverting "CDSDefaultOutput_2p5v") (bufferModelInverting "CDSDefaultOutput_2p5v") (stimuli nil) (offsets nil) (state "tristate") (cycle "1") (termMap nil) (setup "0.9e-09") (hold "0.4e-09") (rise nil) (fall nil) (threshOutputHighMin "2.375  V") (threshOutputHighTyp "2.5  V") (threshOutputHighMax "2.625  V") (threshOutputLowMin "1.275  V") (threshOutputLowTyp "1.7  V") (threshOutputLowMax "1.985  V") (mappingTagNonInverting nil) (mappingTagInverting nil) (spice nil))) (Capacitor ((capacitance "10 pF") (orientation "0"))) (DiffOutputPkg ((temperature "27") (bufferModelNonInverting "CDSDefaultOutput_2p5v") (bufferModelInverting "CDSDefaultOutput_2p5v") (stimuli nil) (offsets nil) (state "tristate") (cycle "1") (termMap nil) (setup "0.9e-09") (hold "0.4e-09") (rise nil) (fall nil) (threshOutputHighMin "2.375  V") (threshOutputHighTyp "2.5  V") (threshOutputHighMax "2.625  V") (threshOutputLowMin "1.275  V") (threshOutputLowTyp "1.7  V") (threshOutputLowMax "1.985  V") (mappingTagNonInverting nil) (mappingTagInverting nil) (spice nil))) (IbisOutput ((temperature "27") (bufferModel "CDSDefaultOutput_2p5v") (stimuli nil) (offsets nil) (state "tristate") (cycle "1") (termMap nil) (setup "2.0e-09") (hold "1.0e-09") (rise nil) (fall nil) (macroType nil) (voltage nil) (spice nil) (LEFDEFPinName nil) (LEFDEFPinType nil) (mappingTag nil))) (IbisIO ((temperature "27") (bufferModel "CDSDefaultIO_2p5v") (stimuli nil) (offsets nil) (state "tristate") (cycle "1") (termMap nil) (setup "2.0e-09") (hold "1.0e-09") (rise nil) (fall nil) (macroType nil) (voltage nil) (spice nil) (LEFDEFPinName nil) (LEFDEFPinType nil) (mappingTag nil))) (CPWMS ((d1Thickness "10 mil") (d1Constant "4.5") (d1LossTangent "0.035") (d2Thickness "0.72 mil") (d2Constant "4.5") (d2LossTangent "0.035") (d3Thickness "0.0") (d3Constant "1") (d3LossTangent "0") length("1000 mil") (spacing "5 mil") (spacing2 "5 mil") (spacing3 "5 mil") (spacing4 "5 mil") (spacing5 "5 mil") (traceConductivity "595900 mho/cm") (traceGeometry "cpwms") (traceLayerName "") (traceThickness "0.72 mil") (traceType "single") (traceWidth "5.0 mil") (traceWidth2 "5.0 mil") (traceWidth3 "5.0 mil") (traceWidth4 "5.0 mil") (traceWidth5 "5.0 mil") (traceWidth6 "5.0 mil") (offset "0 mil") (traceCount "1") (impedance nil))) (CPW ((d1Thickness "10 mil") (d1Constant "4.5") (d1LossTangent "0.035") (d2Thickness "0.72 mil") (d2Constant "1") (d2LossTangent "0") (d3Thickness "0.0") (d3Constant "1") (d3LossTangent "0") length("1000 mil") (spacing "5 mil") (spacing2 "5 mil") (spacing3 "5 mil") (spacing4 "5 mil") (spacing5 "5 mil") (traceConductivity "595900 mho/cm") (traceGeometry "cpwms") (traceLayerName "") (traceThickness "0.72 mil") (traceType "single") (traceWidth "5.0 mil") (traceWidth2 "5.0 mil") (traceWidth3 "5.0 mil") (traceWidth4 "5.0 mil") (traceWidth5 "5.0 mil") (traceWidth6 "5.0 mil") (offset "0 mil") (traceCount "1") (impedance nil))) (Resistor ((resistance "50 ohm") (orientation "0"))) (async ((asyncTimePoints "") (asyncInitState "1"))) (DiffInput ((temperature "27") (bufferModelNonInverting "CDSDefaultInput_2p5v") (bufferModelInverting "CDSDefaultInput_2p5v") (threshInputHighMin "1.7 V") (threshInputHighTyp "1.7  V") (threshInputHighMax "1.7  V") (threshInputLowMin "0.7  V") (threshInputLowTyp "0.7  V") (threshInputLowMax "0.7  V") (mappingTagNonInverting nil) (mappingTagInverting nil) (cycle "1"))) (Cable (length("1 m"))) (CPWSL ((d1Thickness "10 mil") (d1Constant "4.5") (d1LossTangent "0.035") (d2Thickness "0.72 mil") (d2Constant "4.5") (d2LossTangent "0.035") (d3Thickness "10 mil") (d3Constant "4.5") (d3LossTangent "0.035") length("1000 mil") (spacing "5 mil") (spacing2 "5 mil") (spacing3 "5 mil") (spacing4 "5 mil") (spacing5 "5 mil") (traceConductivity "595900 mho/cm") (traceGeometry "cpwms") (traceLayerName "") (traceThickness "0.72 mil") (traceType "single") (traceWidth "5.0 mil") (traceWidth2 "5.0 mil") (traceWidth3 "5.0 mil") (traceWidth4 "5.0 mil") (traceWidth5 "5.0 mil") (traceWidth6 "5.0 mil") (offset "0 mil") (traceCount "1") (impedance nil))) (Trace ((d1Thickness "10 mil") (d1Constant "4.5") (d1LossTangent "0.035") (d2Thickness "10 mil") (d2Constant "4.5") (d2LossTangent "0.035") (d3Thickness "0.0") (d3Constant "1.0") (d3LossTangent "0") length("1000 mil") (spacing "5 mil") (spacing2 "5 mil") (spacing3 "5 mil") (spacing4 "5 mil") (spacing5 "5 mil") (traceConductivity "595900 mho/cm") (traceGeometry "microstrip") (traceLayerName "") (traceThickness "0.72 mil") (traceType "single") (traceWidth "5.0 mil") (traceWidth2 "5.0 mil") (traceWidth3 "5.0 mil") (traceWidth4 "5.0 mil") (traceWidth5 "5.0 mil") (traceWidth6 "5.0 mil") (offset "0 mil") (traceCount "1") (impedance nil))) (Via ((model "Unknown") (viaOutputFormat "Unknown") (viaPadstack nil) (viaTopLayer nil) (viaBottomLayer nil) (viaIsPower nil) (viaIsGround nil))) (Connector nil) (IbisOutput_OpenPullUp ((temperature "27") (bufferModel "CDSDefaultOutput_2p5v") (stimuli nil) (offsets nil) (state "tristate") (cycle "1") (termMap nil) (setup "2.0e-09") (hold "1.0e-09") (rise nil) (fall nil) (macroType nil) (voltage nil) (spice nil) (LEFDEFPinName nil) (LEFDEFPinType nil) (mappingTag nil))) (TLine ((diffImpedance "100ohm") (diffVelocity "1.4142e+08M/s") (impedance "60ohm") length("2800 mil") (propDelay "0.5 ns") (velocity "5600 mil/ns") (traceCount "1") (traceGeometry "Microstrip") (impedanceMin nil) (impedanceMax nil) (lengthMin nil) (lengthMax nil) (propDelayMin nil) (propDelayMax nil) (impedanceSweepCount nil) (propDelaySweepCount nil) (velocitySweepCount nil) (lengthSweepCount nil) (matchSetName nil))) (sync ((syncFreq "100e6") (syncInitState "1") (syncPattern "10") (syncEdgeSwitch "rise"))) (idlCircuit ((allDrivers "active") (ftsMode '("Typ")) (rcvrSelect "all") (simMode "Reflection") (tlineDelayMode "time") (userRevision "1.0") (autoSolve "On"))) (IbisInputPkg ((temperature "27") (bufferModel "CDSDefaultInput_2p5v") (cycle "1") (LEFDEFPinName nil) (LEFDEFPinType nil) (mappingTag nil))) (IbisOutputPkg ((temperature "27") (bufferModel "CDSDefaultOutput_2p5v") (stimuli nil) (offsets nil) (state "tristate") (cycle "1") (termMap nil) (setup "2.0e-09") (hold "1.0e-09") (rise nil) (fall nil) (macroType nil) (voltage nil) (spice nil) (LEFDEFPinName nil) (LEFDEFPinType nil) (mappingTag nil))) (IbisIOPkg ((temperature "27") (bufferModel "CDSDefaultIO_2p5v") (stimuli nil) (offsets nil) (state "tristate") (cycle "1") (termMap nil) (setup "2.0e-09") (hold "1.0e-09") (rise nil) (fall nil) (macroType nil) (voltage nil) (spice nil) (LEFDEFPinName nil) (LEFDEFPinType nil) (mappingTag nil))) (IbisIOMacro ((temperature "27") (bufferModel "CDSDefaultIO_2p5v") (stimuli nil) (offsets nil) (state "tristate") (cycle "1") (termMap nil) (setup "2.0e-09") (hold "1.0e-09") (rise nil) (fall nil) (macroType nil) (voltage nil) (spice nil) (LEFDEFPinName nil) (LEFDEFPinType nil) (mappingTag nil))) (CurrentProbe nil) (DiffInputPkg ((temperature "27") (bufferModelNonInverting "CDSDefaultInput_2p5v") (bufferModelInverting "CDSDefaultInput_2p5v") (threshInputHighMin "1.7 V") (threshInputHighTyp "1.7  V") (threshInputHighMax "1.7  V") (threshInputLowMin "0.7  V") (threshInputLowTyp "0.7  V") (threshInputLowMax "0.7  V") (mappingTagNonInverting nil) (mappingTagInverting nil) (cycle "1"))) (Diode ((cutoffVoltage "0.7 V"))) (HiClampTerm ((cutoffVoltage "0.7 V") (voltage "5 V") (maxDelay "0.1 ns"))) (DualClampTerm ((cutoffVoltageUp "0.7 V") (cutoffVoltageDown "0.7 V") (voltageUp "5 V") (voltageDown "0 V") (maxDelay "0.1 ns"))) (RCTerm ((resistance "50 ohm") (capacitance "20 pF") (voltage "5 V") (maxDelay "0.1 ns"))) (LowClampTerm ((cutoffVoltage "0.7 V") (voltage "0 V") (maxDelay "0.1 ns"))) (ShuntTerm ((resistance "50 ohm") (voltage "5 V") (maxDelay "0.1 ns"))) (SeriesTerm ((resistance "22 ohm") (maxDelay "0.1 ns"))) (periodic ((periodicFreq "100e6") (periodicPattern "10") (periodicJitter "0"))) (IbisIO_OpenPullDown ((temperature "27") (bufferModel "CDSDefaultIO_2p5v") (stimuli nil) (offsets nil) (state "tristate") (cycle "1") (termMap nil) (setup "2.0e-09") (hold "1.0e-09") (rise nil) (fall nil) (macroType nil) (voltage nil) (spice nil) (LEFDEFPinName nil) (LEFDEFPinType nil) (mappingTag nil))) (IbisIO_OpenPullUp ((temperature "27") (bufferModel "CDSDefaultIO_2p5v") (stimuli nil) (offsets nil) (state "tristate") (cycle "1") (termMap nil) (setup "2.0e-09") (hold "1.0e-09") (rise nil) (fall nil) (macroType nil) (voltage nil) (spice nil) (LEFDEFPinName nil) (LEFDEFPinType nil) (mappingTag nil))) (TheveninTerm ((resistanceUp "180 ohm") (resistanceDown "270 ohm") (voltageUp "5 V") (voltageDown "0 V") (maxDelay "0.1 ns"))) (clocked ((clockRise "1e-09") (clockFall "1e-09") (clockFreq "100e6") (clockInitState "0") (clockDutyCycle "0.5") (clockJitter "0"))) (ESpiceDevice nil) (IbisInput ((temperature "27") (bufferModel "CDSDefaultInput_2p5v") (cycle "1") (LEFDEFPinName nil) (LEFDEFPinType nil) (mappingTag nil)))))
				)
				( objectStatus "CLK_100M_MEZZ_&_SLOT" )
			)
			( electricalCSet "@crescent_city_bb_fab1_lib.crescent_city_bb_fab1(sch_1):\SFI\"
				( pinPairRef "SFI:J9C1.13:U7C1.BH31" )
				( attribute "MAX_VIA_COUNT" "2"
					( Origin gBackEnd )
				)
				( attribute "DIFFP_GATHER_CONTROL" "IGNORE"
					( Origin gBackEnd )
				)
				( attribute "DIFFP_UNCOUPLED_LENGTH" "170.00"
					( Origin gBackEnd )
				)
				( attribute "DIFFP_COUPLED_PLUS" "4.00"
					( Origin gBackEnd )
				)
				( attribute "DIFFP_COUPLED_MINUS" "0.10"
					( Origin gBackEnd )
				)
				( attribute "DIFFP_PHASE_TOL" "2 mil"
					( Units "uPhaseTol" "ns" 1.000000)
					( Origin gBackEnd )
				)
				( attribute "DIFFP_PHASE_MAX_LENGTH" "450.00"
					( Origin gBackEnd )
				)
				( attribute "DIFFP_PHASE_TOL_DYNAMIC" "50 mil"
					( Units "uPhaseTol" "mil" 1.000000)
					( Origin gBackEnd )
				)
				( attribute "DIFFP_MIN_SPACE" "4.00"
					( Origin gBackEnd )
				)
				( attribute "TOPOLOGY_TEMPLATE_REVISION" "1.0"
					( Origin gBackEnd )
				)
				( topologyData 22212
(SKIDL (Circuits ("MAIN" (Parts ("CRESCENT_CITY_181_20150107_Q.@@U22.BH31" IbisIOPkg (xy (5528 4240)) (refDes "U7C1") (model "Unknown") (Props (_SXDesignName "CRESCENT_CITY_181_20150107_Q") (brdx "15577.25 MIL") (brdy "4223.6 MIL") (bufferModel "CDSDefaultIO_2p5v") (cycle "1") (hold "1.0e-09") (mappingTag "") (offsets ("4" "0") ("5" "0")) (setup "2.0e-09") (state "tristate") (stimuli ("4" "local0") ("5" "local1")) (temperature "27") (termMap ("4" "Data") ("5" "Enable"))) (Terms ("CRESCENT_CITY_181_20150107_Q.X1557725Y422360L2LRATS" "BH31"))) ("CRESCENT_CITY_181_20150107_Q.@@J58.13" IbisIOPkg (xy (5502 4240)) (refDes "J9C1") (model "Unknown") (Props (_SXDesignName "CRESCENT_CITY_181_20150107_Q") (brdx "18196.85 MIL") (brdy "3853.53 MIL") (bufferModel "CDSDefaultIO_2p5v") (cycle "1") (hold "1.0e-09") (mappingTag "") (offsets ("4" "0") ("5" "0")) (setup "2.0e-09") (state "tristate") (stimuli ("4" "local2") ("5" "local3")) (temperature "27") (termMap ("4" "Data") ("5" "Enable"))) (Terms ("CRESCENT_CITY_181_20150107_Q.X1819685Y385353L2LRATS" "13"))) ("CRESCENT_CITY_181_20150107_Q.T@@RATS@@U22.BH31@@J58.13" TLine (xy (5513 4235)) (mirror x) (refDes "TL1") (Props (_SXDesignName "CRESCENT_CITY_181_20150107_Q") (impedance "49.675 ohm") length("2989.67 MIL") (propDelay "0.53697 ns") (traceCount "1") (traceGeometry "Microstrip") (velocity "5567.68 mil/ns")) (Terms ("CRESCENT_CITY_181_20150107_Q.X1557725Y422360L2LRATS" "1") ("CRESCENT_CITY_181_20150107_Q.X1819685Y385353L2LRATS" "2")))) (Nodes ("CRESCENT_CITY_181_20150107_Q.X1819685Y385353L2LRATS" (terms "CRESCENT_CITY_181_20150107_Q.T@@RATS@@U22.BH31@@J58.13.2" "CRESCENT_CITY_181_20150107_Q.@@J58.13.1")) ("CRESCENT_CITY_181_20150107_Q.X1557725Y422360L2LRATS" (terms "CRESCENT_CITY_181_20150107_Q.T@@RATS@@U22.BH31@@J58.13.1" "CRESCENT_CITY_181_20150107_Q.@@U22.BH31.1"))) (Ports) (Stimuli ("local2" (scope local) (stimType periodic) (Props (periodicFreq "5e+007") (periodicJitter "0") (periodicPattern "1"))) ("local0" (scope local) (stimType periodic) (Props (periodicFreq "5e+007") (periodicJitter "0") (periodicPattern "1"))) ("local1" (scope local) (stimType periodic) (Props (periodicFreq "5e+007") (periodicJitter "0") (periodicPattern "1"))) ("local3" (scope local) (stimType periodic) (Props (periodicFreq "5e+007") (periodicJitter "0") (periodicPattern "1")))) (Notes) (Constraints ("DELAY_RULE" ("CRESCENT_CITY_181_20150107_Q J58.13" "CRESCENT_CITY_181_20150107_Q U22.BH31" "LENGTH" "" "LENGTH" "0.127")) ("DP_MAX_UNCOUPLED_LENGTH" "0.000254") ("DP_PHASE_TOLERANCE" ("LENGTH" "5.08e-005")) ("DP_POSITIVE_COUPLED_TOLERANCE" "1.27e-006") ("MAX_VIA_COUNT" "2")) (MeasurementSets ("EMI" ("EMIStatus" status("on")) ("PeakEmission" status("on")) ("PeakFrequency" status("on")) ("PulseFreq" status("on")) ("RiseTime" status("on")) ("VoltageSwing" status("on"))) ("Reflection" ("BufferDelayFall" status("off")) ("BufferDelayRise" status("off")) ("EyeHeight" status("off")) ("EyeJitter" status("off")) ("EyeWidth" status("off")) ("FirstIncidentFall" status("off")) ("FirstIncidentRise" status("off")) ("Glitch" status("on")) ("GlitchFall" status("off")) ("GlitchRise" status("off")) ("Monotonic" status("on")) ("MonotonicFall" status("off")) ("MonotonicRise" status("off")) ("NoiseMargin" status("on")) ("NoiseMarginHigh" status("off")) ("NoiseMarginLow" status("off")) ("OvershootHigh" status("on")) ("OvershootLow" status("on")) ("PropDelay" status("on")) ("SettleDelay" status("on")) ("SettleDelayFall" status("off")) ("SettleDelayRise" status("off")) ("SwitchDelay" status("on")) ("SwitchDelayFall" status("off")) ("SwitchDelayRise" status("off"))) ("Crosstalk" ("Crosstalk" status("on"))) ("Custom")) (VectorSets) (Props (XnetName "SFI_P0_RX_DN") (allDrivers "active") (customSimType "Reflection") (ftsMode ("Typ")) (rcvrSelect "all") (tlineDelayMode "time") (userRevision "1.0")))) (Subckts) (CrossSections ("CRESCENT_CITY_181_20150107_Q" (Props (SXDesignName "CRESCENT_CITY_181_20150107_Q")) (Layers ("" (layerType "SURFACE") (material "AIR") (thickness "0 mil") (dielectricConstant "1.000000") (lossTangent "0") (etchFactor "0.000000") (elecCondVal "0 mho/cm") (thermCondVal "0 w/cm-degC")) ("" (layerType "DIELECTRIC") (material "CONFORMAL_COAT") (thickness "0.5 mil") (dielectricConstant "3.800000") (lossTangent "0.035") (etchFactor "0.000000") (elecCondVal "0 mho/cm") (thermCondVal "0.012 w/cm-degC")) ("TOP" (layerType "CONDUCTOR") (material "COPPER") (thickness "  2.100000 mil") (width "4.00 MIL") (dielectricConstant "4.500000") (lossTangent "0") (etchFactor "70.000000") (elecCondVal "595900.000000 mho/cm") (thermCondVal "0 w/cm-degC") (signalDieConstant "3.800000") (signalLossTangent "0.035")) ("" (layerType "DIELECTRIC") (material "FR-4") (thickness "  2.670000 mil") (dielectricConstant "4.000000") (lossTangent "0.035") (etchFactor "0.000000") (elecCondVal "0 mho/cm") (thermCondVal "0.012 w/cm-degC")) ("L2_GND1" (layerType "PLANE") (material "COPPER") (isShield t) (thickness "  1.250000 mil") (dielectricConstant "4.500000") (lossTangent "0.035") (etchFactor "90.000000") (elecCondVal "595900.000000 mho/cm") (thermCondVal "0.012 w/cm-degC")) ("" (layerType "DIELECTRIC") (material "FR-4") (thickness "  9.000000 mil") (dielectricConstant "4.100000") (lossTangent "0.035") (etchFactor "0.000000") (elecCondVal "0 mho/cm") (thermCondVal "0.012 w/cm-degC")) ("L3_SIG1" (layerType "CONDUCTOR") (material "COPPER") (thickness "  1.250000 mil") (width "4.00 MIL") (dielectricConstant "4.500000") (lossTangent "0.035") (etchFactor "90.000000") (elecCondVal "595900.000000 mho/cm") (thermCondVal "0.012 w/cm-degC") (signalDieConstant "4.100000") (signalLossTangent "0.035")) ("" (layerType "DIELECTRIC") (material "FR-4") (thickness "  3.000000 mil") (dielectricConstant "4.500000") (lossTangent "0.035") (etchFactor "0.000000") (elecCondVal "0 mho/cm") (thermCondVal "0 w/cm-degC")) ("L4_GND2" (layerType "PLANE") (material "COPPER") (isShield t) (thickness "  1.250000 mil") (dielectricConstant "4.500000") (lossTangent "0.035") (etchFactor "90.000000") (elecCondVal "595900.000000 mho/cm") (thermCondVal "0 w/cm-degC")) ("" (layerType "DIELECTRIC") (material "FR-4") (thickness "  9.000000 mil") (dielectricConstant "4.000000") (lossTangent "0.035") (etchFactor "0.000000") (elecCondVal "0 mho/cm") (thermCondVal "0.012 w/cm-degC")) ("L5_SIG2" (layerType "CONDUCTOR") (material "COPPER") (thickness "  1.250000 mil") (width "4.00 MIL") (dielectricConstant "4.500000") (lossTangent "0.035") (etchFactor "90.000000") (elecCondVal "595900.000000 mho/cm") (thermCondVal "0.012 w/cm-degC") (signalDieConstant "4.000000") (signalLossTangent "0.035")) ("" (layerType "DIELECTRIC") (material "FR-4") (thickness "  3.000000 mil") (dielectricConstant "4.500000") (lossTangent "0.035") (etchFactor "0.000000") (elecCondVal "0 mho/cm") (thermCondVal "0 w/cm-degC")) ("L6_GND3" (layerType "PLANE") (material "COPPER") (isShield t) (thickness "  1.250000 mil") (dielectricConstant "4.500000") (lossTangent "0.035") (etchFactor "90.000000") (elecCondVal "595900.000000 mho/cm") (thermCondVal "0 w/cm-degC")) ("" (layerType "DIELECTRIC") (material "FR-4") (thickness "  4.500000 mil") (dielectricConstant "4.100000") (lossTangent "0.035") (etchFactor "0.000000") (elecCondVal "0 mho/cm") (thermCondVal "0.012 w/cm-degC")) ("L7_PWR1-SIG" (layerType "PLANE") (material "COPPER") (isShield t) (thickness "  2.400000 mil") (dielectricConstant "4.500000") (lossTangent "0.035") (etchFactor "90.000000") (elecCondVal "595900.000000 mho/cm") (thermCondVal "0.012 w/cm-degC")) ("" (layerType "DIELECTRIC") (material "FR-4") (thickness "  4.600000 mil") (dielectricConstant "4.000000") (lossTangent "0.035") (etchFactor "0.000000") (elecCondVal "0 mho/cm") (thermCondVal "0.012 w/cm-degC")) ("L8_PWR2-SIG" (layerType "PLANE") (material "COPPER") (isShield t) (thickness "  2.400000 mil") (dielectricConstant "4.500000") (lossTangent "0.035") (etchFactor "90.000000") (elecCondVal "595900.000000 mho/cm") (thermCondVal "0.012 w/cm-degC")) ("" (layerType "DIELECTRIC") (material "FR-4") (thickness "  4.500000 mil") (dielectricConstant "4.500000") (lossTangent "0.035") (etchFactor "0.000000") (elecCondVal "0 mho/cm") (thermCondVal "0 w/cm-degC")) ("L9_GND4" (layerType "PLANE") (material "COPPER") (isShield t) (thickness "  1.250000 mil") (dielectricConstant "4.500000") (lossTangent "0.035") (etchFactor "90.000000") (elecCondVal "595900.000000 mho/cm") (thermCondVal "0 w/cm-degC")) ("" (layerType "DIELECTRIC") (material "FR-4") (thickness "  3.000000 mil") (dielectricConstant "4.100000") (lossTangent "0.035") (etchFactor "0.000000") (elecCondVal "0 mho/cm") (thermCondVal "0.012 w/cm-degC")) ("L10_SIG3" (layerType "CONDUCTOR") (material "COPPER") (thickness "  1.250000 mil") (width "4.00 MIL") (dielectricConstant "4.500000") (lossTangent "0.035") (etchFactor "90.000000") (elecCondVal "595900.000000 mho/cm") (thermCondVal "0.012 w/cm-degC") (signalDieConstant "4.100000") (signalLossTangent "0.035")) ("" (layerType "DIELECTRIC") (material "FR-4") (thickness "  9.000000 mil") (dielectricConstant "4.500000") (lossTangent "0.035") (etchFactor "0.000000") (elecCondVal "0 mho/cm") (thermCondVal "0 w/cm-degC")) ("L11_GND5" (layerType "PLANE") (material "COPPER") (isShield t) (thickness "  1.250000 mil") (dielectricConstant "4.500000") (lossTangent "0.035") (etchFactor "90.000000") (elecCondVal "595900.000000 mho/cm") (thermCondVal "0 w/cm-degC")) ("" (layerType "DIELECTRIC") (material "FR-4") (thickness "  3.000000 mil") (dielectricConstant "4.500000") (lossTangent "0.035") (etchFactor "0.000000") (elecCondVal "0 mho/cm") (thermCondVal "0.012 w/cm-degC")) ("L12_SIG4" (layerType "CONDUCTOR") (material "COPPER") (thickness "  1.250000 mil") (width "4.00 MIL") (dielectricConstant "4.500000") (lossTangent "0.035") (etchFactor "90.000000") (elecCondVal "595900.000000 mho/cm") (thermCondVal "0.012 w/cm-degC") (signalDieConstant "4.500000") (signalLossTangent "0.035")) ("" (layerType "DIELECTRIC") (material "FR-4") (thickness "  9.000000 mil") (dielectricConstant "4.500000") (lossTangent "0.035") (etchFactor "0.000000") (elecCondVal "0 mho/cm") (thermCondVal "0 w/cm-degC")) ("L13_GND6" (layerType "PLANE") (material "COPPER") (isShield t) (thickness "  1.250000 mil") (dielectricConstant "4.500000") (lossTangent "0.035") (etchFactor "90.000000") (elecCondVal "595900.000000 mho/cm") (thermCondVal "0.012 w/cm-degC")) ("" (layerType "DIELECTRIC") (material "FR-4") (thickness "  2.670000 mil") (dielectricConstant "4.500000") (lossTangent "0.035") (etchFactor "0.000000") (elecCondVal "0 mho/cm") (thermCondVal "0.012 w/cm-degC")) ("BOTTOM" (layerType "CONDUCTOR") (material "COPPER") (thickness "  2.100000 mil") (width "4.00 MIL") (dielectricConstant "4.500000") (lossTangent "0") (etchFactor "70.000000") (elecCondVal "595900.000000 mho/cm") (thermCondVal "0 w/cm-degC") (signalDieConstant "3.800000") (signalLossTangent "0.035")) ("" (layerType "DIELECTRIC") (material "CONFORMAL_COAT") (thickness "0.5 mil") (dielectricConstant "3.800000") (lossTangent "0.035") (etchFactor "0.000000") (elecCondVal "0 mho/cm") (thermCondVal "0.012 w/cm-degC")) ("" (layerType "SURFACE") (material "AIR") (thickness "0 mil") (dielectricConstant "1.000000") (lossTangent "0") (etchFactor "0.000000") (elecCondVal "0 mho/cm") (thermCondVal "0 w/cm-degC"))))) (Props (DesUnits "mils 2") (LayerStack ("DIELECTRIC" "DIELECTRIC" "BOTTOM" "DIELECTRIC" "L13_GND6" "DIELECTRIC" "L12_SIG4" "DIELECTRIC" "L11_GND5" "DIELECTRIC" "L10_SIG3" "DIELECTRIC" "L9_GND4" "DIELECTRIC" "L8_PWR2-SIG" "DIELECTRIC" "L7_PWR1-SIG" "DIELECTRIC" "L6_GND3" "DIELECTRIC" "L5_SIG2" "DIELECTRIC" "L4_GND2" "DIELECTRIC" "L3_SIG1" "DIELECTRIC" "L2_GND1" "DIELECTRIC" "TOP" "DIELECTRIC" "DIELECTRIC")) (Revision "16.600")) (Params (IbisIOMacro ((temperature "27") (bufferModel "CDSDefaultIO_2p5v") (stimuli nil) (offsets nil) (state "tristate") (cycle "1") (termMap nil) (setup "2.0e-09") (hold "1.0e-09") (rise nil) (fall nil) (macroType nil) (voltage nil) (spice nil) (LEFDEFPinName nil) (LEFDEFPinType nil) (mappingTag nil))) (IbisIO_OpenPullUp ((temperature "27") (bufferModel "CDSDefaultIO_2p5v") (stimuli nil) (offsets nil) (state "tristate") (cycle "1") (termMap nil) (setup "2.0e-09") (hold "1.0e-09") (rise nil) (fall nil) (macroType nil) (voltage nil) (spice nil) (LEFDEFPinName nil) (LEFDEFPinType nil) (mappingTag nil))) (Capacitor ((capacitance "10 pF") (orientation "0"))) (Inductor ((inductance "5 nH") (orientation "0"))) (DiffInputPkg ((temperature "27") (bufferModelNonInverting "CDSDefaultInput_2p5v") (bufferModelInverting "CDSDefaultInput_2p5v") (threshInputHighMin "1.7 V") (threshInputHighTyp "1.7  V") (threshInputHighMax "1.7  V") (threshInputLowMin "0.7  V") (threshInputLowTyp "0.7  V") (threshInputLowMax "0.7  V") (mappingTagNonInverting nil) (mappingTagInverting nil) (cycle "1"))) (IbisOutput_OpenPullUp ((temperature "27") (bufferModel "CDSDefaultOutput_2p5v") (stimuli nil) (offsets nil) (state "tristate") (cycle "1") (termMap nil) (setup "2.0e-09") (hold "1.0e-09") (rise nil) (fall nil) (macroType nil) (voltage nil) (spice nil) (LEFDEFPinName nil) (LEFDEFPinType nil) (mappingTag nil))) (Diode ((cutoffVoltage "0.7 V"))) (IbisInputPkg ((temperature "27") (bufferModel "CDSDefaultInput_2p5v") (cycle "1") (LEFDEFPinName nil) (LEFDEFPinType nil) (mappingTag nil))) (Resistor ((resistance "50 ohm") (orientation "0"))) (IbisIO_OpenPullDown ((temperature "27") (bufferModel "CDSDefaultIO_2p5v") (stimuli nil) (offsets nil) (state "tristate") (cycle "1") (termMap nil) (setup "2.0e-09") (hold "1.0e-09") (rise nil) (fall nil) (macroType nil) (voltage nil) (spice nil) (LEFDEFPinName nil) (LEFDEFPinType nil) (mappingTag nil))) (IbisOutputPkg ((temperature "27") (bufferModel "CDSDefaultOutput_2p5v") (stimuli nil) (offsets nil) (state "tristate") (cycle "1") (termMap nil) (setup "2.0e-09") (hold "1.0e-09") (rise nil) (fall nil) (macroType nil) (voltage nil) (spice nil) (LEFDEFPinName nil) (LEFDEFPinType nil) (mappingTag nil))) (IbisIO ((temperature "27") (bufferModel "CDSDefaultIO_2p5v") (stimuli nil) (offsets nil) (state "tristate") (cycle "1") (termMap nil) (setup "2.0e-09") (hold "1.0e-09") (rise nil) (fall nil) (macroType nil) (voltage nil) (spice nil) (LEFDEFPinName nil) (LEFDEFPinType nil) (mappingTag nil))) (IbisIOPkg ((temperature "27") (bufferModel "CDSDefaultIO_2p5v") (stimuli nil) (offsets nil) (state "tristate") (cycle "1") (termMap nil) (setup "2.0e-09") (hold "1.0e-09") (rise nil) (fall nil) (macroType nil) (voltage nil) (spice nil) (LEFDEFPinName nil) (LEFDEFPinType nil) (mappingTag nil))) (Via ((model "Unknown") (viaOutputFormat "Unknown") (viaPadstack nil) (viaTopLayer nil) (viaBottomLayer nil) (viaIsPower nil) (viaIsGround nil))) (DualClampTerm ((cutoffVoltageUp "0.7 V") (cutoffVoltageDown "0.7 V") (voltageUp "5 V") (voltageDown "0 V") (maxDelay "0.1 ns"))) (Trace ((d1Thickness "10 mil") (d1Constant "4.5") (d1LossTangent "0.035") (d2Thickness "10 mil") (d2Constant "4.5") (d2LossTangent "0.035") (d3Thickness "0.0") (d3Constant "1.0") (d3LossTangent "0") length("1000 mil") (spacing "5 mil") (spacing2 "5 mil") (spacing3 "5 mil") (spacing4 "5 mil") (spacing5 "5 mil") (traceConductivity "595900 mho/cm") (traceGeometry "microstrip") (traceLayerName "") (traceThickness "0.72 mil") (traceType "single") (traceWidth "5.0 mil") (traceWidth2 "5.0 mil") (traceWidth3 "5.0 mil") (traceWidth4 "5.0 mil") (traceWidth5 "5.0 mil") (traceWidth6 "5.0 mil") (offset "0 mil") (traceCount "1") (impedance nil))) (RLGC (length("1000 mil"))) (HiClampTerm ((cutoffVoltage "0.7 V") (voltage "5 V") (maxDelay "0.1 ns"))) (RCTerm ((resistance "50 ohm") (capacitance "20 pF") (voltage "5 V") (maxDelay "0.1 ns"))) (periodic ((periodicFreq "100e6") (periodicPattern "10") (periodicJitter "0"))) (LowClampTerm ((cutoffVoltage "0.7 V") (voltage "0 V") (maxDelay "0.1 ns"))) (clocked ((clockRise "1e-09") (clockFall "1e-09") (clockFreq "100e6") (clockInitState "0") (clockDutyCycle "0.5") (clockJitter "0"))) (IbisInput ((temperature "27") (bufferModel "CDSDefaultInput_2p5v") (cycle "1") (LEFDEFPinName nil) (LEFDEFPinType nil) (mappingTag nil))) (TheveninTerm ((resistanceUp "180 ohm") (resistanceDown "270 ohm") (voltageUp "5 V") (voltageDown "0 V") (maxDelay "0.1 ns"))) (ShuntTerm ((resistance "50 ohm") (voltage "5 V") (maxDelay "0.1 ns"))) (DiffInput ((temperature "27") (bufferModelNonInverting "CDSDefaultInput_2p5v") (bufferModelInverting "CDSDefaultInput_2p5v") (threshInputHighMin "1.7 V") (threshInputHighTyp "1.7  V") (threshInputHighMax "1.7  V") (threshInputLowMin "0.7  V") (threshInputLowTyp "0.7  V") (threshInputLowMax "0.7  V") (mappingTagNonInverting nil) (mappingTagInverting nil) (cycle "1"))) (sync ((syncFreq "100e6") (syncInitState "1") (syncPattern "10") (syncEdgeSwitch "rise"))) (DiffIO ((temperature "27") (bufferModelNonInverting "CDSDefaultIO_2p5v") (bufferModelInverting "CDSDefaultIO_2p5v") (stimuli nil) (offsets nil) (state "tristate") (cycle "1") (termMap nil) (setup "0.9e-09") (hold "0.4e-09") (rise nil) (fall nil) (threshInputHighMin "1.7 V") (threshInputHighTyp "1.7  V") (threshInputHighMax "1.7  V") (threshInputLowMin "0.7  V") (threshInputLowTyp "0.7  V") (threshInputLowMax "0.7 ") (threshOutputHighMin "2.365  V") (threshOutputHighTyp "2.5  V") (threshOutputHighMax "2.625  V") (threshOutputLowMin "1.275  V") (threshOutputLowTyp "1.7  V") (threshOutputLowMax "1.985  V") (mappingTagNonInverting nil) (mappingTagInverting nil) (spice nil))) (IbisOutput ((temperature "27") (bufferModel "CDSDefaultOutput_2p5v") (stimuli nil) (offsets nil) (state "tristate") (cycle "1") (termMap nil) (setup "2.0e-09") (hold "1.0e-09") (rise nil) (fall nil) (macroType nil) (voltage nil) (spice nil) (LEFDEFPinName nil) (LEFDEFPinType nil) (mappingTag nil))) (ESpiceDevice nil) (SeriesTerm ((resistance "22 ohm") (maxDelay "0.1 ns"))) (async ((asyncTimePoints "") (asyncInitState "1"))) (DiffOutputPkg ((temperature "27") (bufferModelNonInverting "CDSDefaultOutput_2p5v") (bufferModelInverting "CDSDefaultOutput_2p5v") (stimuli nil) (offsets nil) (state "tristate") (cycle "1") (termMap nil) (setup "0.9e-09") (hold "0.4e-09") (rise nil) (fall nil) (threshOutputHighMin "2.375  V") (threshOutputHighTyp "2.5  V") (threshOutputHighMax "2.625  V") (threshOutputLowMin "1.275  V") (threshOutputLowTyp "1.7  V") (threshOutputLowMax "1.985  V") (mappingTagNonInverting nil) (mappingTagInverting nil) (spice nil))) (DiffOutput ((temperature "27") (bufferModelNonInverting "CDSDefaultOutput_2p5v") (bufferModelInverting "CDSDefaultOutput_2p5v") (stimuli nil) (offsets nil) (state "tristate") (cycle "1") (termMap nil) (setup "0.9e-09") (hold "0.4e-09") (rise nil) (fall nil) (threshOutputHighMin "2.375  V") (threshOutputHighTyp "2.5  V") (threshOutputHighMax "2.625  V") (threshOutputLowMin "1.275  V") (threshOutputLowTyp "1.7  V") (threshOutputLowMax "1.985  V") (mappingTagNonInverting nil) (mappingTagInverting nil) (spice nil))) (DiffIOPkg ((temperature "27") (bufferModelNonInverting "CDSDefaultIO_2p5v") (bufferModelInverting "CDSDefaultIO_2p5v") (stimuli nil) (offsets nil) (state "tristate") (cycle "1") (termMap nil) (setup "0.9e-09") (hold "0.4e-09") (rise nil) (fall nil) (threshInputHighMin "1.7 V") (threshInputHighTyp "1.7  V") (threshInputHighMax "1.7  V") (threshInputLowMin "0.7  V") (threshInputLowTyp "0.7  V") (threshInputLowMax "0.7 ") (threshOutputHighMin "2.365  V") (threshOutputHighTyp "2.5  V") (threshOutputHighMax "2.625  V") (threshOutputLowMin "1.275  V") (threshOutputLowTyp "1.7  V") (threshOutputLowMax "1.985  V") (mappingTagNonInverting nil) (mappingTagInverting nil) (spice nil))) (CPWSL ((d1Thickness "10 mil") (d1Constant "4.5") (d1LossTangent "0.035") (d2Thickness "0.72 mil") (d2Constant "4.5") (d2LossTangent "0.035") (d3Thickness "10 mil") (d3Constant "4.5") (d3LossTangent "0.035") length("1000 mil") (spacing "5 mil") (spacing2 "5 mil") (spacing3 "5 mil") (spacing4 "5 mil") (spacing5 "5 mil") (traceConductivity "595900 mho/cm") (traceGeometry "cpwms") (traceLayerName "") (traceThickness "0.72 mil") (traceType "single") (traceWidth "5.0 mil") (traceWidth2 "5.0 mil") (traceWidth3 "5.0 mil") (traceWidth4 "5.0 mil") (traceWidth5 "5.0 mil") (traceWidth6 "5.0 mil") (offset "0 mil") (traceCount "1") (impedance nil))) (CPWMS ((d1Thickness "10 mil") (d1Constant "4.5") (d1LossTangent "0.035") (d2Thickness "0.72 mil") (d2Constant "4.5") (d2LossTangent "0.035") (d3Thickness "0.0") (d3Constant "1") (d3LossTangent "0") length("1000 mil") (spacing "5 mil") (spacing2 "5 mil") (spacing3 "5 mil") (spacing4 "5 mil") (spacing5 "5 mil") (traceConductivity "595900 mho/cm") (traceGeometry "cpwms") (traceLayerName "") (traceThickness "0.72 mil") (traceType "single") (traceWidth "5.0 mil") (traceWidth2 "5.0 mil") (traceWidth3 "5.0 mil") (traceWidth4 "5.0 mil") (traceWidth5 "5.0 mil") (traceWidth6 "5.0 mil") (offset "0 mil") (traceCount "1") (impedance nil))) (TLine ((diffImpedance "100ohm") (diffVelocity "1.4142e+08M/s") (impedance "60ohm") length("2800 mil") (propDelay "0.5 ns") (velocity "5600 mil/ns") (traceCount "1") (traceGeometry "Microstrip") (impedanceMin nil) (impedanceMax nil) (lengthMin nil) (lengthMax nil) (propDelayMin nil) (propDelayMax nil) (impedanceSweepCount nil) (propDelaySweepCount nil) (velocitySweepCount nil) (lengthSweepCount nil) (matchSetName nil))) (CPW ((d1Thickness "10 mil") (d1Constant "4.5") (d1LossTangent "0.035") (d2Thickness "0.72 mil") (d2Constant "1") (d2LossTangent "0") (d3Thickness "0.0") (d3Constant "1") (d3LossTangent "0") length("1000 mil") (spacing "5 mil") (spacing2 "5 mil") (spacing3 "5 mil") (spacing4 "5 mil") (spacing5 "5 mil") (traceConductivity "595900 mho/cm") (traceGeometry "cpwms") (traceLayerName "") (traceThickness "0.72 mil") (traceType "single") (traceWidth "5.0 mil") (traceWidth2 "5.0 mil") (traceWidth3 "5.0 mil") (traceWidth4 "5.0 mil") (traceWidth5 "5.0 mil") (traceWidth6 "5.0 mil") (offset "0 mil") (traceCount "1") (impedance nil))) (Source ((voltage "5 V"))) (Cable (length("1 m"))) (Connector nil) (CurrentProbe nil) (idlCircuit ((allDrivers "active") (ftsMode '("Typ")) (rcvrSelect "all") (simMode "Reflection") (tlineDelayMode "time") (userRevision "1.0") (autoSolve "On")))))
				)
				( objectStatus "SFI" )
			)
			( electricalCSet "@crescent_city_bb_fab1_lib.crescent_city_bb_fab1(sch_1):\CLK_100M_CPU1_MCP_DN\"
				( groupRef "CLK_100M_CPU1_MCP_DN:MG_CLK_G1-BCLK" )
				( pinPairRef "CLK_100M_CPU1_MCP_DN:EU4D2.64:U2D1.BB25" )
				( attribute "RATSNEST_SCHEDULE" "TEMPLATE"
					( Status sLocked )
					( Origin gBackEnd )
				)
				( attribute "DIFFP_GATHER_CONTROL" "IGNORE"
					( Origin gBackEnd )
				)
				( attribute "DIFFP_UNCOUPLED_LENGTH" "500.00"
					( Origin gBackEnd )
				)
				( attribute "DIFFP_COUPLED_PLUS" "0.50"
					( Origin gBackEnd )
				)
				( attribute "DIFFP_COUPLED_MINUS" "0.50"
					( Origin gBackEnd )
				)
				( attribute "DIFFP_PHASE_TOL" "10 mil"
					( Units "uPhaseTol" "ns" 1.000000)
					( Origin gBackEnd )
				)
				( attribute "TOPOLOGY_TEMPLATE_REVISION" "1.0"
					( Origin gBackEnd )
				)
				( topologyData 31378
(SKIDL (Circuits ("MAIN" (Parts ("CRESCENT_CITY_638_20150416_C.@@EU119.64" IbisOutputPkg (xy (5498 4235)) (refDes "EU4D2") (model "Unknown") (Props (_SXDesignName "CRESCENT_CITY_638_20150416_C") (brdx "6498.19 MIL") (brdy "3039.81 MIL") (bufferModel "CDSDefaultOutput_2p5v") (cycle "1") (hold "1.0e-09") (mappingTag "") (offsets ("4" "0")) (setup "2.0e-09") (state "tristate") (stimuli ("4" "local36")) (temperature "27") (termMap ("4" "Data"))) (Terms ("CRESCENT_CITY_638_20150416_C.X649819Y303981L2LRATS" "64"))) ("CRESCENT_CITY_638_20150416_C.@@U100.BB25" IbisIOPkg (xy (5575 4240)) (refDes "U2D1") (model "Unknown") (Props (_SXDesignName "CRESCENT_CITY_638_20150416_C") (brdx "4789.22 MIL") (brdy "2824.96 MIL") (bufferModel "CDSDefaultIO_2p5v") (cycle "1") (hold "1.0e-09") (mappingTag "") (offsets ("4" "0") ("5" "0")) (setup "2.0e-09") (state "tristate") (stimuli ("4" "local37") ("5" "local38")) (temperature "27") (termMap ("4" "Data") ("5" "Enable"))) (Terms ("CRESCENT_CITY_638_20150416_C.X478922Y282496L2LRATS" "BB25"))) ("CRESCENT_CITY_638_20150416_C.@@U22.E67" IbisIOPkg (xy (5586.5 4227.5)) (refDes "U7C1") (model "Unknown") (Props (_SXDesignName "CRESCENT_CITY_638_20150416_C") (brdx "14816.34 MIL") (brdy "4876.18 MIL") (bufferModel "CDSDefaultIO_2p5v") (cycle "1") (hold "1.0e-09") (mappingTag "") (offsets ("4" "0") ("5" "0")) (setup "2.0e-09") (state "tristate") (stimuli ("4" "local39") ("5" "local40")) (temperature "27") (termMap ("4" "Data") ("5" "Enable"))) (Terms ("CRESCENT_CITY_638_20150416_C.X1481634Y487618L2LRATS" "E67"))) ("CRESCENT_CITY_638_20150416_C.@@R688.2.1" Resistor (xy (5561 4216)) (refDes "R7B7") (value "10000 Ohm") (Props (_SXDesignName "CRESCENT_CITY_638_20150416_C")) (Terms ("CRESCENT_CITY_638_20150416_C.X1467330Y521740L2RATS" "2") ("CRESCENT_CITY_638_20150416_C.X1467330Y518240L2LRATS" "1"))) ("CRESCENT_CITY_638_20150416_C.@@R688.2_SOURCE" Source (xy (5554 4216)) (refDes "GND_1") (value "0 V") (Props (_SXDesignName "CRESCENT_CITY_638_20150416_C")) (Terms ("CRESCENT_CITY_638_20150416_C.X1467330Y521740L2RATS" "1"))) ("CRESCENT_CITY_638_20150416_C.T@@RATS@@U22.E67@@R688.1" TLine (xy (5582.5 4216.0)) (mirror x) (refDes "TL20") (Props (_SXDesignName "CRESCENT_CITY_638_20150416_C") (impedance "49.728 ohm") length("449.26 MIL") (propDelay "0.08069 ns") (traceCount "1") (traceGeometry "Microstrip") (velocity "5567.72 mil/ns")) (Terms ("CRESCENT_CITY_638_20150416_C.X1481634Y487618L2LRATS" "1") ("CRESCENT_CITY_638_20150416_C.X1467330Y518240L2LRATS" "2"))) ("CRESCENT_CITY_638_20150416_C.T@@RATS@@R737.2@@U22.E67" TLine (xy (5576.0 4222.5)) (refDes "TL21") (Props (_SXDesignName "CRESCENT_CITY_638_20150416_C") (impedance "49.728 ohm") length("10347.52 MIL") (propDelay "1.85849 ns") (traceCount "1") (traceGeometry "Microstrip") (velocity "5567.72 mil/ns")) (Terms ("CRESCENT_CITY_638_20150416_C.X635000Y299500L2LRATS" "1") ("CRESCENT_CITY_638_20150416_C.X1481634Y487618L2LRATS" "2"))) ("CRESCENT_CITY_638_20150416_C.T@@RATS@@R3391.1@@EU119.64" TLine (xy (5506 4235)) (mirror x) (refDes "TL22") (Props (_SXDesignName "CRESCENT_CITY_638_20150416_C") (impedance "47.169 ohm") length("78.00 MIL") (propDelay "0.01401 ns") (traceCount "1") (traceGeometry "Microstrip") (velocity "5567.44 mil/ns")) (Terms ("CRESCENT_CITY_638_20150416_C.X644000Y302000L2LRATS" "1") ("CRESCENT_CITY_638_20150416_C.X649819Y303981L2LRATS" "2"))) ("CRESCENT_CITY_638_20150416_C.@@R3391.2.1" Resistor (xy (5521 4235)) (mirror x) (refDes "R4D28") (value "27.4 Ohm") (Props (_SXDesignName "CRESCENT_CITY_638_20150416_C")) (Terms ("CRESCENT_CITY_638_20150416_C.X640500Y302000L2LRATS" "2") ("CRESCENT_CITY_638_20150416_C.X644000Y302000L2LRATS" "1"))) ("CRESCENT_CITY_638_20150416_C.@@R736.1.2" Resistor (xy (5551 4235)) (refDes "R3D10") (value "1 Ohm") (Props (_SXDesignName "CRESCENT_CITY_638_20150416_C")) (Terms ("idlNode_18" "1") ("CRESCENT_CITY_638_20150416_C.X631500Y303000L2LRATS" "2"))) ("CRESCENT_CITY_638_20150416_C.T@@RATS@@U100.BB25@@R736.2" TLine (xy (5560 4235)) (mirror x) (refDes "TL23") (Props (_SXDesignName "CRESCENT_CITY_638_20150416_C") (impedance "47.169 ohm") length("1730.82 MIL") (propDelay "0.31087 ns") (traceCount "1") (traceGeometry "Microstrip") (velocity "5567.68 mil/ns")) (Terms ("CRESCENT_CITY_638_20150416_C.X478922Y282496L2LRATS" "1") ("CRESCENT_CITY_638_20150416_C.X631500Y303000L2LRATS" "2"))) ("CRESCENT_CITY_638_20150416_C.@@R3402.2.1" Resistor (xy (5512 4228)) (refDes "R7P12") (value "42.2 Ohm") (Props (_SXDesignName "CRESCENT_CITY_638_20150416_C")) (Terms ("CRESCENT_CITY_638_20150416_C.X644000Y302000L36RATS" "2") ("CRESCENT_CITY_638_20150416_C.X640500Y302000L36LRATS" "1"))) ("CRESCENT_CITY_638_20150416_C.T@@RATS@@R3391.2@@R3402.1" TLine (xy (5521.0 4228.0)) (mirror x) (refDes "TL24") (Props (_SXDesignName "CRESCENT_CITY_638_20150416_C") (impedance "47.169 ohm") (propDelay "1.79607e-006 ns") (traceCount "1") (traceGeometry "Microstrip")) (Terms ("CRESCENT_CITY_638_20150416_C.X640500Y302000L2LRATS" "1") ("CRESCENT_CITY_638_20150416_C.X640500Y302000L36LRATS" "2"))) ("idlPart_14" TLine (xy (5551.5 4228.5)) (mirror x) (refDes "TL26") (Props (_SXDesignName "CRESCENT_CITY_638_20150416_C") (impedance "47.169 ohm") length("65.00 MIL") (propDelay "0.01167 ns") (traceCount "1") (traceGeometry "Microstrip") (velocity "5569.84 mil/ns")) (Terms ("idlNode_22" "1") ("idlNode_18" "2"))) ("CRESCENT_CITY_638_20150416_C.@@R3402.2_SOURCE" Source (xy (5505 4228)) (refDes "GND") (value "0 V") (Props (_SXDesignName "CRESCENT_CITY_638_20150416_C")) (Terms ("CRESCENT_CITY_638_20150416_C.X644000Y302000L36RATS" "1"))) ("CRESCENT_CITY_638_20150416_C.@@R737.2.1" Resistor (xy (5557.5 4222.5)) (mirror x) (refDes "R3D11") (value "1 Ohm") (Props (_SXDesignName "CRESCENT_CITY_638_20150416_C")) (Terms ("CRESCENT_CITY_638_20150416_C.X635000Y299500L2LRATS" "2") ("idlNode_22" "1"))) ("CRESCENT_CITY_638_20150416_C.T@@RATS@@R736.1@@R3391.2" TLine (xy (5536 4235)) (mirror x) (refDes "TL25") (Props (_SXDesignName "CRESCENT_CITY_638_20150416_C") (impedance "47.169 ohm") length("65.00 MIL") (propDelay "0.01167 ns") (traceCount "1") (traceGeometry "Microstrip") (velocity "5569.84 mil/ns")) (Terms ("idlNode_18" "1") ("CRESCENT_CITY_638_20150416_C.X640500Y302000L2LRATS" "2")))) (Nodes ("CRESCENT_CITY_638_20150416_C.X644000Y302000L2LRATS" (terms "CRESCENT_CITY_638_20150416_C.@@R3391.2.1.2" "CRESCENT_CITY_638_20150416_C.T@@RATS@@R3391.1@@EU119.64.1")) ("CRESCENT_CITY_638_20150416_C.X640500Y302000L2LRATS" (terms "CRESCENT_CITY_638_20150416_C.T@@RATS@@R736.1@@R3391.2.2" "CRESCENT_CITY_638_20150416_C.T@@RATS@@R3391.2@@R3402.1.1" "CRESCENT_CITY_638_20150416_C.@@R3391.2.1.1")) ("CRESCENT_CITY_638_20150416_C.X635000Y299500L2LRATS" (terms "CRESCENT_CITY_638_20150416_C.@@R737.2.1.1" "CRESCENT_CITY_638_20150416_C.T@@RATS@@R737.2@@U22.E67.1")) ("idlNode_18" (terms "CRESCENT_CITY_638_20150416_C.T@@RATS@@R736.1@@R3391.2.1" "idlPart_14.2" "CRESCENT_CITY_638_20150416_C.@@R736.1.2.1")) ("CRESCENT_CITY_638_20150416_C.X631500Y303000L2LRATS" (terms "CRESCENT_CITY_638_20150416_C.T@@RATS@@U100.BB25@@R736.2.2" "CRESCENT_CITY_638_20150416_C.@@R736.1.2.2")) ("CRESCENT_CITY_638_20150416_C.X1467330Y521740L2RATS" (terms "CRESCENT_CITY_638_20150416_C.@@R688.2_SOURCE.1" "CRESCENT_CITY_638_20150416_C.@@R688.2.1.1")) ("CRESCENT_CITY_638_20150416_C.X644000Y302000L36RATS" (terms "CRESCENT_CITY_638_20150416_C.@@R3402.2_SOURCE.1" "CRESCENT_CITY_638_20150416_C.@@R3402.2.1.1")) ("idlNode_22" (terms "CRESCENT_CITY_638_20150416_C.@@R737.2.1.2" "idlPart_14.1")) ("CRESCENT_CITY_638_20150416_C.X478922Y282496L2LRATS" (terms "CRESCENT_CITY_638_20150416_C.T@@RATS@@U100.BB25@@R736.2.1" "CRESCENT_CITY_638_20150416_C.@@U100.BB25.1")) ("CRESCENT_CITY_638_20150416_C.X1467330Y518240L2LRATS" (terms "CRESCENT_CITY_638_20150416_C.T@@RATS@@U22.E67@@R688.1.2" "CRESCENT_CITY_638_20150416_C.@@R688.2.1.2")) ("CRESCENT_CITY_638_20150416_C.X1481634Y487618L2LRATS" (terms "CRESCENT_CITY_638_20150416_C.T@@RATS@@R737.2@@U22.E67.2" "CRESCENT_CITY_638_20150416_C.T@@RATS@@U22.E67@@R688.1.1" "CRESCENT_CITY_638_20150416_C.@@U22.E67.1")) ("CRESCENT_CITY_638_20150416_C.X649819Y303981L2LRATS" (terms "CRESCENT_CITY_638_20150416_C.T@@RATS@@R3391.1@@EU119.64.2" "CRESCENT_CITY_638_20150416_C.@@EU119.64.1")) ("CRESCENT_CITY_638_20150416_C.X640500Y302000L36LRATS" (terms "CRESCENT_CITY_638_20150416_C.T@@RATS@@R3391.2@@R3402.1.2" "CRESCENT_CITY_638_20150416_C.@@R3402.2.1.2"))) (Ports) (Stimuli ("local8" (scope local) (stimType periodic) (Props (periodicFreq "5e+007") (periodicJitter "0") (periodicPattern "1"))) ("local10" (scope local) (stimType periodic) (Props (periodicFreq "5e+007") (periodicJitter "0") (periodicPattern "1"))) ("local9" (scope local) (stimType periodic) (Props (periodicFreq "5e+007") (periodicJitter "0") (periodicPattern "1"))) ("local36" (scope local) (stimType periodic) (Props (periodicFreq "5e+007") (periodicJitter "0") (periodicPattern "1"))) ("local40" (scope local) (stimType periodic) (Props (periodicFreq "5e+007") (periodicJitter "0") (periodicPattern "1"))) ("local37" (scope local) (stimType periodic) (Props (periodicFreq "5e+007") (periodicJitter "0") (periodicPattern "1"))) ("local39" (scope local) (stimType periodic) (Props (periodicFreq "5e+007") (periodicJitter "0") (periodicPattern "1"))) ("local38" (scope local) (stimType periodic) (Props (periodicFreq "5e+007") (periodicJitter "0") (periodicPattern "1")))) (Notes) (Constraints ("DP_GATHER_CONTROL" "IGNORE") ("DP_MAX_UNCOUPLED_LENGTH" "0.00254") ("DP_PHASE_TOLERANCE" ("LENGTH" "0.000254")) ("RATSNEST_SCHEDULE" "TEMPLATE") ("RELATIVE_PROPAGATION_DELAY" ("MG_CLK_G1-BCLK" "CRESCENT_CITY_638_20150416_C EU119.64" "CRESCENT_CITY_638_20150416_C U100.BB25" "GLOBAL" "LENGTH" "0.127" "LENGTH" "0"))) (MeasurementSets ("EMI" ("EMIStatus" status("on")) ("PeakEmission" status("on")) ("PeakFrequency" status("on")) ("PulseFreq" status("on")) ("RiseTime" status("on")) ("VoltageSwing" status("on"))) ("Reflection" ("BufferDelayFall" status("off")) ("BufferDelayRise" status("off")) ("EyeHeight" status("off")) ("EyeJitter" status("off")) ("EyeWidth" status("off")) ("FirstIncidentFall" status("off")) ("FirstIncidentRise" status("off")) ("Glitch" status("on")) ("GlitchFall" status("off")) ("GlitchRise" status("off")) ("Monotonic" status("on")) ("MonotonicFall" status("off")) ("MonotonicRise" status("off")) ("NoiseMargin" status("on")) ("NoiseMarginHigh" status("off")) ("NoiseMarginLow" status("off")) ("OvershootHigh" status("on")) ("OvershootLow" status("on")) ("PropDelay" status("on")) ("SettleDelay" status("on")) ("SettleDelayFall" status("off")) ("SettleDelayRise" status("off")) ("SwitchDelay" status("on")) ("SwitchDelayFall" status("off")) ("SwitchDelayRise" status("off"))) ("Crosstalk" ("Crosstalk" status("on"))) ("Custom")) (VectorSets) (Props (XnetName "CLK_100M_CPU1_MCP_DN") (allDrivers "active") (autoSolve "Off") (customSimType "Reflection") (ftsMode ("Typ")) (rcvrSelect "all") (tlineDelayMode "time") (userRevision "1.0")))) (Subckts) (CrossSections ("CRESCENT_CITY_638_20150416_C" (Props (SXDesignName "CRESCENT_CITY_638_20150416_C")) (Layers ("" (layerType "SURFACE") (material "AIR") (thickness "0 mil") (dielectricConstant "1.000000") (lossTangent "0") (etchFactor "0.000000") (elecCondVal "0 mho/cm") (thermCondVal "0 w/cm-degC")) ("" (layerType "DIELECTRIC") (material "CONFORMAL_COAT") (thickness "0.5 mil") (dielectricConstant "3.800000") (lossTangent "0.035") (etchFactor "0.000000") (elecCondVal "0 mho/cm") (thermCondVal "0.012 w/cm-degC")) ("TOP" (layerType "CONDUCTOR") (material "COPPER") (thickness "  2.100000 mil") (width "4.00 MIL") (dielectricConstant "4.500000") (lossTangent "0") (etchFactor "70.000000") (elecCondVal "595900.000000 mho/cm") (thermCondVal "0 w/cm-degC") (signalDieConstant "3.800000") (signalLossTangent "0.035")) ("" (layerType "DIELECTRIC") (material "FR-4") (thickness "  2.670000 mil") (dielectricConstant "4.000000") (lossTangent "0.035") (etchFactor "0.000000") (elecCondVal "0 mho/cm") (thermCondVal "0.012 w/cm-degC")) ("L2_GND1" (layerType "PLANE") (material "COPPER") (isShield t) (thickness "  1.250000 mil") (dielectricConstant "4.500000") (lossTangent "0.035") (etchFactor "90.000000") (elecCondVal "595900.000000 mho/cm") (thermCondVal "0.012 w/cm-degC")) ("" (layerType "DIELECTRIC") (material "FR-4") (thickness "  9.000000 mil") (dielectricConstant "4.100000") (lossTangent "0.035") (etchFactor "0.000000") (elecCondVal "0 mho/cm") (thermCondVal "0.012 w/cm-degC")) ("L3_SIG1" (layerType "CONDUCTOR") (material "COPPER") (thickness "  1.250000 mil") (width "4.00 MIL") (dielectricConstant "4.500000") (lossTangent "0.035") (etchFactor "90.000000") (elecCondVal "595900.000000 mho/cm") (thermCondVal "0.012 w/cm-degC") (signalDieConstant "4.100000") (signalLossTangent "0.035")) ("" (layerType "DIELECTRIC") (material "FR-4") (thickness "  3.000000 mil") (dielectricConstant "4.500000") (lossTangent "0.035") (etchFactor "0.000000") (elecCondVal "0 mho/cm") (thermCondVal "0 w/cm-degC")) ("L4_GND2" (layerType "PLANE") (material "COPPER") (isShield t) (thickness "  1.250000 mil") (dielectricConstant "4.500000") (lossTangent "0.035") (etchFactor "90.000000") (elecCondVal "595900.000000 mho/cm") (thermCondVal "0 w/cm-degC")) ("" (layerType "DIELECTRIC") (material "FR-4") (thickness "  9.000000 mil") (dielectricConstant "4.000000") (lossTangent "0.035") (etchFactor "0.000000") (elecCondVal "0 mho/cm") (thermCondVal "0.012 w/cm-degC")) ("L5_SIG2" (layerType "CONDUCTOR") (material "COPPER") (thickness "  1.250000 mil") (width "4.00 MIL") (dielectricConstant "4.500000") (lossTangent "0.035") (etchFactor "90.000000") (elecCondVal "595900.000000 mho/cm") (thermCondVal "0.012 w/cm-degC") (signalDieConstant "4.000000") (signalLossTangent "0.035")) ("" (layerType "DIELECTRIC") (material "FR-4") (thickness "  3.000000 mil") (dielectricConstant "4.500000") (lossTangent "0.035") (etchFactor "0.000000") (elecCondVal "0 mho/cm") (thermCondVal "0 w/cm-degC")) ("L6_GND3" (layerType "PLANE") (material "COPPER") (isShield t) (thickness "  1.250000 mil") (dielectricConstant "4.500000") (lossTangent "0.035") (etchFactor "90.000000") (elecCondVal "595900.000000 mho/cm") (thermCondVal "0 w/cm-degC")) ("" (layerType "DIELECTRIC") (material "FR-4") (thickness "  4.500000 mil") (dielectricConstant "4.100000") (lossTangent "0.035") (etchFactor "0.000000") (elecCondVal "0 mho/cm") (thermCondVal "0.012 w/cm-degC")) ("L7_PWR1-SIG" (layerType "PLANE") (material "COPPER") (isShield t) (thickness "  2.610000 mil") (dielectricConstant "4.500000") (lossTangent "0.035") (etchFactor "90.000000") (elecCondVal "595900.000000 mho/cm") (thermCondVal "0.012 w/cm-degC")) ("" (layerType "DIELECTRIC") (material "FR-4") (thickness "  3.100000 mil") (dielectricConstant "4.500000") (lossTangent "0.035") (etchFactor "0.000000") (elecCondVal "0 mho/cm") (thermCondVal "0 w/cm-degC")) ("L8_GND_TEMP" (layerType "PLANE") (material "COPPER") (isShield t) (thickness "  1.250000 mil") (dielectricConstant "4.500000") (lossTangent "0.035") (etchFactor "90.000000") (elecCondVal "595900.000000 mho/cm") (thermCondVal "0 w/cm-degC")) ("" (layerType "DIELECTRIC") (material "FR-4") (thickness "  3.030000 mil") (dielectricConstant "4.500000") (lossTangent "0.035") (etchFactor "0.000000") (elecCondVal "0 mho/cm") (thermCondVal "0 w/cm-degC")) ("L9_SIG_TEMP" (layerType "CONDUCTOR") (material "COPPER") (thickness "  1.250000 mil") (width "3.52 MIL") (dielectricConstant "4.500000") (lossTangent "0.035") (etchFactor "90.000000") (elecCondVal "595900.000000 mho/cm") (thermCondVal "0 w/cm-degC") (signalDieConstant "4.500000") (signalLossTangent "0.035")) ("" (layerType "DIELECTRIC") (material "FR-4") (thickness "  5.000000 mil") (dielectricConstant "4.500000") (lossTangent "0.035") (etchFactor "0.000000") (elecCondVal "0 mho/cm") (thermCondVal "0 w/cm-degC")) ("L10_SIG_TEMP" (layerType "CONDUCTOR") (material "COPPER") (thickness "  1.250000 mil") (width "3.52 MIL") (dielectricConstant "4.500000") (lossTangent "0.035") (etchFactor "90.000000") (elecCondVal "595900.000000 mho/cm") (thermCondVal "0 w/cm-degC") (signalDieConstant "4.500000") (signalLossTangent "0.035")) ("" (layerType "DIELECTRIC") (material "FR-4") (thickness "  3.030000 mil") (dielectricConstant "4.500000") (lossTangent "0.035") (etchFactor "0.000000") (elecCondVal "0 mho/cm") (thermCondVal "0 w/cm-degC")) ("L11_GND_TEMP" (layerType "PLANE") (material "COPPER") (isShield t) (thickness "  1.250000 mil") (dielectricConstant "4.500000") (lossTangent "0.035") (etchFactor "90.000000") (elecCondVal "595900.000000 mho/cm") (thermCondVal "0 w/cm-degC")) ("" (layerType "DIELECTRIC") (material "FR-4") (thickness "  3.100000 mil") (dielectricConstant "4.000000") (lossTangent "0.035") (etchFactor "0.000000") (elecCondVal "0 mho/cm") (thermCondVal "0.012 w/cm-degC")) ("L12_PWR2-SIG" (layerType "PLANE") (material "COPPER") (isShield t) (thickness "  2.610000 mil") (dielectricConstant "4.500000") (lossTangent "0.035") (etchFactor "90.000000") (elecCondVal "595900.000000 mho/cm") (thermCondVal "0.012 w/cm-degC")) ("" (layerType "DIELECTRIC") (material "FR-4") (thickness "  4.500000 mil") (dielectricConstant "4.500000") (lossTangent "0.035") (etchFactor "0.000000") (elecCondVal "0 mho/cm") (thermCondVal "0 w/cm-degC")) ("L13_GND4" (layerType "PLANE") (material "COPPER") (isShield t) (thickness "  1.250000 mil") (dielectricConstant "4.500000") (lossTangent "0.035") (etchFactor "90.000000") (elecCondVal "595900.000000 mho/cm") (thermCondVal "0 w/cm-degC")) ("" (layerType "DIELECTRIC") (material "FR-4") (thickness "  3.000000 mil") (dielectricConstant "4.100000") (lossTangent "0.035") (etchFactor "0.000000") (elecCondVal "0 mho/cm") (thermCondVal "0.012 w/cm-degC")) ("L14_SIG3" (layerType "CONDUCTOR") (material "COPPER") (thickness "  1.250000 mil") (width "4.00 MIL") (dielectricConstant "4.500000") (lossTangent "0.035") (etchFactor "90.000000") (elecCondVal "595900.000000 mho/cm") (thermCondVal "0.012 w/cm-degC") (signalDieConstant "4.100000") (signalLossTangent "0.035")) ("" (layerType "DIELECTRIC") (material "FR-4") (thickness "  9.000000 mil") (dielectricConstant "4.500000") (lossTangent "0.035") (etchFactor "0.000000") (elecCondVal "0 mho/cm") (thermCondVal "0 w/cm-degC")) ("L15_GND5" (layerType "PLANE") (material "COPPER") (isShield t) (thickness "  1.250000 mil") (dielectricConstant "4.500000") (lossTangent "0.035") (etchFactor "90.000000") (elecCondVal "595900.000000 mho/cm") (thermCondVal "0 w/cm-degC")) ("" (layerType "DIELECTRIC") (material "FR-4") (thickness "  3.000000 mil") (dielectricConstant "4.500000") (lossTangent "0.035") (etchFactor "0.000000") (elecCondVal "0 mho/cm") (thermCondVal "0.012 w/cm-degC")) ("L16_SIG4" (layerType "CONDUCTOR") (material "COPPER") (thickness "  1.250000 mil") (width "4.00 MIL") (dielectricConstant "4.500000") (lossTangent "0.035") (etchFactor "90.000000") (elecCondVal "595900.000000 mho/cm") (thermCondVal "0.012 w/cm-degC") (signalDieConstant "4.500000") (signalLossTangent "0.035")) ("" (layerType "DIELECTRIC") (material "FR-4") (thickness "  9.000000 mil") (dielectricConstant "4.500000") (lossTangent "0.035") (etchFactor "0.000000") (elecCondVal "0 mho/cm") (thermCondVal "0 w/cm-degC")) ("L17_GND6" (layerType "PLANE") (material "COPPER") (isShield t) (thickness "  1.250000 mil") (dielectricConstant "4.500000") (lossTangent "0.035") (etchFactor "90.000000") (elecCondVal "595900.000000 mho/cm") (thermCondVal "0.012 w/cm-degC")) ("" (layerType "DIELECTRIC") (material "FR-4") (thickness "  2.670000 mil") (dielectricConstant "4.500000") (lossTangent "0.035") (etchFactor "0.000000") (elecCondVal "0 mho/cm") (thermCondVal "0.012 w/cm-degC")) ("BOTTOM" (layerType "CONDUCTOR") (material "COPPER") (thickness "  2.100000 mil") (width "4.00 MIL") (dielectricConstant "4.500000") (lossTangent "0") (etchFactor "70.000000") (elecCondVal "595900.000000 mho/cm") (thermCondVal "0 w/cm-degC") (signalDieConstant "3.800000") (signalLossTangent "0.035")) ("" (layerType "DIELECTRIC") (material "CONFORMAL_COAT") (thickness "0.5 mil") (dielectricConstant "3.800000") (lossTangent "0.035") (etchFactor "0.000000") (elecCondVal "0 mho/cm") (thermCondVal "0.012 w/cm-degC")) ("" (layerType "SURFACE") (material "AIR") (thickness "0 mil") (dielectricConstant "1.000000") (lossTangent "0") (etchFactor "0.000000") (elecCondVal "0 mho/cm") (thermCondVal "0 w/cm-degC"))))) (Props (DesUnits "mils 2") (LayerStack ("DIELECTRIC" "DIELECTRIC" "BOTTOM" "DIELECTRIC" "L17_GND6" "DIELECTRIC" "L16_SIG4" "DIELECTRIC" "L15_GND5" "DIELECTRIC" "L14_SIG3" "DIELECTRIC" "L13_GND4" "DIELECTRIC" "L12_PWR2-SIG" "DIELECTRIC" "L11_GND_TEMP" "DIELECTRIC" "L10_SIG_TEMP" "DIELECTRIC" "L9_SIG_TEMP" "DIELECTRIC" "L8_GND_TEMP" "DIELECTRIC" "L7_PWR1-SIG" "DIELECTRIC" "L6_GND3" "DIELECTRIC" "L5_SIG2" "DIELECTRIC" "L4_GND2" "DIELECTRIC" "L3_SIG1" "DIELECTRIC" "L2_GND1" "DIELECTRIC" "TOP" "DIELECTRIC" "DIELECTRIC")) (Revision "16.600")) (Params (DiffInput ((temperature "27") (bufferModelNonInverting "CDSDefaultInput_2p5v") (bufferModelInverting "CDSDefaultInput_2p5v") (threshInputHighMin "1.7 V") (threshInputHighTyp "1.7  V") (threshInputHighMax "1.7  V") (threshInputLowMin "0.7  V") (threshInputLowTyp "0.7  V") (threshInputLowMax "0.7  V") (mappingTagNonInverting nil) (mappingTagInverting nil) (cycle "1"))) (Resistor ((resistance "50 ohm") (orientation "0"))) (DiffOutputPkg ((temperature "27") (bufferModelNonInverting "CDSDefaultOutput_2p5v") (bufferModelInverting "CDSDefaultOutput_2p5v") (stimuli nil) (offsets nil) (state "tristate") (cycle "1") (termMap nil) (setup "0.9e-09") (hold "0.4e-09") (rise nil) (fall nil) (threshOutputHighMin "2.375  V") (threshOutputHighTyp "2.5  V") (threshOutputHighMax "2.625  V") (threshOutputLowMin "1.275  V") (threshOutputLowTyp "1.7  V") (threshOutputLowMax "1.985  V") (mappingTagNonInverting nil) (mappingTagInverting nil) (spice nil))) (DiffOutput ((temperature "27") (bufferModelNonInverting "CDSDefaultOutput_2p5v") (bufferModelInverting "CDSDefaultOutput_2p5v") (stimuli nil) (offsets nil) (state "tristate") (cycle "1") (termMap nil) (setup "0.9e-09") (hold "0.4e-09") (rise nil) (fall nil) (threshOutputHighMin "2.375  V") (threshOutputHighTyp "2.5  V") (threshOutputHighMax "2.625  V") (threshOutputLowMin "1.275  V") (threshOutputLowTyp "1.7  V") (threshOutputLowMax "1.985  V") (mappingTagNonInverting nil) (mappingTagInverting nil) (spice nil))) (Inductor ((inductance "5 nH") (orientation "0"))) (Capacitor ((capacitance "10 pF") (orientation "0"))) (DiffIOPkg ((temperature "27") (bufferModelNonInverting "CDSDefaultIO_2p5v") (bufferModelInverting "CDSDefaultIO_2p5v") (stimuli nil) (offsets nil) (state "tristate") (cycle "1") (termMap nil) (setup "0.9e-09") (hold "0.4e-09") (rise nil) (fall nil) (threshInputHighMin "1.7 V") (threshInputHighTyp "1.7  V") (threshInputHighMax "1.7  V") (threshInputLowMin "0.7  V") (threshInputLowTyp "0.7  V") (threshInputLowMax "0.7 ") (threshOutputHighMin "2.365  V") (threshOutputHighTyp "2.5  V") (threshOutputHighMax "2.625  V") (threshOutputLowMin "1.275  V") (threshOutputLowTyp "1.7  V") (threshOutputLowMax "1.985  V") (mappingTagNonInverting nil) (mappingTagInverting nil) (spice nil))) (Source ((voltage "5 V"))) (DiffIO ((temperature "27") (bufferModelNonInverting "CDSDefaultIO_2p5v") (bufferModelInverting "CDSDefaultIO_2p5v") (stimuli nil) (offsets nil) (state "tristate") (cycle "1") (termMap nil) (setup "0.9e-09") (hold "0.4e-09") (rise nil) (fall nil) (threshInputHighMin "1.7 V") (threshInputHighTyp "1.7  V") (threshInputHighMax "1.7  V") (threshInputLowMin "0.7  V") (threshInputLowTyp "0.7  V") (threshInputLowMax "0.7 ") (threshOutputHighMin "2.365  V") (threshOutputHighTyp "2.5  V") (threshOutputHighMax "2.625  V") (threshOutputLowMin "1.275  V") (threshOutputLowTyp "1.7  V") (threshOutputLowMax "1.985  V") (mappingTagNonInverting nil) (mappingTagInverting nil) (spice nil))) (RLGC (length("1000 mil"))) (DiffInputPkg ((temperature "27") (bufferModelNonInverting "CDSDefaultInput_2p5v") (bufferModelInverting "CDSDefaultInput_2p5v") (threshInputHighMin "1.7 V") (threshInputHighTyp "1.7  V") (threshInputHighMax "1.7  V") (threshInputLowMin "0.7  V") (threshInputLowTyp "0.7  V") (threshInputLowMax "0.7  V") (mappingTagNonInverting nil) (mappingTagInverting nil) (cycle "1"))) (IbisInput ((temperature "27") (bufferModel "CDSDefaultInput_2p5v") (cycle "1") (LEFDEFPinName nil) (LEFDEFPinType nil) (mappingTag nil))) (Diode ((cutoffVoltage "0.7 V"))) (idlCircuit ((allDrivers "active") (ftsMode '("Typ")) (rcvrSelect "all") (simMode "Reflection") (tlineDelayMode "time") (userRevision "1.0") (autoSolve "On"))) (CPW ((d1Thickness "10 mil") (d1Constant "4.5") (d1LossTangent "0.035") (d2Thickness "0.72 mil") (d2Constant "1") (d2LossTangent "0") (d3Thickness "0.0") (d3Constant "1") (d3LossTangent "0") length("1000 mil") (spacing "5 mil") (spacing2 "5 mil") (spacing3 "5 mil") (spacing4 "5 mil") (spacing5 "5 mil") (traceConductivity "595900 mho/cm") (traceGeometry "cpwms") (traceLayerName "") (traceThickness "0.72 mil") (traceType "single") (traceWidth "5.0 mil") (traceWidth2 "5.0 mil") (traceWidth3 "5.0 mil") (traceWidth4 "5.0 mil") (traceWidth5 "5.0 mil") (traceWidth6 "5.0 mil") (offset "0 mil") (traceCount "1") (impedance nil))) (DualClampTerm ((cutoffVoltageUp "0.7 V") (cutoffVoltageDown "0.7 V") (voltageUp "5 V") (voltageDown "0 V") (maxDelay "0.1 ns"))) (ESpiceDevice nil) (HiClampTerm ((cutoffVoltage "0.7 V") (voltage "5 V") (maxDelay "0.1 ns"))) (IbisOutput ((temperature "27") (bufferModel "CDSDefaultOutput_2p5v") (stimuli nil) (offsets nil) (state "tristate") (cycle "1") (termMap nil) (setup "2.0e-09") (hold "1.0e-09") (rise nil) (fall nil) (macroType nil) (voltage nil) (spice nil) (LEFDEFPinName nil) (LEFDEFPinType nil) (mappingTag nil))) (sync ((syncFreq "100e6") (syncInitState "1") (syncPattern "10") (syncEdgeSwitch "rise"))) (IbisIO ((temperature "27") (bufferModel "CDSDefaultIO_2p5v") (stimuli nil) (offsets nil) (state "tristate") (cycle "1") (termMap nil) (setup "2.0e-09") (hold "1.0e-09") (rise nil) (fall nil) (macroType nil) (voltage nil) (spice nil) (LEFDEFPinName nil) (LEFDEFPinType nil) (mappingTag nil))) (RCTerm ((resistance "50 ohm") (capacitance "20 pF") (voltage "5 V") (maxDelay "0.1 ns"))) (TLine ((diffImpedance "100ohm") (diffVelocity "1.4142e+08M/s") (impedance "60ohm") length("2800 mil") (propDelay "0.5 ns") (velocity "5600 mil/ns") (traceCount "1") (traceGeometry "Microstrip") (impedanceMin nil) (impedanceMax nil) (lengthMin nil) (lengthMax nil) (propDelayMin nil) (propDelayMax nil) (impedanceSweepCount nil) (propDelaySweepCount nil) (velocitySweepCount nil) (lengthSweepCount nil) (matchSetName nil))) (LowClampTerm ((cutoffVoltage "0.7 V") (voltage "0 V") (maxDelay "0.1 ns"))) (Connector nil) (ShuntTerm ((resistance "50 ohm") (voltage "5 V") (maxDelay "0.1 ns"))) (IbisIO_OpenPullDown ((temperature "27") (bufferModel "CDSDefaultIO_2p5v") (stimuli nil) (offsets nil) (state "tristate") (cycle "1") (termMap nil) (setup "2.0e-09") (hold "1.0e-09") (rise nil) (fall nil) (macroType nil) (voltage nil) (spice nil) (LEFDEFPinName nil) (LEFDEFPinType nil) (mappingTag nil))) (clocked ((clockRise "1e-09") (clockFall "1e-09") (clockFreq "100e6") (clockInitState "0") (clockDutyCycle "0.5") (clockJitter "0"))) (TheveninTerm ((resistanceUp "180 ohm") (resistanceDown "270 ohm") (voltageUp "5 V") (voltageDown "0 V") (maxDelay "0.1 ns"))) (IbisIO_OpenPullUp ((temperature "27") (bufferModel "CDSDefaultIO_2p5v") (stimuli nil) (offsets nil) (state "tristate") (cycle "1") (termMap nil) (setup "2.0e-09") (hold "1.0e-09") (rise nil) (fall nil) (macroType nil) (voltage nil) (spice nil) (LEFDEFPinName nil) (LEFDEFPinType nil) (mappingTag nil))) (CPWSL ((d1Thickness "10 mil") (d1Constant "4.5") (d1LossTangent "0.035") (d2Thickness "0.72 mil") (d2Constant "4.5") (d2LossTangent "0.035") (d3Thickness "10 mil") (d3Constant "4.5") (d3LossTangent "0.035") length("1000 mil") (spacing "5 mil") (spacing2 "5 mil") (spacing3 "5 mil") (spacing4 "5 mil") (spacing5 "5 mil") (traceConductivity "595900 mho/cm") (traceGeometry "cpwms") (traceLayerName "") (traceThickness "0.72 mil") (traceType "single") (traceWidth "5.0 mil") (traceWidth2 "5.0 mil") (traceWidth3 "5.0 mil") (traceWidth4 "5.0 mil") (traceWidth5 "5.0 mil") (traceWidth6 "5.0 mil") (offset "0 mil") (traceCount "1") (impedance nil))) (IbisOutput_OpenPullUp ((temperature "27") (bufferModel "CDSDefaultOutput_2p5v") (stimuli nil) (offsets nil) (state "tristate") (cycle "1") (termMap nil) (setup "2.0e-09") (hold "1.0e-09") (rise nil) (fall nil) (macroType nil) (voltage nil) (spice nil) (LEFDEFPinName nil) (LEFDEFPinType nil) (mappingTag nil))) (CPWMS ((d1Thickness "10 mil") (d1Constant "4.5") (d1LossTangent "0.035") (d2Thickness "0.72 mil") (d2Constant "4.5") (d2LossTangent "0.035") (d3Thickness "0.0") (d3Constant "1") (d3LossTangent "0") length("1000 mil") (spacing "5 mil") (spacing2 "5 mil") (spacing3 "5 mil") (spacing4 "5 mil") (spacing5 "5 mil") (traceConductivity "595900 mho/cm") (traceGeometry "cpwms") (traceLayerName "") (traceThickness "0.72 mil") (traceType "single") (traceWidth "5.0 mil") (traceWidth2 "5.0 mil") (traceWidth3 "5.0 mil") (traceWidth4 "5.0 mil") (traceWidth5 "5.0 mil") (traceWidth6 "5.0 mil") (offset "0 mil") (traceCount "1") (impedance nil))) (periodic ((periodicFreq "100e6") (periodicPattern "10") (periodicJitter "0"))) (IbisInputPkg ((temperature "27") (bufferModel "CDSDefaultInput_2p5v") (cycle "1") (LEFDEFPinName nil) (LEFDEFPinType nil) (mappingTag nil))) (IbisIOMacro ((temperature "27") (bufferModel "CDSDefaultIO_2p5v") (stimuli nil) (offsets nil) (state "tristate") (cycle "1") (termMap nil) (setup "2.0e-09") (hold "1.0e-09") (rise nil) (fall nil) (macroType nil) (voltage nil) (spice nil) (LEFDEFPinName nil) (LEFDEFPinType nil) (mappingTag nil))) (CurrentProbe nil) (IbisOutputPkg ((temperature "27") (bufferModel "CDSDefaultOutput_2p5v") (stimuli nil) (offsets nil) (state "tristate") (cycle "1") (termMap nil) (setup "2.0e-09") (hold "1.0e-09") (rise nil) (fall nil) (macroType nil) (voltage nil) (spice nil) (LEFDEFPinName nil) (LEFDEFPinType nil) (mappingTag nil))) (IbisIOPkg ((temperature "27") (bufferModel "CDSDefaultIO_2p5v") (stimuli nil) (offsets nil) (state "tristate") (cycle "1") (termMap nil) (setup "2.0e-09") (hold "1.0e-09") (rise nil) (fall nil) (macroType nil) (voltage nil) (spice nil) (LEFDEFPinName nil) (LEFDEFPinType nil) (mappingTag nil))) (SeriesTerm ((resistance "22 ohm") (maxDelay "0.1 ns"))) (Trace ((d1Thickness "10 mil") (d1Constant "4.5") (d1LossTangent "0.035") (d2Thickness "10 mil") (d2Constant "4.5") (d2LossTangent "0.035") (d3Thickness "0.0") (d3Constant "1.0") (d3LossTangent "0") length("1000 mil") (spacing "5 mil") (spacing2 "5 mil") (spacing3 "5 mil") (spacing4 "5 mil") (spacing5 "5 mil") (traceConductivity "595900 mho/cm") (traceGeometry "microstrip") (traceLayerName "") (traceThickness "0.72 mil") (traceType "single") (traceWidth "5.0 mil") (traceWidth2 "5.0 mil") (traceWidth3 "5.0 mil") (traceWidth4 "5.0 mil") (traceWidth5 "5.0 mil") (traceWidth6 "5.0 mil") (offset "0 mil") (traceCount "1") (impedance nil))) (async ((asyncTimePoints "") (asyncInitState "1"))) (Cable (length("1 m"))) (Via ((model "Unknown") (viaOutputFormat "Unknown") (viaPadstack nil) (viaTopLayer nil) (viaBottomLayer nil) (viaIsPower nil) (viaIsGround nil)))))
				)
				( objectStatus "CLK_100M_CPU1_MCP_DN" )
			)
			( electricalCSet "@baseboard_fab2_lib.baseboard_fab2(sch_1):\XDP_CPU_TCK0\"
				( pinPairRef "XDP_CPU_TCK0:U2D1.AA14:R7P29.1" )
				( pinPairRef "XDP_CPU_TCK0:U7C1.AF54:R3M10.1" )
				( pinPairRef "XDP_CPU_TCK0:J9A3.57:U2D1.AA14" )
				( attribute "RATSNEST_SCHEDULE" "TEMPLATE"
					( Status sLocked )
					( Origin gBackEnd )
				)
				( attribute "TOPOLOGY_TEMPLATE_REVISION" "1.0"
					( Origin gBackEnd )
				)
				( topologyData 32361
(SKIDL (Circuits ("MAIN" (Parts ("CRESCENT_CITY_198_20150202_Q.@@U4.1" IbisOutputPkg (xy (5498 4235)) (refDes "U4") (model "Unknown") (Props (_SXDesignName "CRESCENT_CITY_198_20150202_Q") (brdx "18115 MIL") (brdy "6191 MIL") (bufferModel "CDSDefaultOutput_2p5v") (cycle "1") (hold "1.0e-09") (mappingTag "") (offsets ("4" "0")) (setup "2.0e-09") (state "tristate") (stimuli ("4" "local39")) (temperature "27") (termMap ("4" "Data"))) (Terms ("CRESCENT_CITY_198_20150202_Q.X1811500Y619100L2LRATS" "1"))) ("CRESCENT_CITY_198_20150202_Q.@@U4.3" IbisInputPkg (xy (5521.5 4182.0)) (refDes "U4") (model "Unknown") (Props (_SXDesignName "CRESCENT_CITY_198_20150202_Q") (brdx "18115 MIL") (brdy "6116.2 MIL") (bufferModel "CDSDefaultInput_2p5v") (mappingTag "") (temperature "27")) (Terms ("idlNode_12" "3"))) ("CRESCENT_CITY_198_20150202_Q.@@U4.4" IbisInputPkg (xy (5559 4235)) (refDes "U4") (model "Unknown") (Props (_SXDesignName "CRESCENT_CITY_198_20150202_Q") (brdx "18204 MIL") (brdy "6116.2 MIL") (bufferModel "CDSDefaultInput_2p5v") (mappingTag "") (temperature "27")) (Terms ("idlNode_34" "4"))) ("CRESCENT_CITY_198_20150202_Q.@@J54.57" Connector (xy (5584.0 4233.5)) (refDes "J9A3") (Props (_SXDesignName "CRESCENT_CITY_198_20150202_Q") (brdx "18222.76 MIL") (brdy "5894.64 MIL") (pin_use "1")) (Terms ("idlNode_32" "57"))) ("CRESCENT_CITY_198_20150202_Q.@@U22.AF54" IbisIOPkg (xy (5579 4200)) (refDes "U7C1") (model "Unknown") (Props (_SXDesignName "CRESCENT_CITY_198_20150202_Q") (brdx "15187.25 MIL") (brdy "4629.2 MIL") (bufferModel "CDSDefaultIO_2p5v") (cycle "1") (hold "1.0e-09") (mappingTag "") (offsets ("4" "0") ("5" "0")) (setup "2.0e-09") (state "tristate") (stimuli ("4" "local40") ("5" "local41")) (temperature "27") (termMap ("4" "Data") ("5" "Enable"))) (Terms ("CRESCENT_CITY_198_20150202_Q.X1518725Y462920L2LRATS" "AF54"))) ("CRESCENT_CITY_198_20150202_Q.@@U36.AA14" IbisInputPkg (xy (5556 4203)) (refDes "U5D1") (model "Unknown") (Props (_SXDesignName "CRESCENT_CITY_198_20150202_Q") (brdx "11657.1 MIL") (brdy "2415.47 MIL") (bufferModel "CDSDefaultInput_2p5v") (mappingTag "") (temperature "27")) (Terms ("CRESCENT_CITY_198_20150202_Q.X1165710Y241547L2LRATS" "AA14"))) ("CRESCENT_CITY_198_20150202_Q.@@U100.AA14" IbisInputPkg (xy (5584 4220)) (refDes "U2D1") (model "Unknown") (Props (_SXDesignName "CRESCENT_CITY_198_20150202_Q") (brdx "5161.02 MIL") (brdy "2415.47 MIL") (bufferModel "CDSDefaultInput_2p5v") (mappingTag "") (temperature "27")) (Terms ("CRESCENT_CITY_198_20150202_Q.X516102Y241547L2LRATS" "AA14"))) ("CRESCENT_CITY_198_20150202_Q.@@R812.2_SOURCE" Source (xy (5555 4189)) (refDes "GND_1") (value "0 V") (Props (_SXDesignName "CRESCENT_CITY_198_20150202_Q")) (Terms ("CRESCENT_CITY_198_20150202_Q.X1806500Y609500L2RATS" "1"))) ("CRESCENT_CITY_198_20150202_Q.T@@RATS@@U4.4@@U4.1" TLine (xy (5534 4235)) (mirror x) (refDes "TL21") (Props (_SXDesignName "CRESCENT_CITY_198_20150202_Q") (impedance "48.412 ohm") length("163.80 MIL") (propDelay "0.02942 ns") (traceCount "1") (traceGeometry "Microstrip") (velocity "5567.64 mil/ns")) (Terms ("idlNode_34" "1") ("CRESCENT_CITY_198_20150202_Q.X1811500Y619100L2LRATS" "2"))) ("CRESCENT_CITY_198_20150202_Q.T@@RATS@@U36.AA14@@J54.57" TLine (xy (5542 4220)) (mirror x) (refDes "TL22") (Props (_SXDesignName "CRESCENT_CITY_198_20150202_Q") (impedance "60 ohm") length("10044.84 MIL") (propDelay "1.80412 ns") (traceCount "1") (traceGeometry "Microstrip") (velocity "5567.72 mil/ns")) (Terms ("CRESCENT_CITY_198_20150202_Q.X1165710Y241547L2LRATS" "1") ("idlNode_34" "2"))) ("CRESCENT_CITY_198_20150202_Q.T@@RATS@@J54.57@@U4.4" TLine (xy (5566.0 4229.5)) (refDes "TL23") (Props (_SXDesignName "CRESCENT_CITY_198_20150202_Q") (impedance "48.412 ohm") length("240.32 MIL") (propDelay "0.04316 ns") (traceCount "1") (traceGeometry "Microstrip") (velocity "5568.11 mil/ns")) (Terms ("idlNode_34" "1") ("idlNode_32" "2"))) ("CRESCENT_CITY_198_20150202_Q.@@R3C60.2_SOURCE" Source (xy (5563 4212)) (refDes "GND_2") (value "0 V") (Props (_SXDesignName "CRESCENT_CITY_198_20150202_Q")) (Terms ("CRESCENT_CITY_198_20150202_Q.X508000Y256000L28RATS" "1"))) ("CRESCENT_CITY_198_20150202_Q.T@@RATS@@R3.1@@R5.1" TLine (xy (5519 4195)) (mirror x) (refDes "TL24") (Props (_SXDesignName "CRESCENT_CITY_198_20150202_Q") (impedance "48.412 ohm") length("34.00 MIL") (propDelay "0.00611 ns") (traceCount "1") (traceGeometry "Microstrip") (velocity "5564.65 mil/ns")) (Terms ("CRESCENT_CITY_198_20150202_Q.X1803000Y616300L2LRATS" "1") ("CRESCENT_CITY_198_20150202_Q.X1803000Y619700L2LRATS" "2"))) ("CRESCENT_CITY_198_20150202_Q.@@R3.2_SOURCE" Source (xy (5512 4189)) (refDes "GND") (value "0 V") (Props (_SXDesignName "CRESCENT_CITY_198_20150202_Q")) (Terms ("CRESCENT_CITY_198_20150202_Q.X1806500Y616300L2RATS" "1"))) ("CRESCENT_CITY_198_20150202_Q.T@@RATS@@R812.1@@R4.1" TLine (xy (5549 4195)) (mirror x) (refDes "TL25") (Props (_SXDesignName "CRESCENT_CITY_198_20150202_Q") (impedance "48.412 ohm") length("33.00 MIL") (propDelay "0.00593 ns") (traceCount "1") (traceGeometry "Microstrip") (velocity "5564.92 mil/ns")) (Terms ("CRESCENT_CITY_198_20150202_Q.X1803000Y609500L2LRATS" "1") ("idlNode_18" "2"))) ("CRESCENT_CITY_198_20150202_Q.@@R5.1.2" Resistor (xy (5520.5 4213.5)) (refDes "R9A3") (value "1 Ohm") (Props (_SXDesignName "CRESCENT_CITY_198_20150202_Q")) (Terms ("CRESCENT_CITY_198_20150202_Q.X1803000Y619700L2LRATS" "1") ("CRESCENT_CITY_198_20150202_Q.X1806500Y619700L2LRATS" "2"))) ("CRESCENT_CITY_198_20150202_Q.T@@RATS@@U100.AA14@@U36.AA14" TLine (xy (5557 4220)) (mirror x) (refDes "TL26") (Props (_SXDesignName "CRESCENT_CITY_198_20150202_Q") (impedance "60 ohm") length("6496.06 MIL") (propDelay "1.16674 ns") (traceCount "1") (traceGeometry "Microstrip") (velocity "5567.72 mil/ns")) (Terms ("CRESCENT_CITY_198_20150202_Q.X516102Y241547L2LRATS" "1") ("CRESCENT_CITY_198_20150202_Q.X1165710Y241547L2LRATS" "2"))) ("CRESCENT_CITY_198_20150202_Q.@@R812.2.1" Resistor (xy (5562 4189)) (refDes "R3M10") (value "51.1 Ohm") (Props (_SXDesignName "CRESCENT_CITY_198_20150202_Q")) (Terms ("CRESCENT_CITY_198_20150202_Q.X1806500Y609500L2RATS" "2") ("CRESCENT_CITY_198_20150202_Q.X1803000Y609500L2LRATS" "1"))) ("CRESCENT_CITY_198_20150202_Q.@@R3C60.2.1" Resistor (xy (5570 4212)) (refDes "R7P29") (value "75 Ohm") (Props (_SXDesignName "CRESCENT_CITY_198_20150202_Q")) (Terms ("CRESCENT_CITY_198_20150202_Q.X508000Y256000L28RATS" "2") ("CRESCENT_CITY_198_20150202_Q.X511500Y256000L28LRATS" "1"))) ("CRESCENT_CITY_198_20150202_Q.@@R4.2.1" Resistor (xy (5542.5 4181.5)) (mirror x) (refDes "R9A2") (value "1 Ohm") (Props (_SXDesignName "CRESCENT_CITY_198_20150202_Q")) (Terms ("idlNode_18" "2") ("idlNode_10" "1"))) ("CRESCENT_CITY_198_20150202_Q.T@@RATS@@U22.AF54@@R812.1" TLine (xy (5564 4195)) (mirror x) (refDes "TL27") (Props (_SXDesignName "CRESCENT_CITY_198_20150202_Q") (impedance "49.728 ohm") length("4308.54 MIL") (propDelay "0.77385 ns") (traceCount "1") (traceGeometry "Microstrip") (velocity "5567.68 mil/ns")) (Terms ("CRESCENT_CITY_198_20150202_Q.X1518725Y462920L2LRATS" "1") ("CRESCENT_CITY_198_20150202_Q.X1803000Y609500L2LRATS" "2"))) ("CRESCENT_CITY_198_20150202_Q.T@@RATS@@R3C60.1@@U100.AA14" TLine (xy (5578.5 4216.5)) (refDes "TL28") (Props (_SXDesignName "CRESCENT_CITY_198_20150202_Q") (impedance "49.728 ohm") length("190.55 MIL") (propDelay "0.03422 ns") (traceCount "1") (traceGeometry "Microstrip") (velocity "5568.39 mil/ns")) (Terms ("CRESCENT_CITY_198_20150202_Q.X511500Y256000L28LRATS" "1") ("CRESCENT_CITY_198_20150202_Q.X516102Y241547L2LRATS" "2"))) ("CRESCENT_CITY_198_20150202_Q.@@R3.2.1" Resistor (xy (5519 4189)) (refDes "R3") (value "1 Ohm") (Props (_SXDesignName "CRESCENT_CITY_198_20150202_Q")) (Terms ("CRESCENT_CITY_198_20150202_Q.X1806500Y616300L2RATS" "2") ("CRESCENT_CITY_198_20150202_Q.X1803000Y616300L2LRATS" "1"))) ("CRESCENT_CITY_198_20150202_Q.T@@RATS@@R4.2@@U4.3" TLine (xy (5531.5 4181.0)) (refDes "TL29") (Props (_SXDesignName "CRESCENT_CITY_198_20150202_Q") (impedance "48.412 ohm") length("61.80 MIL") (propDelay "0.0111 ns") (traceCount "1") (traceGeometry "Microstrip") (velocity "5567.56 mil/ns")) (Terms ("idlNode_12" "1") ("idlNode_10" "2"))) ("CRESCENT_CITY_198_20150202_Q.T@@RATS@@R4.1@@R3.1" TLine (xy (5534 4195)) (mirror x) (refDes "TL30") (Props (_SXDesignName "CRESCENT_CITY_198_20150202_Q") (impedance "48.412 ohm") length("35.00 MIL") (propDelay "0.00629 ns") (traceCount "1") (traceGeometry "Microstrip") (velocity "5564.37 mil/ns")) (Terms ("idlNode_18" "1") ("CRESCENT_CITY_198_20150202_Q.X1803000Y616300L2LRATS" "2"))) ("CRESCENT_CITY_198_20150202_Q.T@@RATS@@U4.1@@R5.2" TLine (xy (5526.0 4224.5)) (mirror x) (refDes "TL31") (Props (_SXDesignName "CRESCENT_CITY_198_20150202_Q") (impedance "48.412 ohm") length("56.00 MIL") (propDelay "0.01006 ns") (traceCount "1") (traceGeometry "Microstrip") (velocity "5566.61 mil/ns")) (Terms ("CRESCENT_CITY_198_20150202_Q.X1811500Y619100L2LRATS" "1") ("CRESCENT_CITY_198_20150202_Q.X1806500Y619700L2LRATS" "2")))) (Nodes ("idlNode_18" (terms "CRESCENT_CITY_198_20150202_Q.T@@RATS@@R4.1@@R3.1.1" "CRESCENT_CITY_198_20150202_Q.@@R4.2.1.1" "CRESCENT_CITY_198_20150202_Q.T@@RATS@@R812.1@@R4.1.2")) ("CRESCENT_CITY_198_20150202_Q.X1806500Y609500L2RATS" (terms "CRESCENT_CITY_198_20150202_Q.@@R812.2.1.1" "CRESCENT_CITY_198_20150202_Q.@@R812.2_SOURCE.1")) ("CRESCENT_CITY_198_20150202_Q.X511500Y256000L28LRATS" (terms "CRESCENT_CITY_198_20150202_Q.T@@RATS@@R3C60.1@@U100.AA14.1" "CRESCENT_CITY_198_20150202_Q.@@R3C60.2.1.2")) ("CRESCENT_CITY_198_20150202_Q.X1803000Y616300L2LRATS" (terms "CRESCENT_CITY_198_20150202_Q.T@@RATS@@R4.1@@R3.1.2" "CRESCENT_CITY_198_20150202_Q.@@R3.2.1.2" "CRESCENT_CITY_198_20150202_Q.T@@RATS@@R3.1@@R5.1.1")) ("CRESCENT_CITY_198_20150202_Q.X1806500Y616300L2RATS" (terms "CRESCENT_CITY_198_20150202_Q.@@R3.2.1.1" "CRESCENT_CITY_198_20150202_Q.@@R3.2_SOURCE.1")) ("idlNode_12" (terms "CRESCENT_CITY_198_20150202_Q.T@@RATS@@R4.2@@U4.3.1" "CRESCENT_CITY_198_20150202_Q.@@U4.3.1")) ("idlNode_32" (terms "CRESCENT_CITY_198_20150202_Q.T@@RATS@@J54.57@@U4.4.2" "CRESCENT_CITY_198_20150202_Q.@@J54.57.1")) ("CRESCENT_CITY_198_20150202_Q.X516102Y241547L2LRATS" (terms "CRESCENT_CITY_198_20150202_Q.T@@RATS@@R3C60.1@@U100.AA14.2" "CRESCENT_CITY_198_20150202_Q.T@@RATS@@U100.AA14@@U36.AA14.1" "CRESCENT_CITY_198_20150202_Q.@@U100.AA14.1")) ("CRESCENT_CITY_198_20150202_Q.X1811500Y619100L2LRATS" (terms "CRESCENT_CITY_198_20150202_Q.T@@RATS@@U4.1@@R5.2.1" "CRESCENT_CITY_198_20150202_Q.T@@RATS@@U4.4@@U4.1.2" "CRESCENT_CITY_198_20150202_Q.@@U4.1.1")) ("CRESCENT_CITY_198_20150202_Q.X1518725Y462920L2LRATS" (terms "CRESCENT_CITY_198_20150202_Q.T@@RATS@@U22.AF54@@R812.1.1" "CRESCENT_CITY_198_20150202_Q.@@U22.AF54.1")) ("CRESCENT_CITY_198_20150202_Q.X1803000Y619700L2LRATS" (terms "CRESCENT_CITY_198_20150202_Q.@@R5.1.2.1" "CRESCENT_CITY_198_20150202_Q.T@@RATS@@R3.1@@R5.1.2")) ("CRESCENT_CITY_198_20150202_Q.X1803000Y609500L2LRATS" (terms "CRESCENT_CITY_198_20150202_Q.T@@RATS@@U22.AF54@@R812.1.2" "CRESCENT_CITY_198_20150202_Q.@@R812.2.1.2" "CRESCENT_CITY_198_20150202_Q.T@@RATS@@R812.1@@R4.1.1")) ("idlNode_10" (terms "CRESCENT_CITY_198_20150202_Q.T@@RATS@@R4.2@@U4.3.2" "CRESCENT_CITY_198_20150202_Q.@@R4.2.1.2")) ("CRESCENT_CITY_198_20150202_Q.X1806500Y619700L2LRATS" (terms "CRESCENT_CITY_198_20150202_Q.T@@RATS@@U4.1@@R5.2.2" "CRESCENT_CITY_198_20150202_Q.@@R5.1.2.2")) ("idlNode_34" (terms "CRESCENT_CITY_198_20150202_Q.T@@RATS@@J54.57@@U4.4.1" "CRESCENT_CITY_198_20150202_Q.T@@RATS@@U36.AA14@@J54.57.2" "CRESCENT_CITY_198_20150202_Q.T@@RATS@@U4.4@@U4.1.1" "CRESCENT_CITY_198_20150202_Q.@@U4.4.1")) ("CRESCENT_CITY_198_20150202_Q.X1165710Y241547L2LRATS" (terms "CRESCENT_CITY_198_20150202_Q.T@@RATS@@U100.AA14@@U36.AA14.2" "CRESCENT_CITY_198_20150202_Q.T@@RATS@@U36.AA14@@J54.57.1" "CRESCENT_CITY_198_20150202_Q.@@U36.AA14.1")) ("CRESCENT_CITY_198_20150202_Q.X508000Y256000L28RATS" (terms "CRESCENT_CITY_198_20150202_Q.@@R3C60.2.1.1" "CRESCENT_CITY_198_20150202_Q.@@R3C60.2_SOURCE.1"))) (Ports) (Stimuli ("local40" (scope local) (stimType periodic) (Props (periodicFreq "5e+007") (periodicJitter "0") (periodicPattern "1"))) ("local39" (scope local) (stimType periodic) (Props (periodicFreq "5e+007") (periodicJitter "0") (periodicPattern "1"))) ("local41" (scope local) (stimType periodic) (Props (periodicFreq "5e+007") (periodicJitter "0") (periodicPattern "1")))) (Notes) (Constraints ("DELAY_RULE" ("CRESCENT_CITY_198_20150202_Q U100.AA14" "CRESCENT_CITY_198_20150202_Q R3C60.1" "LENGTH" "" "LENGTH" "0.02794") ("CRESCENT_CITY_198_20150202_Q U22.AF54" "CRESCENT_CITY_198_20150202_Q R812.1" "LENGTH" "" "LENGTH" "0.02794") ("CRESCENT_CITY_198_20150202_Q J54.57" "CRESCENT_CITY_198_20150202_Q U100.AA14" "LENGTH" "" "LENGTH" "0.6096")) ("RATSNEST_SCHEDULE" "TEMPLATE")) (MeasurementSets ("EMI" ("EMIStatus" status("on")) ("PeakEmission" status("on")) ("PeakFrequency" status("on")) ("PulseFreq" status("on")) ("RiseTime" status("on")) ("VoltageSwing" status("on"))) ("Reflection" ("BufferDelayFall" status("off")) ("BufferDelayRise" status("off")) ("EyeHeight" status("off")) ("EyeJitter" status("off")) ("EyeWidth" status("off")) ("FirstIncidentFall" status("off")) ("FirstIncidentRise" status("off")) ("Glitch" status("on")) ("GlitchFall" status("off")) ("GlitchRise" status("off")) ("Monotonic" status("on")) ("MonotonicFall" status("off")) ("MonotonicRise" status("off")) ("NoiseMargin" status("on")) ("NoiseMarginHigh" status("off")) ("NoiseMarginLow" status("off")) ("OvershootHigh" status("on")) ("OvershootLow" status("on")) ("PropDelay" status("on")) ("SettleDelay" status("on")) ("SettleDelayFall" status("off")) ("SettleDelayRise" status("off")) ("SwitchDelay" status("on")) ("SwitchDelayFall" status("off")) ("SwitchDelayRise" status("off"))) ("Crosstalk" ("Crosstalk" status("on"))) ("Custom")) (VectorSets) (Props (XnetName "XDP_CPU_TCK0") (allDrivers "active") (autoSolve "Off") (customSimType "Reflection") (ftsMode ("Typ")) (rcvrSelect "all") (tlineDelayMode "time") (userRevision "1.0")))) (Subckts) (CrossSections ("CRESCENT_CITY_198_20150202_Q" (Props (SXDesignName "CRESCENT_CITY_198_20150202_Q")) (Layers ("" (layerType "SURFACE") (material "AIR") (thickness "0 mil") (dielectricConstant "1.000000") (lossTangent "0") (etchFactor "0.000000") (elecCondVal "0 mho/cm") (thermCondVal "0 w/cm-degC")) ("" (layerType "DIELECTRIC") (material "CONFORMAL_COAT") (thickness "0.5 mil") (dielectricConstant "3.800000") (lossTangent "0.035") (etchFactor "0.000000") (elecCondVal "0 mho/cm") (thermCondVal "0.012 w/cm-degC")) ("TOP" (layerType "CONDUCTOR") (material "COPPER") (thickness "  2.100000 mil") (width "4.00 MIL") (dielectricConstant "4.500000") (lossTangent "0") (etchFactor "70.000000") (elecCondVal "595900.000000 mho/cm") (thermCondVal "0 w/cm-degC") (signalDieConstant "3.800000") (signalLossTangent "0.035")) ("" (layerType "DIELECTRIC") (material "FR-4") (thickness "  2.670000 mil") (dielectricConstant "4.000000") (lossTangent "0.035") (etchFactor "0.000000") (elecCondVal "0 mho/cm") (thermCondVal "0.012 w/cm-degC")) ("L2_GND1" (layerType "PLANE") (material "COPPER") (isShield t) (thickness "  1.250000 mil") (dielectricConstant "4.500000") (lossTangent "0.035") (etchFactor "90.000000") (elecCondVal "595900.000000 mho/cm") (thermCondVal "0.012 w/cm-degC")) ("" (layerType "DIELECTRIC") (material "FR-4") (thickness "  9.000000 mil") (dielectricConstant "4.100000") (lossTangent "0.035") (etchFactor "0.000000") (elecCondVal "0 mho/cm") (thermCondVal "0.012 w/cm-degC")) ("L3_SIG1" (layerType "CONDUCTOR") (material "COPPER") (thickness "  1.250000 mil") (width "4.00 MIL") (dielectricConstant "4.500000") (lossTangent "0.035") (etchFactor "90.000000") (elecCondVal "595900.000000 mho/cm") (thermCondVal "0.012 w/cm-degC") (signalDieConstant "4.100000") (signalLossTangent "0.035")) ("" (layerType "DIELECTRIC") (material "FR-4") (thickness "  3.000000 mil") (dielectricConstant "4.500000") (lossTangent "0.035") (etchFactor "0.000000") (elecCondVal "0 mho/cm") (thermCondVal "0 w/cm-degC")) ("L4_GND2" (layerType "PLANE") (material "COPPER") (isShield t) (thickness "  1.250000 mil") (dielectricConstant "4.500000") (lossTangent "0.035") (etchFactor "90.000000") (elecCondVal "595900.000000 mho/cm") (thermCondVal "0 w/cm-degC")) ("" (layerType "DIELECTRIC") (material "FR-4") (thickness "  9.000000 mil") (dielectricConstant "4.000000") (lossTangent "0.035") (etchFactor "0.000000") (elecCondVal "0 mho/cm") (thermCondVal "0.012 w/cm-degC")) ("L5_SIG2" (layerType "CONDUCTOR") (material "COPPER") (thickness "  1.250000 mil") (width "4.00 MIL") (dielectricConstant "4.500000") (lossTangent "0.035") (etchFactor "90.000000") (elecCondVal "595900.000000 mho/cm") (thermCondVal "0.012 w/cm-degC") (signalDieConstant "4.000000") (signalLossTangent "0.035")) ("" (layerType "DIELECTRIC") (material "FR-4") (thickness "  3.000000 mil") (dielectricConstant "4.500000") (lossTangent "0.035") (etchFactor "0.000000") (elecCondVal "0 mho/cm") (thermCondVal "0 w/cm-degC")) ("L6_GND3" (layerType "PLANE") (material "COPPER") (isShield t) (thickness "  1.250000 mil") (dielectricConstant "4.500000") (lossTangent "0.035") (etchFactor "90.000000") (elecCondVal "595900.000000 mho/cm") (thermCondVal "0 w/cm-degC")) ("" (layerType "DIELECTRIC") (material "FR-4") (thickness "  4.500000 mil") (dielectricConstant "4.100000") (lossTangent "0.035") (etchFactor "0.000000") (elecCondVal "0 mho/cm") (thermCondVal "0.012 w/cm-degC")) ("L7_PWR1-SIG" (layerType "PLANE") (material "COPPER") (isShield t) (thickness "  2.400000 mil") (dielectricConstant "4.500000") (lossTangent "0.035") (etchFactor "90.000000") (elecCondVal "595900.000000 mho/cm") (thermCondVal "0.012 w/cm-degC")) ("" (layerType "DIELECTRIC") (material "FR-4") (thickness "  4.600000 mil") (dielectricConstant "4.000000") (lossTangent "0.035") (etchFactor "0.000000") (elecCondVal "0 mho/cm") (thermCondVal "0.012 w/cm-degC")) ("L8_PWR2-SIG" (layerType "PLANE") (material "COPPER") (isShield t) (thickness "  2.400000 mil") (dielectricConstant "4.500000") (lossTangent "0.035") (etchFactor "90.000000") (elecCondVal "595900.000000 mho/cm") (thermCondVal "0.012 w/cm-degC")) ("" (layerType "DIELECTRIC") (material "FR-4") (thickness "  4.500000 mil") (dielectricConstant "4.500000") (lossTangent "0.035") (etchFactor "0.000000") (elecCondVal "0 mho/cm") (thermCondVal "0 w/cm-degC")) ("L9_GND4" (layerType "PLANE") (material "COPPER") (isShield t) (thickness "  1.250000 mil") (dielectricConstant "4.500000") (lossTangent "0.035") (etchFactor "90.000000") (elecCondVal "595900.000000 mho/cm") (thermCondVal "0 w/cm-degC")) ("" (layerType "DIELECTRIC") (material "FR-4") (thickness "  3.000000 mil") (dielectricConstant "4.100000") (lossTangent "0.035") (etchFactor "0.000000") (elecCondVal "0 mho/cm") (thermCondVal "0.012 w/cm-degC")) ("L10_SIG3" (layerType "CONDUCTOR") (material "COPPER") (thickness "  1.250000 mil") (width "4.00 MIL") (dielectricConstant "4.500000") (lossTangent "0.035") (etchFactor "90.000000") (elecCondVal "595900.000000 mho/cm") (thermCondVal "0.012 w/cm-degC") (signalDieConstant "4.100000") (signalLossTangent "0.035")) ("" (layerType "DIELECTRIC") (material "FR-4") (thickness "  9.000000 mil") (dielectricConstant "4.500000") (lossTangent "0.035") (etchFactor "0.000000") (elecCondVal "0 mho/cm") (thermCondVal "0 w/cm-degC")) ("L11_GND5" (layerType "PLANE") (material "COPPER") (isShield t) (thickness "  1.250000 mil") (dielectricConstant "4.500000") (lossTangent "0.035") (etchFactor "90.000000") (elecCondVal "595900.000000 mho/cm") (thermCondVal "0 w/cm-degC")) ("" (layerType "DIELECTRIC") (material "FR-4") (thickness "  3.000000 mil") (dielectricConstant "4.500000") (lossTangent "0.035") (etchFactor "0.000000") (elecCondVal "0 mho/cm") (thermCondVal "0.012 w/cm-degC")) ("L12_SIG4" (layerType "CONDUCTOR") (material "COPPER") (thickness "  1.250000 mil") (width "4.00 MIL") (dielectricConstant "4.500000") (lossTangent "0.035") (etchFactor "90.000000") (elecCondVal "595900.000000 mho/cm") (thermCondVal "0.012 w/cm-degC") (signalDieConstant "4.500000") (signalLossTangent "0.035")) ("" (layerType "DIELECTRIC") (material "FR-4") (thickness "  9.000000 mil") (dielectricConstant "4.500000") (lossTangent "0.035") (etchFactor "0.000000") (elecCondVal "0 mho/cm") (thermCondVal "0 w/cm-degC")) ("L13_GND6" (layerType "PLANE") (material "COPPER") (isShield t) (thickness "  1.250000 mil") (dielectricConstant "4.500000") (lossTangent "0.035") (etchFactor "90.000000") (elecCondVal "595900.000000 mho/cm") (thermCondVal "0.012 w/cm-degC")) ("" (layerType "DIELECTRIC") (material "FR-4") (thickness "  2.670000 mil") (dielectricConstant "4.500000") (lossTangent "0.035") (etchFactor "0.000000") (elecCondVal "0 mho/cm") (thermCondVal "0.012 w/cm-degC")) ("BOTTOM" (layerType "CONDUCTOR") (material "COPPER") (thickness "  2.100000 mil") (width "4.00 MIL") (dielectricConstant "4.500000") (lossTangent "0") (etchFactor "70.000000") (elecCondVal "595900.000000 mho/cm") (thermCondVal "0 w/cm-degC") (signalDieConstant "3.800000") (signalLossTangent "0.035")) ("" (layerType "DIELECTRIC") (material "CONFORMAL_COAT") (thickness "0.5 mil") (dielectricConstant "3.800000") (lossTangent "0.035") (etchFactor "0.000000") (elecCondVal "0 mho/cm") (thermCondVal "0.012 w/cm-degC")) ("" (layerType "SURFACE") (material "AIR") (thickness "0 mil") (dielectricConstant "1.000000") (lossTangent "0") (etchFactor "0.000000") (elecCondVal "0 mho/cm") (thermCondVal "0 w/cm-degC"))))) (Props (DesUnits "mils 2") (LayerStack ("DIELECTRIC" "DIELECTRIC" "BOTTOM" "DIELECTRIC" "L13_GND6" "DIELECTRIC" "L12_SIG4" "DIELECTRIC" "L11_GND5" "DIELECTRIC" "L10_SIG3" "DIELECTRIC" "L9_GND4" "DIELECTRIC" "L8_PWR2-SIG" "DIELECTRIC" "L7_PWR1-SIG" "DIELECTRIC" "L6_GND3" "DIELECTRIC" "L5_SIG2" "DIELECTRIC" "L4_GND2" "DIELECTRIC" "L3_SIG1" "DIELECTRIC" "L2_GND1" "DIELECTRIC" "TOP" "DIELECTRIC" "DIELECTRIC")) (Revision "16.600")) (Params (IbisIOPkg ((temperature "27") (bufferModel "CDSDefaultIO_2p5v") (stimuli nil) (offsets nil) (state "tristate") (cycle "1") (termMap nil) (setup "2.0e-09") (hold "1.0e-09") (rise nil) (fall nil) (macroType nil) (voltage nil) (spice nil) (LEFDEFPinName nil) (LEFDEFPinType nil) (mappingTag nil))) (IbisIOMacro ((temperature "27") (bufferModel "CDSDefaultIO_2p5v") (stimuli nil) (offsets nil) (state "tristate") (cycle "1") (termMap nil) (setup "2.0e-09") (hold "1.0e-09") (rise nil) (fall nil) (macroType nil) (voltage nil) (spice nil) (LEFDEFPinName nil) (LEFDEFPinType nil) (mappingTag nil))) (IbisOutput ((temperature "27") (bufferModel "CDSDefaultOutput_2p5v") (stimuli nil) (offsets nil) (state "tristate") (cycle "1") (termMap nil) (setup "2.0e-09") (hold "1.0e-09") (rise nil) (fall nil) (macroType nil) (voltage nil) (spice nil) (LEFDEFPinName nil) (LEFDEFPinType nil) (mappingTag nil))) (IbisInputPkg ((temperature "27") (bufferModel "CDSDefaultInput_2p5v") (cycle "1") (LEFDEFPinName nil) (LEFDEFPinType nil) (mappingTag nil))) (IbisIO ((temperature "27") (bufferModel "CDSDefaultIO_2p5v") (stimuli nil) (offsets nil) (state "tristate") (cycle "1") (termMap nil) (setup "2.0e-09") (hold "1.0e-09") (rise nil) (fall nil) (macroType nil) (voltage nil) (spice nil) (LEFDEFPinName nil) (LEFDEFPinType nil) (mappingTag nil))) (IbisOutputPkg ((temperature "27") (bufferModel "CDSDefaultOutput_2p5v") (stimuli nil) (offsets nil) (state "tristate") (cycle "1") (termMap nil) (setup "2.0e-09") (hold "1.0e-09") (rise nil) (fall nil) (macroType nil) (voltage nil) (spice nil) (LEFDEFPinName nil) (LEFDEFPinType nil) (mappingTag nil))) (periodic ((periodicFreq "100e6") (periodicPattern "10") (periodicJitter "0"))) (IbisIO_OpenPullUp ((temperature "27") (bufferModel "CDSDefaultIO_2p5v") (stimuli nil) (offsets nil) (state "tristate") (cycle "1") (termMap nil) (setup "2.0e-09") (hold "1.0e-09") (rise nil) (fall nil) (macroType nil) (voltage nil) (spice nil) (LEFDEFPinName nil) (LEFDEFPinType nil) (mappingTag nil))) (clocked ((clockRise "1e-09") (clockFall "1e-09") (clockFreq "100e6") (clockInitState "0") (clockDutyCycle "0.5") (clockJitter "0"))) (IbisIO_OpenPullDown ((temperature "27") (bufferModel "CDSDefaultIO_2p5v") (stimuli nil) (offsets nil) (state "tristate") (cycle "1") (termMap nil) (setup "2.0e-09") (hold "1.0e-09") (rise nil) (fall nil) (macroType nil) (voltage nil) (spice nil) (LEFDEFPinName nil) (LEFDEFPinType nil) (mappingTag nil))) (async ((asyncTimePoints "") (asyncInitState "1"))) (TLine ((diffImpedance "100ohm") (diffVelocity "1.4142e+08M/s") (impedance "60ohm") length("2800 mil") (propDelay "0.5 ns") (velocity "5600 mil/ns") (traceCount "1") (traceGeometry "Microstrip") (impedanceMin nil) (impedanceMax nil) (lengthMin nil) (lengthMax nil) (propDelayMin nil) (propDelayMax nil) (impedanceSweepCount nil) (propDelaySweepCount nil) (velocitySweepCount nil) (lengthSweepCount nil) (matchSetName nil))) (Connector nil) (CurrentProbe nil) (SeriesTerm ((resistance "22 ohm") (maxDelay "0.1 ns"))) (IbisOutput_OpenPullUp ((temperature "27") (bufferModel "CDSDefaultOutput_2p5v") (stimuli nil) (offsets nil) (state "tristate") (cycle "1") (termMap nil) (setup "2.0e-09") (hold "1.0e-09") (rise nil) (fall nil) (macroType nil) (voltage nil) (spice nil) (LEFDEFPinName nil) (LEFDEFPinType nil) (mappingTag nil))) (DiffInputPkg ((temperature "27") (bufferModelNonInverting "CDSDefaultInput_2p5v") (bufferModelInverting "CDSDefaultInput_2p5v") (threshInputHighMin "1.7 V") (threshInputHighTyp "1.7  V") (threshInputHighMax "1.7  V") (threshInputLowMin "0.7  V") (threshInputLowTyp "0.7  V") (threshInputLowMax "0.7  V") (mappingTagNonInverting nil) (mappingTagInverting nil) (cycle "1"))) (idlCircuit ((allDrivers "active") (ftsMode '("Typ")) (rcvrSelect "all") (simMode "Reflection") (tlineDelayMode "time") (userRevision "1.0") (autoSolve "On"))) (IbisInput ((temperature "27") (bufferModel "CDSDefaultInput_2p5v") (cycle "1") (LEFDEFPinName nil) (LEFDEFPinType nil) (mappingTag nil))) (sync ((syncFreq "100e6") (syncInitState "1") (syncPattern "10") (syncEdgeSwitch "rise"))) (Trace ((d1Thickness "10 mil") (d1Constant "4.5") (d1LossTangent "0.035") (d2Thickness "10 mil") (d2Constant "4.5") (d2LossTangent "0.035") (d3Thickness "0.0") (d3Constant "1.0") (d3LossTangent "0") length("1000 mil") (spacing "5 mil") (spacing2 "5 mil") (spacing3 "5 mil") (spacing4 "5 mil") (spacing5 "5 mil") (traceConductivity "595900 mho/cm") (traceGeometry "microstrip") (traceLayerName "") (traceThickness "0.72 mil") (traceType "single") (traceWidth "5.0 mil") (traceWidth2 "5.0 mil") (traceWidth3 "5.0 mil") (traceWidth4 "5.0 mil") (traceWidth5 "5.0 mil") (traceWidth6 "5.0 mil") (offset "0 mil") (traceCount "1") (impedance nil))) (DiffOutput ((temperature "27") (bufferModelNonInverting "CDSDefaultOutput_2p5v") (bufferModelInverting "CDSDefaultOutput_2p5v") (stimuli nil) (offsets nil) (state "tristate") (cycle "1") (termMap nil) (setup "0.9e-09") (hold "0.4e-09") (rise nil) (fall nil) (threshOutputHighMin "2.375  V") (threshOutputHighTyp "2.5  V") (threshOutputHighMax "2.625  V") (threshOutputLowMin "1.275  V") (threshOutputLowTyp "1.7  V") (threshOutputLowMax "1.985  V") (mappingTagNonInverting nil) (mappingTagInverting nil) (spice nil))) (DualClampTerm ((cutoffVoltageUp "0.7 V") (cutoffVoltageDown "0.7 V") (voltageUp "5 V") (voltageDown "0 V") (maxDelay "0.1 ns"))) (Via ((model "Unknown") (viaOutputFormat "Unknown") (viaPadstack nil) (viaTopLayer nil) (viaBottomLayer nil) (viaIsPower nil) (viaIsGround nil))) (Resistor ((resistance "50 ohm") (orientation "0"))) (DiffOutputPkg ((temperature "27") (bufferModelNonInverting "CDSDefaultOutput_2p5v") (bufferModelInverting "CDSDefaultOutput_2p5v") (stimuli nil) (offsets nil) (state "tristate") (cycle "1") (termMap nil) (setup "0.9e-09") (hold "0.4e-09") (rise nil) (fall nil) (threshOutputHighMin "2.375  V") (threshOutputHighTyp "2.5  V") (threshOutputHighMax "2.625  V") (threshOutputLowMin "1.275  V") (threshOutputLowTyp "1.7  V") (threshOutputLowMax "1.985  V") (mappingTagNonInverting nil) (mappingTagInverting nil) (spice nil))) (DiffIO ((temperature "27") (bufferModelNonInverting "CDSDefaultIO_2p5v") (bufferModelInverting "CDSDefaultIO_2p5v") (stimuli nil) (offsets nil) (state "tristate") (cycle "1") (termMap nil) (setup "0.9e-09") (hold "0.4e-09") (rise nil) (fall nil) (threshInputHighMin "1.7 V") (threshInputHighTyp "1.7  V") (threshInputHighMax "1.7  V") (threshInputLowMin "0.7  V") (threshInputLowTyp "0.7  V") (threshInputLowMax "0.7 ") (threshOutputHighMin "2.365  V") (threshOutputHighTyp "2.5  V") (threshOutputHighMax "2.625  V") (threshOutputLowMin "1.275  V") (threshOutputLowTyp "1.7  V") (threshOutputLowMax "1.985  V") (mappingTagNonInverting nil) (mappingTagInverting nil) (spice nil))) (Diode ((cutoffVoltage "0.7 V"))) (DiffIOPkg ((temperature "27") (bufferModelNonInverting "CDSDefaultIO_2p5v") (bufferModelInverting "CDSDefaultIO_2p5v") (stimuli nil) (offsets nil) (state "tristate") (cycle "1") (termMap nil) (setup "0.9e-09") (hold "0.4e-09") (rise nil) (fall nil) (threshInputHighMin "1.7 V") (threshInputHighTyp "1.7  V") (threshInputHighMax "1.7  V") (threshInputLowMin "0.7  V") (threshInputLowTyp "0.7  V") (threshInputLowMax "0.7 ") (threshOutputHighMin "2.365  V") (threshOutputHighTyp "2.5  V") (threshOutputHighMax "2.625  V") (threshOutputLowMin "1.275  V") (threshOutputLowTyp "1.7  V") (threshOutputLowMax "1.985  V") (mappingTagNonInverting nil) (mappingTagInverting nil) (spice nil))) (Source ((voltage "5 V"))) (RLGC (length("1000 mil"))) (Capacitor ((capacitance "10 pF") (orientation "0"))) (DiffInput ((temperature "27") (bufferModelNonInverting "CDSDefaultInput_2p5v") (bufferModelInverting "CDSDefaultInput_2p5v") (threshInputHighMin "1.7 V") (threshInputHighTyp "1.7  V") (threshInputHighMax "1.7  V") (threshInputLowMin "0.7  V") (threshInputLowTyp "0.7  V") (threshInputLowMax "0.7  V") (mappingTagNonInverting nil) (mappingTagInverting nil) (cycle "1"))) (Inductor ((inductance "5 nH") (orientation "0"))) (Cable (length("1 m"))) (ShuntTerm ((resistance "50 ohm") (voltage "5 V") (maxDelay "0.1 ns"))) (CPWSL ((d1Thickness "10 mil") (d1Constant "4.5") (d1LossTangent "0.035") (d2Thickness "0.72 mil") (d2Constant "4.5") (d2LossTangent "0.035") (d3Thickness "10 mil") (d3Constant "4.5") (d3LossTangent "0.035") length("1000 mil") (spacing "5 mil") (spacing2 "5 mil") (spacing3 "5 mil") (spacing4 "5 mil") (spacing5 "5 mil") (traceConductivity "595900 mho/cm") (traceGeometry "cpwms") (traceLayerName "") (traceThickness "0.72 mil") (traceType "single") (traceWidth "5.0 mil") (traceWidth2 "5.0 mil") (traceWidth3 "5.0 mil") (traceWidth4 "5.0 mil") (traceWidth5 "5.0 mil") (traceWidth6 "5.0 mil") (offset "0 mil") (traceCount "1") (impedance nil))) (TheveninTerm ((resistanceUp "180 ohm") (resistanceDown "270 ohm") (voltageUp "5 V") (voltageDown "0 V") (maxDelay "0.1 ns"))) (CPWMS ((d1Thickness "10 mil") (d1Constant "4.5") (d1LossTangent "0.035") (d2Thickness "0.72 mil") (d2Constant "4.5") (d2LossTangent "0.035") (d3Thickness "0.0") (d3Constant "1") (d3LossTangent "0") length("1000 mil") (spacing "5 mil") (spacing2 "5 mil") (spacing3 "5 mil") (spacing4 "5 mil") (spacing5 "5 mil") (traceConductivity "595900 mho/cm") (traceGeometry "cpwms") (traceLayerName "") (traceThickness "0.72 mil") (traceType "single") (traceWidth "5.0 mil") (traceWidth2 "5.0 mil") (traceWidth3 "5.0 mil") (traceWidth4 "5.0 mil") (traceWidth5 "5.0 mil") (traceWidth6 "5.0 mil") (offset "0 mil") (traceCount "1") (impedance nil))) (RCTerm ((resistance "50 ohm") (capacitance "20 pF") (voltage "5 V") (maxDelay "0.1 ns"))) (CPW ((d1Thickness "10 mil") (d1Constant "4.5") (d1LossTangent "0.035") (d2Thickness "0.72 mil") (d2Constant "1") (d2LossTangent "0") (d3Thickness "0.0") (d3Constant "1") (d3LossTangent "0") length("1000 mil") (spacing "5 mil") (spacing2 "5 mil") (spacing3 "5 mil") (spacing4 "5 mil") (spacing5 "5 mil") (traceConductivity "595900 mho/cm") (traceGeometry "cpwms") (traceLayerName "") (traceThickness "0.72 mil") (traceType "single") (traceWidth "5.0 mil") (traceWidth2 "5.0 mil") (traceWidth3 "5.0 mil") (traceWidth4 "5.0 mil") (traceWidth5 "5.0 mil") (traceWidth6 "5.0 mil") (offset "0 mil") (traceCount "1") (impedance nil))) (LowClampTerm ((cutoffVoltage "0.7 V") (voltage "0 V") (maxDelay "0.1 ns"))) (ESpiceDevice nil) (HiClampTerm ((cutoffVoltage "0.7 V") (voltage "5 V") (maxDelay "0.1 ns")))))
				)
				( objectStatus "XDP_CPU_TCK0" )
			)
			( electricalCSet "@crescent_city_bb_fab1_lib.crescent_city_bb_fab1(sch_1):\PMSYNC\"
				( pinPairRef "PMSYNC:U7C1.U13:R3N9.1" )
				( pinPairRef "PMSYNC:U5D1.AR14:R4P18.1" )
				( pinPairRef "PMSYNC:U2D1.AR14:R7P25.1" )
				( attribute "RATSNEST_SCHEDULE" "TEMPLATE"
					( Status sLocked )
					( Origin gBackEnd )
				)
				( attribute "TOPOLOGY_TEMPLATE_REVISION" "1.0"
					( Origin gBackEnd )
				)
				( topologyData 28344
(SKIDL (Circuits ("MAIN" (Parts ("CRESCENT_CITY_176_20141216_Q.@@U100.AR14" IbisIOPkg (xy (5541.0 4212.5)) (refDes "U2D1") (model "Unknown") (Props (_SXDesignName "CRESCENT_CITY_176_20141216_Q") (brdx "5161.02 MIL") (brdy "2688.47 MIL") (bufferModel "CDSDefaultIO_2p5v") (cycle "1") (hold "1.0e-09") (mappingTag "") (offsets ("4" "0") ("5" "0")) (setup "2.0e-09") (state "tristate") (stimuli ("4" "local66") ("5" "local67")) (temperature "27") (termMap ("4" "Data") ("5" "Enable"))) (Terms ("CRESCENT_CITY_176_20141216_Q.X516102Y268847L2LRATS" "AR14"))) ("CRESCENT_CITY_176_20141216_Q.@@U22.U13" IbisIOPkg (xy (5502 4240)) (refDes "U7C1") (model "Unknown") (Props (_SXDesignName "CRESCENT_CITY_176_20141216_Q") (brdx "15031.25 MIL") (brdy "3885.6 MIL") (bufferModel "CDSDefaultIO_2p5v") (cycle "1") (hold "1.0e-09") (mappingTag "") (offsets ("4" "0") ("5" "0")) (setup "2.0e-09") (state "tristate") (stimuli ("4" "local68") ("5" "local69")) (temperature "27") (termMap ("4" "Data") ("5" "Enable"))) (Terms ("CRESCENT_CITY_176_20141216_Q.X1503125Y388560L2LRATS" "U13"))) ("CRESCENT_CITY_176_20141216_Q.@@U36.AR14" IbisInputPkg (xy (5541 4222)) (refDes "U5D1") (model "Unknown") (Props (_SXDesignName "CRESCENT_CITY_176_20141216_Q") (brdx "11657.1 MIL") (brdy "2688.47 MIL") (bufferModel "CDSDefaultInput_2p5v") (mappingTag "") (temperature "27")) (Terms ("CRESCENT_CITY_176_20141216_Q.X1165710Y268847L2LRATS" "AR14"))) ("CRESCENT_CITY_176_20141216_Q.@@R1725.2_SOURCE" Source (xy (5475 4216)) (refDes "GND") (value "0 V") (Props (_SXDesignName "CRESCENT_CITY_176_20141216_Q")) (Terms ("CRESCENT_CITY_176_20141216_Q.X1495800Y360400L28RATS" "1"))) ("CRESCENT_CITY_176_20141216_Q.T@@RATS@@R1724.1@@U22.U13" TLine (xy (5497 4229)) (refDes "TL28") (Props (_SXDesignName "CRESCENT_CITY_176_20141216_Q") (impedance "48.412 ohm") length("249.85 MIL") (propDelay "0.04487 ns") (traceCount "1") (traceGeometry "Microstrip") (velocity "5568.31 mil/ns")) (Terms ("CRESCENT_CITY_176_20141216_Q.X1495800Y370900L28LRATS" "1") ("CRESCENT_CITY_176_20141216_Q.X1503125Y388560L2LRATS" "2"))) ("CRESCENT_CITY_176_20141216_Q.@@R3537.2.1" Resistor (xy (5517.5 4207.5)) (refDes "R7P25") (value "49.9 Ohm") (Props (_SXDesignName "CRESCENT_CITY_176_20141216_Q")) (Terms ("CRESCENT_CITY_176_20141216_Q.X514200Y262500L28LRATS" "2") ("CRESCENT_CITY_176_20141216_Q.X514200Y266000L28LRATS" "1"))) ("CRESCENT_CITY_176_20141216_Q.@@R1725.2.1" Resistor (xy (5482 4216)) (refDes "R3N14") (value "1000 Ohm") (Props (_SXDesignName "CRESCENT_CITY_176_20141216_Q")) (Terms ("CRESCENT_CITY_176_20141216_Q.X1495800Y360400L28RATS" "2") ("CRESCENT_CITY_176_20141216_Q.X1495800Y363900L28LRATS" "1"))) ("CRESCENT_CITY_176_20141216_Q.@@R3536.1.2" Resistor (xy (5517.5 4222.0)) (mirror x) (refDes "R4P18") (value "49.9 Ohm") (Props (_SXDesignName "CRESCENT_CITY_176_20141216_Q")) (Terms ("CRESCENT_CITY_176_20141216_Q.X1165000Y266000L28LRATS" "1") ("idlNode_15" "2"))) ("CRESCENT_CITY_176_20141216_Q.T@@RATS@@R3536.2@@R3537.2" TLine (xy (5509.0 4208.0)) (refDes "TL29") (Props (_SXDesignName "CRESCENT_CITY_176_20141216_Q") (impedance "60 ohm") length("6507.99 MIL") (propDelay "1.16888 ns") (traceCount "1") (traceGeometry "Microstrip") (velocity "5567.72 mil/ns")) (Terms ("idlNode_35" "1") ("CRESCENT_CITY_176_20141216_Q.X514200Y262500L28LRATS" "2"))) ("CRESCENT_CITY_176_20141216_Q.T@@RATS@@U36.AR14@@R3536.1" TLine (xy (5527 4222)) (mirror x) (refDes "TL30") (Props (_SXDesignName "CRESCENT_CITY_176_20141216_Q") (impedance "49.728 ohm") length("35.57 MIL") (propDelay "0.00639 ns") (traceCount "1") (traceGeometry "Microstrip") (velocity "5566.5 mil/ns")) (Terms ("CRESCENT_CITY_176_20141216_Q.X1165710Y268847L2LRATS" "1") ("CRESCENT_CITY_176_20141216_Q.X1165000Y266000L28LRATS" "2"))) ("CRESCENT_CITY_176_20141216_Q.T@@RATS@@R3536.2@@R1725.1" TLine (xy (5497 4222)) (mirror x) (refDes "TL31") (Props (_SXDesignName "CRESCENT_CITY_176_20141216_Q") (impedance "60 ohm") length("4322.01 MIL") (propDelay "0.776261 ns") (traceCount "1") (traceGeometry "Microstrip") (velocity "5567.72 mil/ns")) (Terms ("idlNode_35" "1") ("CRESCENT_CITY_176_20141216_Q.X1495800Y363900L28LRATS" "2"))) ("CRESCENT_CITY_176_20141216_Q.T@@RATS@@R1725.1@@R1724.2" TLine (xy (5482 4222)) (mirror x) (refDes "TL32") (Props (_SXDesignName "CRESCENT_CITY_176_20141216_Q") (impedance "46.577 ohm") length("35.00 MIL") (propDelay "0.00629 ns") (traceCount "1") (traceGeometry "Microstrip") (velocity "5564.37 mil/ns")) (Terms ("CRESCENT_CITY_176_20141216_Q.X1495800Y363900L28LRATS" "1") ("CRESCENT_CITY_176_20141216_Q.X1495800Y367400L28LRATS" "2"))) ("CRESCENT_CITY_176_20141216_Q.@@R1724.1.2" Resistor (xy (5488 4229)) (mirror x) (refDes "R3N9") (value "10 Ohm") (Props (_SXDesignName "CRESCENT_CITY_176_20141216_Q")) (Terms ("CRESCENT_CITY_176_20141216_Q.X1495800Y370900L28LRATS" "1") ("CRESCENT_CITY_176_20141216_Q.X1495800Y367400L28LRATS" "2"))) ("idlPart_18" TLine (xy (5509.5 4221.5)) (refDes "TL34") (Props (_SXDesignName "CRESCENT_CITY_176_20141216_Q") (impedance "60 ohm") length("6507.99 MIL") (propDelay "1.16888 ns") (traceCount "1") (traceGeometry "Microstrip") (velocity "5567.72 mil/ns")) (Terms ("idlNode_35" "1") ("idlNode_15" "2"))) ("CRESCENT_CITY_176_20141216_Q.T@@RATS@@R3537.1@@U100.AR14" TLine (xy (5527.5 4207.5)) (refDes "TL33") (Props (_SXDesignName "CRESCENT_CITY_176_20141216_Q") (impedance "49.728 ohm") length("47.49 MIL") (propDelay "0.00853 ns") (traceCount "1") (traceGeometry "Microstrip") (velocity "5567.4 mil/ns")) (Terms ("CRESCENT_CITY_176_20141216_Q.X514200Y266000L28LRATS" "1") ("CRESCENT_CITY_176_20141216_Q.X516102Y268847L2LRATS" "2")))) (Nodes ("CRESCENT_CITY_176_20141216_Q.X516102Y268847L2LRATS" (terms "CRESCENT_CITY_176_20141216_Q.T@@RATS@@R3537.1@@U100.AR14.2" "CRESCENT_CITY_176_20141216_Q.@@U100.AR14.1")) ("CRESCENT_CITY_176_20141216_Q.X1165000Y266000L28LRATS" (terms "CRESCENT_CITY_176_20141216_Q.T@@RATS@@U36.AR14@@R3536.1.2" "CRESCENT_CITY_176_20141216_Q.@@R3536.1.2.1")) ("CRESCENT_CITY_176_20141216_Q.X1503125Y388560L2LRATS" (terms "CRESCENT_CITY_176_20141216_Q.T@@RATS@@R1724.1@@U22.U13.2" "CRESCENT_CITY_176_20141216_Q.@@U22.U13.1")) ("idlNode_35" (terms "idlPart_18.1" "CRESCENT_CITY_176_20141216_Q.T@@RATS@@R3536.2@@R1725.1.1" "CRESCENT_CITY_176_20141216_Q.T@@RATS@@R3536.2@@R3537.2.1") (tee "CRESCENT_CITY_176_20141216_Q NET.T.1")) ("CRESCENT_CITY_176_20141216_Q.X1495800Y363900L28LRATS" (terms "CRESCENT_CITY_176_20141216_Q.T@@RATS@@R1725.1@@R1724.2.1" "CRESCENT_CITY_176_20141216_Q.T@@RATS@@R3536.2@@R1725.1.2" "CRESCENT_CITY_176_20141216_Q.@@R1725.2.1.2")) ("CRESCENT_CITY_176_20141216_Q.X1495800Y367400L28LRATS" (terms "CRESCENT_CITY_176_20141216_Q.@@R1724.1.2.2" "CRESCENT_CITY_176_20141216_Q.T@@RATS@@R1725.1@@R1724.2.2")) ("CRESCENT_CITY_176_20141216_Q.X1165710Y268847L2LRATS" (terms "CRESCENT_CITY_176_20141216_Q.T@@RATS@@U36.AR14@@R3536.1.1" "CRESCENT_CITY_176_20141216_Q.@@U36.AR14.1")) ("CRESCENT_CITY_176_20141216_Q.X1495800Y370900L28LRATS" (terms "CRESCENT_CITY_176_20141216_Q.@@R1724.1.2.1" "CRESCENT_CITY_176_20141216_Q.T@@RATS@@R1724.1@@U22.U13.1")) ("CRESCENT_CITY_176_20141216_Q.X1495800Y360400L28RATS" (terms "CRESCENT_CITY_176_20141216_Q.@@R1725.2.1.1" "CRESCENT_CITY_176_20141216_Q.@@R1725.2_SOURCE.1")) ("CRESCENT_CITY_176_20141216_Q.X514200Y262500L28LRATS" (terms "CRESCENT_CITY_176_20141216_Q.T@@RATS@@R3536.2@@R3537.2.2" "CRESCENT_CITY_176_20141216_Q.@@R3537.2.1.1")) ("idlNode_15" (terms "idlPart_18.2" "CRESCENT_CITY_176_20141216_Q.@@R3536.1.2.2")) ("CRESCENT_CITY_176_20141216_Q.X514200Y266000L28LRATS" (terms "CRESCENT_CITY_176_20141216_Q.T@@RATS@@R3537.1@@U100.AR14.1" "CRESCENT_CITY_176_20141216_Q.@@R3537.2.1.2"))) (Ports) (Stimuli ("local67" (scope local) (stimType periodic) (Props (periodicFreq "5e+007") (periodicJitter "0") (periodicPattern "1"))) ("local66" (scope local) (stimType periodic) (Props (periodicFreq "5e+007") (periodicJitter "0") (periodicPattern "1"))) ("local68" (scope local) (stimType periodic) (Props (periodicFreq "5e+007") (periodicJitter "0") (periodicPattern "1"))) ("local69" (scope local) (stimType periodic) (Props (periodicFreq "5e+007") (periodicJitter "0") (periodicPattern "1")))) (Notes) (Constraints ("DELAY_RULE" ("CRESCENT_CITY_176_20141216_Q R3536.2" "CRESCENT_CITY_176_20141216_Q NET.T.1" "LENGTH" "" "LENGTH" "0.00254") ("CRESCENT_CITY_176_20141216_Q R3537.2" "CRESCENT_CITY_176_20141216_Q NET.T.1" "LENGTH" "" "LENGTH" "0.00254") ("CRESCENT_CITY_176_20141216_Q U22.U13" "CRESCENT_CITY_176_20141216_Q R1724.1" "LENGTH" "" "LENGTH" "0.00254") ("CRESCENT_CITY_176_20141216_Q U36.AR14" "CRESCENT_CITY_176_20141216_Q R3536.1" "LENGTH" "" "LENGTH" "0.0635") ("CRESCENT_CITY_176_20141216_Q U100.AR14" "CRESCENT_CITY_176_20141216_Q R3537.1" "LENGTH" "" "LENGTH" "0.0635")) ("RATSNEST_SCHEDULE" "TEMPLATE")) (MeasurementSets ("EMI" ("EMIStatus" status("on")) ("PeakEmission" status("on")) ("PeakFrequency" status("on")) ("PulseFreq" status("on")) ("RiseTime" status("on")) ("VoltageSwing" status("on"))) ("Reflection" ("BufferDelayFall" status("off")) ("BufferDelayRise" status("off")) ("EyeHeight" status("off")) ("EyeJitter" status("off")) ("EyeWidth" status("off")) ("FirstIncidentFall" status("off")) ("FirstIncidentRise" status("off")) ("Glitch" status("on")) ("GlitchFall" status("off")) ("GlitchRise" status("off")) ("Monotonic" status("on")) ("MonotonicFall" status("off")) ("MonotonicRise" status("off")) ("NoiseMargin" status("on")) ("NoiseMarginHigh" status("off")) ("NoiseMarginLow" status("off")) ("OvershootHigh" status("on")) ("OvershootLow" status("on")) ("PropDelay" status("on")) ("SettleDelay" status("on")) ("SettleDelayFall" status("off")) ("SettleDelayRise" status("off")) ("SwitchDelay" status("on")) ("SwitchDelayFall" status("off")) ("SwitchDelayRise" status("off"))) ("Crosstalk" ("Crosstalk" status("on"))) ("Custom")) (VectorSets) (Props (XnetName "H_PM_SYNC_GTL_R1") (allDrivers "active") (customSimType "Reflection") (ftsMode ("Typ")) (rcvrSelect "all") (tlineDelayMode "time") (userRevision "1.0")))) (Subckts) (CrossSections ("CRESCENT_CITY_176_20141216_Q" (Props (SXDesignName "CRESCENT_CITY_176_20141216_Q")) (Layers ("" (layerType "SURFACE") (material "AIR") (thickness "0 mil") (dielectricConstant "1.000000") (lossTangent "0") (etchFactor "0.000000") (elecCondVal "0 mho/cm") (thermCondVal "0 w/cm-degC")) ("" (layerType "DIELECTRIC") (material "CONFORMAL_COAT") (thickness "0.5 mil") (dielectricConstant "3.800000") (lossTangent "0.035") (etchFactor "0.000000") (elecCondVal "0 mho/cm") (thermCondVal "0.012 w/cm-degC")) ("TOP" (layerType "CONDUCTOR") (material "COPPER") (thickness "  2.100000 mil") (width "4.00 MIL") (dielectricConstant "4.500000") (lossTangent "0") (etchFactor "70.000000") (elecCondVal "595900.000000 mho/cm") (thermCondVal "0 w/cm-degC") (signalDieConstant "3.800000") (signalLossTangent "0.035")) ("" (layerType "DIELECTRIC") (material "FR-4") (thickness "  2.670000 mil") (dielectricConstant "4.000000") (lossTangent "0.035") (etchFactor "0.000000") (elecCondVal "0 mho/cm") (thermCondVal "0.012 w/cm-degC")) ("L2_GND1" (layerType "PLANE") (material "COPPER") (isShield t) (thickness "  1.250000 mil") (dielectricConstant "4.500000") (lossTangent "0.035") (etchFactor "90.000000") (elecCondVal "595900.000000 mho/cm") (thermCondVal "0.012 w/cm-degC")) ("" (layerType "DIELECTRIC") (material "FR-4") (thickness "  9.000000 mil") (dielectricConstant "4.100000") (lossTangent "0.035") (etchFactor "0.000000") (elecCondVal "0 mho/cm") (thermCondVal "0.012 w/cm-degC")) ("L3_SIG1" (layerType "CONDUCTOR") (material "COPPER") (thickness "  1.250000 mil") (width "4.00 MIL") (dielectricConstant "4.500000") (lossTangent "0.035") (etchFactor "90.000000") (elecCondVal "595900.000000 mho/cm") (thermCondVal "0.012 w/cm-degC") (signalDieConstant "4.100000") (signalLossTangent "0.035")) ("" (layerType "DIELECTRIC") (material "FR-4") (thickness "  3.000000 mil") (dielectricConstant "4.500000") (lossTangent "0.035") (etchFactor "0.000000") (elecCondVal "0 mho/cm") (thermCondVal "0 w/cm-degC")) ("L4_GND2" (layerType "PLANE") (material "COPPER") (isShield t) (thickness "  1.250000 mil") (dielectricConstant "4.500000") (lossTangent "0.035") (etchFactor "90.000000") (elecCondVal "595900.000000 mho/cm") (thermCondVal "0 w/cm-degC")) ("" (layerType "DIELECTRIC") (material "FR-4") (thickness "  9.000000 mil") (dielectricConstant "4.000000") (lossTangent "0.035") (etchFactor "0.000000") (elecCondVal "0 mho/cm") (thermCondVal "0.012 w/cm-degC")) ("L5_SIG2" (layerType "CONDUCTOR") (material "COPPER") (thickness "  1.250000 mil") (width "4.00 MIL") (dielectricConstant "4.500000") (lossTangent "0.035") (etchFactor "90.000000") (elecCondVal "595900.000000 mho/cm") (thermCondVal "0.012 w/cm-degC") (signalDieConstant "4.000000") (signalLossTangent "0.035")) ("" (layerType "DIELECTRIC") (material "FR-4") (thickness "  3.000000 mil") (dielectricConstant "4.500000") (lossTangent "0.035") (etchFactor "0.000000") (elecCondVal "0 mho/cm") (thermCondVal "0 w/cm-degC")) ("L6_GND3" (layerType "PLANE") (material "COPPER") (isShield t) (thickness "  1.250000 mil") (dielectricConstant "4.500000") (lossTangent "0.035") (etchFactor "90.000000") (elecCondVal "595900.000000 mho/cm") (thermCondVal "0 w/cm-degC")) ("" (layerType "DIELECTRIC") (material "FR-4") (thickness "  4.500000 mil") (dielectricConstant "4.100000") (lossTangent "0.035") (etchFactor "0.000000") (elecCondVal "0 mho/cm") (thermCondVal "0.012 w/cm-degC")) ("L7_PWR1-SIG" (layerType "PLANE") (material "COPPER") (isShield t) (thickness "  2.400000 mil") (dielectricConstant "4.500000") (lossTangent "0.035") (etchFactor "90.000000") (elecCondVal "595900.000000 mho/cm") (thermCondVal "0.012 w/cm-degC")) ("" (layerType "DIELECTRIC") (material "FR-4") (thickness "  4.600000 mil") (dielectricConstant "4.000000") (lossTangent "0.035") (etchFactor "0.000000") (elecCondVal "0 mho/cm") (thermCondVal "0.012 w/cm-degC")) ("L8_PWR2-SIG" (layerType "PLANE") (material "COPPER") (isShield t) (thickness "  2.400000 mil") (dielectricConstant "4.500000") (lossTangent "0.035") (etchFactor "90.000000") (elecCondVal "595900.000000 mho/cm") (thermCondVal "0.012 w/cm-degC")) ("" (layerType "DIELECTRIC") (material "FR-4") (thickness "  4.500000 mil") (dielectricConstant "4.500000") (lossTangent "0.035") (etchFactor "0.000000") (elecCondVal "0 mho/cm") (thermCondVal "0 w/cm-degC")) ("L9_GND4" (layerType "PLANE") (material "COPPER") (isShield t) (thickness "  1.250000 mil") (dielectricConstant "4.500000") (lossTangent "0.035") (etchFactor "90.000000") (elecCondVal "595900.000000 mho/cm") (thermCondVal "0 w/cm-degC")) ("" (layerType "DIELECTRIC") (material "FR-4") (thickness "  3.000000 mil") (dielectricConstant "4.100000") (lossTangent "0.035") (etchFactor "0.000000") (elecCondVal "0 mho/cm") (thermCondVal "0.012 w/cm-degC")) ("L10_SIG3" (layerType "CONDUCTOR") (material "COPPER") (thickness "  1.250000 mil") (width "4.00 MIL") (dielectricConstant "4.500000") (lossTangent "0.035") (etchFactor "90.000000") (elecCondVal "595900.000000 mho/cm") (thermCondVal "0.012 w/cm-degC") (signalDieConstant "4.100000") (signalLossTangent "0.035")) ("" (layerType "DIELECTRIC") (material "FR-4") (thickness "  9.000000 mil") (dielectricConstant "4.500000") (lossTangent "0.035") (etchFactor "0.000000") (elecCondVal "0 mho/cm") (thermCondVal "0 w/cm-degC")) ("L11_GND5" (layerType "PLANE") (material "COPPER") (isShield t) (thickness "  1.250000 mil") (dielectricConstant "4.500000") (lossTangent "0.035") (etchFactor "90.000000") (elecCondVal "595900.000000 mho/cm") (thermCondVal "0 w/cm-degC")) ("" (layerType "DIELECTRIC") (material "FR-4") (thickness "  3.000000 mil") (dielectricConstant "4.500000") (lossTangent "0.035") (etchFactor "0.000000") (elecCondVal "0 mho/cm") (thermCondVal "0.012 w/cm-degC")) ("L12_SIG4" (layerType "CONDUCTOR") (material "COPPER") (thickness "  1.250000 mil") (width "4.00 MIL") (dielectricConstant "4.500000") (lossTangent "0.035") (etchFactor "90.000000") (elecCondVal "595900.000000 mho/cm") (thermCondVal "0.012 w/cm-degC") (signalDieConstant "4.500000") (signalLossTangent "0.035")) ("" (layerType "DIELECTRIC") (material "FR-4") (thickness "  9.000000 mil") (dielectricConstant "4.500000") (lossTangent "0.035") (etchFactor "0.000000") (elecCondVal "0 mho/cm") (thermCondVal "0 w/cm-degC")) ("L13_GND6" (layerType "PLANE") (material "COPPER") (isShield t) (thickness "  1.250000 mil") (dielectricConstant "4.500000") (lossTangent "0.035") (etchFactor "90.000000") (elecCondVal "595900.000000 mho/cm") (thermCondVal "0.012 w/cm-degC")) ("" (layerType "DIELECTRIC") (material "FR-4") (thickness "  2.670000 mil") (dielectricConstant "4.500000") (lossTangent "0.035") (etchFactor "0.000000") (elecCondVal "0 mho/cm") (thermCondVal "0.012 w/cm-degC")) ("BOTTOM" (layerType "CONDUCTOR") (material "COPPER") (thickness "  2.100000 mil") (width "4.00 MIL") (dielectricConstant "4.500000") (lossTangent "0") (etchFactor "70.000000") (elecCondVal "595900.000000 mho/cm") (thermCondVal "0 w/cm-degC") (signalDieConstant "3.800000") (signalLossTangent "0.035")) ("" (layerType "DIELECTRIC") (material "CONFORMAL_COAT") (thickness "0.5 mil") (dielectricConstant "3.800000") (lossTangent "0.035") (etchFactor "0.000000") (elecCondVal "0 mho/cm") (thermCondVal "0.012 w/cm-degC")) ("" (layerType "SURFACE") (material "AIR") (thickness "0 mil") (dielectricConstant "1.000000") (lossTangent "0") (etchFactor "0.000000") (elecCondVal "0 mho/cm") (thermCondVal "0 w/cm-degC"))))) (Props (DesUnits "mils 2") (LayerStack ("DIELECTRIC" "DIELECTRIC" "BOTTOM" "DIELECTRIC" "L13_GND6" "DIELECTRIC" "L12_SIG4" "DIELECTRIC" "L11_GND5" "DIELECTRIC" "L10_SIG3" "DIELECTRIC" "L9_GND4" "DIELECTRIC" "L8_PWR2-SIG" "DIELECTRIC" "L7_PWR1-SIG" "DIELECTRIC" "L6_GND3" "DIELECTRIC" "L5_SIG2" "DIELECTRIC" "L4_GND2" "DIELECTRIC" "L3_SIG1" "DIELECTRIC" "L2_GND1" "DIELECTRIC" "TOP" "DIELECTRIC" "DIELECTRIC")) (Revision "16.600")) (Params (Via ((model "Unknown") (viaOutputFormat "Unknown") (viaPadstack nil) (viaTopLayer nil) (viaBottomLayer nil) (viaIsPower nil) (viaIsGround nil))) (IbisIOMacro ((temperature "27") (bufferModel "CDSDefaultIO_2p5v") (stimuli nil) (offsets nil) (state "tristate") (cycle "1") (termMap nil) (setup "2.0e-09") (hold "1.0e-09") (rise nil) (fall nil) (macroType nil) (voltage nil) (spice nil) (LEFDEFPinName nil) (LEFDEFPinType nil) (mappingTag nil))) (DiffInputPkg ((temperature "27") (bufferModelNonInverting "CDSDefaultInput_2p5v") (bufferModelInverting "CDSDefaultInput_2p5v") (threshInputHighMin "1.7 V") (threshInputHighTyp "1.7  V") (threshInputHighMax "1.7  V") (threshInputLowMin "0.7  V") (threshInputLowTyp "0.7  V") (threshInputLowMax "0.7  V") (mappingTagNonInverting nil) (mappingTagInverting nil) (cycle "1"))) (DiffIO ((temperature "27") (bufferModelNonInverting "CDSDefaultIO_2p5v") (bufferModelInverting "CDSDefaultIO_2p5v") (stimuli nil) (offsets nil) (state "tristate") (cycle "1") (termMap nil) (setup "0.9e-09") (hold "0.4e-09") (rise nil) (fall nil) (threshInputHighMin "1.7 V") (threshInputHighTyp "1.7  V") (threshInputHighMax "1.7  V") (threshInputLowMin "0.7  V") (threshInputLowTyp "0.7  V") (threshInputLowMax "0.7 ") (threshOutputHighMin "2.365  V") (threshOutputHighTyp "2.5  V") (threshOutputHighMax "2.625  V") (threshOutputLowMin "1.275  V") (threshOutputLowTyp "1.7  V") (threshOutputLowMax "1.985  V") (mappingTagNonInverting nil) (mappingTagInverting nil) (spice nil))) (Trace ((d1Thickness "10 mil") (d1Constant "4.5") (d1LossTangent "0.035") (d2Thickness "10 mil") (d2Constant "4.5") (d2LossTangent "0.035") (d3Thickness "0.0") (d3Constant "1.0") (d3LossTangent "0") length("1000 mil") (spacing "5 mil") (spacing2 "5 mil") (spacing3 "5 mil") (spacing4 "5 mil") (spacing5 "5 mil") (traceConductivity "595900 mho/cm") (traceGeometry "microstrip") (traceLayerName "") (traceThickness "0.72 mil") (traceType "single") (traceWidth "5.0 mil") (traceWidth2 "5.0 mil") (traceWidth3 "5.0 mil") (traceWidth4 "5.0 mil") (traceWidth5 "5.0 mil") (traceWidth6 "5.0 mil") (offset "0 mil") (traceCount "1") (impedance nil))) (sync ((syncFreq "100e6") (syncInitState "1") (syncPattern "10") (syncEdgeSwitch "rise"))) (DiffOutputPkg ((temperature "27") (bufferModelNonInverting "CDSDefaultOutput_2p5v") (bufferModelInverting "CDSDefaultOutput_2p5v") (stimuli nil) (offsets nil) (state "tristate") (cycle "1") (termMap nil) (setup "0.9e-09") (hold "0.4e-09") (rise nil) (fall nil) (threshOutputHighMin "2.375  V") (threshOutputHighTyp "2.5  V") (threshOutputHighMax "2.625  V") (threshOutputLowMin "1.275  V") (threshOutputLowTyp "1.7  V") (threshOutputLowMax "1.985  V") (mappingTagNonInverting nil) (mappingTagInverting nil) (spice nil))) (DiffOutput ((temperature "27") (bufferModelNonInverting "CDSDefaultOutput_2p5v") (bufferModelInverting "CDSDefaultOutput_2p5v") (stimuli nil) (offsets nil) (state "tristate") (cycle "1") (termMap nil) (setup "0.9e-09") (hold "0.4e-09") (rise nil) (fall nil) (threshOutputHighMin "2.375  V") (threshOutputHighTyp "2.5  V") (threshOutputHighMax "2.625  V") (threshOutputLowMin "1.275  V") (threshOutputLowTyp "1.7  V") (threshOutputLowMax "1.985  V") (mappingTagNonInverting nil) (mappingTagInverting nil) (spice nil))) (IbisOutputPkg ((temperature "27") (bufferModel "CDSDefaultOutput_2p5v") (stimuli nil) (offsets nil) (state "tristate") (cycle "1") (termMap nil) (setup "2.0e-09") (hold "1.0e-09") (rise nil) (fall nil) (macroType nil) (voltage nil) (spice nil) (LEFDEFPinName nil) (LEFDEFPinType nil) (mappingTag nil))) (DiffIOPkg ((temperature "27") (bufferModelNonInverting "CDSDefaultIO_2p5v") (bufferModelInverting "CDSDefaultIO_2p5v") (stimuli nil) (offsets nil) (state "tristate") (cycle "1") (termMap nil) (setup "0.9e-09") (hold "0.4e-09") (rise nil) (fall nil) (threshInputHighMin "1.7 V") (threshInputHighTyp "1.7  V") (threshInputHighMax "1.7  V") (threshInputLowMin "0.7  V") (threshInputLowTyp "0.7  V") (threshInputLowMax "0.7 ") (threshOutputHighMin "2.365  V") (threshOutputHighTyp "2.5  V") (threshOutputHighMax "2.625  V") (threshOutputLowMin "1.275  V") (threshOutputLowTyp "1.7  V") (threshOutputLowMax "1.985  V") (mappingTagNonInverting nil) (mappingTagInverting nil) (spice nil))) (IbisIOPkg ((temperature "27") (bufferModel "CDSDefaultIO_2p5v") (stimuli nil) (offsets nil) (state "tristate") (cycle "1") (termMap nil) (setup "2.0e-09") (hold "1.0e-09") (rise nil) (fall nil) (macroType nil) (voltage nil) (spice nil) (LEFDEFPinName nil) (LEFDEFPinType nil) (mappingTag nil))) (CurrentProbe nil) (DiffInput ((temperature "27") (bufferModelNonInverting "CDSDefaultInput_2p5v") (bufferModelInverting "CDSDefaultInput_2p5v") (threshInputHighMin "1.7 V") (threshInputHighTyp "1.7  V") (threshInputHighMax "1.7  V") (threshInputLowMin "0.7  V") (threshInputLowTyp "0.7  V") (threshInputLowMax "0.7  V") (mappingTagNonInverting nil) (mappingTagInverting nil) (cycle "1"))) (IbisInputPkg ((temperature "27") (bufferModel "CDSDefaultInput_2p5v") (cycle "1") (LEFDEFPinName nil) (LEFDEFPinType nil) (mappingTag nil))) (idlCircuit ((allDrivers "active") (ftsMode '("Typ")) (rcvrSelect "all") (simMode "Reflection") (tlineDelayMode "time") (userRevision "1.0") (autoSolve "On"))) (SeriesTerm ((resistance "22 ohm") (maxDelay "0.1 ns"))) (RLGC (length("1000 mil"))) (periodic ((periodicFreq "100e6") (periodicPattern "10") (periodicJitter "0"))) (Resistor ((resistance "50 ohm") (orientation "0"))) (async ((asyncTimePoints "") (asyncInitState "1"))) (Capacitor ((capacitance "10 pF") (orientation "0"))) (Inductor ((inductance "5 nH") (orientation "0"))) (clocked ((clockRise "1e-09") (clockFall "1e-09") (clockFreq "100e6") (clockInitState "0") (clockDutyCycle "0.5") (clockJitter "0"))) (TLine ((diffImpedance "100ohm") (diffVelocity "1.4142e+08M/s") (impedance "60ohm") length("2800 mil") (propDelay "0.5 ns") (velocity "5600 mil/ns") (traceCount "1") (traceGeometry "Microstrip") (impedanceMin nil) (impedanceMax nil) (lengthMin nil) (lengthMax nil) (propDelayMin nil) (propDelayMax nil) (impedanceSweepCount nil) (propDelaySweepCount nil) (velocitySweepCount nil) (lengthSweepCount nil) (matchSetName nil))) (Cable (length("1 m"))) (DualClampTerm ((cutoffVoltageUp "0.7 V") (cutoffVoltageDown "0.7 V") (voltageUp "5 V") (voltageDown "0 V") (maxDelay "0.1 ns"))) (LowClampTerm ((cutoffVoltage "0.7 V") (voltage "0 V") (maxDelay "0.1 ns"))) (HiClampTerm ((cutoffVoltage "0.7 V") (voltage "5 V") (maxDelay "0.1 ns"))) (RCTerm ((resistance "50 ohm") (capacitance "20 pF") (voltage "5 V") (maxDelay "0.1 ns"))) (IbisOutput ((temperature "27") (bufferModel "CDSDefaultOutput_2p5v") (stimuli nil) (offsets nil) (state "tristate") (cycle "1") (termMap nil) (setup "2.0e-09") (hold "1.0e-09") (rise nil) (fall nil) (macroType nil) (voltage nil) (spice nil) (LEFDEFPinName nil) (LEFDEFPinType nil) (mappingTag nil))) (IbisIO ((temperature "27") (bufferModel "CDSDefaultIO_2p5v") (stimuli nil) (offsets nil) (state "tristate") (cycle "1") (termMap nil) (setup "2.0e-09") (hold "1.0e-09") (rise nil) (fall nil) (macroType nil) (voltage nil) (spice nil) (LEFDEFPinName nil) (LEFDEFPinType nil) (mappingTag nil))) (Diode ((cutoffVoltage "0.7 V"))) (IbisInput ((temperature "27") (bufferModel "CDSDefaultInput_2p5v") (cycle "1") (LEFDEFPinName nil) (LEFDEFPinType nil) (mappingTag nil))) (ESpiceDevice nil) (CPW ((d1Thickness "10 mil") (d1Constant "4.5") (d1LossTangent "0.035") (d2Thickness "0.72 mil") (d2Constant "1") (d2LossTangent "0") (d3Thickness "0.0") (d3Constant "1") (d3LossTangent "0") length("1000 mil") (spacing "5 mil") (spacing2 "5 mil") (spacing3 "5 mil") (spacing4 "5 mil") (spacing5 "5 mil") (traceConductivity "595900 mho/cm") (traceGeometry "cpwms") (traceLayerName "") (traceThickness "0.72 mil") (traceType "single") (traceWidth "5.0 mil") (traceWidth2 "5.0 mil") (traceWidth3 "5.0 mil") (traceWidth4 "5.0 mil") (traceWidth5 "5.0 mil") (traceWidth6 "5.0 mil") (offset "0 mil") (traceCount "1") (impedance nil))) (IbisOutput_OpenPullUp ((temperature "27") (bufferModel "CDSDefaultOutput_2p5v") (stimuli nil) (offsets nil) (state "tristate") (cycle "1") (termMap nil) (setup "2.0e-09") (hold "1.0e-09") (rise nil) (fall nil) (macroType nil) (voltage nil) (spice nil) (LEFDEFPinName nil) (LEFDEFPinType nil) (mappingTag nil))) (CPWMS ((d1Thickness "10 mil") (d1Constant "4.5") (d1LossTangent "0.035") (d2Thickness "0.72 mil") (d2Constant "4.5") (d2LossTangent "0.035") (d3Thickness "0.0") (d3Constant "1") (d3LossTangent "0") length("1000 mil") (spacing "5 mil") (spacing2 "5 mil") (spacing3 "5 mil") (spacing4 "5 mil") (spacing5 "5 mil") (traceConductivity "595900 mho/cm") (traceGeometry "cpwms") (traceLayerName "") (traceThickness "0.72 mil") (traceType "single") (traceWidth "5.0 mil") (traceWidth2 "5.0 mil") (traceWidth3 "5.0 mil") (traceWidth4 "5.0 mil") (traceWidth5 "5.0 mil") (traceWidth6 "5.0 mil") (offset "0 mil") (traceCount "1") (impedance nil))) (IbisIO_OpenPullDown ((temperature "27") (bufferModel "CDSDefaultIO_2p5v") (stimuli nil) (offsets nil) (state "tristate") (cycle "1") (termMap nil) (setup "2.0e-09") (hold "1.0e-09") (rise nil) (fall nil) (macroType nil) (voltage nil) (spice nil) (LEFDEFPinName nil) (LEFDEFPinType nil) (mappingTag nil))) (Connector nil) (CPWSL ((d1Thickness "10 mil") (d1Constant "4.5") (d1LossTangent "0.035") (d2Thickness "0.72 mil") (d2Constant "4.5") (d2LossTangent "0.035") (d3Thickness "10 mil") (d3Constant "4.5") (d3LossTangent "0.035") length("1000 mil") (spacing "5 mil") (spacing2 "5 mil") (spacing3 "5 mil") (spacing4 "5 mil") (spacing5 "5 mil") (traceConductivity "595900 mho/cm") (traceGeometry "cpwms") (traceLayerName "") (traceThickness "0.72 mil") (traceType "single") (traceWidth "5.0 mil") (traceWidth2 "5.0 mil") (traceWidth3 "5.0 mil") (traceWidth4 "5.0 mil") (traceWidth5 "5.0 mil") (traceWidth6 "5.0 mil") (offset "0 mil") (traceCount "1") (impedance nil))) (IbisIO_OpenPullUp ((temperature "27") (bufferModel "CDSDefaultIO_2p5v") (stimuli nil) (offsets nil) (state "tristate") (cycle "1") (termMap nil) (setup "2.0e-09") (hold "1.0e-09") (rise nil) (fall nil) (macroType nil) (voltage nil) (spice nil) (LEFDEFPinName nil) (LEFDEFPinType nil) (mappingTag nil))) (TheveninTerm ((resistanceUp "180 ohm") (resistanceDown "270 ohm") (voltageUp "5 V") (voltageDown "0 V") (maxDelay "0.1 ns"))) (ShuntTerm ((resistance "50 ohm") (voltage "5 V") (maxDelay "0.1 ns"))) (Source ((voltage "5 V")))))
				)
				( objectStatus "PMSYNC" )
			)
			( electricalCSet "@crescent_city_bb_fab1_lib.crescent_city_bb_fab1(sch_1):\PCIE_C_D\"
				( groupRef "PCIE_C_D:MG_PCIE_L0" )
				( groupRef "PCIE_C_D:MG_PCIE_L1" )
				( groupRef "PCIE_C_D:MG_PCIE_L2" )
				( groupRef "PCIE_C_D:MG_PCIE_ALL0" )
				( groupRef "PCIE_C_D:MG_PCIE_ALL1" )
				( pinPairRef "PCIE_C_D:J8G1.102:R2U29.1" )
				( pinPairRef "PCIE_C_D:U7C1.P59:R3641.1" )
				( pinPairRef "PCIE_C_D:U5D1.DM9:R2U29.1" )
				( pinPairRef "PCIE_C_D:U5D1.DM9:J8G1.102" )
				( pinPairRef "PCIE_C_D:U5D1.DM9:U7C1.P59" )
				( attribute "RATSNEST_SCHEDULE" "TEMPLATE"
					( Status sLocked )
					( Origin gBackEnd )
				)
				( attribute "DIFFP_COUPLED_PLUS" "0.10"
					( Origin gBackEnd )
				)
				( attribute "DIFFP_COUPLED_MINUS" "0.10"
					( Origin gBackEnd )
				)
				( attribute "TOPOLOGY_TEMPLATE_REVISION" "1.0"
					( Origin gBackEnd )
				)
				( topologyData 26061
(SKIDL (Circuits ("MAIN" (Parts ("CRESCENT_CITY_178_20141217_B.@@U22.P59" IbisIOPkg (xy (5514.0 4214.0)) (refDes "U7C1") (model "Unknown") (Props (_SXDesignName "CRESCENT_CITY_178_20141217_B") (brdx "14972.75 MIL") (brdy "4730.6 MIL") (bufferModel "CDSDefaultIO_2p5v") (cycle "1") (hold "1.0e-09") (mappingTag "") (offsets ("4" "0") ("5" "0")) (setup "2.0e-09") (state "tristate") (stimuli ("5" "local8") ("4" "local7")) (temperature "27") (termMap ("4" "Data") ("5" "Enable"))) (Terms ("CRESCENT_CITY_178_20141217_B.X1497275Y473060L2LRATS" "P59"))) ("CRESCENT_CITY_178_20141217_B.@@U36.DM9" IbisInputPkg (xy (5520 4223)) (refDes "U5D1") (model "Unknown") (Props (_SXDesignName "CRESCENT_CITY_178_20141217_B") (brdx "11826.09 MIL") (brdy "3799.96 MIL") (bufferModel "CDSDefaultInput_2p5v") (mappingTag "") (temperature "27")) (Terms ("CRESCENT_CITY_178_20141217_B.X1182609Y379996L2LRATS" "DM9"))) ("CRESCENT_CITY_178_20141217_B.@@J73.102" IbisIOPkg (xy (5502 4240)) (refDes "J8G1") (model "Unknown") (Props (_SXDesignName "CRESCENT_CITY_178_20141217_B") (brdx "15795.87 MIL") (brdy "172.76 MIL") (bufferModel "CDSDefaultIO_2p5v") (cycle "1") (hold "1.0e-09") (mappingTag "") (offsets ("4" "0") ("5" "0")) (setup "2.0e-09") (state "tristate") (stimuli ("5" "local10") ("4" "local9")) (temperature "27") (termMap ("4" "Data") ("5" "Enable"))) (Terms ("CRESCENT_CITY_178_20141217_B.X1579587Y17276L2LRATS" "102"))) ("CRESCENT_CITY_178_20141217_B.@@R3641.1.2" Resistor (xy (5491 4217)) (refDes "R3641") (value "1 Ohm") (Props (_SXDesignName "CRESCENT_CITY_178_20141217_B")) (Terms ("CRESCENT_CITY_178_20141217_B.X1583416Y55036L28LRATS" "1") ("idlNode_22" "2"))) ("CRESCENT_CITY_178_20141217_B.T@@RATS@@U36.DM9@@R3657.2" TLine (xy (5506 4223)) (mirror x) (refDes "TL2") (Props (_SXDesignName "CRESCENT_CITY_178_20141217_B") (impedance "47.169 ohm") length("7292.68 MIL") (propDelay "1.30981 ns") (traceCount "1") (traceGeometry "Microstrip") (velocity "5567.72 mil/ns")) (Terms ("CRESCENT_CITY_178_20141217_B.X1182609Y379996L2LRATS" "1") ("idlNode_36" "2"))) ("CRESCENT_CITY_178_20141217_B.T@@RATS@@U22.P59@@R3641.1" TLine (xy (5491.0 4209.0)) (mirror x) (refDes "TL3") (Props (_SXDesignName "CRESCENT_CITY_178_20141217_B") (impedance "47.169 ohm") length("5041.65 MIL") (propDelay "0.90551 ns") (traceCount "1") (traceGeometry "Microstrip") (velocity "5567.76 mil/ns")) (Terms ("CRESCENT_CITY_178_20141217_B.X1497275Y473060L2LRATS" "1") ("CRESCENT_CITY_178_20141217_B.X1583416Y55036L28LRATS" "2"))) ("CRESCENT_CITY_178_20141217_B.@@R3657.2.1" Resistor (xy (5491 4223)) (mirror x) (refDes "R2U29") (value "2.2e-007 Ohm") (Props (_SXDesignName "CRESCENT_CITY_178_20141217_B")) (Terms ("idlNode_49" "2") ("CRESCENT_CITY_178_20141217_B.X1583416Y48036L28LRATS" "1"))) ("idlPart_12" TLine (xy (5498.5 4217.0)) (mirror x) (refDes "TL5") (Props (_SXDesignName "CRESCENT_CITY_178_20141217_B") (impedance "47.169 ohm") length("7292.68 MIL") (propDelay "1.30981 ns") (traceCount "1") (traceGeometry "Microstrip") (velocity "5567.72 mil/ns")) (Terms ("idlNode_36" "1") ("idlNode_22" "2"))) ("idlPart_47" TLine (xy (5498.5 4223.0)) (mirror x) (refDes "TL6") (Props (_SXDesignName "CRESCENT_CITY_178_20141217_B") (impedance "47.169 ohm") length("7292.68 MIL") (propDelay "1.30981 ns") (traceCount "1") (traceGeometry "Microstrip") (velocity "5567.72 mil/ns")) (Terms ("idlNode_36" "1") ("idlNode_49" "2"))) ("CRESCENT_CITY_178_20141217_B.T@@RATS@@R3657.1@@J73.102" TLine (xy (5491.0 4235.0)) (refDes "TL4") (Props (_SXDesignName "CRESCENT_CITY_178_20141217_B") (impedance "47.169 ohm") length("345.89 MIL") (propDelay "0.06212 ns") (traceCount "1") (traceGeometry "Microstrip") (velocity "5568.11 mil/ns")) (Terms ("CRESCENT_CITY_178_20141217_B.X1583416Y48036L28LRATS" "1") ("CRESCENT_CITY_178_20141217_B.X1579587Y17276L2LRATS" "2")))) (Nodes ("idlNode_22" (terms "idlPart_12.2" "CRESCENT_CITY_178_20141217_B.@@R3641.1.2.2")) ("CRESCENT_CITY_178_20141217_B.X1497275Y473060L2LRATS" (terms "CRESCENT_CITY_178_20141217_B.T@@RATS@@U22.P59@@R3641.1.1" "CRESCENT_CITY_178_20141217_B.@@U22.P59.1")) ("CRESCENT_CITY_178_20141217_B.X1182609Y379996L2LRATS" (terms "CRESCENT_CITY_178_20141217_B.T@@RATS@@U36.DM9@@R3657.2.1" "CRESCENT_CITY_178_20141217_B.@@U36.DM9.1")) ("CRESCENT_CITY_178_20141217_B.X1583416Y55036L28LRATS" (terms "CRESCENT_CITY_178_20141217_B.T@@RATS@@U22.P59@@R3641.1.2" "CRESCENT_CITY_178_20141217_B.@@R3641.1.2.1")) ("idlNode_49" (terms "idlPart_47.2" "CRESCENT_CITY_178_20141217_B.@@R3657.2.1.1")) ("CRESCENT_CITY_178_20141217_B.X1579587Y17276L2LRATS" (terms "CRESCENT_CITY_178_20141217_B.T@@RATS@@R3657.1@@J73.102.2" "CRESCENT_CITY_178_20141217_B.@@J73.102.1")) ("CRESCENT_CITY_178_20141217_B.X1583416Y48036L28LRATS" (terms "CRESCENT_CITY_178_20141217_B.T@@RATS@@R3657.1@@J73.102.1" "CRESCENT_CITY_178_20141217_B.@@R3657.2.1.2")) ("idlNode_36" (terms "idlPart_47.1" "idlPart_12.1" "CRESCENT_CITY_178_20141217_B.T@@RATS@@U36.DM9@@R3657.2.2") (tee "CRESCENT_CITY_178_20141217_B NET.T.1"))) (Ports) (Stimuli ("local8" (scope local) (stimType periodic) (Props (periodicFreq "5e+007") (periodicJitter "0") (periodicPattern "1"))) ("local10" (scope local) (stimType periodic) (Props (periodicFreq "5e+007") (periodicJitter "0") (periodicPattern "1"))) ("local9" (scope local) (stimType periodic) (Props (periodicFreq "5e+007") (periodicJitter "0") (periodicPattern "1"))) ("local7" (scope local) (stimType periodic) (Props (periodicFreq "5e+007") (periodicJitter "0") (periodicPattern "1")))) (Notes) (Constraints ("DELAY_RULE" ("CRESCENT_CITY_178_20141217_B U36.DM9" "CRESCENT_CITY_178_20141217_B J73.102" "LENGTH" "0.0762" "LENGTH" "0.4064") ("CRESCENT_CITY_178_20141217_B U36.DM9" "CRESCENT_CITY_178_20141217_B U22.P59" "LENGTH" "0.0762" "LENGTH" "0.4318")) ("RATSNEST_SCHEDULE" "TEMPLATE") ("RELATIVE_PROPAGATION_DELAY" ("TMP" "CRESCENT_CITY_178_20141217_B U36.DM9" "CRESCENT_CITY_178_20141217_B U22.P59" "LOCAL" "LENGTH" "0.000127" "DELAY" "") ("TMP" "CRESCENT_CITY_178_20141217_B U36.DM9" "CRESCENT_CITY_178_20141217_B J73.102" "LOCAL" "LENGTH" "0.000127" "DELAY" "") ("MG_PCIE_LOCAL" "CRESCENT_CITY_178_20141217_B U36.DM9" "CRESCENT_CITY_178_20141217_B NET.T.1" "LOCAL" "LENGTH" "0.000127" "DELAY" "") ("MG_PCIE_LOCAL" "CRESCENT_CITY_178_20141217_B U22.P59" "CRESCENT_CITY_178_20141217_B R3641.1" "LOCAL" "LENGTH" "0.000127" "DELAY" "") ("MG_PCIE_LOCAL" "CRESCENT_CITY_178_20141217_B J73.102" "CRESCENT_CITY_178_20141217_B R3657.1" "LOCAL" "LENGTH" "0.000127" "DELAY" ""))) (MeasurementSets ("EMI" ("EMIStatus" status("on")) ("PeakEmission" status("on")) ("PeakFrequency" status("on")) ("PulseFreq" status("on")) ("RiseTime" status("on")) ("VoltageSwing" status("on"))) ("Reflection" ("BufferDelayFall" status("off")) ("BufferDelayRise" status("off")) ("EyeHeight" status("off")) ("EyeJitter" status("off")) ("EyeWidth" status("off")) ("FirstIncidentFall" status("off")) ("FirstIncidentRise" status("off")) ("Glitch" status("on")) ("GlitchFall" status("off")) ("GlitchRise" status("off")) ("Monotonic" status("on")) ("MonotonicFall" status("off")) ("MonotonicRise" status("off")) ("NoiseMargin" status("on")) ("NoiseMarginHigh" status("off")) ("NoiseMarginLow" status("off")) ("OvershootHigh" status("on")) ("OvershootLow" status("on")) ("PropDelay" status("on")) ("SettleDelay" status("on")) ("SettleDelayFall" status("off")) ("SettleDelayRise" status("off")) ("SwitchDelay" status("on")) ("SwitchDelayFall" status("off")) ("SwitchDelayRise" status("off"))) ("Crosstalk" ("Crosstalk" status("on"))) ("Custom")) (VectorSets) (Props (XnetName "P3E_CPU0_PE1_SS_PCIEUP_RXN<7>") (allDrivers "active") (customSimType "Reflection") (ftsMode ("Typ")) (rcvrSelect "all") (tlineDelayMode "time") (userRevision "1.0")))) (Subckts) (CrossSections ("CRESCENT_CITY_178_20141217_B" (Props (SXDesignName "CRESCENT_CITY_178_20141217_B")) (Layers ("" (layerType "SURFACE") (material "AIR") (thickness "0 mil") (dielectricConstant "1.000000") (lossTangent "0") (etchFactor "0.000000") (elecCondVal "0 mho/cm") (thermCondVal "0 w/cm-degC")) ("" (layerType "DIELECTRIC") (material "CONFORMAL_COAT") (thickness "0.5 mil") (dielectricConstant "3.800000") (lossTangent "0.035") (etchFactor "0.000000") (elecCondVal "0 mho/cm") (thermCondVal "0.012 w/cm-degC")) ("TOP" (layerType "CONDUCTOR") (material "COPPER") (thickness "  2.100000 mil") (width "4.00 MIL") (dielectricConstant "4.500000") (lossTangent "0") (etchFactor "70.000000") (elecCondVal "595900.000000 mho/cm") (thermCondVal "0 w/cm-degC") (signalDieConstant "3.800000") (signalLossTangent "0.035")) ("" (layerType "DIELECTRIC") (material "FR-4") (thickness "  2.670000 mil") (dielectricConstant "4.000000") (lossTangent "0.035") (etchFactor "0.000000") (elecCondVal "0 mho/cm") (thermCondVal "0.012 w/cm-degC")) ("L2_GND1" (layerType "PLANE") (material "COPPER") (isShield t) (thickness "  1.250000 mil") (dielectricConstant "4.500000") (lossTangent "0.035") (etchFactor "90.000000") (elecCondVal "595900.000000 mho/cm") (thermCondVal "0.012 w/cm-degC")) ("" (layerType "DIELECTRIC") (material "FR-4") (thickness "  9.000000 mil") (dielectricConstant "4.100000") (lossTangent "0.035") (etchFactor "0.000000") (elecCondVal "0 mho/cm") (thermCondVal "0.012 w/cm-degC")) ("L3_SIG1" (layerType "CONDUCTOR") (material "COPPER") (thickness "  1.250000 mil") (width "4.00 MIL") (dielectricConstant "4.500000") (lossTangent "0.035") (etchFactor "90.000000") (elecCondVal "595900.000000 mho/cm") (thermCondVal "0.012 w/cm-degC") (signalDieConstant "4.100000") (signalLossTangent "0.035")) ("" (layerType "DIELECTRIC") (material "FR-4") (thickness "  3.000000 mil") (dielectricConstant "4.500000") (lossTangent "0.035") (etchFactor "0.000000") (elecCondVal "0 mho/cm") (thermCondVal "0 w/cm-degC")) ("L4_GND2" (layerType "PLANE") (material "COPPER") (isShield t) (thickness "  1.250000 mil") (dielectricConstant "4.500000") (lossTangent "0.035") (etchFactor "90.000000") (elecCondVal "595900.000000 mho/cm") (thermCondVal "0 w/cm-degC")) ("" (layerType "DIELECTRIC") (material "FR-4") (thickness "  9.000000 mil") (dielectricConstant "4.000000") (lossTangent "0.035") (etchFactor "0.000000") (elecCondVal "0 mho/cm") (thermCondVal "0.012 w/cm-degC")) ("L5_SIG2" (layerType "CONDUCTOR") (material "COPPER") (thickness "  1.250000 mil") (width "4.00 MIL") (dielectricConstant "4.500000") (lossTangent "0.035") (etchFactor "90.000000") (elecCondVal "595900.000000 mho/cm") (thermCondVal "0.012 w/cm-degC") (signalDieConstant "4.000000") (signalLossTangent "0.035")) ("" (layerType "DIELECTRIC") (material "FR-4") (thickness "  3.000000 mil") (dielectricConstant "4.500000") (lossTangent "0.035") (etchFactor "0.000000") (elecCondVal "0 mho/cm") (thermCondVal "0 w/cm-degC")) ("L6_GND3" (layerType "PLANE") (material "COPPER") (isShield t) (thickness "  1.250000 mil") (dielectricConstant "4.500000") (lossTangent "0.035") (etchFactor "90.000000") (elecCondVal "595900.000000 mho/cm") (thermCondVal "0 w/cm-degC")) ("" (layerType "DIELECTRIC") (material "FR-4") (thickness "  4.500000 mil") (dielectricConstant "4.100000") (lossTangent "0.035") (etchFactor "0.000000") (elecCondVal "0 mho/cm") (thermCondVal "0.012 w/cm-degC")) ("L7_PWR1-SIG" (layerType "PLANE") (material "COPPER") (isShield t) (thickness "  2.400000 mil") (dielectricConstant "4.500000") (lossTangent "0.035") (etchFactor "90.000000") (elecCondVal "595900.000000 mho/cm") (thermCondVal "0.012 w/cm-degC")) ("" (layerType "DIELECTRIC") (material "FR-4") (thickness "  4.600000 mil") (dielectricConstant "4.000000") (lossTangent "0.035") (etchFactor "0.000000") (elecCondVal "0 mho/cm") (thermCondVal "0.012 w/cm-degC")) ("L8_PWR2-SIG" (layerType "PLANE") (material "COPPER") (isShield t) (thickness "  2.400000 mil") (dielectricConstant "4.500000") (lossTangent "0.035") (etchFactor "90.000000") (elecCondVal "595900.000000 mho/cm") (thermCondVal "0.012 w/cm-degC")) ("" (layerType "DIELECTRIC") (material "FR-4") (thickness "  4.500000 mil") (dielectricConstant "4.500000") (lossTangent "0.035") (etchFactor "0.000000") (elecCondVal "0 mho/cm") (thermCondVal "0 w/cm-degC")) ("L9_GND4" (layerType "PLANE") (material "COPPER") (isShield t) (thickness "  1.250000 mil") (dielectricConstant "4.500000") (lossTangent "0.035") (etchFactor "90.000000") (elecCondVal "595900.000000 mho/cm") (thermCondVal "0 w/cm-degC")) ("" (layerType "DIELECTRIC") (material "FR-4") (thickness "  3.000000 mil") (dielectricConstant "4.100000") (lossTangent "0.035") (etchFactor "0.000000") (elecCondVal "0 mho/cm") (thermCondVal "0.012 w/cm-degC")) ("L10_SIG3" (layerType "CONDUCTOR") (material "COPPER") (thickness "  1.250000 mil") (width "4.00 MIL") (dielectricConstant "4.500000") (lossTangent "0.035") (etchFactor "90.000000") (elecCondVal "595900.000000 mho/cm") (thermCondVal "0.012 w/cm-degC") (signalDieConstant "4.100000") (signalLossTangent "0.035")) ("" (layerType "DIELECTRIC") (material "FR-4") (thickness "  9.000000 mil") (dielectricConstant "4.500000") (lossTangent "0.035") (etchFactor "0.000000") (elecCondVal "0 mho/cm") (thermCondVal "0 w/cm-degC")) ("L11_GND5" (layerType "PLANE") (material "COPPER") (isShield t) (thickness "  1.250000 mil") (dielectricConstant "4.500000") (lossTangent "0.035") (etchFactor "90.000000") (elecCondVal "595900.000000 mho/cm") (thermCondVal "0 w/cm-degC")) ("" (layerType "DIELECTRIC") (material "FR-4") (thickness "  3.000000 mil") (dielectricConstant "4.500000") (lossTangent "0.035") (etchFactor "0.000000") (elecCondVal "0 mho/cm") (thermCondVal "0.012 w/cm-degC")) ("L12_SIG4" (layerType "CONDUCTOR") (material "COPPER") (thickness "  1.250000 mil") (width "4.00 MIL") (dielectricConstant "4.500000") (lossTangent "0.035") (etchFactor "90.000000") (elecCondVal "595900.000000 mho/cm") (thermCondVal "0.012 w/cm-degC") (signalDieConstant "4.500000") (signalLossTangent "0.035")) ("" (layerType "DIELECTRIC") (material "FR-4") (thickness "  9.000000 mil") (dielectricConstant "4.500000") (lossTangent "0.035") (etchFactor "0.000000") (elecCondVal "0 mho/cm") (thermCondVal "0 w/cm-degC")) ("L13_GND6" (layerType "PLANE") (material "COPPER") (isShield t) (thickness "  1.250000 mil") (dielectricConstant "4.500000") (lossTangent "0.035") (etchFactor "90.000000") (elecCondVal "595900.000000 mho/cm") (thermCondVal "0.012 w/cm-degC")) ("" (layerType "DIELECTRIC") (material "FR-4") (thickness "  2.670000 mil") (dielectricConstant "4.500000") (lossTangent "0.035") (etchFactor "0.000000") (elecCondVal "0 mho/cm") (thermCondVal "0.012 w/cm-degC")) ("BOTTOM" (layerType "CONDUCTOR") (material "COPPER") (thickness "  2.100000 mil") (width "4.00 MIL") (dielectricConstant "4.500000") (lossTangent "0") (etchFactor "70.000000") (elecCondVal "595900.000000 mho/cm") (thermCondVal "0 w/cm-degC") (signalDieConstant "3.800000") (signalLossTangent "0.035")) ("" (layerType "DIELECTRIC") (material "CONFORMAL_COAT") (thickness "0.5 mil") (dielectricConstant "3.800000") (lossTangent "0.035") (etchFactor "0.000000") (elecCondVal "0 mho/cm") (thermCondVal "0.012 w/cm-degC")) ("" (layerType "SURFACE") (material "AIR") (thickness "0 mil") (dielectricConstant "1.000000") (lossTangent "0") (etchFactor "0.000000") (elecCondVal "0 mho/cm") (thermCondVal "0 w/cm-degC"))))) (Props (DesUnits "mils 2") (LayerStack ("DIELECTRIC" "DIELECTRIC" "BOTTOM" "DIELECTRIC" "L13_GND6" "DIELECTRIC" "L12_SIG4" "DIELECTRIC" "L11_GND5" "DIELECTRIC" "L10_SIG3" "DIELECTRIC" "L9_GND4" "DIELECTRIC" "L8_PWR2-SIG" "DIELECTRIC" "L7_PWR1-SIG" "DIELECTRIC" "L6_GND3" "DIELECTRIC" "L5_SIG2" "DIELECTRIC" "L4_GND2" "DIELECTRIC" "L3_SIG1" "DIELECTRIC" "L2_GND1" "DIELECTRIC" "TOP" "DIELECTRIC" "DIELECTRIC")) (Revision "16.600")) (Params (Source ((voltage "5 V"))) (Inductor ((inductance "5 nH") (orientation "0"))) (IbisIO_OpenPullDown ((temperature "27") (bufferModel "CDSDefaultIO_2p5v") (stimuli nil) (offsets nil) (state "tristate") (cycle "1") (termMap nil) (setup "2.0e-09") (hold "1.0e-09") (rise nil) (fall nil) (macroType nil) (voltage nil) (spice nil) (LEFDEFPinName nil) (LEFDEFPinType nil) (mappingTag nil))) (DiffInputPkg ((temperature "27") (bufferModelNonInverting "CDSDefaultInput_2p5v") (bufferModelInverting "CDSDefaultInput_2p5v") (threshInputHighMin "1.7 V") (threshInputHighTyp "1.7  V") (threshInputHighMax "1.7  V") (threshInputLowMin "0.7  V") (threshInputLowTyp "0.7  V") (threshInputLowMax "0.7  V") (mappingTagNonInverting nil) (mappingTagInverting nil) (cycle "1"))) (IbisIO ((temperature "27") (bufferModel "CDSDefaultIO_2p5v") (stimuli nil) (offsets nil) (state "tristate") (cycle "1") (termMap nil) (setup "2.0e-09") (hold "1.0e-09") (rise nil) (fall nil) (macroType nil) (voltage nil) (spice nil) (LEFDEFPinName nil) (LEFDEFPinType nil) (mappingTag nil))) (Trace ((d1Thickness "10 mil") (d1Constant "4.5") (d1LossTangent "0.035") (d2Thickness "10 mil") (d2Constant "4.5") (d2LossTangent "0.035") (d3Thickness "0.0") (d3Constant "1.0") (d3LossTangent "0") length("1000 mil") (spacing "5 mil") (spacing2 "5 mil") (spacing3 "5 mil") (spacing4 "5 mil") (spacing5 "5 mil") (traceConductivity "595900 mho/cm") (traceGeometry "microstrip") (traceLayerName "") (traceThickness "0.72 mil") (traceType "single") (traceWidth "5.0 mil") (traceWidth2 "5.0 mil") (traceWidth3 "5.0 mil") (traceWidth4 "5.0 mil") (traceWidth5 "5.0 mil") (traceWidth6 "5.0 mil") (offset "0 mil") (traceCount "1") (impedance nil))) (IbisIOMacro ((temperature "27") (bufferModel "CDSDefaultIO_2p5v") (stimuli nil) (offsets nil) (state "tristate") (cycle "1") (termMap nil) (setup "2.0e-09") (hold "1.0e-09") (rise nil) (fall nil) (macroType nil) (voltage nil) (spice nil) (LEFDEFPinName nil) (LEFDEFPinType nil) (mappingTag nil))) (Cable (length("1 m"))) (Capacitor ((capacitance "10 pF") (orientation "0"))) (Via ((model "Unknown") (viaOutputFormat "Unknown") (viaPadstack nil) (viaTopLayer nil) (viaBottomLayer nil) (viaIsPower nil) (viaIsGround nil))) (Resistor ((resistance "50 ohm") (orientation "0"))) (IbisOutputPkg ((temperature "27") (bufferModel "CDSDefaultOutput_2p5v") (stimuli nil) (offsets nil) (state "tristate") (cycle "1") (termMap nil) (setup "2.0e-09") (hold "1.0e-09") (rise nil) (fall nil) (macroType nil) (voltage nil) (spice nil) (LEFDEFPinName nil) (LEFDEFPinType nil) (mappingTag nil))) (IbisOutput_OpenPullUp ((temperature "27") (bufferModel "CDSDefaultOutput_2p5v") (stimuli nil) (offsets nil) (state "tristate") (cycle "1") (termMap nil) (setup "2.0e-09") (hold "1.0e-09") (rise nil) (fall nil) (macroType nil) (voltage nil) (spice nil) (LEFDEFPinName nil) (LEFDEFPinType nil) (mappingTag nil))) (IbisIOPkg ((temperature "27") (bufferModel "CDSDefaultIO_2p5v") (stimuli nil) (offsets nil) (state "tristate") (cycle "1") (termMap nil) (setup "2.0e-09") (hold "1.0e-09") (rise nil) (fall nil) (macroType nil) (voltage nil) (spice nil) (LEFDEFPinName nil) (LEFDEFPinType nil) (mappingTag nil))) (IbisIO_OpenPullUp ((temperature "27") (bufferModel "CDSDefaultIO_2p5v") (stimuli nil) (offsets nil) (state "tristate") (cycle "1") (termMap nil) (setup "2.0e-09") (hold "1.0e-09") (rise nil) (fall nil) (macroType nil) (voltage nil) (spice nil) (LEFDEFPinName nil) (LEFDEFPinType nil) (mappingTag nil))) (ESpiceDevice nil) (IbisInputPkg ((temperature "27") (bufferModel "CDSDefaultInput_2p5v") (cycle "1") (LEFDEFPinName nil) (LEFDEFPinType nil) (mappingTag nil))) (IbisInput ((temperature "27") (bufferModel "CDSDefaultInput_2p5v") (cycle "1") (LEFDEFPinName nil) (LEFDEFPinType nil) (mappingTag nil))) (TLine ((diffImpedance "100ohm") (diffVelocity "1.4142e+08M/s") (impedance "60ohm") length("2800 mil") (propDelay "0.5 ns") (velocity "5600 mil/ns") (traceCount "1") (traceGeometry "Microstrip") (impedanceMin nil) (impedanceMax nil) (lengthMin nil) (lengthMax nil) (propDelayMin nil) (propDelayMax nil) (impedanceSweepCount nil) (propDelaySweepCount nil) (velocitySweepCount nil) (lengthSweepCount nil) (matchSetName nil))) (periodic ((periodicFreq "100e6") (periodicPattern "10") (periodicJitter "0"))) (clocked ((clockRise "1e-09") (clockFall "1e-09") (clockFreq "100e6") (clockInitState "0") (clockDutyCycle "0.5") (clockJitter "0"))) (RLGC (length("1000 mil"))) (DiffInput ((temperature "27") (bufferModelNonInverting "CDSDefaultInput_2p5v") (bufferModelInverting "CDSDefaultInput_2p5v") (threshInputHighMin "1.7 V") (threshInputHighTyp "1.7  V") (threshInputHighMax "1.7  V") (threshInputLowMin "0.7  V") (threshInputLowTyp "0.7  V") (threshInputLowMax "0.7  V") (mappingTagNonInverting nil) (mappingTagInverting nil) (cycle "1"))) (async ((asyncTimePoints "") (asyncInitState "1"))) (idlCircuit ((allDrivers "active") (ftsMode '("Typ")) (rcvrSelect "all") (simMode "Reflection") (tlineDelayMode "time") (userRevision "1.0") (autoSolve "On"))) (DiffIO ((temperature "27") (bufferModelNonInverting "CDSDefaultIO_2p5v") (bufferModelInverting "CDSDefaultIO_2p5v") (stimuli nil) (offsets nil) (state "tristate") (cycle "1") (termMap nil) (setup "0.9e-09") (hold "0.4e-09") (rise nil) (fall nil) (threshInputHighMin "1.7 V") (threshInputHighTyp "1.7  V") (threshInputHighMax "1.7  V") (threshInputLowMin "0.7  V") (threshInputLowTyp "0.7  V") (threshInputLowMax "0.7 ") (threshOutputHighMin "2.365  V") (threshOutputHighTyp "2.5  V") (threshOutputHighMax "2.625  V") (threshOutputLowMin "1.275  V") (threshOutputLowTyp "1.7  V") (threshOutputLowMax "1.985  V") (mappingTagNonInverting nil) (mappingTagInverting nil) (spice nil))) (DiffOutput ((temperature "27") (bufferModelNonInverting "CDSDefaultOutput_2p5v") (bufferModelInverting "CDSDefaultOutput_2p5v") (stimuli nil) (offsets nil) (state "tristate") (cycle "1") (termMap nil) (setup "0.9e-09") (hold "0.4e-09") (rise nil) (fall nil) (threshOutputHighMin "2.375  V") (threshOutputHighTyp "2.5  V") (threshOutputHighMax "2.625  V") (threshOutputLowMin "1.275  V") (threshOutputLowTyp "1.7  V") (threshOutputLowMax "1.985  V") (mappingTagNonInverting nil) (mappingTagInverting nil) (spice nil))) (DiffIOPkg ((temperature "27") (bufferModelNonInverting "CDSDefaultIO_2p5v") (bufferModelInverting "CDSDefaultIO_2p5v") (stimuli nil) (offsets nil) (state "tristate") (cycle "1") (termMap nil) (setup "0.9e-09") (hold "0.4e-09") (rise nil) (fall nil) (threshInputHighMin "1.7 V") (threshInputHighTyp "1.7  V") (threshInputHighMax "1.7  V") (threshInputLowMin "0.7  V") (threshInputLowTyp "0.7  V") (threshInputLowMax "0.7 ") (threshOutputHighMin "2.365  V") (threshOutputHighTyp "2.5  V") (threshOutputHighMax "2.625  V") (threshOutputLowMin "1.275  V") (threshOutputLowTyp "1.7  V") (threshOutputLowMax "1.985  V") (mappingTagNonInverting nil) (mappingTagInverting nil) (spice nil))) (sync ((syncFreq "100e6") (syncInitState "1") (syncPattern "10") (syncEdgeSwitch "rise"))) (SeriesTerm ((resistance "22 ohm") (maxDelay "0.1 ns"))) (DiffOutputPkg ((temperature "27") (bufferModelNonInverting "CDSDefaultOutput_2p5v") (bufferModelInverting "CDSDefaultOutput_2p5v") (stimuli nil) (offsets nil) (state "tristate") (cycle "1") (termMap nil) (setup "0.9e-09") (hold "0.4e-09") (rise nil) (fall nil) (threshOutputHighMin "2.375  V") (threshOutputHighTyp "2.5  V") (threshOutputHighMax "2.625  V") (threshOutputLowMin "1.275  V") (threshOutputLowTyp "1.7  V") (threshOutputLowMax "1.985  V") (mappingTagNonInverting nil) (mappingTagInverting nil) (spice nil))) (IbisOutput ((temperature "27") (bufferModel "CDSDefaultOutput_2p5v") (stimuli nil) (offsets nil) (state "tristate") (cycle "1") (termMap nil) (setup "2.0e-09") (hold "1.0e-09") (rise nil) (fall nil) (macroType nil) (voltage nil) (spice nil) (LEFDEFPinName nil) (LEFDEFPinType nil) (mappingTag nil))) (CPW ((d1Thickness "10 mil") (d1Constant "4.5") (d1LossTangent "0.035") (d2Thickness "0.72 mil") (d2Constant "1") (d2LossTangent "0") (d3Thickness "0.0") (d3Constant "1") (d3LossTangent "0") length("1000 mil") (spacing "5 mil") (spacing2 "5 mil") (spacing3 "5 mil") (spacing4 "5 mil") (spacing5 "5 mil") (traceConductivity "595900 mho/cm") (traceGeometry "cpwms") (traceLayerName "") (traceThickness "0.72 mil") (traceType "single") (traceWidth "5.0 mil") (traceWidth2 "5.0 mil") (traceWidth3 "5.0 mil") (traceWidth4 "5.0 mil") (traceWidth5 "5.0 mil") (traceWidth6 "5.0 mil") (offset "0 mil") (traceCount "1") (impedance nil))) (CPWMS ((d1Thickness "10 mil") (d1Constant "4.5") (d1LossTangent "0.035") (d2Thickness "0.72 mil") (d2Constant "4.5") (d2LossTangent "0.035") (d3Thickness "0.0") (d3Constant "1") (d3LossTangent "0") length("1000 mil") (spacing "5 mil") (spacing2 "5 mil") (spacing3 "5 mil") (spacing4 "5 mil") (spacing5 "5 mil") (traceConductivity "595900 mho/cm") (traceGeometry "cpwms") (traceLayerName "") (traceThickness "0.72 mil") (traceType "single") (traceWidth "5.0 mil") (traceWidth2 "5.0 mil") (traceWidth3 "5.0 mil") (traceWidth4 "5.0 mil") (traceWidth5 "5.0 mil") (traceWidth6 "5.0 mil") (offset "0 mil") (traceCount "1") (impedance nil))) (CurrentProbe nil) (CPWSL ((d1Thickness "10 mil") (d1Constant "4.5") (d1LossTangent "0.035") (d2Thickness "0.72 mil") (d2Constant "4.5") (d2LossTangent "0.035") (d3Thickness "10 mil") (d3Constant "4.5") (d3LossTangent "0.035") length("1000 mil") (spacing "5 mil") (spacing2 "5 mil") (spacing3 "5 mil") (spacing4 "5 mil") (spacing5 "5 mil") (traceConductivity "595900 mho/cm") (traceGeometry "cpwms") (traceLayerName "") (traceThickness "0.72 mil") (traceType "single") (traceWidth "5.0 mil") (traceWidth2 "5.0 mil") (traceWidth3 "5.0 mil") (traceWidth4 "5.0 mil") (traceWidth5 "5.0 mil") (traceWidth6 "5.0 mil") (offset "0 mil") (traceCount "1") (impedance nil))) (ShuntTerm ((resistance "50 ohm") (voltage "5 V") (maxDelay "0.1 ns"))) (TheveninTerm ((resistanceUp "180 ohm") (resistanceDown "270 ohm") (voltageUp "5 V") (voltageDown "0 V") (maxDelay "0.1 ns"))) (Connector nil) (RCTerm ((resistance "50 ohm") (capacitance "20 pF") (voltage "5 V") (maxDelay "0.1 ns"))) (LowClampTerm ((cutoffVoltage "0.7 V") (voltage "0 V") (maxDelay "0.1 ns"))) (HiClampTerm ((cutoffVoltage "0.7 V") (voltage "5 V") (maxDelay "0.1 ns"))) (DualClampTerm ((cutoffVoltageUp "0.7 V") (cutoffVoltageDown "0.7 V") (voltageUp "5 V") (voltageDown "0 V") (maxDelay "0.1 ns"))) (Diode ((cutoffVoltage "0.7 V")))))
				)
				( objectStatus "PCIE_C_D" )
			)
			( electricalCSet "@crescent_city_bb_fab1_lib.crescent_city_bb_fab1(sch_1):\DMI_CPU0_PCH_RX_C_DN_0_\"
				( groupRef "DMI:MG_DMI_L0" )
				( groupRef "DMI:MG_DMI_L1" )
				( pinPairRef "DMI:U7C1.H46:C3M44.1" )
				( pinPairRef "DMI:C3M44.2:U5D1.CK9" )
				( pinPairRef "DMI:U7C1.H46:U5D1.CK9" )
				( attribute "DIFFP_GATHER_CONTROL" "IGNORE"
					( Origin gBackEnd )
				)
				( attribute "DIFFP_COUPLED_PLUS" "0.05"
					( Origin gBackEnd )
				)
				( attribute "DIFFP_COUPLED_MINUS" "0.02"
					( Origin gBackEnd )
				)
				( attribute "DIFFP_PHASE_TOL" "5 mil"
					( Units "uPhaseTol" "ns" 1.000000)
					( Origin gBackEnd )
				)
				( attribute "DIFFP_PHASE_MAX_LENGTH" "600.00"
					( Origin gBackEnd )
				)
				( attribute "DIFFP_PHASE_TOL_DYNAMIC" "30 mil"
					( Units "uPhaseTol" "mil" 1.000000)
					( Origin gBackEnd )
				)
				( attribute "DIFFP_MIN_SPACE" "3.98"
					( Origin gBackEnd )
				)
				( attribute "TOPOLOGY_TEMPLATE_REVISION" "1.0"
					( Origin gBackEnd )
				)
				( topologyData 23125
(SKIDL (Circuits ("MAIN" (Parts ("CRESCENT_CITY_176_20141216_Q.@@U22.H46" IbisIOPkg (xy (5502 4240)) (refDes "U7C1") (model "Unknown") (Props (_SXDesignName "CRESCENT_CITY_176_20141216_Q") (brdx "14875.25 MIL") (brdy "4494 MIL") (bufferModel "CDSDefaultIO_2p5v") (cycle "1") (hold "1.0e-09") (mappingTag "") (offsets ("4" "0") ("5" "0")) (setup "2.0e-09") (state "tristate") (stimuli ("4" "local1") ("5" "local2")) (temperature "27") (termMap ("4" "Data") ("5" "Enable"))) (Terms ("CRESCENT_CITY_176_20141216_Q.X1487525Y449400L2LRATS" "H46"))) ("CRESCENT_CITY_176_20141216_Q.@@U36.CK9" IbisInputPkg (xy (5526 4223)) (refDes "U5D1") (model "Unknown") (Props (_SXDesignName "CRESCENT_CITY_176_20141216_Q") (brdx "11826.09 MIL") (brdy "3370.96 MIL") (bufferModel "CDSDefaultInput_2p5v") (mappingTag "") (temperature "27")) (Terms ("CRESCENT_CITY_176_20141216_Q.X1182609Y337096L2LRATS" "CK9"))) ("CRESCENT_CITY_176_20141216_Q.T@@RATS@@U22.H46@@C386.1" TLine (xy (5503 4229)) (mirror x) (refDes "TL1") (Props (_SXDesignName "CRESCENT_CITY_176_20141216_Q") (impedance "50.521 ohm") length("399.25 MIL") (propDelay "0.07171 ns") (traceCount "1") (traceGeometry "Microstrip") (velocity "5567.56 mil/ns")) (Terms ("CRESCENT_CITY_176_20141216_Q.X1487525Y449400L2LRATS" "1") ("CRESCENT_CITY_176_20141216_Q.X1454500Y442500L28LRATS" "2"))) ("CRESCENT_CITY_176_20141216_Q.T@@RATS@@U36.CK9@@C386.2" TLine (xy (5512 4223)) (mirror x) (refDes "TL2") (Props (_SXDesignName "CRESCENT_CITY_176_20141216_Q") (impedance "47.169 ohm") length("3737.95 MIL") (propDelay "0.67136 ns") (traceCount "1") (traceGeometry "Microstrip") (velocity "5567.72 mil/ns")) (Terms ("CRESCENT_CITY_176_20141216_Q.X1182609Y337096L2LRATS" "1") ("CRESCENT_CITY_176_20141216_Q.X1451000Y442500L28LRATS" "2"))) ("CRESCENT_CITY_176_20141216_Q.@@C386.1.2" Capacitor (xy (5503 4223)) (refDes "C3M44") (value "220000 pF") (Props (_SXDesignName "CRESCENT_CITY_176_20141216_Q")) (Terms ("CRESCENT_CITY_176_20141216_Q.X1454500Y442500L28LRATS" "1") ("CRESCENT_CITY_176_20141216_Q.X1451000Y442500L28LRATS" "2")))) (Nodes ("CRESCENT_CITY_176_20141216_Q.X1454500Y442500L28LRATS" (terms "CRESCENT_CITY_176_20141216_Q.@@C386.1.2.1" "CRESCENT_CITY_176_20141216_Q.T@@RATS@@U22.H46@@C386.1.2")) ("CRESCENT_CITY_176_20141216_Q.X1182609Y337096L2LRATS" (terms "CRESCENT_CITY_176_20141216_Q.T@@RATS@@U36.CK9@@C386.2.1" "CRESCENT_CITY_176_20141216_Q.@@U36.CK9.1")) ("CRESCENT_CITY_176_20141216_Q.X1451000Y442500L28LRATS" (terms "CRESCENT_CITY_176_20141216_Q.@@C386.1.2.2" "CRESCENT_CITY_176_20141216_Q.T@@RATS@@U36.CK9@@C386.2.2")) ("CRESCENT_CITY_176_20141216_Q.X1487525Y449400L2LRATS" (terms "CRESCENT_CITY_176_20141216_Q.T@@RATS@@U22.H46@@C386.1.1" "CRESCENT_CITY_176_20141216_Q.@@U22.H46.1"))) (Ports) (Stimuli ("local2" (scope local) (stimType periodic) (Props (periodicFreq "5e+007") (periodicJitter "0") (periodicPattern "1"))) ("local1" (scope local) (stimType periodic) (Props (periodicFreq "5e+007") (periodicJitter "0") (periodicPattern "1")))) (Notes) (Constraints ("DELAY_RULE" ("CRESCENT_CITY_176_20141216_Q U22.H46" "CRESCENT_CITY_176_20141216_Q U36.CK9" "LENGTH" "" "LENGTH" "0.381")) ("DP_MIN_LINE_SPACING" "0.0001016") ("DP_PHASE_TOLERANCE" ("LENGTH" "0.000127")) ("DP_POSITIVE_COUPLED_TOLERANCE" "1.27e-006") ("RELATIVE_PROPAGATION_DELAY" ("M1" "CRESCENT_CITY_176_20141216_Q U22.H46" "CRESCENT_CITY_176_20141216_Q C386.1" "LOCAL" "LENGTH" "0.000127" "DELAY" "") ("M1" "CRESCENT_CITY_176_20141216_Q C386.2" "CRESCENT_CITY_176_20141216_Q U36.CK9" "LOCAL" "LENGTH" "0.000127" "DELAY" ""))) (MeasurementSets ("EMI" ("EMIStatus" status("on")) ("PeakEmission" status("on")) ("PeakFrequency" status("on")) ("PulseFreq" status("on")) ("RiseTime" status("on")) ("VoltageSwing" status("on"))) ("Reflection" ("BufferDelayFall" status("off")) ("BufferDelayRise" status("off")) ("EyeHeight" status("off")) ("EyeJitter" status("off")) ("EyeWidth" status("off")) ("FirstIncidentFall" status("off")) ("FirstIncidentRise" status("off")) ("Glitch" status("on")) ("GlitchFall" status("off")) ("GlitchRise" status("off")) ("Monotonic" status("on")) ("MonotonicFall" status("off")) ("MonotonicRise" status("off")) ("NoiseMargin" status("on")) ("NoiseMarginHigh" status("off")) ("NoiseMarginLow" status("off")) ("OvershootHigh" status("on")) ("OvershootLow" status("on")) ("PropDelay" status("on")) ("SettleDelay" status("on")) ("SettleDelayFall" status("off")) ("SettleDelayRise" status("off")) ("SwitchDelay" status("on")) ("SwitchDelayFall" status("off")) ("SwitchDelayRise" status("off"))) ("Crosstalk" ("Crosstalk" status("on"))) ("Custom")) (VectorSets) (Props (XnetName "DMI_CPU0_PCH_RX_C_DN<0>") (allDrivers "active") (customSimType "Reflection") (ftsMode ("Typ")) (rcvrSelect "all") (tlineDelayMode "time") (userRevision "1.0")))) (Subckts) (CrossSections ("CRESCENT_CITY_176_20141216_Q" (Props (SXDesignName "CRESCENT_CITY_176_20141216_Q")) (Layers ("" (layerType "SURFACE") (material "AIR") (thickness "0 mil") (dielectricConstant "1.000000") (lossTangent "0") (etchFactor "0.000000") (elecCondVal "0 mho/cm") (thermCondVal "0 w/cm-degC")) ("" (layerType "DIELECTRIC") (material "CONFORMAL_COAT") (thickness "0.5 mil") (dielectricConstant "3.800000") (lossTangent "0.035") (etchFactor "0.000000") (elecCondVal "0 mho/cm") (thermCondVal "0.012 w/cm-degC")) ("TOP" (layerType "CONDUCTOR") (material "COPPER") (thickness "  2.100000 mil") (width "4.00 MIL") (dielectricConstant "4.500000") (lossTangent "0") (etchFactor "70.000000") (elecCondVal "595900.000000 mho/cm") (thermCondVal "0 w/cm-degC") (signalDieConstant "3.800000") (signalLossTangent "0.035")) ("" (layerType "DIELECTRIC") (material "FR-4") (thickness "  2.670000 mil") (dielectricConstant "4.000000") (lossTangent "0.035") (etchFactor "0.000000") (elecCondVal "0 mho/cm") (thermCondVal "0.012 w/cm-degC")) ("L2_GND1" (layerType "PLANE") (material "COPPER") (isShield t) (thickness "  1.250000 mil") (dielectricConstant "4.500000") (lossTangent "0.035") (etchFactor "90.000000") (elecCondVal "595900.000000 mho/cm") (thermCondVal "0.012 w/cm-degC")) ("" (layerType "DIELECTRIC") (material "FR-4") (thickness "  9.000000 mil") (dielectricConstant "4.100000") (lossTangent "0.035") (etchFactor "0.000000") (elecCondVal "0 mho/cm") (thermCondVal "0.012 w/cm-degC")) ("L3_SIG1" (layerType "CONDUCTOR") (material "COPPER") (thickness "  1.250000 mil") (width "4.00 MIL") (dielectricConstant "4.500000") (lossTangent "0.035") (etchFactor "90.000000") (elecCondVal "595900.000000 mho/cm") (thermCondVal "0.012 w/cm-degC") (signalDieConstant "4.100000") (signalLossTangent "0.035")) ("" (layerType "DIELECTRIC") (material "FR-4") (thickness "  3.000000 mil") (dielectricConstant "4.500000") (lossTangent "0.035") (etchFactor "0.000000") (elecCondVal "0 mho/cm") (thermCondVal "0 w/cm-degC")) ("L4_GND2" (layerType "PLANE") (material "COPPER") (isShield t) (thickness "  1.250000 mil") (dielectricConstant "4.500000") (lossTangent "0.035") (etchFactor "90.000000") (elecCondVal "595900.000000 mho/cm") (thermCondVal "0 w/cm-degC")) ("" (layerType "DIELECTRIC") (material "FR-4") (thickness "  9.000000 mil") (dielectricConstant "4.000000") (lossTangent "0.035") (etchFactor "0.000000") (elecCondVal "0 mho/cm") (thermCondVal "0.012 w/cm-degC")) ("L5_SIG2" (layerType "CONDUCTOR") (material "COPPER") (thickness "  1.250000 mil") (width "4.00 MIL") (dielectricConstant "4.500000") (lossTangent "0.035") (etchFactor "90.000000") (elecCondVal "595900.000000 mho/cm") (thermCondVal "0.012 w/cm-degC") (signalDieConstant "4.000000") (signalLossTangent "0.035")) ("" (layerType "DIELECTRIC") (material "FR-4") (thickness "  3.000000 mil") (dielectricConstant "4.500000") (lossTangent "0.035") (etchFactor "0.000000") (elecCondVal "0 mho/cm") (thermCondVal "0 w/cm-degC")) ("L6_GND3" (layerType "PLANE") (material "COPPER") (isShield t) (thickness "  1.250000 mil") (dielectricConstant "4.500000") (lossTangent "0.035") (etchFactor "90.000000") (elecCondVal "595900.000000 mho/cm") (thermCondVal "0 w/cm-degC")) ("" (layerType "DIELECTRIC") (material "FR-4") (thickness "  4.500000 mil") (dielectricConstant "4.100000") (lossTangent "0.035") (etchFactor "0.000000") (elecCondVal "0 mho/cm") (thermCondVal "0.012 w/cm-degC")) ("L7_PWR1-SIG" (layerType "PLANE") (material "COPPER") (isShield t) (thickness "  2.400000 mil") (dielectricConstant "4.500000") (lossTangent "0.035") (etchFactor "90.000000") (elecCondVal "595900.000000 mho/cm") (thermCondVal "0.012 w/cm-degC")) ("" (layerType "DIELECTRIC") (material "FR-4") (thickness "  4.600000 mil") (dielectricConstant "4.000000") (lossTangent "0.035") (etchFactor "0.000000") (elecCondVal "0 mho/cm") (thermCondVal "0.012 w/cm-degC")) ("L8_PWR2-SIG" (layerType "PLANE") (material "COPPER") (isShield t) (thickness "  2.400000 mil") (dielectricConstant "4.500000") (lossTangent "0.035") (etchFactor "90.000000") (elecCondVal "595900.000000 mho/cm") (thermCondVal "0.012 w/cm-degC")) ("" (layerType "DIELECTRIC") (material "FR-4") (thickness "  4.500000 mil") (dielectricConstant "4.500000") (lossTangent "0.035") (etchFactor "0.000000") (elecCondVal "0 mho/cm") (thermCondVal "0 w/cm-degC")) ("L9_GND4" (layerType "PLANE") (material "COPPER") (isShield t) (thickness "  1.250000 mil") (dielectricConstant "4.500000") (lossTangent "0.035") (etchFactor "90.000000") (elecCondVal "595900.000000 mho/cm") (thermCondVal "0 w/cm-degC")) ("" (layerType "DIELECTRIC") (material "FR-4") (thickness "  3.000000 mil") (dielectricConstant "4.100000") (lossTangent "0.035") (etchFactor "0.000000") (elecCondVal "0 mho/cm") (thermCondVal "0.012 w/cm-degC")) ("L10_SIG3" (layerType "CONDUCTOR") (material "COPPER") (thickness "  1.250000 mil") (width "4.00 MIL") (dielectricConstant "4.500000") (lossTangent "0.035") (etchFactor "90.000000") (elecCondVal "595900.000000 mho/cm") (thermCondVal "0.012 w/cm-degC") (signalDieConstant "4.100000") (signalLossTangent "0.035")) ("" (layerType "DIELECTRIC") (material "FR-4") (thickness "  9.000000 mil") (dielectricConstant "4.500000") (lossTangent "0.035") (etchFactor "0.000000") (elecCondVal "0 mho/cm") (thermCondVal "0 w/cm-degC")) ("L11_GND5" (layerType "PLANE") (material "COPPER") (isShield t) (thickness "  1.250000 mil") (dielectricConstant "4.500000") (lossTangent "0.035") (etchFactor "90.000000") (elecCondVal "595900.000000 mho/cm") (thermCondVal "0 w/cm-degC")) ("" (layerType "DIELECTRIC") (material "FR-4") (thickness "  3.000000 mil") (dielectricConstant "4.500000") (lossTangent "0.035") (etchFactor "0.000000") (elecCondVal "0 mho/cm") (thermCondVal "0.012 w/cm-degC")) ("L12_SIG4" (layerType "CONDUCTOR") (material "COPPER") (thickness "  1.250000 mil") (width "4.00 MIL") (dielectricConstant "4.500000") (lossTangent "0.035") (etchFactor "90.000000") (elecCondVal "595900.000000 mho/cm") (thermCondVal "0.012 w/cm-degC") (signalDieConstant "4.500000") (signalLossTangent "0.035")) ("" (layerType "DIELECTRIC") (material "FR-4") (thickness "  9.000000 mil") (dielectricConstant "4.500000") (lossTangent "0.035") (etchFactor "0.000000") (elecCondVal "0 mho/cm") (thermCondVal "0 w/cm-degC")) ("L13_GND6" (layerType "PLANE") (material "COPPER") (isShield t) (thickness "  1.250000 mil") (dielectricConstant "4.500000") (lossTangent "0.035") (etchFactor "90.000000") (elecCondVal "595900.000000 mho/cm") (thermCondVal "0.012 w/cm-degC")) ("" (layerType "DIELECTRIC") (material "FR-4") (thickness "  2.670000 mil") (dielectricConstant "4.500000") (lossTangent "0.035") (etchFactor "0.000000") (elecCondVal "0 mho/cm") (thermCondVal "0.012 w/cm-degC")) ("BOTTOM" (layerType "CONDUCTOR") (material "COPPER") (thickness "  2.100000 mil") (width "4.00 MIL") (dielectricConstant "4.500000") (lossTangent "0") (etchFactor "70.000000") (elecCondVal "595900.000000 mho/cm") (thermCondVal "0 w/cm-degC") (signalDieConstant "3.800000") (signalLossTangent "0.035")) ("" (layerType "DIELECTRIC") (material "CONFORMAL_COAT") (thickness "0.5 mil") (dielectricConstant "3.800000") (lossTangent "0.035") (etchFactor "0.000000") (elecCondVal "0 mho/cm") (thermCondVal "0.012 w/cm-degC")) ("" (layerType "SURFACE") (material "AIR") (thickness "0 mil") (dielectricConstant "1.000000") (lossTangent "0") (etchFactor "0.000000") (elecCondVal "0 mho/cm") (thermCondVal "0 w/cm-degC"))))) (Props (DesUnits "mils 2") (LayerStack ("DIELECTRIC" "DIELECTRIC" "BOTTOM" "DIELECTRIC" "L13_GND6" "DIELECTRIC" "L12_SIG4" "DIELECTRIC" "L11_GND5" "DIELECTRIC" "L10_SIG3" "DIELECTRIC" "L9_GND4" "DIELECTRIC" "L8_PWR2-SIG" "DIELECTRIC" "L7_PWR1-SIG" "DIELECTRIC" "L6_GND3" "DIELECTRIC" "L5_SIG2" "DIELECTRIC" "L4_GND2" "DIELECTRIC" "L3_SIG1" "DIELECTRIC" "L2_GND1" "DIELECTRIC" "TOP" "DIELECTRIC" "DIELECTRIC")) (Revision "16.600")) (Params (Via ((model "Unknown") (viaOutputFormat "Unknown") (viaPadstack nil) (viaTopLayer nil) (viaBottomLayer nil) (viaIsPower nil) (viaIsGround nil))) (IbisIOMacro ((temperature "27") (bufferModel "CDSDefaultIO_2p5v") (stimuli nil) (offsets nil) (state "tristate") (cycle "1") (termMap nil) (setup "2.0e-09") (hold "1.0e-09") (rise nil) (fall nil) (macroType nil) (voltage nil) (spice nil) (LEFDEFPinName nil) (LEFDEFPinType nil) (mappingTag nil))) (DiffInputPkg ((temperature "27") (bufferModelNonInverting "CDSDefaultInput_2p5v") (bufferModelInverting "CDSDefaultInput_2p5v") (threshInputHighMin "1.7 V") (threshInputHighTyp "1.7  V") (threshInputHighMax "1.7  V") (threshInputLowMin "0.7  V") (threshInputLowTyp "0.7  V") (threshInputLowMax "0.7  V") (mappingTagNonInverting nil) (mappingTagInverting nil) (cycle "1"))) (DiffIO ((temperature "27") (bufferModelNonInverting "CDSDefaultIO_2p5v") (bufferModelInverting "CDSDefaultIO_2p5v") (stimuli nil) (offsets nil) (state "tristate") (cycle "1") (termMap nil) (setup "0.9e-09") (hold "0.4e-09") (rise nil) (fall nil) (threshInputHighMin "1.7 V") (threshInputHighTyp "1.7  V") (threshInputHighMax "1.7  V") (threshInputLowMin "0.7  V") (threshInputLowTyp "0.7  V") (threshInputLowMax "0.7 ") (threshOutputHighMin "2.365  V") (threshOutputHighTyp "2.5  V") (threshOutputHighMax "2.625  V") (threshOutputLowMin "1.275  V") (threshOutputLowTyp "1.7  V") (threshOutputLowMax "1.985  V") (mappingTagNonInverting nil) (mappingTagInverting nil) (spice nil))) (Trace ((d1Thickness "10 mil") (d1Constant "4.5") (d1LossTangent "0.035") (d2Thickness "10 mil") (d2Constant "4.5") (d2LossTangent "0.035") (d3Thickness "0.0") (d3Constant "1.0") (d3LossTangent "0") length("1000 mil") (spacing "5 mil") (spacing2 "5 mil") (spacing3 "5 mil") (spacing4 "5 mil") (spacing5 "5 mil") (traceConductivity "595900 mho/cm") (traceGeometry "microstrip") (traceLayerName "") (traceThickness "0.72 mil") (traceType "single") (traceWidth "5.0 mil") (traceWidth2 "5.0 mil") (traceWidth3 "5.0 mil") (traceWidth4 "5.0 mil") (traceWidth5 "5.0 mil") (traceWidth6 "5.0 mil") (offset "0 mil") (traceCount "1") (impedance nil))) (sync ((syncFreq "100e6") (syncInitState "1") (syncPattern "10") (syncEdgeSwitch "rise"))) (DiffOutputPkg ((temperature "27") (bufferModelNonInverting "CDSDefaultOutput_2p5v") (bufferModelInverting "CDSDefaultOutput_2p5v") (stimuli nil) (offsets nil) (state "tristate") (cycle "1") (termMap nil) (setup "0.9e-09") (hold "0.4e-09") (rise nil) (fall nil) (threshOutputHighMin "2.375  V") (threshOutputHighTyp "2.5  V") (threshOutputHighMax "2.625  V") (threshOutputLowMin "1.275  V") (threshOutputLowTyp "1.7  V") (threshOutputLowMax "1.985  V") (mappingTagNonInverting nil) (mappingTagInverting nil) (spice nil))) (DiffOutput ((temperature "27") (bufferModelNonInverting "CDSDefaultOutput_2p5v") (bufferModelInverting "CDSDefaultOutput_2p5v") (stimuli nil) (offsets nil) (state "tristate") (cycle "1") (termMap nil) (setup "0.9e-09") (hold "0.4e-09") (rise nil) (fall nil) (threshOutputHighMin "2.375  V") (threshOutputHighTyp "2.5  V") (threshOutputHighMax "2.625  V") (threshOutputLowMin "1.275  V") (threshOutputLowTyp "1.7  V") (threshOutputLowMax "1.985  V") (mappingTagNonInverting nil) (mappingTagInverting nil) (spice nil))) (IbisOutputPkg ((temperature "27") (bufferModel "CDSDefaultOutput_2p5v") (stimuli nil) (offsets nil) (state "tristate") (cycle "1") (termMap nil) (setup "2.0e-09") (hold "1.0e-09") (rise nil) (fall nil) (macroType nil) (voltage nil) (spice nil) (LEFDEFPinName nil) (LEFDEFPinType nil) (mappingTag nil))) (DiffIOPkg ((temperature "27") (bufferModelNonInverting "CDSDefaultIO_2p5v") (bufferModelInverting "CDSDefaultIO_2p5v") (stimuli nil) (offsets nil) (state "tristate") (cycle "1") (termMap nil) (setup "0.9e-09") (hold "0.4e-09") (rise nil) (fall nil) (threshInputHighMin "1.7 V") (threshInputHighTyp "1.7  V") (threshInputHighMax "1.7  V") (threshInputLowMin "0.7  V") (threshInputLowTyp "0.7  V") (threshInputLowMax "0.7 ") (threshOutputHighMin "2.365  V") (threshOutputHighTyp "2.5  V") (threshOutputHighMax "2.625  V") (threshOutputLowMin "1.275  V") (threshOutputLowTyp "1.7  V") (threshOutputLowMax "1.985  V") (mappingTagNonInverting nil) (mappingTagInverting nil) (spice nil))) (IbisIOPkg ((temperature "27") (bufferModel "CDSDefaultIO_2p5v") (stimuli nil) (offsets nil) (state "tristate") (cycle "1") (termMap nil) (setup "2.0e-09") (hold "1.0e-09") (rise nil) (fall nil) (macroType nil) (voltage nil) (spice nil) (LEFDEFPinName nil) (LEFDEFPinType nil) (mappingTag nil))) (CurrentProbe nil) (DiffInput ((temperature "27") (bufferModelNonInverting "CDSDefaultInput_2p5v") (bufferModelInverting "CDSDefaultInput_2p5v") (threshInputHighMin "1.7 V") (threshInputHighTyp "1.7  V") (threshInputHighMax "1.7  V") (threshInputLowMin "0.7  V") (threshInputLowTyp "0.7  V") (threshInputLowMax "0.7  V") (mappingTagNonInverting nil) (mappingTagInverting nil) (cycle "1"))) (IbisInputPkg ((temperature "27") (bufferModel "CDSDefaultInput_2p5v") (cycle "1") (LEFDEFPinName nil) (LEFDEFPinType nil) (mappingTag nil))) (idlCircuit ((allDrivers "active") (ftsMode '("Typ")) (rcvrSelect "all") (simMode "Reflection") (tlineDelayMode "time") (userRevision "1.0") (autoSolve "On"))) (SeriesTerm ((resistance "22 ohm") (maxDelay "0.1 ns"))) (RLGC (length("1000 mil"))) (periodic ((periodicFreq "100e6") (periodicPattern "10") (periodicJitter "0"))) (Resistor ((resistance "50 ohm") (orientation "0"))) (async ((asyncTimePoints "") (asyncInitState "1"))) (Capacitor ((capacitance "10 pF") (orientation "0"))) (Inductor ((inductance "5 nH") (orientation "0"))) (clocked ((clockRise "1e-09") (clockFall "1e-09") (clockFreq "100e6") (clockInitState "0") (clockDutyCycle "0.5") (clockJitter "0"))) (TLine ((diffImpedance "100ohm") (diffVelocity "1.4142e+08M/s") (impedance "60ohm") length("2800 mil") (propDelay "0.5 ns") (velocity "5600 mil/ns") (traceCount "1") (traceGeometry "Microstrip") (impedanceMin nil) (impedanceMax nil) (lengthMin nil) (lengthMax nil) (propDelayMin nil) (propDelayMax nil) (impedanceSweepCount nil) (propDelaySweepCount nil) (velocitySweepCount nil) (lengthSweepCount nil) (matchSetName nil))) (Cable (length("1 m"))) (DualClampTerm ((cutoffVoltageUp "0.7 V") (cutoffVoltageDown "0.7 V") (voltageUp "5 V") (voltageDown "0 V") (maxDelay "0.1 ns"))) (LowClampTerm ((cutoffVoltage "0.7 V") (voltage "0 V") (maxDelay "0.1 ns"))) (HiClampTerm ((cutoffVoltage "0.7 V") (voltage "5 V") (maxDelay "0.1 ns"))) (RCTerm ((resistance "50 ohm") (capacitance "20 pF") (voltage "5 V") (maxDelay "0.1 ns"))) (IbisOutput ((temperature "27") (bufferModel "CDSDefaultOutput_2p5v") (stimuli nil) (offsets nil) (state "tristate") (cycle "1") (termMap nil) (setup "2.0e-09") (hold "1.0e-09") (rise nil) (fall nil) (macroType nil) (voltage nil) (spice nil) (LEFDEFPinName nil) (LEFDEFPinType nil) (mappingTag nil))) (IbisIO ((temperature "27") (bufferModel "CDSDefaultIO_2p5v") (stimuli nil) (offsets nil) (state "tristate") (cycle "1") (termMap nil) (setup "2.0e-09") (hold "1.0e-09") (rise nil) (fall nil) (macroType nil) (voltage nil) (spice nil) (LEFDEFPinName nil) (LEFDEFPinType nil) (mappingTag nil))) (Diode ((cutoffVoltage "0.7 V"))) (IbisInput ((temperature "27") (bufferModel "CDSDefaultInput_2p5v") (cycle "1") (LEFDEFPinName nil) (LEFDEFPinType nil) (mappingTag nil))) (ESpiceDevice nil) (CPW ((d1Thickness "10 mil") (d1Constant "4.5") (d1LossTangent "0.035") (d2Thickness "0.72 mil") (d2Constant "1") (d2LossTangent "0") (d3Thickness "0.0") (d3Constant "1") (d3LossTangent "0") length("1000 mil") (spacing "5 mil") (spacing2 "5 mil") (spacing3 "5 mil") (spacing4 "5 mil") (spacing5 "5 mil") (traceConductivity "595900 mho/cm") (traceGeometry "cpwms") (traceLayerName "") (traceThickness "0.72 mil") (traceType "single") (traceWidth "5.0 mil") (traceWidth2 "5.0 mil") (traceWidth3 "5.0 mil") (traceWidth4 "5.0 mil") (traceWidth5 "5.0 mil") (traceWidth6 "5.0 mil") (offset "0 mil") (traceCount "1") (impedance nil))) (IbisOutput_OpenPullUp ((temperature "27") (bufferModel "CDSDefaultOutput_2p5v") (stimuli nil) (offsets nil) (state "tristate") (cycle "1") (termMap nil) (setup "2.0e-09") (hold "1.0e-09") (rise nil) (fall nil) (macroType nil) (voltage nil) (spice nil) (LEFDEFPinName nil) (LEFDEFPinType nil) (mappingTag nil))) (CPWMS ((d1Thickness "10 mil") (d1Constant "4.5") (d1LossTangent "0.035") (d2Thickness "0.72 mil") (d2Constant "4.5") (d2LossTangent "0.035") (d3Thickness "0.0") (d3Constant "1") (d3LossTangent "0") length("1000 mil") (spacing "5 mil") (spacing2 "5 mil") (spacing3 "5 mil") (spacing4 "5 mil") (spacing5 "5 mil") (traceConductivity "595900 mho/cm") (traceGeometry "cpwms") (traceLayerName "") (traceThickness "0.72 mil") (traceType "single") (traceWidth "5.0 mil") (traceWidth2 "5.0 mil") (traceWidth3 "5.0 mil") (traceWidth4 "5.0 mil") (traceWidth5 "5.0 mil") (traceWidth6 "5.0 mil") (offset "0 mil") (traceCount "1") (impedance nil))) (IbisIO_OpenPullDown ((temperature "27") (bufferModel "CDSDefaultIO_2p5v") (stimuli nil) (offsets nil) (state "tristate") (cycle "1") (termMap nil) (setup "2.0e-09") (hold "1.0e-09") (rise nil) (fall nil) (macroType nil) (voltage nil) (spice nil) (LEFDEFPinName nil) (LEFDEFPinType nil) (mappingTag nil))) (Connector nil) (CPWSL ((d1Thickness "10 mil") (d1Constant "4.5") (d1LossTangent "0.035") (d2Thickness "0.72 mil") (d2Constant "4.5") (d2LossTangent "0.035") (d3Thickness "10 mil") (d3Constant "4.5") (d3LossTangent "0.035") length("1000 mil") (spacing "5 mil") (spacing2 "5 mil") (spacing3 "5 mil") (spacing4 "5 mil") (spacing5 "5 mil") (traceConductivity "595900 mho/cm") (traceGeometry "cpwms") (traceLayerName "") (traceThickness "0.72 mil") (traceType "single") (traceWidth "5.0 mil") (traceWidth2 "5.0 mil") (traceWidth3 "5.0 mil") (traceWidth4 "5.0 mil") (traceWidth5 "5.0 mil") (traceWidth6 "5.0 mil") (offset "0 mil") (traceCount "1") (impedance nil))) (IbisIO_OpenPullUp ((temperature "27") (bufferModel "CDSDefaultIO_2p5v") (stimuli nil) (offsets nil) (state "tristate") (cycle "1") (termMap nil) (setup "2.0e-09") (hold "1.0e-09") (rise nil) (fall nil) (macroType nil) (voltage nil) (spice nil) (LEFDEFPinName nil) (LEFDEFPinType nil) (mappingTag nil))) (TheveninTerm ((resistanceUp "180 ohm") (resistanceDown "270 ohm") (voltageUp "5 V") (voltageDown "0 V") (maxDelay "0.1 ns"))) (ShuntTerm ((resistance "50 ohm") (voltage "5 V") (maxDelay "0.1 ns"))) (Source ((voltage "5 V")))))
				)
				( objectStatus "DMI" )
			)
			( electricalCSet "@crescent_city_bb_fab1_lib.crescent_city_bb_fab1(sch_1):\PCIE_DEVICE_C\"
				( groupRef "PCIE_DEVICE:MG" )
				( groupRef "PCIE_DEVICE:MG_PCIE_L1" )
				( groupRef "PCIE_DEVICE:MG_PCIE_L0" )
				( pinPairRef "PCIE_DEVICE:U5D1.DW4:U7C1.A59" )
				( pinPairRef "PCIE_DEVICE:U5D1.DW4:C6B15.1" )
				( pinPairRef "PCIE_DEVICE:C6B15.2:U7C1.A59" )
				( attribute "DIFFP_GATHER_CONTROL" "IGNORE"
					( Origin gBackEnd )
				)
				( attribute "DIFFP_UNCOUPLED_LENGTH" "1000.00"
					( Origin gBackEnd )
				)
				( attribute "DIFFP_COUPLED_PLUS" "0.10"
					( Origin gBackEnd )
				)
				( attribute "DIFFP_COUPLED_MINUS" "0.10"
					( Origin gBackEnd )
				)
				( attribute "DIFFP_PHASE_TOL" "5 mil"
					( Units "uPhaseTol" "ns" 1.000000)
					( Origin gBackEnd )
				)
				( attribute "TOPOLOGY_TEMPLATE_REVISION" "1.0"
					( Origin gBackEnd )
				)
				( topologyData 23901
(SKIDL (Circuits ("MAIN" (Parts ("CRESCENT_CITY_177_20141217_Q.@@U22.A59" IbisIOPkg (xy (5539 4240)) (refDes "U7C1") (model "Unknown") (Props (_SXDesignName "CRESCENT_CITY_177_20141217_Q") (brdx "14750.98 MIL") (brdy "4718.7 MIL") (bufferModel "CDSDefaultIO_2p5v") (cycle "1") (hold "1.0e-09") (mappingTag "") (offsets ("4" "0") ("5" "0")) (setup "2.0e-09") (state "tristate") (stimuli ("4" "local126") ("5" "local127")) (temperature "27") (termMap ("4" "Data") ("5" "Enable"))) (Terms ("CRESCENT_CITY_177_20141217_Q.X1475098Y471870L2LRATS" "A59"))) ("CRESCENT_CITY_177_20141217_Q.@@U36.DW4" IbisOutputPkg (xy (5498 4235)) (refDes "U5D1") (model "Unknown") (Props (_SXDesignName "CRESCENT_CITY_177_20141217_Q") (brdx "11995.09 MIL") (brdy "3936.47 MIL") (bufferModel "CDSDefaultOutput_2p5v") (cycle "1") (hold "1.0e-09") (mappingTag "") (offsets ("4" "0")) (setup "2.0e-09") (state "tristate") (stimuli ("4" "local128")) (temperature "27") (termMap ("4" "Data"))) (Terms ("CRESCENT_CITY_177_20141217_Q.X1199509Y393647L2LRATS" "DW4"))) ("CRESCENT_CITY_177_20141217_Q.T@@RATS@@C3667.2@@U22.A59" TLine (xy (5530 4235)) (refDes "TL6") (Props (_SXDesignName "CRESCENT_CITY_177_20141217_Q") (impedance "52.449 ohm") length("1865.29 MIL") (propDelay "0.33502 ns") (traceCount "1") (traceGeometry "Microstrip") (velocity "5567.72 mil/ns")) (Terms ("CRESCENT_CITY_177_20141217_Q.X1291812Y475113L2LRATS" "1") ("CRESCENT_CITY_177_20141217_Q.X1475098Y471870L2LRATS" "2"))) ("CRESCENT_CITY_177_20141217_Q.T@@RATS@@U36.DW4@@C3667.1" TLine (xy (5506 4235)) (refDes "TL7") (Props (_SXDesignName "CRESCENT_CITY_177_20141217_Q") (impedance "52.449 ohm") length("1702.69 MIL") (propDelay "0.30581 ns") (traceCount "1") (traceGeometry "Microstrip") (velocity "5567.8 mil/ns")) (Terms ("CRESCENT_CITY_177_20141217_Q.X1199509Y393647L2LRATS" "1") ("CRESCENT_CITY_177_20141217_Q.X1288312Y475113L2LRATS" "2"))) ("CRESCENT_CITY_177_20141217_Q.@@C3667.2.1" Capacitor (xy (5515 4235)) (mirror x) (refDes "C6B15") (value "220000 pF") (Props (_SXDesignName "CRESCENT_CITY_177_20141217_Q")) (Terms ("CRESCENT_CITY_177_20141217_Q.X1291812Y475113L2LRATS" "2") ("CRESCENT_CITY_177_20141217_Q.X1288312Y475113L2LRATS" "1")))) (Nodes ("CRESCENT_CITY_177_20141217_Q.X1291812Y475113L2LRATS" (terms "CRESCENT_CITY_177_20141217_Q.@@C3667.2.1.1" "CRESCENT_CITY_177_20141217_Q.T@@RATS@@C3667.2@@U22.A59.1")) ("CRESCENT_CITY_177_20141217_Q.X1288312Y475113L2LRATS" (terms "CRESCENT_CITY_177_20141217_Q.@@C3667.2.1.2" "CRESCENT_CITY_177_20141217_Q.T@@RATS@@U36.DW4@@C3667.1.2")) ("CRESCENT_CITY_177_20141217_Q.X1475098Y471870L2LRATS" (terms "CRESCENT_CITY_177_20141217_Q.T@@RATS@@C3667.2@@U22.A59.2" "CRESCENT_CITY_177_20141217_Q.@@U22.A59.1")) ("CRESCENT_CITY_177_20141217_Q.X1199509Y393647L2LRATS" (terms "CRESCENT_CITY_177_20141217_Q.T@@RATS@@U36.DW4@@C3667.1.1" "CRESCENT_CITY_177_20141217_Q.@@U36.DW4.1"))) (Ports) (Stimuli ("local126" (scope local) (stimType periodic) (Props (periodicFreq "5e+007") (periodicJitter "0") (periodicPattern "1"))) ("local128" (scope local) (stimType periodic) (Props (periodicFreq "5e+007") (periodicJitter "0") (periodicPattern "1"))) ("local127" (scope local) (stimType periodic) (Props (periodicFreq "5e+007") (periodicJitter "0") (periodicPattern "1")))) (Notes) (Constraints ("DELAY_RULE" ("CRESCENT_CITY_177_20141217_Q U36.DW4" "CRESCENT_CITY_177_20141217_Q U22.A59" "LENGTH" "0.0762" "LENGTH" "0.4318")) ("DP_GATHER_CONTROL" "IGNORE") ("DP_MAX_UNCOUPLED_LENGTH" "0.000254") ("DP_NEGATIVE_COUPLED_TOLERANCE" "2.54e-006") ("DP_PHASE_TOLERANCE" ("LENGTH" "0.000127")) ("DP_POSITIVE_COUPLED_TOLERANCE" "2.54e-006") ("RELATIVE_PROPAGATION_DELAY" ("MG_PCIE_LOCAL" "CRESCENT_CITY_177_20141217_Q C3667.2" "CRESCENT_CITY_177_20141217_Q U22.A59" "LOCAL" "LENGTH" "0.000127" "LENGTH" "") ("MG_PCIE_LOCAL" "CRESCENT_CITY_177_20141217_Q U36.DW4" "CRESCENT_CITY_177_20141217_Q C3667.1" "LOCAL" "LENGTH" "0.000127" "LENGTH" "") ("MG" "CRESCENT_CITY_177_20141217_Q U36.DW4" "CRESCENT_CITY_177_20141217_Q U22.A59" "NET GROUP" "LENGTH" "0.0127" "LENGTH" "") ("MG_PCIE_L1" "CRESCENT_CITY_177_20141217_Q U36.DW4" "CRESCENT_CITY_177_20141217_Q C3667.1" "LOCAL" "LENGTH" "0.000127" "LENGTH" "") ("MG_PCIE_L0" "CRESCENT_CITY_177_20141217_Q C3667.2" "CRESCENT_CITY_177_20141217_Q U22.A59" "LOCAL" "LENGTH" "0.000127" "LENGTH" ""))) (MeasurementSets ("EMI" ("EMIStatus" status("on")) ("PeakEmission" status("on")) ("PeakFrequency" status("on")) ("PulseFreq" status("on")) ("RiseTime" status("on")) ("VoltageSwing" status("on"))) ("Reflection" ("BufferDelayFall" status("off")) ("BufferDelayRise" status("off")) ("EyeHeight" status("off")) ("EyeJitter" status("off")) ("EyeWidth" status("off")) ("FirstIncidentFall" status("off")) ("FirstIncidentRise" status("off")) ("Glitch" status("on")) ("GlitchFall" status("off")) ("GlitchRise" status("off")) ("Monotonic" status("on")) ("MonotonicFall" status("off")) ("MonotonicRise" status("off")) ("NoiseMargin" status("on")) ("NoiseMarginHigh" status("off")) ("NoiseMarginLow" status("off")) ("OvershootHigh" status("on")) ("OvershootLow" status("on")) ("PropDelay" status("on")) ("SettleDelay" status("on")) ("SettleDelayFall" status("off")) ("SettleDelayRise" status("off")) ("SwitchDelay" status("on")) ("SwitchDelayFall" status("off")) ("SwitchDelayRise" status("off"))) ("Crosstalk" ("Crosstalk" status("on"))) ("Custom")) (VectorSets) (Props (XnetName "P3E_CPU0_PE1_PCH_PCIEUP_C_T<10>") (allDrivers "active") (customSimType "Reflection") (ftsMode ("Typ")) (rcvrSelect "all") (tlineDelayMode "time") (userRevision "1.0")))) (Subckts) (CrossSections ("CRESCENT_CITY_177_20141217_Q" (Props (SXDesignName "CRESCENT_CITY_177_20141217_Q")) (Layers ("" (layerType "SURFACE") (material "AIR") (thickness "0 mil") (dielectricConstant "1.000000") (lossTangent "0") (etchFactor "0.000000") (elecCondVal "0 mho/cm") (thermCondVal "0 w/cm-degC")) ("" (layerType "DIELECTRIC") (material "CONFORMAL_COAT") (thickness "0.5 mil") (dielectricConstant "3.800000") (lossTangent "0.035") (etchFactor "0.000000") (elecCondVal "0 mho/cm") (thermCondVal "0.012 w/cm-degC")) ("TOP" (layerType "CONDUCTOR") (material "COPPER") (thickness "  2.100000 mil") (width "4.00 MIL") (dielectricConstant "4.500000") (lossTangent "0") (etchFactor "70.000000") (elecCondVal "595900.000000 mho/cm") (thermCondVal "0 w/cm-degC") (signalDieConstant "3.800000") (signalLossTangent "0.035")) ("" (layerType "DIELECTRIC") (material "FR-4") (thickness "  2.670000 mil") (dielectricConstant "4.000000") (lossTangent "0.035") (etchFactor "0.000000") (elecCondVal "0 mho/cm") (thermCondVal "0.012 w/cm-degC")) ("L2_GND1" (layerType "PLANE") (material "COPPER") (isShield t) (thickness "  1.250000 mil") (dielectricConstant "4.500000") (lossTangent "0.035") (etchFactor "90.000000") (elecCondVal "595900.000000 mho/cm") (thermCondVal "0.012 w/cm-degC")) ("" (layerType "DIELECTRIC") (material "FR-4") (thickness "  9.000000 mil") (dielectricConstant "4.100000") (lossTangent "0.035") (etchFactor "0.000000") (elecCondVal "0 mho/cm") (thermCondVal "0.012 w/cm-degC")) ("L3_SIG1" (layerType "CONDUCTOR") (material "COPPER") (thickness "  1.250000 mil") (width "4.00 MIL") (dielectricConstant "4.500000") (lossTangent "0.035") (etchFactor "90.000000") (elecCondVal "595900.000000 mho/cm") (thermCondVal "0.012 w/cm-degC") (signalDieConstant "4.100000") (signalLossTangent "0.035")) ("" (layerType "DIELECTRIC") (material "FR-4") (thickness "  3.000000 mil") (dielectricConstant "4.500000") (lossTangent "0.035") (etchFactor "0.000000") (elecCondVal "0 mho/cm") (thermCondVal "0 w/cm-degC")) ("L4_GND2" (layerType "PLANE") (material "COPPER") (isShield t) (thickness "  1.250000 mil") (dielectricConstant "4.500000") (lossTangent "0.035") (etchFactor "90.000000") (elecCondVal "595900.000000 mho/cm") (thermCondVal "0 w/cm-degC")) ("" (layerType "DIELECTRIC") (material "FR-4") (thickness "  9.000000 mil") (dielectricConstant "4.000000") (lossTangent "0.035") (etchFactor "0.000000") (elecCondVal "0 mho/cm") (thermCondVal "0.012 w/cm-degC")) ("L5_SIG2" (layerType "CONDUCTOR") (material "COPPER") (thickness "  1.250000 mil") (width "4.00 MIL") (dielectricConstant "4.500000") (lossTangent "0.035") (etchFactor "90.000000") (elecCondVal "595900.000000 mho/cm") (thermCondVal "0.012 w/cm-degC") (signalDieConstant "4.000000") (signalLossTangent "0.035")) ("" (layerType "DIELECTRIC") (material "FR-4") (thickness "  3.000000 mil") (dielectricConstant "4.500000") (lossTangent "0.035") (etchFactor "0.000000") (elecCondVal "0 mho/cm") (thermCondVal "0 w/cm-degC")) ("L6_GND3" (layerType "PLANE") (material "COPPER") (isShield t) (thickness "  1.250000 mil") (dielectricConstant "4.500000") (lossTangent "0.035") (etchFactor "90.000000") (elecCondVal "595900.000000 mho/cm") (thermCondVal "0 w/cm-degC")) ("" (layerType "DIELECTRIC") (material "FR-4") (thickness "  4.500000 mil") (dielectricConstant "4.100000") (lossTangent "0.035") (etchFactor "0.000000") (elecCondVal "0 mho/cm") (thermCondVal "0.012 w/cm-degC")) ("L7_PWR1-SIG" (layerType "PLANE") (material "COPPER") (isShield t) (thickness "  2.400000 mil") (dielectricConstant "4.500000") (lossTangent "0.035") (etchFactor "90.000000") (elecCondVal "595900.000000 mho/cm") (thermCondVal "0.012 w/cm-degC")) ("" (layerType "DIELECTRIC") (material "FR-4") (thickness "  4.600000 mil") (dielectricConstant "4.000000") (lossTangent "0.035") (etchFactor "0.000000") (elecCondVal "0 mho/cm") (thermCondVal "0.012 w/cm-degC")) ("L8_PWR2-SIG" (layerType "PLANE") (material "COPPER") (isShield t) (thickness "  2.400000 mil") (dielectricConstant "4.500000") (lossTangent "0.035") (etchFactor "90.000000") (elecCondVal "595900.000000 mho/cm") (thermCondVal "0.012 w/cm-degC")) ("" (layerType "DIELECTRIC") (material "FR-4") (thickness "  4.500000 mil") (dielectricConstant "4.500000") (lossTangent "0.035") (etchFactor "0.000000") (elecCondVal "0 mho/cm") (thermCondVal "0 w/cm-degC")) ("L9_GND4" (layerType "PLANE") (material "COPPER") (isShield t) (thickness "  1.250000 mil") (dielectricConstant "4.500000") (lossTangent "0.035") (etchFactor "90.000000") (elecCondVal "595900.000000 mho/cm") (thermCondVal "0 w/cm-degC")) ("" (layerType "DIELECTRIC") (material "FR-4") (thickness "  3.000000 mil") (dielectricConstant "4.100000") (lossTangent "0.035") (etchFactor "0.000000") (elecCondVal "0 mho/cm") (thermCondVal "0.012 w/cm-degC")) ("L10_SIG3" (layerType "CONDUCTOR") (material "COPPER") (thickness "  1.250000 mil") (width "4.00 MIL") (dielectricConstant "4.500000") (lossTangent "0.035") (etchFactor "90.000000") (elecCondVal "595900.000000 mho/cm") (thermCondVal "0.012 w/cm-degC") (signalDieConstant "4.100000") (signalLossTangent "0.035")) ("" (layerType "DIELECTRIC") (material "FR-4") (thickness "  9.000000 mil") (dielectricConstant "4.500000") (lossTangent "0.035") (etchFactor "0.000000") (elecCondVal "0 mho/cm") (thermCondVal "0 w/cm-degC")) ("L11_GND5" (layerType "PLANE") (material "COPPER") (isShield t) (thickness "  1.250000 mil") (dielectricConstant "4.500000") (lossTangent "0.035") (etchFactor "90.000000") (elecCondVal "595900.000000 mho/cm") (thermCondVal "0 w/cm-degC")) ("" (layerType "DIELECTRIC") (material "FR-4") (thickness "  3.000000 mil") (dielectricConstant "4.500000") (lossTangent "0.035") (etchFactor "0.000000") (elecCondVal "0 mho/cm") (thermCondVal "0.012 w/cm-degC")) ("L12_SIG4" (layerType "CONDUCTOR") (material "COPPER") (thickness "  1.250000 mil") (width "4.00 MIL") (dielectricConstant "4.500000") (lossTangent "0.035") (etchFactor "90.000000") (elecCondVal "595900.000000 mho/cm") (thermCondVal "0.012 w/cm-degC") (signalDieConstant "4.500000") (signalLossTangent "0.035")) ("" (layerType "DIELECTRIC") (material "FR-4") (thickness "  9.000000 mil") (dielectricConstant "4.500000") (lossTangent "0.035") (etchFactor "0.000000") (elecCondVal "0 mho/cm") (thermCondVal "0 w/cm-degC")) ("L13_GND6" (layerType "PLANE") (material "COPPER") (isShield t) (thickness "  1.250000 mil") (dielectricConstant "4.500000") (lossTangent "0.035") (etchFactor "90.000000") (elecCondVal "595900.000000 mho/cm") (thermCondVal "0.012 w/cm-degC")) ("" (layerType "DIELECTRIC") (material "FR-4") (thickness "  2.670000 mil") (dielectricConstant "4.500000") (lossTangent "0.035") (etchFactor "0.000000") (elecCondVal "0 mho/cm") (thermCondVal "0.012 w/cm-degC")) ("BOTTOM" (layerType "CONDUCTOR") (material "COPPER") (thickness "  2.100000 mil") (width "4.00 MIL") (dielectricConstant "4.500000") (lossTangent "0") (etchFactor "70.000000") (elecCondVal "595900.000000 mho/cm") (thermCondVal "0 w/cm-degC") (signalDieConstant "3.800000") (signalLossTangent "0.035")) ("" (layerType "DIELECTRIC") (material "CONFORMAL_COAT") (thickness "0.5 mil") (dielectricConstant "3.800000") (lossTangent "0.035") (etchFactor "0.000000") (elecCondVal "0 mho/cm") (thermCondVal "0.012 w/cm-degC")) ("" (layerType "SURFACE") (material "AIR") (thickness "0 mil") (dielectricConstant "1.000000") (lossTangent "0") (etchFactor "0.000000") (elecCondVal "0 mho/cm") (thermCondVal "0 w/cm-degC"))))) (Props (DesUnits "mils 2") (LayerStack ("DIELECTRIC" "DIELECTRIC" "BOTTOM" "DIELECTRIC" "L13_GND6" "DIELECTRIC" "L12_SIG4" "DIELECTRIC" "L11_GND5" "DIELECTRIC" "L10_SIG3" "DIELECTRIC" "L9_GND4" "DIELECTRIC" "L8_PWR2-SIG" "DIELECTRIC" "L7_PWR1-SIG" "DIELECTRIC" "L6_GND3" "DIELECTRIC" "L5_SIG2" "DIELECTRIC" "L4_GND2" "DIELECTRIC" "L3_SIG1" "DIELECTRIC" "L2_GND1" "DIELECTRIC" "TOP" "DIELECTRIC" "DIELECTRIC")) (Revision "16.600")) (Params (Resistor ((resistance "50 ohm") (orientation "0"))) (DiffInput ((temperature "27") (bufferModelNonInverting "CDSDefaultInput_2p5v") (bufferModelInverting "CDSDefaultInput_2p5v") (threshInputHighMin "1.7 V") (threshInputHighTyp "1.7  V") (threshInputHighMax "1.7  V") (threshInputLowMin "0.7  V") (threshInputLowTyp "0.7  V") (threshInputLowMax "0.7  V") (mappingTagNonInverting nil) (mappingTagInverting nil) (cycle "1"))) (Capacitor ((capacitance "10 pF") (orientation "0"))) (DiffOutputPkg ((temperature "27") (bufferModelNonInverting "CDSDefaultOutput_2p5v") (bufferModelInverting "CDSDefaultOutput_2p5v") (stimuli nil) (offsets nil) (state "tristate") (cycle "1") (termMap nil) (setup "0.9e-09") (hold "0.4e-09") (rise nil) (fall nil) (threshOutputHighMin "2.375  V") (threshOutputHighTyp "2.5  V") (threshOutputHighMax "2.625  V") (threshOutputLowMin "1.275  V") (threshOutputLowTyp "1.7  V") (threshOutputLowMax "1.985  V") (mappingTagNonInverting nil) (mappingTagInverting nil) (spice nil))) (DiffOutput ((temperature "27") (bufferModelNonInverting "CDSDefaultOutput_2p5v") (bufferModelInverting "CDSDefaultOutput_2p5v") (stimuli nil) (offsets nil) (state "tristate") (cycle "1") (termMap nil) (setup "0.9e-09") (hold "0.4e-09") (rise nil) (fall nil) (threshOutputHighMin "2.375  V") (threshOutputHighTyp "2.5  V") (threshOutputHighMax "2.625  V") (threshOutputLowMin "1.275  V") (threshOutputLowTyp "1.7  V") (threshOutputLowMax "1.985  V") (mappingTagNonInverting nil) (mappingTagInverting nil) (spice nil))) (CPWSL ((d1Thickness "10 mil") (d1Constant "4.5") (d1LossTangent "0.035") (d2Thickness "0.72 mil") (d2Constant "4.5") (d2LossTangent "0.035") (d3Thickness "10 mil") (d3Constant "4.5") (d3LossTangent "0.035") length("1000 mil") (spacing "5 mil") (spacing2 "5 mil") (spacing3 "5 mil") (spacing4 "5 mil") (spacing5 "5 mil") (traceConductivity "595900 mho/cm") (traceGeometry "cpwms") (traceLayerName "") (traceThickness "0.72 mil") (traceType "single") (traceWidth "5.0 mil") (traceWidth2 "5.0 mil") (traceWidth3 "5.0 mil") (traceWidth4 "5.0 mil") (traceWidth5 "5.0 mil") (traceWidth6 "5.0 mil") (offset "0 mil") (traceCount "1") (impedance nil))) (Connector nil) (CPWMS ((d1Thickness "10 mil") (d1Constant "4.5") (d1LossTangent "0.035") (d2Thickness "0.72 mil") (d2Constant "4.5") (d2LossTangent "0.035") (d3Thickness "0.0") (d3Constant "1") (d3LossTangent "0") length("1000 mil") (spacing "5 mil") (spacing2 "5 mil") (spacing3 "5 mil") (spacing4 "5 mil") (spacing5 "5 mil") (traceConductivity "595900 mho/cm") (traceGeometry "cpwms") (traceLayerName "") (traceThickness "0.72 mil") (traceType "single") (traceWidth "5.0 mil") (traceWidth2 "5.0 mil") (traceWidth3 "5.0 mil") (traceWidth4 "5.0 mil") (traceWidth5 "5.0 mil") (traceWidth6 "5.0 mil") (offset "0 mil") (traceCount "1") (impedance nil))) (TLine ((diffImpedance "100ohm") (diffVelocity "1.4142e+08M/s") (impedance "60ohm") length("2800 mil") (propDelay "0.5 ns") (velocity "5600 mil/ns") (traceCount "1") (traceGeometry "Microstrip") (impedanceMin nil) (impedanceMax nil) (lengthMin nil) (lengthMax nil) (propDelayMin nil) (propDelayMax nil) (impedanceSweepCount nil) (propDelaySweepCount nil) (velocitySweepCount nil) (lengthSweepCount nil) (matchSetName nil))) (CPW ((d1Thickness "10 mil") (d1Constant "4.5") (d1LossTangent "0.035") (d2Thickness "0.72 mil") (d2Constant "1") (d2LossTangent "0") (d3Thickness "0.0") (d3Constant "1") (d3LossTangent "0") length("1000 mil") (spacing "5 mil") (spacing2 "5 mil") (spacing3 "5 mil") (spacing4 "5 mil") (spacing5 "5 mil") (traceConductivity "595900 mho/cm") (traceGeometry "cpwms") (traceLayerName "") (traceThickness "0.72 mil") (traceType "single") (traceWidth "5.0 mil") (traceWidth2 "5.0 mil") (traceWidth3 "5.0 mil") (traceWidth4 "5.0 mil") (traceWidth5 "5.0 mil") (traceWidth6 "5.0 mil") (offset "0 mil") (traceCount "1") (impedance nil))) (Via ((model "Unknown") (viaOutputFormat "Unknown") (viaPadstack nil) (viaTopLayer nil) (viaBottomLayer nil) (viaIsPower nil) (viaIsGround nil))) (Trace ((d1Thickness "10 mil") (d1Constant "4.5") (d1LossTangent "0.035") (d2Thickness "10 mil") (d2Constant "4.5") (d2LossTangent "0.035") (d3Thickness "0.0") (d3Constant "1.0") (d3LossTangent "0") length("1000 mil") (spacing "5 mil") (spacing2 "5 mil") (spacing3 "5 mil") (spacing4 "5 mil") (spacing5 "5 mil") (traceConductivity "595900 mho/cm") (traceGeometry "microstrip") (traceLayerName "") (traceThickness "0.72 mil") (traceType "single") (traceWidth "5.0 mil") (traceWidth2 "5.0 mil") (traceWidth3 "5.0 mil") (traceWidth4 "5.0 mil") (traceWidth5 "5.0 mil") (traceWidth6 "5.0 mil") (offset "0 mil") (traceCount "1") (impedance nil))) (sync ((syncFreq "100e6") (syncInitState "1") (syncPattern "10") (syncEdgeSwitch "rise"))) (idlCircuit ((allDrivers "active") (ftsMode '("Typ")) (rcvrSelect "all") (simMode "Reflection") (tlineDelayMode "time") (userRevision "1.0") (autoSolve "On"))) (CurrentProbe nil) (DiffInputPkg ((temperature "27") (bufferModelNonInverting "CDSDefaultInput_2p5v") (bufferModelInverting "CDSDefaultInput_2p5v") (threshInputHighMin "1.7 V") (threshInputHighTyp "1.7  V") (threshInputHighMax "1.7  V") (threshInputLowMin "0.7  V") (threshInputLowTyp "0.7  V") (threshInputLowMax "0.7  V") (mappingTagNonInverting nil) (mappingTagInverting nil) (cycle "1"))) (IbisIOMacro ((temperature "27") (bufferModel "CDSDefaultIO_2p5v") (stimuli nil) (offsets nil) (state "tristate") (cycle "1") (termMap nil) (setup "2.0e-09") (hold "1.0e-09") (rise nil) (fall nil) (macroType nil) (voltage nil) (spice nil) (LEFDEFPinName nil) (LEFDEFPinType nil) (mappingTag nil))) (IbisOutputPkg ((temperature "27") (bufferModel "CDSDefaultOutput_2p5v") (stimuli nil) (offsets nil) (state "tristate") (cycle "1") (termMap nil) (setup "2.0e-09") (hold "1.0e-09") (rise nil) (fall nil) (macroType nil) (voltage nil) (spice nil) (LEFDEFPinName nil) (LEFDEFPinType nil) (mappingTag nil))) (IbisIOPkg ((temperature "27") (bufferModel "CDSDefaultIO_2p5v") (stimuli nil) (offsets nil) (state "tristate") (cycle "1") (termMap nil) (setup "2.0e-09") (hold "1.0e-09") (rise nil) (fall nil) (macroType nil) (voltage nil) (spice nil) (LEFDEFPinName nil) (LEFDEFPinType nil) (mappingTag nil))) (IbisInputPkg ((temperature "27") (bufferModel "CDSDefaultInput_2p5v") (cycle "1") (LEFDEFPinName nil) (LEFDEFPinType nil) (mappingTag nil))) (TheveninTerm ((resistanceUp "180 ohm") (resistanceDown "270 ohm") (voltageUp "5 V") (voltageDown "0 V") (maxDelay "0.1 ns"))) (SeriesTerm ((resistance "22 ohm") (maxDelay "0.1 ns"))) (IbisIO_OpenPullDown ((temperature "27") (bufferModel "CDSDefaultIO_2p5v") (stimuli nil) (offsets nil) (state "tristate") (cycle "1") (termMap nil) (setup "2.0e-09") (hold "1.0e-09") (rise nil) (fall nil) (macroType nil) (voltage nil) (spice nil) (LEFDEFPinName nil) (LEFDEFPinType nil) (mappingTag nil))) (async ((asyncTimePoints "") (asyncInitState "1"))) (RCTerm ((resistance "50 ohm") (capacitance "20 pF") (voltage "5 V") (maxDelay "0.1 ns"))) (LowClampTerm ((cutoffVoltage "0.7 V") (voltage "0 V") (maxDelay "0.1 ns"))) (IbisIO_OpenPullUp ((temperature "27") (bufferModel "CDSDefaultIO_2p5v") (stimuli nil) (offsets nil) (state "tristate") (cycle "1") (termMap nil) (setup "2.0e-09") (hold "1.0e-09") (rise nil) (fall nil) (macroType nil) (voltage nil) (spice nil) (LEFDEFPinName nil) (LEFDEFPinType nil) (mappingTag nil))) (clocked ((clockRise "1e-09") (clockFall "1e-09") (clockFreq "100e6") (clockInitState "0") (clockDutyCycle "0.5") (clockJitter "0"))) (HiClampTerm ((cutoffVoltage "0.7 V") (voltage "5 V") (maxDelay "0.1 ns"))) (periodic ((periodicFreq "100e6") (periodicPattern "10") (periodicJitter "0"))) (DualClampTerm ((cutoffVoltageUp "0.7 V") (cutoffVoltageDown "0.7 V") (voltageUp "5 V") (voltageDown "0 V") (maxDelay "0.1 ns"))) (Cable (length("1 m"))) (ShuntTerm ((resistance "50 ohm") (voltage "5 V") (maxDelay "0.1 ns"))) (IbisOutput_OpenPullUp ((temperature "27") (bufferModel "CDSDefaultOutput_2p5v") (stimuli nil) (offsets nil) (state "tristate") (cycle "1") (termMap nil) (setup "2.0e-09") (hold "1.0e-09") (rise nil) (fall nil) (macroType nil) (voltage nil) (spice nil) (LEFDEFPinName nil) (LEFDEFPinType nil) (mappingTag nil))) (IbisInput ((temperature "27") (bufferModel "CDSDefaultInput_2p5v") (cycle "1") (LEFDEFPinName nil) (LEFDEFPinType nil) (mappingTag nil))) (IbisOutput ((temperature "27") (bufferModel "CDSDefaultOutput_2p5v") (stimuli nil) (offsets nil) (state "tristate") (cycle "1") (termMap nil) (setup "2.0e-09") (hold "1.0e-09") (rise nil) (fall nil) (macroType nil) (voltage nil) (spice nil) (LEFDEFPinName nil) (LEFDEFPinType nil) (mappingTag nil))) (IbisIO ((temperature "27") (bufferModel "CDSDefaultIO_2p5v") (stimuli nil) (offsets nil) (state "tristate") (cycle "1") (termMap nil) (setup "2.0e-09") (hold "1.0e-09") (rise nil) (fall nil) (macroType nil) (voltage nil) (spice nil) (LEFDEFPinName nil) (LEFDEFPinType nil) (mappingTag nil))) (Source ((voltage "5 V"))) (Inductor ((inductance "5 nH") (orientation "0"))) (DiffIOPkg ((temperature "27") (bufferModelNonInverting "CDSDefaultIO_2p5v") (bufferModelInverting "CDSDefaultIO_2p5v") (stimuli nil) (offsets nil) (state "tristate") (cycle "1") (termMap nil) (setup "0.9e-09") (hold "0.4e-09") (rise nil) (fall nil) (threshInputHighMin "1.7 V") (threshInputHighTyp "1.7  V") (threshInputHighMax "1.7  V") (threshInputLowMin "0.7  V") (threshInputLowTyp "0.7  V") (threshInputLowMax "0.7 ") (threshOutputHighMin "2.365  V") (threshOutputHighTyp "2.5  V") (threshOutputHighMax "2.625  V") (threshOutputLowMin "1.275  V") (threshOutputLowTyp "1.7  V") (threshOutputLowMax "1.985  V") (mappingTagNonInverting nil) (mappingTagInverting nil) (spice nil))) (Diode ((cutoffVoltage "0.7 V"))) (RLGC (length("1000 mil"))) (DiffIO ((temperature "27") (bufferModelNonInverting "CDSDefaultIO_2p5v") (bufferModelInverting "CDSDefaultIO_2p5v") (stimuli nil) (offsets nil) (state "tristate") (cycle "1") (termMap nil) (setup "0.9e-09") (hold "0.4e-09") (rise nil) (fall nil) (threshInputHighMin "1.7 V") (threshInputHighTyp "1.7  V") (threshInputHighMax "1.7  V") (threshInputLowMin "0.7  V") (threshInputLowTyp "0.7  V") (threshInputLowMax "0.7 ") (threshOutputHighMin "2.365  V") (threshOutputHighTyp "2.5  V") (threshOutputHighMax "2.625  V") (threshOutputLowMin "1.275  V") (threshOutputLowTyp "1.7  V") (threshOutputLowMax "1.985  V") (mappingTagNonInverting nil) (mappingTagInverting nil) (spice nil))) (ESpiceDevice nil)))
				)
				( objectStatus "PCIE_DEVICE" )
			)
			( electricalCSet "@crescent_city_bb_fab1_lib.crescent_city_bb_fab1(sch_1):\BCLK\"
				( groupRef "CLK_100M_CPU_BCLKS:MG" )
				( pinPairRef "CLK_100M_CPU_BCLKS:U5D1.AU24:EU4D2.18" )
				( attribute "DIFFP_GATHER_CONTROL" "IGNORE"
					( Origin gBackEnd )
				)
				( attribute "DIFFP_UNCOUPLED_LENGTH" "205.00"
					( Origin gBackEnd )
				)
				( attribute "DIFFP_COUPLED_PLUS" "7.00"
					( Origin gBackEnd )
				)
				( attribute "DIFFP_COUPLED_MINUS" "0.50"
					( Origin gBackEnd )
				)
				( attribute "DIFFP_PHASE_TOL" "10 mil"
					( Units "uPhaseTol" "ns" 1.000000)
					( Origin gBackEnd )
				)
				( attribute "TOPOLOGY_TEMPLATE_REVISION" "1.0"
					( Origin gBackEnd )
				)
				( topologyData 24025
(SKIDL (Circuits ("MAIN" (Parts ("CRESCENT_CITY_178_20141219_Q.@@EU119.18" IbisOutputPkg (xy (5498 4235)) (refDes "EU4D2") (model "Unknown") (Props (_SXDesignName "CRESCENT_CITY_178_20141219_Q") (brdx "6842.19 MIL") (brdy "3059.5 MIL") (bufferModel "CDSDefaultOutput_2p5v") (cycle "1") (hold "1.0e-09") (mappingTag "") (offsets ("4" "0")) (setup "2.0e-09") (state "tristate") (stimuli ("4" "local18")) (temperature "27") (termMap ("4" "Data"))) (Terms ("CRESCENT_CITY_178_20141219_Q.X684219Y305950L2LRATS" "18"))) ("CRESCENT_CITY_178_20141219_Q.@@U36.AU24" IbisInputPkg (xy (5544 4235)) (refDes "U5D1") (model "Unknown") (Props (_SXDesignName "CRESCENT_CITY_178_20141219_Q") (brdx "11319.1 MIL") (brdy "2727.47 MIL") (bufferModel "CDSDefaultInput_2p5v") (mappingTag "") (temperature "27")) (Terms ("CRESCENT_CITY_178_20141219_Q.X1131910Y272747L2LRATS" "AU24"))) ("CRESCENT_CITY_178_20141219_Q.@@R3435.2_SOURCE" Source (xy (5499 4228)) (refDes "GND") (value "0 V") (Props (_SXDesignName "CRESCENT_CITY_178_20141219_Q")) (Terms ("CRESCENT_CITY_178_20141219_Q.X690500Y305500L28RATS" "1"))) ("CRESCENT_CITY_178_20141219_Q.T@@RATS@@U36.AU24@@R3423.2" TLine (xy (5530 4235)) (mirror x) (refDes "TL1") (Props (_SXDesignName "CRESCENT_CITY_178_20141219_Q") (impedance "47.169 ohm") length("4706.61 MIL") (propDelay "0.84534 ns") (traceCount "1") (traceGeometry "Microstrip") (velocity "5567.72 mil/ns")) (Terms ("CRESCENT_CITY_178_20141219_Q.X1131910Y272747L2LRATS" "1") ("CRESCENT_CITY_178_20141219_Q.X694000Y305500L2LRATS" "2"))) ("CRESCENT_CITY_178_20141219_Q.@@R3423.2.1" Resistor (xy (5515 4235)) (mirror x) (refDes "R4D25") (value "27.4 Ohm") (Props (_SXDesignName "CRESCENT_CITY_178_20141219_Q")) (Terms ("CRESCENT_CITY_178_20141219_Q.X694000Y305500L2LRATS" "2") ("CRESCENT_CITY_178_20141219_Q.X690500Y305500L2LRATS" "1"))) ("CRESCENT_CITY_178_20141219_Q.T@@RATS@@EU119.18@@R3423.1" TLine (xy (5506 4235)) (refDes "TL2") (Props (_SXDesignName "CRESCENT_CITY_178_20141219_Q") (impedance "47.169 ohm") length("67.31 MIL") (propDelay "0.01209 ns") (traceCount "1") (traceGeometry "Microstrip") (velocity "5567.4 mil/ns")) (Terms ("CRESCENT_CITY_178_20141219_Q.X684219Y305950L2LRATS" "1") ("CRESCENT_CITY_178_20141219_Q.X690500Y305500L2LRATS" "2"))) ("CRESCENT_CITY_178_20141219_Q.@@R3435.2.1" Resistor (xy (5506 4228)) (refDes "R6P15") (value "42.2 Ohm") (Props (_SXDesignName "CRESCENT_CITY_178_20141219_Q")) (Terms ("CRESCENT_CITY_178_20141219_Q.X690500Y305500L28RATS" "2") ("CRESCENT_CITY_178_20141219_Q.X694000Y305500L28LRATS" "1"))) ("CRESCENT_CITY_178_20141219_Q.T@@RATS@@R3423.2@@R3435.1" TLine (xy (5521 4228)) (mirror x) (refDes "TL3") (Props (_SXDesignName "CRESCENT_CITY_178_20141219_Q") (impedance "47.169 ohm") (propDelay "1.79607e-006 ns") (traceCount "1") (traceGeometry "Microstrip")) (Terms ("CRESCENT_CITY_178_20141219_Q.X694000Y305500L2LRATS" "1") ("CRESCENT_CITY_178_20141219_Q.X694000Y305500L28LRATS" "2")))) (Nodes ("CRESCENT_CITY_178_20141219_Q.X694000Y305500L28LRATS" (terms "CRESCENT_CITY_178_20141219_Q.T@@RATS@@R3423.2@@R3435.1.2" "CRESCENT_CITY_178_20141219_Q.@@R3435.2.1.2")) ("CRESCENT_CITY_178_20141219_Q.X694000Y305500L2LRATS" (terms "CRESCENT_CITY_178_20141219_Q.T@@RATS@@R3423.2@@R3435.1.1" "CRESCENT_CITY_178_20141219_Q.@@R3423.2.1.1" "CRESCENT_CITY_178_20141219_Q.T@@RATS@@U36.AU24@@R3423.2.2")) ("CRESCENT_CITY_178_20141219_Q.X690500Y305500L28RATS" (terms "CRESCENT_CITY_178_20141219_Q.@@R3435.2.1.1" "CRESCENT_CITY_178_20141219_Q.@@R3435.2_SOURCE.1")) ("CRESCENT_CITY_178_20141219_Q.X690500Y305500L2LRATS" (terms "CRESCENT_CITY_178_20141219_Q.T@@RATS@@EU119.18@@R3423.1.2" "CRESCENT_CITY_178_20141219_Q.@@R3423.2.1.2")) ("CRESCENT_CITY_178_20141219_Q.X1131910Y272747L2LRATS" (terms "CRESCENT_CITY_178_20141219_Q.T@@RATS@@U36.AU24@@R3423.2.1" "CRESCENT_CITY_178_20141219_Q.@@U36.AU24.1")) ("CRESCENT_CITY_178_20141219_Q.X684219Y305950L2LRATS" (terms "CRESCENT_CITY_178_20141219_Q.T@@RATS@@EU119.18@@R3423.1.1" "CRESCENT_CITY_178_20141219_Q.@@EU119.18.1"))) (Ports) (Stimuli ("local18" (scope local) (stimType periodic) (Props (periodicFreq "5e+007") (periodicJitter "0") (periodicPattern "1")))) (Notes) (Constraints ("DELAY_RULE" ("CRESCENT_CITY_178_20141219_Q U36.AU24" "CRESCENT_CITY_178_20141219_Q EU119.18" "LENGTH" "0.1016" "LENGTH" "0.4064")) ("RELATIVE_PROPAGATION_DELAY" ("MG" "CRESCENT_CITY_178_20141219_Q EU119.18" "CRESCENT_CITY_178_20141219_Q U36.AU24" "CLASS" "LENGTH" "0.0127" "DELAY" ""))) (MeasurementSets ("EMI" ("EMIStatus" status("on")) ("PeakEmission" status("on")) ("PeakFrequency" status("on")) ("PulseFreq" status("on")) ("RiseTime" status("on")) ("VoltageSwing" status("on"))) ("Reflection" ("BufferDelayFall" status("off")) ("BufferDelayRise" status("off")) ("EyeHeight" status("off")) ("EyeJitter" status("off")) ("EyeWidth" status("off")) ("FirstIncidentFall" status("off")) ("FirstIncidentRise" status("off")) ("Glitch" status("on")) ("GlitchFall" status("off")) ("GlitchRise" status("off")) ("Monotonic" status("on")) ("MonotonicFall" status("off")) ("MonotonicRise" status("off")) ("NoiseMargin" status("on")) ("NoiseMarginHigh" status("off")) ("NoiseMarginLow" status("off")) ("OvershootHigh" status("on")) ("OvershootLow" status("on")) ("PropDelay" status("on")) ("SettleDelay" status("on")) ("SettleDelayFall" status("off")) ("SettleDelayRise" status("off")) ("SwitchDelay" status("on")) ("SwitchDelayFall" status("off")) ("SwitchDelayRise" status("off"))) ("Crosstalk" ("Crosstalk" status("on"))) ("Custom")) (VectorSets) (Props (XnetName "CLK_100M_CPU0_BCLK0_DN") (allDrivers "active") (customSimType "Reflection") (ftsMode ("Typ")) (rcvrSelect "all") (tlineDelayMode "time") (userRevision "1.0")))) (Subckts) (CrossSections ("CRESCENT_CITY_178_20141219_Q" (Props (SXDesignName "CRESCENT_CITY_178_20141219_Q")) (Layers ("" (layerType "SURFACE") (material "AIR") (thickness "0 mil") (dielectricConstant "1.000000") (lossTangent "0") (etchFactor "0.000000") (elecCondVal "0 mho/cm") (thermCondVal "0 w/cm-degC")) ("" (layerType "DIELECTRIC") (material "CONFORMAL_COAT") (thickness "0.5 mil") (dielectricConstant "3.800000") (lossTangent "0.035") (etchFactor "0.000000") (elecCondVal "0 mho/cm") (thermCondVal "0.012 w/cm-degC")) ("TOP" (layerType "CONDUCTOR") (material "COPPER") (thickness "  2.100000 mil") (width "4.00 MIL") (dielectricConstant "4.500000") (lossTangent "0") (etchFactor "70.000000") (elecCondVal "595900.000000 mho/cm") (thermCondVal "0 w/cm-degC") (signalDieConstant "3.800000") (signalLossTangent "0.035")) ("" (layerType "DIELECTRIC") (material "FR-4") (thickness "  2.670000 mil") (dielectricConstant "4.000000") (lossTangent "0.035") (etchFactor "0.000000") (elecCondVal "0 mho/cm") (thermCondVal "0.012 w/cm-degC")) ("L2_GND1" (layerType "PLANE") (material "COPPER") (isShield t) (thickness "  1.250000 mil") (dielectricConstant "4.500000") (lossTangent "0.035") (etchFactor "90.000000") (elecCondVal "595900.000000 mho/cm") (thermCondVal "0.012 w/cm-degC")) ("" (layerType "DIELECTRIC") (material "FR-4") (thickness "  9.000000 mil") (dielectricConstant "4.100000") (lossTangent "0.035") (etchFactor "0.000000") (elecCondVal "0 mho/cm") (thermCondVal "0.012 w/cm-degC")) ("L3_SIG1" (layerType "CONDUCTOR") (material "COPPER") (thickness "  1.250000 mil") (width "4.00 MIL") (dielectricConstant "4.500000") (lossTangent "0.035") (etchFactor "90.000000") (elecCondVal "595900.000000 mho/cm") (thermCondVal "0.012 w/cm-degC") (signalDieConstant "4.100000") (signalLossTangent "0.035")) ("" (layerType "DIELECTRIC") (material "FR-4") (thickness "  3.000000 mil") (dielectricConstant "4.500000") (lossTangent "0.035") (etchFactor "0.000000") (elecCondVal "0 mho/cm") (thermCondVal "0 w/cm-degC")) ("L4_GND2" (layerType "PLANE") (material "COPPER") (isShield t) (thickness "  1.250000 mil") (dielectricConstant "4.500000") (lossTangent "0.035") (etchFactor "90.000000") (elecCondVal "595900.000000 mho/cm") (thermCondVal "0 w/cm-degC")) ("" (layerType "DIELECTRIC") (material "FR-4") (thickness "  9.000000 mil") (dielectricConstant "4.000000") (lossTangent "0.035") (etchFactor "0.000000") (elecCondVal "0 mho/cm") (thermCondVal "0.012 w/cm-degC")) ("L5_SIG2" (layerType "CONDUCTOR") (material "COPPER") (thickness "  1.250000 mil") (width "4.00 MIL") (dielectricConstant "4.500000") (lossTangent "0.035") (etchFactor "90.000000") (elecCondVal "595900.000000 mho/cm") (thermCondVal "0.012 w/cm-degC") (signalDieConstant "4.000000") (signalLossTangent "0.035")) ("" (layerType "DIELECTRIC") (material "FR-4") (thickness "  3.000000 mil") (dielectricConstant "4.500000") (lossTangent "0.035") (etchFactor "0.000000") (elecCondVal "0 mho/cm") (thermCondVal "0 w/cm-degC")) ("L6_GND3" (layerType "PLANE") (material "COPPER") (isShield t) (thickness "  1.250000 mil") (dielectricConstant "4.500000") (lossTangent "0.035") (etchFactor "90.000000") (elecCondVal "595900.000000 mho/cm") (thermCondVal "0 w/cm-degC")) ("" (layerType "DIELECTRIC") (material "FR-4") (thickness "  4.500000 mil") (dielectricConstant "4.100000") (lossTangent "0.035") (etchFactor "0.000000") (elecCondVal "0 mho/cm") (thermCondVal "0.012 w/cm-degC")) ("L7_PWR1-SIG" (layerType "PLANE") (material "COPPER") (isShield t) (thickness "  2.400000 mil") (dielectricConstant "4.500000") (lossTangent "0.035") (etchFactor "90.000000") (elecCondVal "595900.000000 mho/cm") (thermCondVal "0.012 w/cm-degC")) ("" (layerType "DIELECTRIC") (material "FR-4") (thickness "  4.600000 mil") (dielectricConstant "4.000000") (lossTangent "0.035") (etchFactor "0.000000") (elecCondVal "0 mho/cm") (thermCondVal "0.012 w/cm-degC")) ("L8_PWR2-SIG" (layerType "PLANE") (material "COPPER") (isShield t) (thickness "  2.400000 mil") (dielectricConstant "4.500000") (lossTangent "0.035") (etchFactor "90.000000") (elecCondVal "595900.000000 mho/cm") (thermCondVal "0.012 w/cm-degC")) ("" (layerType "DIELECTRIC") (material "FR-4") (thickness "  4.500000 mil") (dielectricConstant "4.500000") (lossTangent "0.035") (etchFactor "0.000000") (elecCondVal "0 mho/cm") (thermCondVal "0 w/cm-degC")) ("L9_GND4" (layerType "PLANE") (material "COPPER") (isShield t) (thickness "  1.250000 mil") (dielectricConstant "4.500000") (lossTangent "0.035") (etchFactor "90.000000") (elecCondVal "595900.000000 mho/cm") (thermCondVal "0 w/cm-degC")) ("" (layerType "DIELECTRIC") (material "FR-4") (thickness "  3.000000 mil") (dielectricConstant "4.100000") (lossTangent "0.035") (etchFactor "0.000000") (elecCondVal "0 mho/cm") (thermCondVal "0.012 w/cm-degC")) ("L10_SIG3" (layerType "CONDUCTOR") (material "COPPER") (thickness "  1.250000 mil") (width "4.00 MIL") (dielectricConstant "4.500000") (lossTangent "0.035") (etchFactor "90.000000") (elecCondVal "595900.000000 mho/cm") (thermCondVal "0.012 w/cm-degC") (signalDieConstant "4.100000") (signalLossTangent "0.035")) ("" (layerType "DIELECTRIC") (material "FR-4") (thickness "  9.000000 mil") (dielectricConstant "4.500000") (lossTangent "0.035") (etchFactor "0.000000") (elecCondVal "0 mho/cm") (thermCondVal "0 w/cm-degC")) ("L11_GND5" (layerType "PLANE") (material "COPPER") (isShield t) (thickness "  1.250000 mil") (dielectricConstant "4.500000") (lossTangent "0.035") (etchFactor "90.000000") (elecCondVal "595900.000000 mho/cm") (thermCondVal "0 w/cm-degC")) ("" (layerType "DIELECTRIC") (material "FR-4") (thickness "  3.000000 mil") (dielectricConstant "4.500000") (lossTangent "0.035") (etchFactor "0.000000") (elecCondVal "0 mho/cm") (thermCondVal "0.012 w/cm-degC")) ("L12_SIG4" (layerType "CONDUCTOR") (material "COPPER") (thickness "  1.250000 mil") (width "4.00 MIL") (dielectricConstant "4.500000") (lossTangent "0.035") (etchFactor "90.000000") (elecCondVal "595900.000000 mho/cm") (thermCondVal "0.012 w/cm-degC") (signalDieConstant "4.500000") (signalLossTangent "0.035")) ("" (layerType "DIELECTRIC") (material "FR-4") (thickness "  9.000000 mil") (dielectricConstant "4.500000") (lossTangent "0.035") (etchFactor "0.000000") (elecCondVal "0 mho/cm") (thermCondVal "0 w/cm-degC")) ("L13_GND6" (layerType "PLANE") (material "COPPER") (isShield t) (thickness "  1.250000 mil") (dielectricConstant "4.500000") (lossTangent "0.035") (etchFactor "90.000000") (elecCondVal "595900.000000 mho/cm") (thermCondVal "0.012 w/cm-degC")) ("" (layerType "DIELECTRIC") (material "FR-4") (thickness "  2.670000 mil") (dielectricConstant "4.500000") (lossTangent "0.035") (etchFactor "0.000000") (elecCondVal "0 mho/cm") (thermCondVal "0.012 w/cm-degC")) ("BOTTOM" (layerType "CONDUCTOR") (material "COPPER") (thickness "  2.100000 mil") (width "4.00 MIL") (dielectricConstant "4.500000") (lossTangent "0") (etchFactor "70.000000") (elecCondVal "595900.000000 mho/cm") (thermCondVal "0 w/cm-degC") (signalDieConstant "3.800000") (signalLossTangent "0.035")) ("" (layerType "DIELECTRIC") (material "CONFORMAL_COAT") (thickness "0.5 mil") (dielectricConstant "3.800000") (lossTangent "0.035") (etchFactor "0.000000") (elecCondVal "0 mho/cm") (thermCondVal "0.012 w/cm-degC")) ("" (layerType "SURFACE") (material "AIR") (thickness "0 mil") (dielectricConstant "1.000000") (lossTangent "0") (etchFactor "0.000000") (elecCondVal "0 mho/cm") (thermCondVal "0 w/cm-degC"))))) (Props (DesUnits "mils 2") (LayerStack ("DIELECTRIC" "DIELECTRIC" "BOTTOM" "DIELECTRIC" "L13_GND6" "DIELECTRIC" "L12_SIG4" "DIELECTRIC" "L11_GND5" "DIELECTRIC" "L10_SIG3" "DIELECTRIC" "L9_GND4" "DIELECTRIC" "L8_PWR2-SIG" "DIELECTRIC" "L7_PWR1-SIG" "DIELECTRIC" "L6_GND3" "DIELECTRIC" "L5_SIG2" "DIELECTRIC" "L4_GND2" "DIELECTRIC" "L3_SIG1" "DIELECTRIC" "L2_GND1" "DIELECTRIC" "TOP" "DIELECTRIC" "DIELECTRIC")) (Revision "16.600")) (Params (Inductor ((inductance "5 nH") (orientation "0"))) (IbisIO_OpenPullDown ((temperature "27") (bufferModel "CDSDefaultIO_2p5v") (stimuli nil) (offsets nil) (state "tristate") (cycle "1") (termMap nil) (setup "2.0e-09") (hold "1.0e-09") (rise nil) (fall nil) (macroType nil) (voltage nil) (spice nil) (LEFDEFPinName nil) (LEFDEFPinType nil) (mappingTag nil))) (DiffInputPkg ((temperature "27") (bufferModelNonInverting "CDSDefaultInput_2p5v") (bufferModelInverting "CDSDefaultInput_2p5v") (threshInputHighMin "1.7 V") (threshInputHighTyp "1.7  V") (threshInputHighMax "1.7  V") (threshInputLowMin "0.7  V") (threshInputLowTyp "0.7  V") (threshInputLowMax "0.7  V") (mappingTagNonInverting nil) (mappingTagInverting nil) (cycle "1"))) (IbisIO ((temperature "27") (bufferModel "CDSDefaultIO_2p5v") (stimuli nil) (offsets nil) (state "tristate") (cycle "1") (termMap nil) (setup "2.0e-09") (hold "1.0e-09") (rise nil) (fall nil) (macroType nil) (voltage nil) (spice nil) (LEFDEFPinName nil) (LEFDEFPinType nil) (mappingTag nil))) (Trace ((d1Thickness "10 mil") (d1Constant "4.5") (d1LossTangent "0.035") (d2Thickness "10 mil") (d2Constant "4.5") (d2LossTangent "0.035") (d3Thickness "0.0") (d3Constant "1.0") (d3LossTangent "0") length("1000 mil") (spacing "5 mil") (spacing2 "5 mil") (spacing3 "5 mil") (spacing4 "5 mil") (spacing5 "5 mil") (traceConductivity "595900 mho/cm") (traceGeometry "microstrip") (traceLayerName "") (traceThickness "0.72 mil") (traceType "single") (traceWidth "5.0 mil") (traceWidth2 "5.0 mil") (traceWidth3 "5.0 mil") (traceWidth4 "5.0 mil") (traceWidth5 "5.0 mil") (traceWidth6 "5.0 mil") (offset "0 mil") (traceCount "1") (impedance nil))) (IbisIOMacro ((temperature "27") (bufferModel "CDSDefaultIO_2p5v") (stimuli nil) (offsets nil) (state "tristate") (cycle "1") (termMap nil) (setup "2.0e-09") (hold "1.0e-09") (rise nil) (fall nil) (macroType nil) (voltage nil) (spice nil) (LEFDEFPinName nil) (LEFDEFPinType nil) (mappingTag nil))) (Capacitor ((capacitance "10 pF") (orientation "0"))) (Via ((model "Unknown") (viaOutputFormat "Unknown") (viaPadstack nil) (viaTopLayer nil) (viaBottomLayer nil) (viaIsPower nil) (viaIsGround nil))) (TLine ((diffImpedance "100ohm") (diffVelocity "1.4142e+08M/s") (impedance "60ohm") length("2800 mil") (propDelay "0.5 ns") (velocity "5600 mil/ns") (traceCount "1") (traceGeometry "Microstrip") (impedanceMin nil) (impedanceMax nil) (lengthMin nil) (lengthMax nil) (propDelayMin nil) (propDelayMax nil) (impedanceSweepCount nil) (propDelaySweepCount nil) (velocitySweepCount nil) (lengthSweepCount nil) (matchSetName nil))) (Resistor ((resistance "50 ohm") (orientation "0"))) (IbisOutputPkg ((temperature "27") (bufferModel "CDSDefaultOutput_2p5v") (stimuli nil) (offsets nil) (state "tristate") (cycle "1") (termMap nil) (setup "2.0e-09") (hold "1.0e-09") (rise nil) (fall nil) (macroType nil) (voltage nil) (spice nil) (LEFDEFPinName nil) (LEFDEFPinType nil) (mappingTag nil))) (IbisOutput_OpenPullUp ((temperature "27") (bufferModel "CDSDefaultOutput_2p5v") (stimuli nil) (offsets nil) (state "tristate") (cycle "1") (termMap nil) (setup "2.0e-09") (hold "1.0e-09") (rise nil) (fall nil) (macroType nil) (voltage nil) (spice nil) (LEFDEFPinName nil) (LEFDEFPinType nil) (mappingTag nil))) (IbisIOPkg ((temperature "27") (bufferModel "CDSDefaultIO_2p5v") (stimuli nil) (offsets nil) (state "tristate") (cycle "1") (termMap nil) (setup "2.0e-09") (hold "1.0e-09") (rise nil) (fall nil) (macroType nil) (voltage nil) (spice nil) (LEFDEFPinName nil) (LEFDEFPinType nil) (mappingTag nil))) (IbisIO_OpenPullUp ((temperature "27") (bufferModel "CDSDefaultIO_2p5v") (stimuli nil) (offsets nil) (state "tristate") (cycle "1") (termMap nil) (setup "2.0e-09") (hold "1.0e-09") (rise nil) (fall nil) (macroType nil) (voltage nil) (spice nil) (LEFDEFPinName nil) (LEFDEFPinType nil) (mappingTag nil))) (ESpiceDevice nil) (IbisInputPkg ((temperature "27") (bufferModel "CDSDefaultInput_2p5v") (cycle "1") (LEFDEFPinName nil) (LEFDEFPinType nil) (mappingTag nil))) (Source ((voltage "5 V"))) (IbisInput ((temperature "27") (bufferModel "CDSDefaultInput_2p5v") (cycle "1") (LEFDEFPinName nil) (LEFDEFPinType nil) (mappingTag nil))) (Cable (length("1 m"))) (periodic ((periodicFreq "100e6") (periodicPattern "10") (periodicJitter "0"))) (clocked ((clockRise "1e-09") (clockFall "1e-09") (clockFreq "100e6") (clockInitState "0") (clockDutyCycle "0.5") (clockJitter "0"))) (RLGC (length("1000 mil"))) (DiffInput ((temperature "27") (bufferModelNonInverting "CDSDefaultInput_2p5v") (bufferModelInverting "CDSDefaultInput_2p5v") (threshInputHighMin "1.7 V") (threshInputHighTyp "1.7  V") (threshInputHighMax "1.7  V") (threshInputLowMin "0.7  V") (threshInputLowTyp "0.7  V") (threshInputLowMax "0.7  V") (mappingTagNonInverting nil) (mappingTagInverting nil) (cycle "1"))) (async ((asyncTimePoints "") (asyncInitState "1"))) (DiffIO ((temperature "27") (bufferModelNonInverting "CDSDefaultIO_2p5v") (bufferModelInverting "CDSDefaultIO_2p5v") (stimuli nil) (offsets nil) (state "tristate") (cycle "1") (termMap nil) (setup "0.9e-09") (hold "0.4e-09") (rise nil) (fall nil) (threshInputHighMin "1.7 V") (threshInputHighTyp "1.7  V") (threshInputHighMax "1.7  V") (threshInputLowMin "0.7  V") (threshInputLowTyp "0.7  V") (threshInputLowMax "0.7 ") (threshOutputHighMin "2.365  V") (threshOutputHighTyp "2.5  V") (threshOutputHighMax "2.625  V") (threshOutputLowMin "1.275  V") (threshOutputLowTyp "1.7  V") (threshOutputLowMax "1.985  V") (mappingTagNonInverting nil) (mappingTagInverting nil) (spice nil))) (DiffOutput ((temperature "27") (bufferModelNonInverting "CDSDefaultOutput_2p5v") (bufferModelInverting "CDSDefaultOutput_2p5v") (stimuli nil) (offsets nil) (state "tristate") (cycle "1") (termMap nil) (setup "0.9e-09") (hold "0.4e-09") (rise nil) (fall nil) (threshOutputHighMin "2.375  V") (threshOutputHighTyp "2.5  V") (threshOutputHighMax "2.625  V") (threshOutputLowMin "1.275  V") (threshOutputLowTyp "1.7  V") (threshOutputLowMax "1.985  V") (mappingTagNonInverting nil) (mappingTagInverting nil) (spice nil))) (DiffIOPkg ((temperature "27") (bufferModelNonInverting "CDSDefaultIO_2p5v") (bufferModelInverting "CDSDefaultIO_2p5v") (stimuli nil) (offsets nil) (state "tristate") (cycle "1") (termMap nil) (setup "0.9e-09") (hold "0.4e-09") (rise nil) (fall nil) (threshInputHighMin "1.7 V") (threshInputHighTyp "1.7  V") (threshInputHighMax "1.7  V") (threshInputLowMin "0.7  V") (threshInputLowTyp "0.7  V") (threshInputLowMax "0.7 ") (threshOutputHighMin "2.365  V") (threshOutputHighTyp "2.5  V") (threshOutputHighMax "2.625  V") (threshOutputLowMin "1.275  V") (threshOutputLowTyp "1.7  V") (threshOutputLowMax "1.985  V") (mappingTagNonInverting nil) (mappingTagInverting nil) (spice nil))) (idlCircuit ((allDrivers "active") (ftsMode '("Typ")) (rcvrSelect "all") (simMode "Reflection") (tlineDelayMode "time") (userRevision "1.0") (autoSolve "On"))) (sync ((syncFreq "100e6") (syncInitState "1") (syncPattern "10") (syncEdgeSwitch "rise"))) (SeriesTerm ((resistance "22 ohm") (maxDelay "0.1 ns"))) (DiffOutputPkg ((temperature "27") (bufferModelNonInverting "CDSDefaultOutput_2p5v") (bufferModelInverting "CDSDefaultOutput_2p5v") (stimuli nil) (offsets nil) (state "tristate") (cycle "1") (termMap nil) (setup "0.9e-09") (hold "0.4e-09") (rise nil) (fall nil) (threshOutputHighMin "2.375  V") (threshOutputHighTyp "2.5  V") (threshOutputHighMax "2.625  V") (threshOutputLowMin "1.275  V") (threshOutputLowTyp "1.7  V") (threshOutputLowMax "1.985  V") (mappingTagNonInverting nil) (mappingTagInverting nil) (spice nil))) (IbisOutput ((temperature "27") (bufferModel "CDSDefaultOutput_2p5v") (stimuli nil) (offsets nil) (state "tristate") (cycle "1") (termMap nil) (setup "2.0e-09") (hold "1.0e-09") (rise nil) (fall nil) (macroType nil) (voltage nil) (spice nil) (LEFDEFPinName nil) (LEFDEFPinType nil) (mappingTag nil))) (CPW ((d1Thickness "10 mil") (d1Constant "4.5") (d1LossTangent "0.035") (d2Thickness "0.72 mil") (d2Constant "1") (d2LossTangent "0") (d3Thickness "0.0") (d3Constant "1") (d3LossTangent "0") length("1000 mil") (spacing "5 mil") (spacing2 "5 mil") (spacing3 "5 mil") (spacing4 "5 mil") (spacing5 "5 mil") (traceConductivity "595900 mho/cm") (traceGeometry "cpwms") (traceLayerName "") (traceThickness "0.72 mil") (traceType "single") (traceWidth "5.0 mil") (traceWidth2 "5.0 mil") (traceWidth3 "5.0 mil") (traceWidth4 "5.0 mil") (traceWidth5 "5.0 mil") (traceWidth6 "5.0 mil") (offset "0 mil") (traceCount "1") (impedance nil))) (CPWMS ((d1Thickness "10 mil") (d1Constant "4.5") (d1LossTangent "0.035") (d2Thickness "0.72 mil") (d2Constant "4.5") (d2LossTangent "0.035") (d3Thickness "0.0") (d3Constant "1") (d3LossTangent "0") length("1000 mil") (spacing "5 mil") (spacing2 "5 mil") (spacing3 "5 mil") (spacing4 "5 mil") (spacing5 "5 mil") (traceConductivity "595900 mho/cm") (traceGeometry "cpwms") (traceLayerName "") (traceThickness "0.72 mil") (traceType "single") (traceWidth "5.0 mil") (traceWidth2 "5.0 mil") (traceWidth3 "5.0 mil") (traceWidth4 "5.0 mil") (traceWidth5 "5.0 mil") (traceWidth6 "5.0 mil") (offset "0 mil") (traceCount "1") (impedance nil))) (CurrentProbe nil) (CPWSL ((d1Thickness "10 mil") (d1Constant "4.5") (d1LossTangent "0.035") (d2Thickness "0.72 mil") (d2Constant "4.5") (d2LossTangent "0.035") (d3Thickness "10 mil") (d3Constant "4.5") (d3LossTangent "0.035") length("1000 mil") (spacing "5 mil") (spacing2 "5 mil") (spacing3 "5 mil") (spacing4 "5 mil") (spacing5 "5 mil") (traceConductivity "595900 mho/cm") (traceGeometry "cpwms") (traceLayerName "") (traceThickness "0.72 mil") (traceType "single") (traceWidth "5.0 mil") (traceWidth2 "5.0 mil") (traceWidth3 "5.0 mil") (traceWidth4 "5.0 mil") (traceWidth5 "5.0 mil") (traceWidth6 "5.0 mil") (offset "0 mil") (traceCount "1") (impedance nil))) (ShuntTerm ((resistance "50 ohm") (voltage "5 V") (maxDelay "0.1 ns"))) (TheveninTerm ((resistanceUp "180 ohm") (resistanceDown "270 ohm") (voltageUp "5 V") (voltageDown "0 V") (maxDelay "0.1 ns"))) (Connector nil) (RCTerm ((resistance "50 ohm") (capacitance "20 pF") (voltage "5 V") (maxDelay "0.1 ns"))) (LowClampTerm ((cutoffVoltage "0.7 V") (voltage "0 V") (maxDelay "0.1 ns"))) (HiClampTerm ((cutoffVoltage "0.7 V") (voltage "5 V") (maxDelay "0.1 ns"))) (DualClampTerm ((cutoffVoltageUp "0.7 V") (cutoffVoltageDown "0.7 V") (voltageUp "5 V") (voltageDown "0 V") (maxDelay "0.1 ns"))) (Diode ((cutoffVoltage "0.7 V")))))
				)
				( objectStatus "CLK_100M_CPU_BCLKS" )
			)
			( electricalCSet "@crescent_city_bb_fab1_lib.crescent_city_bb_fab1(sch_1):\KTI_CPU1_CPU0_P1P1\"
				( groupRef "UPI_CPU1_CPU0_P1P1:MG_KTI_BUNDLE" )
				( groupRef "UPI_CPU1_CPU0_P1P1:MG_KTI_CPU1_CPU0_P1P1" )
				( pinPairRef "UPI_CPU1_CPU0_P1P1:U5D1.BH3:U2D1.AC10" )
				( attribute "DIFFP_GATHER_CONTROL" "IGNORE"
					( Origin gBackEnd )
				)
				( attribute "DIFFP_UNCOUPLED_LENGTH" "1000.00"
					( Origin gBackEnd )
				)
				( attribute "DIFFP_COUPLED_PLUS" "0.10"
					( Origin gBackEnd )
				)
				( attribute "DIFFP_COUPLED_MINUS" "0.10"
					( Origin gBackEnd )
				)
				( attribute "DIFFP_PHASE_TOL" "5 mil"
					( Units "uPhaseTol" "ns" 1.000000)
					( Origin gBackEnd )
				)
				( attribute "DIFFP_PHASE_MAX_LENGTH" "600.00"
					( Origin gBackEnd )
				)
				( attribute "DIFFP_PHASE_TOL_DYNAMIC" "50 mil"
					( Units "uPhaseTol" "mil" 1.000000)
					( Origin gBackEnd )
				)
				( attribute "DIFFP_MIN_SPACE" "4.00"
					( Origin gBackEnd )
				)
				( attribute "TOPOLOGY_TEMPLATE_REVISION" "1.0"
					( Origin gBackEnd )
				)
				( topologyData 22610
(SKIDL (Circuits ("MAIN" (Parts ("CRESCENT_CITY_089_20140807_B.@@U36.BH3" IbisIOPkg (xy (5528 4240)) (refDes "U5D1") (model "Unknown") (Props (_SXDesignName "CRESCENT_CITY_089_20140807_B") (brdx "12028.89 MIL") (brdy "2941.96 MIL") (bufferModel "CDSDefaultIO_2p5v") (cycle "1") (hold "1.0e-09") (mappingTag "") (offsets ("4" "0") ("5" "0")) (setup "2.0e-09") (state "tristate") (stimuli ("4" "local0") ("5" "local1")) (temperature "27") (termMap ("4" "Data") ("5" "Enable"))) (Terms ("CRESCENT_CITY_089_20140807_B.X1202889Y294196L2LRATS" "BH3"))) ("CRESCENT_CITY_089_20140807_B.@@U100.AC10" IbisIOPkg (xy (5502 4240)) (refDes "U2D1") (model "Unknown") (Props (_SXDesignName "CRESCENT_CITY_089_20140807_B") (brdx "5296.21 MIL") (brdy "2454.47 MIL") (bufferModel "CDSDefaultIO_2p5v") (cycle "1") (hold "1.0e-09") (mappingTag "") (offsets ("4" "0") ("5" "0")) (setup "2.0e-09") (state "tristate") (stimuli ("4" "local2") ("5" "local3")) (temperature "27") (termMap ("4" "Data") ("5" "Enable"))) (Terms ("CRESCENT_CITY_089_20140807_B.X529621Y245447L2LRATS" "AC10"))) ("CRESCENT_CITY_089_20140807_B.T@@RATS@@U36.BH3@@U100.AC10" TLine (xy (5513 4235)) (mirror x) (refDes "TL1") (Props (_SXDesignName "CRESCENT_CITY_089_20140807_B") (impedance "47.807 ohm") length("7220.16 MIL") (propDelay "1.29679 ns") (traceCount "1") (traceGeometry "Microstrip") (velocity "5567.72 mil/ns")) (Terms ("CRESCENT_CITY_089_20140807_B.X1202889Y294196L2LRATS" "1") ("CRESCENT_CITY_089_20140807_B.X529621Y245447L2LRATS" "2")))) (Nodes ("CRESCENT_CITY_089_20140807_B.X1202889Y294196L2LRATS" (terms "CRESCENT_CITY_089_20140807_B.T@@RATS@@U36.BH3@@U100.AC10.1" "CRESCENT_CITY_089_20140807_B.@@U36.BH3.1")) ("CRESCENT_CITY_089_20140807_B.X529621Y245447L2LRATS" (terms "CRESCENT_CITY_089_20140807_B.T@@RATS@@U36.BH3@@U100.AC10.2" "CRESCENT_CITY_089_20140807_B.@@U100.AC10.1"))) (Ports) (Stimuli ("local2" (scope local) (stimType periodic) (Props (periodicFreq "5e+007") (periodicJitter "0") (periodicPattern "1"))) ("local0" (scope local) (stimType periodic) (Props (periodicFreq "5e+007") (periodicJitter "0") (periodicPattern "1"))) ("local1" (scope local) (stimType periodic) (Props (periodicFreq "5e+007") (periodicJitter "0") (periodicPattern "1"))) ("local3" (scope local) (stimType periodic) (Props (periodicFreq "5e+007") (periodicJitter "0") (periodicPattern "1")))) (Notes) (Constraints ("DP_GATHER_CONTROL" "IGNORE") ("DP_MAX_UNCOUPLED_LENGTH" "0.000635") ("DP_MIN_LINE_SPACING" "0.0001016") ("DP_NEGATIVE_COUPLED_TOLERANCE" "2.54e-006") ("DP_PHASE_MAX_LENGTH" "0.01524") ("DP_PHASE_TOLERANCE" ("LENGTH" "0.000127")) ("DP_PHASE_TOLERANCE_DYNAMIC" ("LENGTH" "0.00127")) ("DP_POSITIVE_COUPLED_TOLERANCE" "2.54e-006") ("RELATIVE_PROPAGATION_DELAY" ("MG_KTI_BUNDLE" "CRESCENT_CITY_089_20140807_B U36.BH3" "CRESCENT_CITY_089_20140807_B U100.AC10" "NET GROUP" "LENGTH" "0.0127" "DELAY" "") ("MG_KTI_CPU1_CPU0_P1P1" "CRESCENT_CITY_089_20140807_B U36.BH3" "CRESCENT_CITY_089_20140807_B U100.AC10" "GLOBAL" "LENGTH" "0.026797" "LENGTH" "-0.026797"))) (MeasurementSets ("EMI" ("EMIStatus" status("on")) ("PeakEmission" status("on")) ("PeakFrequency" status("on")) ("PulseFreq" status("on")) ("RiseTime" status("on")) ("VoltageSwing" status("on"))) ("Reflection" ("BufferDelayFall" status("off")) ("BufferDelayRise" status("off")) ("EyeHeight" status("off")) ("EyeJitter" status("off")) ("EyeWidth" status("off")) ("FirstIncidentFall" status("off")) ("FirstIncidentRise" status("off")) ("Glitch" status("on")) ("GlitchFall" status("off")) ("GlitchRise" status("off")) ("Monotonic" status("on")) ("MonotonicFall" status("off")) ("MonotonicRise" status("off")) ("NoiseMargin" status("on")) ("NoiseMarginHigh" status("off")) ("NoiseMarginLow" status("off")) ("OvershootHigh" status("on")) ("OvershootLow" status("on")) ("PropDelay" status("on")) ("SettleDelay" status("on")) ("SettleDelayFall" status("off")) ("SettleDelayRise" status("off")) ("SwitchDelay" status("on")) ("SwitchDelayFall" status("off")) ("SwitchDelayRise" status("off"))) ("Crosstalk" ("Crosstalk" status("on"))) ("Custom")) (VectorSets) (Props (XnetName "KTI_CPU0_CPU1_P0P0_DP<0>") (allDrivers "active") (customSimType "Reflection") (ftsMode ("Typ")) (rcvrSelect "all") (tlineDelayMode "time") (userRevision "1.0")))) (Subckts) (CrossSections ("CRESCENT_CITY_089_20140807_B" (Props (SXDesignName "CRESCENT_CITY_089_20140807_B")) (Layers ("" (layerType "SURFACE") (material "AIR") (thickness "0 mil") (dielectricConstant "1.000000") (lossTangent "0") (etchFactor "0.000000") (elecCondVal "0 mho/cm") (thermCondVal "0 w/cm-degC")) ("" (layerType "DIELECTRIC") (material "CONFORMAL_COAT") (thickness "0.5 mil") (dielectricConstant "3.800000") (lossTangent "0.035") (etchFactor "0.000000") (elecCondVal "0 mho/cm") (thermCondVal "0.012 w/cm-degC")) ("TOP" (layerType "CONDUCTOR") (material "COPPER") (thickness "  1.800000 mil") (width "4.00 MIL") (dielectricConstant "4.500000") (lossTangent "0") (etchFactor "70.000000") (elecCondVal "595900.000000 mho/cm") (thermCondVal "0 w/cm-degC") (signalDieConstant "3.800000") (signalLossTangent "0.035")) ("" (layerType "DIELECTRIC") (material "FR-4") (thickness "  2.700000 mil") (dielectricConstant "4.000000") (lossTangent "0.035") (etchFactor "0.000000") (elecCondVal "0 mho/cm") (thermCondVal "0.012 w/cm-degC")) ("L2_GND1" (layerType "PLANE") (material "COPPER") (isShield t) (thickness "  1.200000 mil") (dielectricConstant "4.500000") (lossTangent "0.035") (etchFactor "90.000000") (elecCondVal "595900.000000 mho/cm") (thermCondVal "0.012 w/cm-degC")) ("" (layerType "DIELECTRIC") (material "FR-4") (thickness "  9.000000 mil") (dielectricConstant "4.100000") (lossTangent "0.035") (etchFactor "0.000000") (elecCondVal "0 mho/cm") (thermCondVal "0.012 w/cm-degC")) ("L3_SIG1" (layerType "CONDUCTOR") (material "COPPER") (thickness "  1.200000 mil") (width "4.00 MIL") (dielectricConstant "4.500000") (lossTangent "0.035") (etchFactor "90.000000") (elecCondVal "595900.000000 mho/cm") (thermCondVal "0.012 w/cm-degC") (signalDieConstant "4.100000") (signalLossTangent "0.035")) ("" (layerType "DIELECTRIC") (material "FR-4") (thickness "  3.300000 mil") (dielectricConstant "4.500000") (lossTangent "0.035") (etchFactor "0.000000") (elecCondVal "0 mho/cm") (thermCondVal "0 w/cm-degC")) ("L4_GND2" (layerType "PLANE") (material "COPPER") (isShield t) (thickness "  1.200000 mil") (dielectricConstant "4.500000") (lossTangent "0.035") (etchFactor "90.000000") (elecCondVal "595900.000000 mho/cm") (thermCondVal "0 w/cm-degC")) ("" (layerType "DIELECTRIC") (material "FR-4") (thickness "  9.000000 mil") (dielectricConstant "4.000000") (lossTangent "0.035") (etchFactor "0.000000") (elecCondVal "0 mho/cm") (thermCondVal "0.012 w/cm-degC")) ("L5_SIG2" (layerType "CONDUCTOR") (material "COPPER") (thickness "  1.200000 mil") (width "4.00 MIL") (dielectricConstant "4.500000") (lossTangent "0.035") (etchFactor "90.000000") (elecCondVal "595900.000000 mho/cm") (thermCondVal "0.012 w/cm-degC") (signalDieConstant "4.000000") (signalLossTangent "0.035")) ("" (layerType "DIELECTRIC") (material "FR-4") (thickness "  3.300000 mil") (dielectricConstant "4.500000") (lossTangent "0.035") (etchFactor "0.000000") (elecCondVal "0 mho/cm") (thermCondVal "0 w/cm-degC")) ("L6_GND3" (layerType "PLANE") (material "COPPER") (isShield t) (thickness "  1.200000 mil") (dielectricConstant "4.500000") (lossTangent "0.035") (etchFactor "90.000000") (elecCondVal "595900.000000 mho/cm") (thermCondVal "0 w/cm-degC")) ("" (layerType "DIELECTRIC") (material "FR-4") (thickness "  3.000000 mil") (dielectricConstant "4.100000") (lossTangent "0.035") (etchFactor "0.000000") (elecCondVal "0 mho/cm") (thermCondVal "0.012 w/cm-degC")) ("L7_PWR1-SIG" (layerType "PLANE") (material "COPPER") (isShield t) (thickness "  2.400000 mil") (dielectricConstant "4.500000") (lossTangent "0.035") (etchFactor "90.000000") (elecCondVal "595900.000000 mho/cm") (thermCondVal "0.012 w/cm-degC")) ("" (layerType "DIELECTRIC") (material "FR-4") (thickness "  6.600000 mil") (dielectricConstant "4.000000") (lossTangent "0.035") (etchFactor "0.000000") (elecCondVal "0 mho/cm") (thermCondVal "0.012 w/cm-degC")) ("L8_PWR2-SIG" (layerType "PLANE") (material "COPPER") (isShield t) (thickness "  2.400000 mil") (dielectricConstant "4.500000") (lossTangent "0.035") (etchFactor "90.000000") (elecCondVal "595900.000000 mho/cm") (thermCondVal "0.012 w/cm-degC")) ("" (layerType "DIELECTRIC") (material "FR-4") (thickness "  3.000000 mil") (dielectricConstant "4.500000") (lossTangent "0.035") (etchFactor "0.000000") (elecCondVal "0 mho/cm") (thermCondVal "0 w/cm-degC")) ("L9_GND4" (layerType "PLANE") (material "COPPER") (isShield t) (thickness "  1.200000 mil") (dielectricConstant "4.500000") (lossTangent "0.035") (etchFactor "90.000000") (elecCondVal "595900.000000 mho/cm") (thermCondVal "0 w/cm-degC")) ("" (layerType "DIELECTRIC") (material "FR-4") (thickness "  3.300000 mil") (dielectricConstant "4.100000") (lossTangent "0.035") (etchFactor "0.000000") (elecCondVal "0 mho/cm") (thermCondVal "0.012 w/cm-degC")) ("L10_SIG3" (layerType "CONDUCTOR") (material "COPPER") (thickness "  1.200000 mil") (width "4.00 MIL") (dielectricConstant "4.500000") (lossTangent "0.035") (etchFactor "90.000000") (elecCondVal "595900.000000 mho/cm") (thermCondVal "0.012 w/cm-degC") (signalDieConstant "4.100000") (signalLossTangent "0.035")) ("" (layerType "DIELECTRIC") (material "FR-4") (thickness "  9.000000 mil") (dielectricConstant "4.500000") (lossTangent "0.035") (etchFactor "0.000000") (elecCondVal "0 mho/cm") (thermCondVal "0 w/cm-degC")) ("L11_GND5" (layerType "PLANE") (material "COPPER") (isShield t) (thickness "  1.200000 mil") (dielectricConstant "4.500000") (lossTangent "0.035") (etchFactor "90.000000") (elecCondVal "595900.000000 mho/cm") (thermCondVal "0 w/cm-degC")) ("" (layerType "DIELECTRIC") (material "FR-4") (thickness "  3.300000 mil") (dielectricConstant "4.500000") (lossTangent "0.035") (etchFactor "0.000000") (elecCondVal "0 mho/cm") (thermCondVal "0.012 w/cm-degC")) ("L12_SIG4" (layerType "CONDUCTOR") (material "COPPER") (thickness "  1.200000 mil") (width "4.00 MIL") (dielectricConstant "4.500000") (lossTangent "0.035") (etchFactor "90.000000") (elecCondVal "595900.000000 mho/cm") (thermCondVal "0.012 w/cm-degC") (signalDieConstant "4.500000") (signalLossTangent "0.035")) ("" (layerType "DIELECTRIC") (material "FR-4") (thickness "  9.000000 mil") (dielectricConstant "4.500000") (lossTangent "0.035") (etchFactor "0.000000") (elecCondVal "0 mho/cm") (thermCondVal "0 w/cm-degC")) ("L13_GND6" (layerType "PLANE") (material "COPPER") (isShield t) (thickness "  1.200000 mil") (dielectricConstant "4.500000") (lossTangent "0.035") (etchFactor "90.000000") (elecCondVal "595900.000000 mho/cm") (thermCondVal "0.012 w/cm-degC")) ("" (layerType "DIELECTRIC") (material "FR-4") (thickness "  2.700000 mil") (dielectricConstant "4.500000") (lossTangent "0.035") (etchFactor "0.000000") (elecCondVal "0 mho/cm") (thermCondVal "0.012 w/cm-degC")) ("BOTTOM" (layerType "CONDUCTOR") (material "COPPER") (thickness "  1.800000 mil") (width "4.00 MIL") (dielectricConstant "4.500000") (lossTangent "0") (etchFactor "70.000000") (elecCondVal "595900.000000 mho/cm") (thermCondVal "0 w/cm-degC") (signalDieConstant "3.800000") (signalLossTangent "0.035")) ("" (layerType "DIELECTRIC") (material "CONFORMAL_COAT") (thickness "0.5 mil") (dielectricConstant "3.800000") (lossTangent "0.035") (etchFactor "0.000000") (elecCondVal "0 mho/cm") (thermCondVal "0.012 w/cm-degC")) ("" (layerType "SURFACE") (material "AIR") (thickness "0 mil") (dielectricConstant "1.000000") (lossTangent "0") (etchFactor "0.000000") (elecCondVal "0 mho/cm") (thermCondVal "0 w/cm-degC"))))) (Props (DesUnits "mils 2") (LayerStack ("DIELECTRIC" "DIELECTRIC" "BOTTOM" "DIELECTRIC" "L13_GND6" "DIELECTRIC" "L12_SIG4" "DIELECTRIC" "L11_GND5" "DIELECTRIC" "L10_SIG3" "DIELECTRIC" "L9_GND4" "DIELECTRIC" "L8_PWR2-SIG" "DIELECTRIC" "L7_PWR1-SIG" "DIELECTRIC" "L6_GND3" "DIELECTRIC" "L5_SIG2" "DIELECTRIC" "L4_GND2" "DIELECTRIC" "L3_SIG1" "DIELECTRIC" "L2_GND1" "DIELECTRIC" "TOP" "DIELECTRIC" "DIELECTRIC")) (Revision "16.600")) (Params (TLine ((diffImpedance "100ohm") (diffVelocity "1.4142e+08M/s") (impedance "60ohm") length("2800 mil") (propDelay "0.5 ns") (velocity "5600 mil/ns") (traceCount "1") (traceGeometry "Microstrip") (impedanceMin nil) (impedanceMax nil) (lengthMin nil) (lengthMax nil) (propDelayMin nil) (propDelayMax nil) (impedanceSweepCount nil) (propDelaySweepCount nil) (velocitySweepCount nil) (lengthSweepCount nil) (matchSetName nil))) (sync ((syncFreq "100e6") (syncInitState "1") (syncPattern "10") (syncEdgeSwitch "rise"))) (Connector nil) (IbisIOMacro ((temperature "27") (bufferModel "CDSDefaultIO_2p5v") (stimuli nil) (offsets nil) (state "tristate") (cycle "1") (termMap nil) (setup "2.0e-09") (hold "1.0e-09") (rise nil) (fall nil) (macroType nil) (voltage nil) (spice nil) (LEFDEFPinName nil) (LEFDEFPinType nil) (mappingTag nil))) (DiffInputPkg ((temperature "27") (bufferModelNonInverting "CDSDefaultInput_2p5v") (bufferModelInverting "CDSDefaultInput_2p5v") (threshInputHighMin "1.7 V") (threshInputHighTyp "1.7  V") (threshInputHighMax "1.7  V") (threshInputLowMin "0.7  V") (threshInputLowTyp "0.7  V") (threshInputLowMax "0.7  V") (mappingTagNonInverting nil) (mappingTagInverting nil) (cycle "1"))) (idlCircuit ((allDrivers "active") (ftsMode '("Typ")) (rcvrSelect "all") (simMode "Reflection") (tlineDelayMode "time") (userRevision "1.0") (autoSolve "On"))) (Inductor ((inductance "5 nH") (orientation "0"))) (DiffOutput ((temperature "27") (bufferModelNonInverting "CDSDefaultOutput_2p5v") (bufferModelInverting "CDSDefaultOutput_2p5v") (stimuli nil) (offsets nil) (state "tristate") (cycle "1") (termMap nil) (setup "0.9e-09") (hold "0.4e-09") (rise nil) (fall nil) (threshOutputHighMin "2.375  V") (threshOutputHighTyp "2.5  V") (threshOutputHighMax "2.625  V") (threshOutputLowMin "1.275  V") (threshOutputLowTyp "1.7  V") (threshOutputLowMax "1.985  V") (mappingTagNonInverting nil) (mappingTagInverting nil) (spice nil))) (HiClampTerm ((cutoffVoltage "0.7 V") (voltage "5 V") (maxDelay "0.1 ns"))) (Capacitor ((capacitance "10 pF") (orientation "0"))) (DiffOutputPkg ((temperature "27") (bufferModelNonInverting "CDSDefaultOutput_2p5v") (bufferModelInverting "CDSDefaultOutput_2p5v") (stimuli nil) (offsets nil) (state "tristate") (cycle "1") (termMap nil) (setup "0.9e-09") (hold "0.4e-09") (rise nil) (fall nil) (threshOutputHighMin "2.375  V") (threshOutputHighTyp "2.5  V") (threshOutputHighMax "2.625  V") (threshOutputLowMin "1.275  V") (threshOutputLowTyp "1.7  V") (threshOutputLowMax "1.985  V") (mappingTagNonInverting nil) (mappingTagInverting nil) (spice nil))) (DualClampTerm ((cutoffVoltageUp "0.7 V") (cutoffVoltageDown "0.7 V") (voltageUp "5 V") (voltageDown "0 V") (maxDelay "0.1 ns"))) (IbisOutput ((temperature "27") (bufferModel "CDSDefaultOutput_2p5v") (stimuli nil) (offsets nil) (state "tristate") (cycle "1") (termMap nil) (setup "2.0e-09") (hold "1.0e-09") (rise nil) (fall nil) (macroType nil) (voltage nil) (spice nil) (LEFDEFPinName nil) (LEFDEFPinType nil) (mappingTag nil))) (IbisIO ((temperature "27") (bufferModel "CDSDefaultIO_2p5v") (stimuli nil) (offsets nil) (state "tristate") (cycle "1") (termMap nil) (setup "2.0e-09") (hold "1.0e-09") (rise nil) (fall nil) (macroType nil) (voltage nil) (spice nil) (LEFDEFPinName nil) (LEFDEFPinType nil) (mappingTag nil))) (RLGC (length("1000 mil"))) (DiffIO ((temperature "27") (bufferModelNonInverting "CDSDefaultIO_2p5v") (bufferModelInverting "CDSDefaultIO_2p5v") (stimuli nil) (offsets nil) (state "tristate") (cycle "1") (termMap nil) (setup "0.9e-09") (hold "0.4e-09") (rise nil) (fall nil) (threshInputHighMin "1.7 V") (threshInputHighTyp "1.7  V") (threshInputHighMax "1.7  V") (threshInputLowMin "0.7  V") (threshInputLowTyp "0.7  V") (threshInputLowMax "0.7 ") (threshOutputHighMin "2.365  V") (threshOutputHighTyp "2.5  V") (threshOutputHighMax "2.625  V") (threshOutputLowMin "1.275  V") (threshOutputLowTyp "1.7  V") (threshOutputLowMax "1.985  V") (mappingTagNonInverting nil) (mappingTagInverting nil) (spice nil))) (Source ((voltage "5 V"))) (DiffIOPkg ((temperature "27") (bufferModelNonInverting "CDSDefaultIO_2p5v") (bufferModelInverting "CDSDefaultIO_2p5v") (stimuli nil) (offsets nil) (state "tristate") (cycle "1") (termMap nil) (setup "0.9e-09") (hold "0.4e-09") (rise nil) (fall nil) (threshInputHighMin "1.7 V") (threshInputHighTyp "1.7  V") (threshInputHighMax "1.7  V") (threshInputLowMin "0.7  V") (threshInputLowTyp "0.7  V") (threshInputLowMax "0.7 ") (threshOutputHighMin "2.365  V") (threshOutputHighTyp "2.5  V") (threshOutputHighMax "2.625  V") (threshOutputLowMin "1.275  V") (threshOutputLowTyp "1.7  V") (threshOutputLowMax "1.985  V") (mappingTagNonInverting nil) (mappingTagInverting nil) (spice nil))) (Diode ((cutoffVoltage "0.7 V"))) (ShuntTerm ((resistance "50 ohm") (voltage "5 V") (maxDelay "0.1 ns"))) (IbisIO_OpenPullDown ((temperature "27") (bufferModel "CDSDefaultIO_2p5v") (stimuli nil) (offsets nil) (state "tristate") (cycle "1") (termMap nil) (setup "2.0e-09") (hold "1.0e-09") (rise nil) (fall nil) (macroType nil) (voltage nil) (spice nil) (LEFDEFPinName nil) (LEFDEFPinType nil) (mappingTag nil))) (IbisIO_OpenPullUp ((temperature "27") (bufferModel "CDSDefaultIO_2p5v") (stimuli nil) (offsets nil) (state "tristate") (cycle "1") (termMap nil) (setup "2.0e-09") (hold "1.0e-09") (rise nil) (fall nil) (macroType nil) (voltage nil) (spice nil) (LEFDEFPinName nil) (LEFDEFPinType nil) (mappingTag nil))) (TheveninTerm ((resistanceUp "180 ohm") (resistanceDown "270 ohm") (voltageUp "5 V") (voltageDown "0 V") (maxDelay "0.1 ns"))) (Resistor ((resistance "50 ohm") (orientation "0"))) (RCTerm ((resistance "50 ohm") (capacitance "20 pF") (voltage "5 V") (maxDelay "0.1 ns"))) (DiffInput ((temperature "27") (bufferModelNonInverting "CDSDefaultInput_2p5v") (bufferModelInverting "CDSDefaultInput_2p5v") (threshInputHighMin "1.7 V") (threshInputHighTyp "1.7  V") (threshInputHighMax "1.7  V") (threshInputLowMin "0.7  V") (threshInputLowTyp "0.7  V") (threshInputLowMax "0.7  V") (mappingTagNonInverting nil) (mappingTagInverting nil) (cycle "1"))) (LowClampTerm ((cutoffVoltage "0.7 V") (voltage "0 V") (maxDelay "0.1 ns"))) (CPWSL ((d1Thickness "10 mil") (d1Constant "4.5") (d1LossTangent "0.035") (d2Thickness "0.72 mil") (d2Constant "4.5") (d2LossTangent "0.035") (d3Thickness "10 mil") (d3Constant "4.5") (d3LossTangent "0.035") length("1000 mil") (spacing "5 mil") (spacing2 "5 mil") (spacing3 "5 mil") (spacing4 "5 mil") (spacing5 "5 mil") (traceConductivity "595900 mho/cm") (traceGeometry "cpwms") (traceLayerName "") (traceThickness "0.72 mil") (traceType "single") (traceWidth "5.0 mil") (traceWidth2 "5.0 mil") (traceWidth3 "5.0 mil") (traceWidth4 "5.0 mil") (traceWidth5 "5.0 mil") (traceWidth6 "5.0 mil") (offset "0 mil") (traceCount "1") (impedance nil))) (Trace ((d1Thickness "10 mil") (d1Constant "4.5") (d1LossTangent "0.035") (d2Thickness "10 mil") (d2Constant "4.5") (d2LossTangent "0.035") (d3Thickness "0.0") (d3Constant "1.0") (d3LossTangent "0") length("1000 mil") (spacing "5 mil") (spacing2 "5 mil") (spacing3 "5 mil") (spacing4 "5 mil") (spacing5 "5 mil") (traceConductivity "595900 mho/cm") (traceGeometry "microstrip") (traceLayerName "") (traceThickness "0.72 mil") (traceType "single") (traceWidth "5.0 mil") (traceWidth2 "5.0 mil") (traceWidth3 "5.0 mil") (traceWidth4 "5.0 mil") (traceWidth5 "5.0 mil") (traceWidth6 "5.0 mil") (offset "0 mil") (traceCount "1") (impedance nil))) (CPWMS ((d1Thickness "10 mil") (d1Constant "4.5") (d1LossTangent "0.035") (d2Thickness "0.72 mil") (d2Constant "4.5") (d2LossTangent "0.035") (d3Thickness "0.0") (d3Constant "1") (d3LossTangent "0") length("1000 mil") (spacing "5 mil") (spacing2 "5 mil") (spacing3 "5 mil") (spacing4 "5 mil") (spacing5 "5 mil") (traceConductivity "595900 mho/cm") (traceGeometry "cpwms") (traceLayerName "") (traceThickness "0.72 mil") (traceType "single") (traceWidth "5.0 mil") (traceWidth2 "5.0 mil") (traceWidth3 "5.0 mil") (traceWidth4 "5.0 mil") (traceWidth5 "5.0 mil") (traceWidth6 "5.0 mil") (offset "0 mil") (traceCount "1") (impedance nil))) (CPW ((d1Thickness "10 mil") (d1Constant "4.5") (d1LossTangent "0.035") (d2Thickness "0.72 mil") (d2Constant "1") (d2LossTangent "0") (d3Thickness "0.0") (d3Constant "1") (d3LossTangent "0") length("1000 mil") (spacing "5 mil") (spacing2 "5 mil") (spacing3 "5 mil") (spacing4 "5 mil") (spacing5 "5 mil") (traceConductivity "595900 mho/cm") (traceGeometry "cpwms") (traceLayerName "") (traceThickness "0.72 mil") (traceType "single") (traceWidth "5.0 mil") (traceWidth2 "5.0 mil") (traceWidth3 "5.0 mil") (traceWidth4 "5.0 mil") (traceWidth5 "5.0 mil") (traceWidth6 "5.0 mil") (offset "0 mil") (traceCount "1") (impedance nil))) (async ((asyncTimePoints "") (asyncInitState "1"))) (IbisOutput_OpenPullUp ((temperature "27") (bufferModel "CDSDefaultOutput_2p5v") (stimuli nil) (offsets nil) (state "tristate") (cycle "1") (termMap nil) (setup "2.0e-09") (hold "1.0e-09") (rise nil) (fall nil) (macroType nil) (voltage nil) (spice nil) (LEFDEFPinName nil) (LEFDEFPinType nil) (mappingTag nil))) (Cable (length("1 m"))) (ESpiceDevice nil) (IbisInput ((temperature "27") (bufferModel "CDSDefaultInput_2p5v") (cycle "1") (LEFDEFPinName nil) (LEFDEFPinType nil) (mappingTag nil))) (SeriesTerm ((resistance "22 ohm") (maxDelay "0.1 ns"))) (IbisOutputPkg ((temperature "27") (bufferModel "CDSDefaultOutput_2p5v") (stimuli nil) (offsets nil) (state "tristate") (cycle "1") (termMap nil) (setup "2.0e-09") (hold "1.0e-09") (rise nil) (fall nil) (macroType nil) (voltage nil) (spice nil) (LEFDEFPinName nil) (LEFDEFPinType nil) (mappingTag nil))) (IbisIOPkg ((temperature "27") (bufferModel "CDSDefaultIO_2p5v") (stimuli nil) (offsets nil) (state "tristate") (cycle "1") (termMap nil) (setup "2.0e-09") (hold "1.0e-09") (rise nil) (fall nil) (macroType nil) (voltage nil) (spice nil) (LEFDEFPinName nil) (LEFDEFPinType nil) (mappingTag nil))) (CurrentProbe nil) (IbisInputPkg ((temperature "27") (bufferModel "CDSDefaultInput_2p5v") (cycle "1") (LEFDEFPinName nil) (LEFDEFPinType nil) (mappingTag nil))) (periodic ((periodicFreq "100e6") (periodicPattern "10") (periodicJitter "0"))) (clocked ((clockRise "1e-09") (clockFall "1e-09") (clockFreq "100e6") (clockInitState "0") (clockDutyCycle "0.5") (clockJitter "0"))) (Via ((model "Unknown") (viaOutputFormat "Unknown") (viaPadstack nil) (viaTopLayer nil) (viaBottomLayer nil) (viaIsPower nil) (viaIsGround nil)))))
				)
				( objectStatus "UPI_CPU1_CPU0_P1P1" )
			)
			( electricalCSet "@crescent_city_bb_fab1_lib.crescent_city_bb_fab1(sch_1):\KTI_CPU1_CPU0_P0P0\"
				( groupRef "UPI_CPU1_CPU0_P0P0:MG_KTI_BUNDLE" )
				( groupRef "UPI_CPU1_CPU0_P0P0:MG_KTI_CPU1_CPU0_P0P0" )
				( pinPairRef "UPI_CPU1_CPU0_P0P0:U5D1.BH3:U2D1.AC10" )
				( attribute "DIFFP_GATHER_CONTROL" "IGNORE"
					( Origin gBackEnd )
				)
				( attribute "DIFFP_UNCOUPLED_LENGTH" "1000.00"
					( Origin gBackEnd )
				)
				( attribute "DIFFP_COUPLED_PLUS" "0.10"
					( Origin gBackEnd )
				)
				( attribute "DIFFP_COUPLED_MINUS" "0.10"
					( Origin gBackEnd )
				)
				( attribute "DIFFP_PHASE_TOL" "5 mil"
					( Units "uPhaseTol" "ns" 1.000000)
					( Origin gBackEnd )
				)
				( attribute "DIFFP_PHASE_MAX_LENGTH" "600.00"
					( Origin gBackEnd )
				)
				( attribute "DIFFP_PHASE_TOL_DYNAMIC" "550 mil"
					( Units "uPhaseTol" "mil" 1.000000)
					( Origin gBackEnd )
				)
				( attribute "DIFFP_MIN_SPACE" "3.99"
					( Origin gBackEnd )
				)
				( attribute "TOPOLOGY_TEMPLATE_REVISION" "1.0"
					( Origin gBackEnd )
				)
				( topologyData 22610
(SKIDL (Circuits ("MAIN" (Parts ("CRESCENT_CITY_089_20140807_B.@@U36.BH3" IbisIOPkg (xy (5528 4240)) (refDes "U5D1") (model "Unknown") (Props (_SXDesignName "CRESCENT_CITY_089_20140807_B") (brdx "12028.89 MIL") (brdy "2941.96 MIL") (bufferModel "CDSDefaultIO_2p5v") (cycle "1") (hold "1.0e-09") (mappingTag "") (offsets ("4" "0") ("5" "0")) (setup "2.0e-09") (state "tristate") (stimuli ("4" "local0") ("5" "local1")) (temperature "27") (termMap ("4" "Data") ("5" "Enable"))) (Terms ("CRESCENT_CITY_089_20140807_B.X1202889Y294196L2LRATS" "BH3"))) ("CRESCENT_CITY_089_20140807_B.@@U100.AC10" IbisIOPkg (xy (5502 4240)) (refDes "U2D1") (model "Unknown") (Props (_SXDesignName "CRESCENT_CITY_089_20140807_B") (brdx "5296.21 MIL") (brdy "2454.47 MIL") (bufferModel "CDSDefaultIO_2p5v") (cycle "1") (hold "1.0e-09") (mappingTag "") (offsets ("4" "0") ("5" "0")) (setup "2.0e-09") (state "tristate") (stimuli ("4" "local2") ("5" "local3")) (temperature "27") (termMap ("4" "Data") ("5" "Enable"))) (Terms ("CRESCENT_CITY_089_20140807_B.X529621Y245447L2LRATS" "AC10"))) ("CRESCENT_CITY_089_20140807_B.T@@RATS@@U36.BH3@@U100.AC10" TLine (xy (5513 4235)) (mirror x) (refDes "TL1") (Props (_SXDesignName "CRESCENT_CITY_089_20140807_B") (impedance "47.807 ohm") length("7220.16 MIL") (propDelay "1.29679 ns") (traceCount "1") (traceGeometry "Microstrip") (velocity "5567.72 mil/ns")) (Terms ("CRESCENT_CITY_089_20140807_B.X1202889Y294196L2LRATS" "1") ("CRESCENT_CITY_089_20140807_B.X529621Y245447L2LRATS" "2")))) (Nodes ("CRESCENT_CITY_089_20140807_B.X1202889Y294196L2LRATS" (terms "CRESCENT_CITY_089_20140807_B.T@@RATS@@U36.BH3@@U100.AC10.1" "CRESCENT_CITY_089_20140807_B.@@U36.BH3.1")) ("CRESCENT_CITY_089_20140807_B.X529621Y245447L2LRATS" (terms "CRESCENT_CITY_089_20140807_B.T@@RATS@@U36.BH3@@U100.AC10.2" "CRESCENT_CITY_089_20140807_B.@@U100.AC10.1"))) (Ports) (Stimuli ("local2" (scope local) (stimType periodic) (Props (periodicFreq "5e+007") (periodicJitter "0") (periodicPattern "1"))) ("local0" (scope local) (stimType periodic) (Props (periodicFreq "5e+007") (periodicJitter "0") (periodicPattern "1"))) ("local1" (scope local) (stimType periodic) (Props (periodicFreq "5e+007") (periodicJitter "0") (periodicPattern "1"))) ("local3" (scope local) (stimType periodic) (Props (periodicFreq "5e+007") (periodicJitter "0") (periodicPattern "1")))) (Notes) (Constraints ("DP_GATHER_CONTROL" "IGNORE") ("DP_MAX_UNCOUPLED_LENGTH" "0.000635") ("DP_MIN_LINE_SPACING" "0.0001016") ("DP_NEGATIVE_COUPLED_TOLERANCE" "2.54e-006") ("DP_PHASE_MAX_LENGTH" "0.01524") ("DP_PHASE_TOLERANCE" ("LENGTH" "0.000127")) ("DP_PHASE_TOLERANCE_DYNAMIC" ("LENGTH" "0.00127")) ("DP_POSITIVE_COUPLED_TOLERANCE" "2.54e-006") ("RELATIVE_PROPAGATION_DELAY" ("MG_KTI_BUNDLE" "CRESCENT_CITY_089_20140807_B U36.BH3" "CRESCENT_CITY_089_20140807_B U100.AC10" "NET GROUP" "LENGTH" "0.0127" "DELAY" "") ("MG_KTI_CPU1_CPU0_P0P0" "CRESCENT_CITY_089_20140807_B U36.BH3" "CRESCENT_CITY_089_20140807_B U100.AC10" "GLOBAL" "LENGTH" "0.033401" "LENGTH" "-0.033401"))) (MeasurementSets ("EMI" ("EMIStatus" status("on")) ("PeakEmission" status("on")) ("PeakFrequency" status("on")) ("PulseFreq" status("on")) ("RiseTime" status("on")) ("VoltageSwing" status("on"))) ("Reflection" ("BufferDelayFall" status("off")) ("BufferDelayRise" status("off")) ("EyeHeight" status("off")) ("EyeJitter" status("off")) ("EyeWidth" status("off")) ("FirstIncidentFall" status("off")) ("FirstIncidentRise" status("off")) ("Glitch" status("on")) ("GlitchFall" status("off")) ("GlitchRise" status("off")) ("Monotonic" status("on")) ("MonotonicFall" status("off")) ("MonotonicRise" status("off")) ("NoiseMargin" status("on")) ("NoiseMarginHigh" status("off")) ("NoiseMarginLow" status("off")) ("OvershootHigh" status("on")) ("OvershootLow" status("on")) ("PropDelay" status("on")) ("SettleDelay" status("on")) ("SettleDelayFall" status("off")) ("SettleDelayRise" status("off")) ("SwitchDelay" status("on")) ("SwitchDelayFall" status("off")) ("SwitchDelayRise" status("off"))) ("Crosstalk" ("Crosstalk" status("on"))) ("Custom")) (VectorSets) (Props (XnetName "KTI_CPU0_CPU1_P0P0_DP<0>") (allDrivers "active") (customSimType "Reflection") (ftsMode ("Typ")) (rcvrSelect "all") (tlineDelayMode "time") (userRevision "1.0")))) (Subckts) (CrossSections ("CRESCENT_CITY_089_20140807_B" (Props (SXDesignName "CRESCENT_CITY_089_20140807_B")) (Layers ("" (layerType "SURFACE") (material "AIR") (thickness "0 mil") (dielectricConstant "1.000000") (lossTangent "0") (etchFactor "0.000000") (elecCondVal "0 mho/cm") (thermCondVal "0 w/cm-degC")) ("" (layerType "DIELECTRIC") (material "CONFORMAL_COAT") (thickness "0.5 mil") (dielectricConstant "3.800000") (lossTangent "0.035") (etchFactor "0.000000") (elecCondVal "0 mho/cm") (thermCondVal "0.012 w/cm-degC")) ("TOP" (layerType "CONDUCTOR") (material "COPPER") (thickness "  1.800000 mil") (width "4.00 MIL") (dielectricConstant "4.500000") (lossTangent "0") (etchFactor "70.000000") (elecCondVal "595900.000000 mho/cm") (thermCondVal "0 w/cm-degC") (signalDieConstant "3.800000") (signalLossTangent "0.035")) ("" (layerType "DIELECTRIC") (material "FR-4") (thickness "  2.700000 mil") (dielectricConstant "4.000000") (lossTangent "0.035") (etchFactor "0.000000") (elecCondVal "0 mho/cm") (thermCondVal "0.012 w/cm-degC")) ("L2_GND1" (layerType "PLANE") (material "COPPER") (isShield t) (thickness "  1.200000 mil") (dielectricConstant "4.500000") (lossTangent "0.035") (etchFactor "90.000000") (elecCondVal "595900.000000 mho/cm") (thermCondVal "0.012 w/cm-degC")) ("" (layerType "DIELECTRIC") (material "FR-4") (thickness "  9.000000 mil") (dielectricConstant "4.100000") (lossTangent "0.035") (etchFactor "0.000000") (elecCondVal "0 mho/cm") (thermCondVal "0.012 w/cm-degC")) ("L3_SIG1" (layerType "CONDUCTOR") (material "COPPER") (thickness "  1.200000 mil") (width "4.00 MIL") (dielectricConstant "4.500000") (lossTangent "0.035") (etchFactor "90.000000") (elecCondVal "595900.000000 mho/cm") (thermCondVal "0.012 w/cm-degC") (signalDieConstant "4.100000") (signalLossTangent "0.035")) ("" (layerType "DIELECTRIC") (material "FR-4") (thickness "  3.300000 mil") (dielectricConstant "4.500000") (lossTangent "0.035") (etchFactor "0.000000") (elecCondVal "0 mho/cm") (thermCondVal "0 w/cm-degC")) ("L4_GND2" (layerType "PLANE") (material "COPPER") (isShield t) (thickness "  1.200000 mil") (dielectricConstant "4.500000") (lossTangent "0.035") (etchFactor "90.000000") (elecCondVal "595900.000000 mho/cm") (thermCondVal "0 w/cm-degC")) ("" (layerType "DIELECTRIC") (material "FR-4") (thickness "  9.000000 mil") (dielectricConstant "4.000000") (lossTangent "0.035") (etchFactor "0.000000") (elecCondVal "0 mho/cm") (thermCondVal "0.012 w/cm-degC")) ("L5_SIG2" (layerType "CONDUCTOR") (material "COPPER") (thickness "  1.200000 mil") (width "4.00 MIL") (dielectricConstant "4.500000") (lossTangent "0.035") (etchFactor "90.000000") (elecCondVal "595900.000000 mho/cm") (thermCondVal "0.012 w/cm-degC") (signalDieConstant "4.000000") (signalLossTangent "0.035")) ("" (layerType "DIELECTRIC") (material "FR-4") (thickness "  3.300000 mil") (dielectricConstant "4.500000") (lossTangent "0.035") (etchFactor "0.000000") (elecCondVal "0 mho/cm") (thermCondVal "0 w/cm-degC")) ("L6_GND3" (layerType "PLANE") (material "COPPER") (isShield t) (thickness "  1.200000 mil") (dielectricConstant "4.500000") (lossTangent "0.035") (etchFactor "90.000000") (elecCondVal "595900.000000 mho/cm") (thermCondVal "0 w/cm-degC")) ("" (layerType "DIELECTRIC") (material "FR-4") (thickness "  3.000000 mil") (dielectricConstant "4.100000") (lossTangent "0.035") (etchFactor "0.000000") (elecCondVal "0 mho/cm") (thermCondVal "0.012 w/cm-degC")) ("L7_PWR1-SIG" (layerType "PLANE") (material "COPPER") (isShield t) (thickness "  2.400000 mil") (dielectricConstant "4.500000") (lossTangent "0.035") (etchFactor "90.000000") (elecCondVal "595900.000000 mho/cm") (thermCondVal "0.012 w/cm-degC")) ("" (layerType "DIELECTRIC") (material "FR-4") (thickness "  6.600000 mil") (dielectricConstant "4.000000") (lossTangent "0.035") (etchFactor "0.000000") (elecCondVal "0 mho/cm") (thermCondVal "0.012 w/cm-degC")) ("L8_PWR2-SIG" (layerType "PLANE") (material "COPPER") (isShield t) (thickness "  2.400000 mil") (dielectricConstant "4.500000") (lossTangent "0.035") (etchFactor "90.000000") (elecCondVal "595900.000000 mho/cm") (thermCondVal "0.012 w/cm-degC")) ("" (layerType "DIELECTRIC") (material "FR-4") (thickness "  3.000000 mil") (dielectricConstant "4.500000") (lossTangent "0.035") (etchFactor "0.000000") (elecCondVal "0 mho/cm") (thermCondVal "0 w/cm-degC")) ("L9_GND4" (layerType "PLANE") (material "COPPER") (isShield t) (thickness "  1.200000 mil") (dielectricConstant "4.500000") (lossTangent "0.035") (etchFactor "90.000000") (elecCondVal "595900.000000 mho/cm") (thermCondVal "0 w/cm-degC")) ("" (layerType "DIELECTRIC") (material "FR-4") (thickness "  3.300000 mil") (dielectricConstant "4.100000") (lossTangent "0.035") (etchFactor "0.000000") (elecCondVal "0 mho/cm") (thermCondVal "0.012 w/cm-degC")) ("L10_SIG3" (layerType "CONDUCTOR") (material "COPPER") (thickness "  1.200000 mil") (width "4.00 MIL") (dielectricConstant "4.500000") (lossTangent "0.035") (etchFactor "90.000000") (elecCondVal "595900.000000 mho/cm") (thermCondVal "0.012 w/cm-degC") (signalDieConstant "4.100000") (signalLossTangent "0.035")) ("" (layerType "DIELECTRIC") (material "FR-4") (thickness "  9.000000 mil") (dielectricConstant "4.500000") (lossTangent "0.035") (etchFactor "0.000000") (elecCondVal "0 mho/cm") (thermCondVal "0 w/cm-degC")) ("L11_GND5" (layerType "PLANE") (material "COPPER") (isShield t) (thickness "  1.200000 mil") (dielectricConstant "4.500000") (lossTangent "0.035") (etchFactor "90.000000") (elecCondVal "595900.000000 mho/cm") (thermCondVal "0 w/cm-degC")) ("" (layerType "DIELECTRIC") (material "FR-4") (thickness "  3.300000 mil") (dielectricConstant "4.500000") (lossTangent "0.035") (etchFactor "0.000000") (elecCondVal "0 mho/cm") (thermCondVal "0.012 w/cm-degC")) ("L12_SIG4" (layerType "CONDUCTOR") (material "COPPER") (thickness "  1.200000 mil") (width "4.00 MIL") (dielectricConstant "4.500000") (lossTangent "0.035") (etchFactor "90.000000") (elecCondVal "595900.000000 mho/cm") (thermCondVal "0.012 w/cm-degC") (signalDieConstant "4.500000") (signalLossTangent "0.035")) ("" (layerType "DIELECTRIC") (material "FR-4") (thickness "  9.000000 mil") (dielectricConstant "4.500000") (lossTangent "0.035") (etchFactor "0.000000") (elecCondVal "0 mho/cm") (thermCondVal "0 w/cm-degC")) ("L13_GND6" (layerType "PLANE") (material "COPPER") (isShield t) (thickness "  1.200000 mil") (dielectricConstant "4.500000") (lossTangent "0.035") (etchFactor "90.000000") (elecCondVal "595900.000000 mho/cm") (thermCondVal "0.012 w/cm-degC")) ("" (layerType "DIELECTRIC") (material "FR-4") (thickness "  2.700000 mil") (dielectricConstant "4.500000") (lossTangent "0.035") (etchFactor "0.000000") (elecCondVal "0 mho/cm") (thermCondVal "0.012 w/cm-degC")) ("BOTTOM" (layerType "CONDUCTOR") (material "COPPER") (thickness "  1.800000 mil") (width "4.00 MIL") (dielectricConstant "4.500000") (lossTangent "0") (etchFactor "70.000000") (elecCondVal "595900.000000 mho/cm") (thermCondVal "0 w/cm-degC") (signalDieConstant "3.800000") (signalLossTangent "0.035")) ("" (layerType "DIELECTRIC") (material "CONFORMAL_COAT") (thickness "0.5 mil") (dielectricConstant "3.800000") (lossTangent "0.035") (etchFactor "0.000000") (elecCondVal "0 mho/cm") (thermCondVal "0.012 w/cm-degC")) ("" (layerType "SURFACE") (material "AIR") (thickness "0 mil") (dielectricConstant "1.000000") (lossTangent "0") (etchFactor "0.000000") (elecCondVal "0 mho/cm") (thermCondVal "0 w/cm-degC"))))) (Props (DesUnits "mils 2") (LayerStack ("DIELECTRIC" "DIELECTRIC" "BOTTOM" "DIELECTRIC" "L13_GND6" "DIELECTRIC" "L12_SIG4" "DIELECTRIC" "L11_GND5" "DIELECTRIC" "L10_SIG3" "DIELECTRIC" "L9_GND4" "DIELECTRIC" "L8_PWR2-SIG" "DIELECTRIC" "L7_PWR1-SIG" "DIELECTRIC" "L6_GND3" "DIELECTRIC" "L5_SIG2" "DIELECTRIC" "L4_GND2" "DIELECTRIC" "L3_SIG1" "DIELECTRIC" "L2_GND1" "DIELECTRIC" "TOP" "DIELECTRIC" "DIELECTRIC")) (Revision "16.600")) (Params (TLine ((diffImpedance "100ohm") (diffVelocity "1.4142e+08M/s") (impedance "60ohm") length("2800 mil") (propDelay "0.5 ns") (velocity "5600 mil/ns") (traceCount "1") (traceGeometry "Microstrip") (impedanceMin nil) (impedanceMax nil) (lengthMin nil) (lengthMax nil) (propDelayMin nil) (propDelayMax nil) (impedanceSweepCount nil) (propDelaySweepCount nil) (velocitySweepCount nil) (lengthSweepCount nil) (matchSetName nil))) (sync ((syncFreq "100e6") (syncInitState "1") (syncPattern "10") (syncEdgeSwitch "rise"))) (Connector nil) (IbisIOMacro ((temperature "27") (bufferModel "CDSDefaultIO_2p5v") (stimuli nil) (offsets nil) (state "tristate") (cycle "1") (termMap nil) (setup "2.0e-09") (hold "1.0e-09") (rise nil) (fall nil) (macroType nil) (voltage nil) (spice nil) (LEFDEFPinName nil) (LEFDEFPinType nil) (mappingTag nil))) (DiffInputPkg ((temperature "27") (bufferModelNonInverting "CDSDefaultInput_2p5v") (bufferModelInverting "CDSDefaultInput_2p5v") (threshInputHighMin "1.7 V") (threshInputHighTyp "1.7  V") (threshInputHighMax "1.7  V") (threshInputLowMin "0.7  V") (threshInputLowTyp "0.7  V") (threshInputLowMax "0.7  V") (mappingTagNonInverting nil) (mappingTagInverting nil) (cycle "1"))) (idlCircuit ((allDrivers "active") (ftsMode '("Typ")) (rcvrSelect "all") (simMode "Reflection") (tlineDelayMode "time") (userRevision "1.0") (autoSolve "On"))) (Inductor ((inductance "5 nH") (orientation "0"))) (DiffOutput ((temperature "27") (bufferModelNonInverting "CDSDefaultOutput_2p5v") (bufferModelInverting "CDSDefaultOutput_2p5v") (stimuli nil) (offsets nil) (state "tristate") (cycle "1") (termMap nil) (setup "0.9e-09") (hold "0.4e-09") (rise nil) (fall nil) (threshOutputHighMin "2.375  V") (threshOutputHighTyp "2.5  V") (threshOutputHighMax "2.625  V") (threshOutputLowMin "1.275  V") (threshOutputLowTyp "1.7  V") (threshOutputLowMax "1.985  V") (mappingTagNonInverting nil) (mappingTagInverting nil) (spice nil))) (HiClampTerm ((cutoffVoltage "0.7 V") (voltage "5 V") (maxDelay "0.1 ns"))) (Capacitor ((capacitance "10 pF") (orientation "0"))) (DiffOutputPkg ((temperature "27") (bufferModelNonInverting "CDSDefaultOutput_2p5v") (bufferModelInverting "CDSDefaultOutput_2p5v") (stimuli nil) (offsets nil) (state "tristate") (cycle "1") (termMap nil) (setup "0.9e-09") (hold "0.4e-09") (rise nil) (fall nil) (threshOutputHighMin "2.375  V") (threshOutputHighTyp "2.5  V") (threshOutputHighMax "2.625  V") (threshOutputLowMin "1.275  V") (threshOutputLowTyp "1.7  V") (threshOutputLowMax "1.985  V") (mappingTagNonInverting nil) (mappingTagInverting nil) (spice nil))) (DualClampTerm ((cutoffVoltageUp "0.7 V") (cutoffVoltageDown "0.7 V") (voltageUp "5 V") (voltageDown "0 V") (maxDelay "0.1 ns"))) (IbisOutput ((temperature "27") (bufferModel "CDSDefaultOutput_2p5v") (stimuli nil) (offsets nil) (state "tristate") (cycle "1") (termMap nil) (setup "2.0e-09") (hold "1.0e-09") (rise nil) (fall nil) (macroType nil) (voltage nil) (spice nil) (LEFDEFPinName nil) (LEFDEFPinType nil) (mappingTag nil))) (IbisIO ((temperature "27") (bufferModel "CDSDefaultIO_2p5v") (stimuli nil) (offsets nil) (state "tristate") (cycle "1") (termMap nil) (setup "2.0e-09") (hold "1.0e-09") (rise nil) (fall nil) (macroType nil) (voltage nil) (spice nil) (LEFDEFPinName nil) (LEFDEFPinType nil) (mappingTag nil))) (RLGC (length("1000 mil"))) (DiffIO ((temperature "27") (bufferModelNonInverting "CDSDefaultIO_2p5v") (bufferModelInverting "CDSDefaultIO_2p5v") (stimuli nil) (offsets nil) (state "tristate") (cycle "1") (termMap nil) (setup "0.9e-09") (hold "0.4e-09") (rise nil) (fall nil) (threshInputHighMin "1.7 V") (threshInputHighTyp "1.7  V") (threshInputHighMax "1.7  V") (threshInputLowMin "0.7  V") (threshInputLowTyp "0.7  V") (threshInputLowMax "0.7 ") (threshOutputHighMin "2.365  V") (threshOutputHighTyp "2.5  V") (threshOutputHighMax "2.625  V") (threshOutputLowMin "1.275  V") (threshOutputLowTyp "1.7  V") (threshOutputLowMax "1.985  V") (mappingTagNonInverting nil) (mappingTagInverting nil) (spice nil))) (Source ((voltage "5 V"))) (DiffIOPkg ((temperature "27") (bufferModelNonInverting "CDSDefaultIO_2p5v") (bufferModelInverting "CDSDefaultIO_2p5v") (stimuli nil) (offsets nil) (state "tristate") (cycle "1") (termMap nil) (setup "0.9e-09") (hold "0.4e-09") (rise nil) (fall nil) (threshInputHighMin "1.7 V") (threshInputHighTyp "1.7  V") (threshInputHighMax "1.7  V") (threshInputLowMin "0.7  V") (threshInputLowTyp "0.7  V") (threshInputLowMax "0.7 ") (threshOutputHighMin "2.365  V") (threshOutputHighTyp "2.5  V") (threshOutputHighMax "2.625  V") (threshOutputLowMin "1.275  V") (threshOutputLowTyp "1.7  V") (threshOutputLowMax "1.985  V") (mappingTagNonInverting nil) (mappingTagInverting nil) (spice nil))) (Diode ((cutoffVoltage "0.7 V"))) (ShuntTerm ((resistance "50 ohm") (voltage "5 V") (maxDelay "0.1 ns"))) (IbisIO_OpenPullDown ((temperature "27") (bufferModel "CDSDefaultIO_2p5v") (stimuli nil) (offsets nil) (state "tristate") (cycle "1") (termMap nil) (setup "2.0e-09") (hold "1.0e-09") (rise nil) (fall nil) (macroType nil) (voltage nil) (spice nil) (LEFDEFPinName nil) (LEFDEFPinType nil) (mappingTag nil))) (IbisIO_OpenPullUp ((temperature "27") (bufferModel "CDSDefaultIO_2p5v") (stimuli nil) (offsets nil) (state "tristate") (cycle "1") (termMap nil) (setup "2.0e-09") (hold "1.0e-09") (rise nil) (fall nil) (macroType nil) (voltage nil) (spice nil) (LEFDEFPinName nil) (LEFDEFPinType nil) (mappingTag nil))) (TheveninTerm ((resistanceUp "180 ohm") (resistanceDown "270 ohm") (voltageUp "5 V") (voltageDown "0 V") (maxDelay "0.1 ns"))) (Resistor ((resistance "50 ohm") (orientation "0"))) (RCTerm ((resistance "50 ohm") (capacitance "20 pF") (voltage "5 V") (maxDelay "0.1 ns"))) (DiffInput ((temperature "27") (bufferModelNonInverting "CDSDefaultInput_2p5v") (bufferModelInverting "CDSDefaultInput_2p5v") (threshInputHighMin "1.7 V") (threshInputHighTyp "1.7  V") (threshInputHighMax "1.7  V") (threshInputLowMin "0.7  V") (threshInputLowTyp "0.7  V") (threshInputLowMax "0.7  V") (mappingTagNonInverting nil) (mappingTagInverting nil) (cycle "1"))) (LowClampTerm ((cutoffVoltage "0.7 V") (voltage "0 V") (maxDelay "0.1 ns"))) (CPWSL ((d1Thickness "10 mil") (d1Constant "4.5") (d1LossTangent "0.035") (d2Thickness "0.72 mil") (d2Constant "4.5") (d2LossTangent "0.035") (d3Thickness "10 mil") (d3Constant "4.5") (d3LossTangent "0.035") length("1000 mil") (spacing "5 mil") (spacing2 "5 mil") (spacing3 "5 mil") (spacing4 "5 mil") (spacing5 "5 mil") (traceConductivity "595900 mho/cm") (traceGeometry "cpwms") (traceLayerName "") (traceThickness "0.72 mil") (traceType "single") (traceWidth "5.0 mil") (traceWidth2 "5.0 mil") (traceWidth3 "5.0 mil") (traceWidth4 "5.0 mil") (traceWidth5 "5.0 mil") (traceWidth6 "5.0 mil") (offset "0 mil") (traceCount "1") (impedance nil))) (Trace ((d1Thickness "10 mil") (d1Constant "4.5") (d1LossTangent "0.035") (d2Thickness "10 mil") (d2Constant "4.5") (d2LossTangent "0.035") (d3Thickness "0.0") (d3Constant "1.0") (d3LossTangent "0") length("1000 mil") (spacing "5 mil") (spacing2 "5 mil") (spacing3 "5 mil") (spacing4 "5 mil") (spacing5 "5 mil") (traceConductivity "595900 mho/cm") (traceGeometry "microstrip") (traceLayerName "") (traceThickness "0.72 mil") (traceType "single") (traceWidth "5.0 mil") (traceWidth2 "5.0 mil") (traceWidth3 "5.0 mil") (traceWidth4 "5.0 mil") (traceWidth5 "5.0 mil") (traceWidth6 "5.0 mil") (offset "0 mil") (traceCount "1") (impedance nil))) (CPWMS ((d1Thickness "10 mil") (d1Constant "4.5") (d1LossTangent "0.035") (d2Thickness "0.72 mil") (d2Constant "4.5") (d2LossTangent "0.035") (d3Thickness "0.0") (d3Constant "1") (d3LossTangent "0") length("1000 mil") (spacing "5 mil") (spacing2 "5 mil") (spacing3 "5 mil") (spacing4 "5 mil") (spacing5 "5 mil") (traceConductivity "595900 mho/cm") (traceGeometry "cpwms") (traceLayerName "") (traceThickness "0.72 mil") (traceType "single") (traceWidth "5.0 mil") (traceWidth2 "5.0 mil") (traceWidth3 "5.0 mil") (traceWidth4 "5.0 mil") (traceWidth5 "5.0 mil") (traceWidth6 "5.0 mil") (offset "0 mil") (traceCount "1") (impedance nil))) (CPW ((d1Thickness "10 mil") (d1Constant "4.5") (d1LossTangent "0.035") (d2Thickness "0.72 mil") (d2Constant "1") (d2LossTangent "0") (d3Thickness "0.0") (d3Constant "1") (d3LossTangent "0") length("1000 mil") (spacing "5 mil") (spacing2 "5 mil") (spacing3 "5 mil") (spacing4 "5 mil") (spacing5 "5 mil") (traceConductivity "595900 mho/cm") (traceGeometry "cpwms") (traceLayerName "") (traceThickness "0.72 mil") (traceType "single") (traceWidth "5.0 mil") (traceWidth2 "5.0 mil") (traceWidth3 "5.0 mil") (traceWidth4 "5.0 mil") (traceWidth5 "5.0 mil") (traceWidth6 "5.0 mil") (offset "0 mil") (traceCount "1") (impedance nil))) (async ((asyncTimePoints "") (asyncInitState "1"))) (IbisOutput_OpenPullUp ((temperature "27") (bufferModel "CDSDefaultOutput_2p5v") (stimuli nil) (offsets nil) (state "tristate") (cycle "1") (termMap nil) (setup "2.0e-09") (hold "1.0e-09") (rise nil) (fall nil) (macroType nil) (voltage nil) (spice nil) (LEFDEFPinName nil) (LEFDEFPinType nil) (mappingTag nil))) (Cable (length("1 m"))) (ESpiceDevice nil) (IbisInput ((temperature "27") (bufferModel "CDSDefaultInput_2p5v") (cycle "1") (LEFDEFPinName nil) (LEFDEFPinType nil) (mappingTag nil))) (SeriesTerm ((resistance "22 ohm") (maxDelay "0.1 ns"))) (IbisOutputPkg ((temperature "27") (bufferModel "CDSDefaultOutput_2p5v") (stimuli nil) (offsets nil) (state "tristate") (cycle "1") (termMap nil) (setup "2.0e-09") (hold "1.0e-09") (rise nil) (fall nil) (macroType nil) (voltage nil) (spice nil) (LEFDEFPinName nil) (LEFDEFPinType nil) (mappingTag nil))) (IbisIOPkg ((temperature "27") (bufferModel "CDSDefaultIO_2p5v") (stimuli nil) (offsets nil) (state "tristate") (cycle "1") (termMap nil) (setup "2.0e-09") (hold "1.0e-09") (rise nil) (fall nil) (macroType nil) (voltage nil) (spice nil) (LEFDEFPinName nil) (LEFDEFPinType nil) (mappingTag nil))) (CurrentProbe nil) (IbisInputPkg ((temperature "27") (bufferModel "CDSDefaultInput_2p5v") (cycle "1") (LEFDEFPinName nil) (LEFDEFPinType nil) (mappingTag nil))) (periodic ((periodicFreq "100e6") (periodicPattern "10") (periodicJitter "0"))) (clocked ((clockRise "1e-09") (clockFall "1e-09") (clockFreq "100e6") (clockInitState "0") (clockDutyCycle "0.5") (clockJitter "0"))) (Via ((model "Unknown") (viaOutputFormat "Unknown") (viaPadstack nil) (viaTopLayer nil) (viaBottomLayer nil) (viaIsPower nil) (viaIsGround nil)))))
				)
				( objectStatus "UPI_CPU1_CPU0_P0P0" )
			)
			( electricalCSet "@crescent_city_bb_fab1_lib.crescent_city_bb_fab1(sch_1):\KTI_CPU0_CPU1_P1P1\"
				( groupRef "UPI_CPU0_CPU1_P1P1:MG_KTI_BUNDLE" )
				( groupRef "UPI_CPU0_CPU1_P1P1:MG_KTI_CPU0_CPU1_P1P1" )
				( pinPairRef "UPI_CPU0_CPU1_P1P1:U5D1.BH3:U2D1.AC10" )
				( attribute "DIFFP_GATHER_CONTROL" "IGNORE"
					( Origin gBackEnd )
				)
				( attribute "DIFFP_UNCOUPLED_LENGTH" "1000.00"
					( Origin gBackEnd )
				)
				( attribute "DIFFP_COUPLED_PLUS" "0.10"
					( Origin gBackEnd )
				)
				( attribute "DIFFP_COUPLED_MINUS" "0.10"
					( Origin gBackEnd )
				)
				( attribute "DIFFP_PHASE_TOL" "5 mil"
					( Units "uPhaseTol" "ns" 1.000000)
					( Origin gBackEnd )
				)
				( attribute "DIFFP_PHASE_MAX_LENGTH" "600.00"
					( Origin gBackEnd )
				)
				( attribute "DIFFP_PHASE_TOL_DYNAMIC" "50 mil"
					( Units "uPhaseTol" "mil" 1.000000)
					( Origin gBackEnd )
				)
				( attribute "DIFFP_MIN_SPACE" "4.00"
					( Origin gBackEnd )
				)
				( attribute "TOPOLOGY_TEMPLATE_REVISION" "1.0"
					( Origin gBackEnd )
				)
				( topologyData 22610
(SKIDL (Circuits ("MAIN" (Parts ("CRESCENT_CITY_089_20140807_B.@@U36.BH3" IbisIOPkg (xy (5528 4240)) (refDes "U5D1") (model "Unknown") (Props (_SXDesignName "CRESCENT_CITY_089_20140807_B") (brdx "12028.89 MIL") (brdy "2941.96 MIL") (bufferModel "CDSDefaultIO_2p5v") (cycle "1") (hold "1.0e-09") (mappingTag "") (offsets ("4" "0") ("5" "0")) (setup "2.0e-09") (state "tristate") (stimuli ("4" "local0") ("5" "local1")) (temperature "27") (termMap ("4" "Data") ("5" "Enable"))) (Terms ("CRESCENT_CITY_089_20140807_B.X1202889Y294196L2LRATS" "BH3"))) ("CRESCENT_CITY_089_20140807_B.@@U100.AC10" IbisIOPkg (xy (5502 4240)) (refDes "U2D1") (model "Unknown") (Props (_SXDesignName "CRESCENT_CITY_089_20140807_B") (brdx "5296.21 MIL") (brdy "2454.47 MIL") (bufferModel "CDSDefaultIO_2p5v") (cycle "1") (hold "1.0e-09") (mappingTag "") (offsets ("4" "0") ("5" "0")) (setup "2.0e-09") (state "tristate") (stimuli ("4" "local2") ("5" "local3")) (temperature "27") (termMap ("4" "Data") ("5" "Enable"))) (Terms ("CRESCENT_CITY_089_20140807_B.X529621Y245447L2LRATS" "AC10"))) ("CRESCENT_CITY_089_20140807_B.T@@RATS@@U36.BH3@@U100.AC10" TLine (xy (5513 4235)) (mirror x) (refDes "TL1") (Props (_SXDesignName "CRESCENT_CITY_089_20140807_B") (impedance "47.807 ohm") length("7220.16 MIL") (propDelay "1.29679 ns") (traceCount "1") (traceGeometry "Microstrip") (velocity "5567.72 mil/ns")) (Terms ("CRESCENT_CITY_089_20140807_B.X1202889Y294196L2LRATS" "1") ("CRESCENT_CITY_089_20140807_B.X529621Y245447L2LRATS" "2")))) (Nodes ("CRESCENT_CITY_089_20140807_B.X1202889Y294196L2LRATS" (terms "CRESCENT_CITY_089_20140807_B.T@@RATS@@U36.BH3@@U100.AC10.1" "CRESCENT_CITY_089_20140807_B.@@U36.BH3.1")) ("CRESCENT_CITY_089_20140807_B.X529621Y245447L2LRATS" (terms "CRESCENT_CITY_089_20140807_B.T@@RATS@@U36.BH3@@U100.AC10.2" "CRESCENT_CITY_089_20140807_B.@@U100.AC10.1"))) (Ports) (Stimuli ("local2" (scope local) (stimType periodic) (Props (periodicFreq "5e+007") (periodicJitter "0") (periodicPattern "1"))) ("local0" (scope local) (stimType periodic) (Props (periodicFreq "5e+007") (periodicJitter "0") (periodicPattern "1"))) ("local1" (scope local) (stimType periodic) (Props (periodicFreq "5e+007") (periodicJitter "0") (periodicPattern "1"))) ("local3" (scope local) (stimType periodic) (Props (periodicFreq "5e+007") (periodicJitter "0") (periodicPattern "1")))) (Notes) (Constraints ("DP_GATHER_CONTROL" "IGNORE") ("DP_MAX_UNCOUPLED_LENGTH" "0.000635") ("DP_MIN_LINE_SPACING" "0.0001016") ("DP_NEGATIVE_COUPLED_TOLERANCE" "2.54e-006") ("DP_PHASE_MAX_LENGTH" "0.01524") ("DP_PHASE_TOLERANCE" ("LENGTH" "0.000127")) ("DP_PHASE_TOLERANCE_DYNAMIC" ("LENGTH" "0.00127")) ("DP_POSITIVE_COUPLED_TOLERANCE" "2.54e-006") ("RELATIVE_PROPAGATION_DELAY" ("MG_KTI_BUNDLE" "CRESCENT_CITY_089_20140807_B U36.BH3" "CRESCENT_CITY_089_20140807_B U100.AC10" "NET GROUP" "LENGTH" "0.0127" "DELAY" "") ("MG_KTI_CPU0_CPU1_P1P1" "CRESCENT_CITY_089_20140807_B U36.BH3" "CRESCENT_CITY_089_20140807_B U100.AC10" "GLOBAL" "LENGTH" "0.033401" "LENGTH" "-0.033401"))) (MeasurementSets ("EMI" ("EMIStatus" status("on")) ("PeakEmission" status("on")) ("PeakFrequency" status("on")) ("PulseFreq" status("on")) ("RiseTime" status("on")) ("VoltageSwing" status("on"))) ("Reflection" ("BufferDelayFall" status("off")) ("BufferDelayRise" status("off")) ("EyeHeight" status("off")) ("EyeJitter" status("off")) ("EyeWidth" status("off")) ("FirstIncidentFall" status("off")) ("FirstIncidentRise" status("off")) ("Glitch" status("on")) ("GlitchFall" status("off")) ("GlitchRise" status("off")) ("Monotonic" status("on")) ("MonotonicFall" status("off")) ("MonotonicRise" status("off")) ("NoiseMargin" status("on")) ("NoiseMarginHigh" status("off")) ("NoiseMarginLow" status("off")) ("OvershootHigh" status("on")) ("OvershootLow" status("on")) ("PropDelay" status("on")) ("SettleDelay" status("on")) ("SettleDelayFall" status("off")) ("SettleDelayRise" status("off")) ("SwitchDelay" status("on")) ("SwitchDelayFall" status("off")) ("SwitchDelayRise" status("off"))) ("Crosstalk" ("Crosstalk" status("on"))) ("Custom")) (VectorSets) (Props (XnetName "KTI_CPU0_CPU1_P0P0_DP<0>") (allDrivers "active") (customSimType "Reflection") (ftsMode ("Typ")) (rcvrSelect "all") (tlineDelayMode "time") (userRevision "1.0")))) (Subckts) (CrossSections ("CRESCENT_CITY_089_20140807_B" (Props (SXDesignName "CRESCENT_CITY_089_20140807_B")) (Layers ("" (layerType "SURFACE") (material "AIR") (thickness "0 mil") (dielectricConstant "1.000000") (lossTangent "0") (etchFactor "0.000000") (elecCondVal "0 mho/cm") (thermCondVal "0 w/cm-degC")) ("" (layerType "DIELECTRIC") (material "CONFORMAL_COAT") (thickness "0.5 mil") (dielectricConstant "3.800000") (lossTangent "0.035") (etchFactor "0.000000") (elecCondVal "0 mho/cm") (thermCondVal "0.012 w/cm-degC")) ("TOP" (layerType "CONDUCTOR") (material "COPPER") (thickness "  1.800000 mil") (width "4.00 MIL") (dielectricConstant "4.500000") (lossTangent "0") (etchFactor "70.000000") (elecCondVal "595900.000000 mho/cm") (thermCondVal "0 w/cm-degC") (signalDieConstant "3.800000") (signalLossTangent "0.035")) ("" (layerType "DIELECTRIC") (material "FR-4") (thickness "  2.700000 mil") (dielectricConstant "4.000000") (lossTangent "0.035") (etchFactor "0.000000") (elecCondVal "0 mho/cm") (thermCondVal "0.012 w/cm-degC")) ("L2_GND1" (layerType "PLANE") (material "COPPER") (isShield t) (thickness "  1.200000 mil") (dielectricConstant "4.500000") (lossTangent "0.035") (etchFactor "90.000000") (elecCondVal "595900.000000 mho/cm") (thermCondVal "0.012 w/cm-degC")) ("" (layerType "DIELECTRIC") (material "FR-4") (thickness "  9.000000 mil") (dielectricConstant "4.100000") (lossTangent "0.035") (etchFactor "0.000000") (elecCondVal "0 mho/cm") (thermCondVal "0.012 w/cm-degC")) ("L3_SIG1" (layerType "CONDUCTOR") (material "COPPER") (thickness "  1.200000 mil") (width "4.00 MIL") (dielectricConstant "4.500000") (lossTangent "0.035") (etchFactor "90.000000") (elecCondVal "595900.000000 mho/cm") (thermCondVal "0.012 w/cm-degC") (signalDieConstant "4.100000") (signalLossTangent "0.035")) ("" (layerType "DIELECTRIC") (material "FR-4") (thickness "  3.300000 mil") (dielectricConstant "4.500000") (lossTangent "0.035") (etchFactor "0.000000") (elecCondVal "0 mho/cm") (thermCondVal "0 w/cm-degC")) ("L4_GND2" (layerType "PLANE") (material "COPPER") (isShield t) (thickness "  1.200000 mil") (dielectricConstant "4.500000") (lossTangent "0.035") (etchFactor "90.000000") (elecCondVal "595900.000000 mho/cm") (thermCondVal "0 w/cm-degC")) ("" (layerType "DIELECTRIC") (material "FR-4") (thickness "  9.000000 mil") (dielectricConstant "4.000000") (lossTangent "0.035") (etchFactor "0.000000") (elecCondVal "0 mho/cm") (thermCondVal "0.012 w/cm-degC")) ("L5_SIG2" (layerType "CONDUCTOR") (material "COPPER") (thickness "  1.200000 mil") (width "4.00 MIL") (dielectricConstant "4.500000") (lossTangent "0.035") (etchFactor "90.000000") (elecCondVal "595900.000000 mho/cm") (thermCondVal "0.012 w/cm-degC") (signalDieConstant "4.000000") (signalLossTangent "0.035")) ("" (layerType "DIELECTRIC") (material "FR-4") (thickness "  3.300000 mil") (dielectricConstant "4.500000") (lossTangent "0.035") (etchFactor "0.000000") (elecCondVal "0 mho/cm") (thermCondVal "0 w/cm-degC")) ("L6_GND3" (layerType "PLANE") (material "COPPER") (isShield t) (thickness "  1.200000 mil") (dielectricConstant "4.500000") (lossTangent "0.035") (etchFactor "90.000000") (elecCondVal "595900.000000 mho/cm") (thermCondVal "0 w/cm-degC")) ("" (layerType "DIELECTRIC") (material "FR-4") (thickness "  3.000000 mil") (dielectricConstant "4.100000") (lossTangent "0.035") (etchFactor "0.000000") (elecCondVal "0 mho/cm") (thermCondVal "0.012 w/cm-degC")) ("L7_PWR1-SIG" (layerType "PLANE") (material "COPPER") (isShield t) (thickness "  2.400000 mil") (dielectricConstant "4.500000") (lossTangent "0.035") (etchFactor "90.000000") (elecCondVal "595900.000000 mho/cm") (thermCondVal "0.012 w/cm-degC")) ("" (layerType "DIELECTRIC") (material "FR-4") (thickness "  6.600000 mil") (dielectricConstant "4.000000") (lossTangent "0.035") (etchFactor "0.000000") (elecCondVal "0 mho/cm") (thermCondVal "0.012 w/cm-degC")) ("L8_PWR2-SIG" (layerType "PLANE") (material "COPPER") (isShield t) (thickness "  2.400000 mil") (dielectricConstant "4.500000") (lossTangent "0.035") (etchFactor "90.000000") (elecCondVal "595900.000000 mho/cm") (thermCondVal "0.012 w/cm-degC")) ("" (layerType "DIELECTRIC") (material "FR-4") (thickness "  3.000000 mil") (dielectricConstant "4.500000") (lossTangent "0.035") (etchFactor "0.000000") (elecCondVal "0 mho/cm") (thermCondVal "0 w/cm-degC")) ("L9_GND4" (layerType "PLANE") (material "COPPER") (isShield t) (thickness "  1.200000 mil") (dielectricConstant "4.500000") (lossTangent "0.035") (etchFactor "90.000000") (elecCondVal "595900.000000 mho/cm") (thermCondVal "0 w/cm-degC")) ("" (layerType "DIELECTRIC") (material "FR-4") (thickness "  3.300000 mil") (dielectricConstant "4.100000") (lossTangent "0.035") (etchFactor "0.000000") (elecCondVal "0 mho/cm") (thermCondVal "0.012 w/cm-degC")) ("L10_SIG3" (layerType "CONDUCTOR") (material "COPPER") (thickness "  1.200000 mil") (width "4.00 MIL") (dielectricConstant "4.500000") (lossTangent "0.035") (etchFactor "90.000000") (elecCondVal "595900.000000 mho/cm") (thermCondVal "0.012 w/cm-degC") (signalDieConstant "4.100000") (signalLossTangent "0.035")) ("" (layerType "DIELECTRIC") (material "FR-4") (thickness "  9.000000 mil") (dielectricConstant "4.500000") (lossTangent "0.035") (etchFactor "0.000000") (elecCondVal "0 mho/cm") (thermCondVal "0 w/cm-degC")) ("L11_GND5" (layerType "PLANE") (material "COPPER") (isShield t) (thickness "  1.200000 mil") (dielectricConstant "4.500000") (lossTangent "0.035") (etchFactor "90.000000") (elecCondVal "595900.000000 mho/cm") (thermCondVal "0 w/cm-degC")) ("" (layerType "DIELECTRIC") (material "FR-4") (thickness "  3.300000 mil") (dielectricConstant "4.500000") (lossTangent "0.035") (etchFactor "0.000000") (elecCondVal "0 mho/cm") (thermCondVal "0.012 w/cm-degC")) ("L12_SIG4" (layerType "CONDUCTOR") (material "COPPER") (thickness "  1.200000 mil") (width "4.00 MIL") (dielectricConstant "4.500000") (lossTangent "0.035") (etchFactor "90.000000") (elecCondVal "595900.000000 mho/cm") (thermCondVal "0.012 w/cm-degC") (signalDieConstant "4.500000") (signalLossTangent "0.035")) ("" (layerType "DIELECTRIC") (material "FR-4") (thickness "  9.000000 mil") (dielectricConstant "4.500000") (lossTangent "0.035") (etchFactor "0.000000") (elecCondVal "0 mho/cm") (thermCondVal "0 w/cm-degC")) ("L13_GND6" (layerType "PLANE") (material "COPPER") (isShield t) (thickness "  1.200000 mil") (dielectricConstant "4.500000") (lossTangent "0.035") (etchFactor "90.000000") (elecCondVal "595900.000000 mho/cm") (thermCondVal "0.012 w/cm-degC")) ("" (layerType "DIELECTRIC") (material "FR-4") (thickness "  2.700000 mil") (dielectricConstant "4.500000") (lossTangent "0.035") (etchFactor "0.000000") (elecCondVal "0 mho/cm") (thermCondVal "0.012 w/cm-degC")) ("BOTTOM" (layerType "CONDUCTOR") (material "COPPER") (thickness "  1.800000 mil") (width "4.00 MIL") (dielectricConstant "4.500000") (lossTangent "0") (etchFactor "70.000000") (elecCondVal "595900.000000 mho/cm") (thermCondVal "0 w/cm-degC") (signalDieConstant "3.800000") (signalLossTangent "0.035")) ("" (layerType "DIELECTRIC") (material "CONFORMAL_COAT") (thickness "0.5 mil") (dielectricConstant "3.800000") (lossTangent "0.035") (etchFactor "0.000000") (elecCondVal "0 mho/cm") (thermCondVal "0.012 w/cm-degC")) ("" (layerType "SURFACE") (material "AIR") (thickness "0 mil") (dielectricConstant "1.000000") (lossTangent "0") (etchFactor "0.000000") (elecCondVal "0 mho/cm") (thermCondVal "0 w/cm-degC"))))) (Props (DesUnits "mils 2") (LayerStack ("DIELECTRIC" "DIELECTRIC" "BOTTOM" "DIELECTRIC" "L13_GND6" "DIELECTRIC" "L12_SIG4" "DIELECTRIC" "L11_GND5" "DIELECTRIC" "L10_SIG3" "DIELECTRIC" "L9_GND4" "DIELECTRIC" "L8_PWR2-SIG" "DIELECTRIC" "L7_PWR1-SIG" "DIELECTRIC" "L6_GND3" "DIELECTRIC" "L5_SIG2" "DIELECTRIC" "L4_GND2" "DIELECTRIC" "L3_SIG1" "DIELECTRIC" "L2_GND1" "DIELECTRIC" "TOP" "DIELECTRIC" "DIELECTRIC")) (Revision "16.600")) (Params (TLine ((diffImpedance "100ohm") (diffVelocity "1.4142e+08M/s") (impedance "60ohm") length("2800 mil") (propDelay "0.5 ns") (velocity "5600 mil/ns") (traceCount "1") (traceGeometry "Microstrip") (impedanceMin nil) (impedanceMax nil) (lengthMin nil) (lengthMax nil) (propDelayMin nil) (propDelayMax nil) (impedanceSweepCount nil) (propDelaySweepCount nil) (velocitySweepCount nil) (lengthSweepCount nil) (matchSetName nil))) (sync ((syncFreq "100e6") (syncInitState "1") (syncPattern "10") (syncEdgeSwitch "rise"))) (Connector nil) (IbisIOMacro ((temperature "27") (bufferModel "CDSDefaultIO_2p5v") (stimuli nil) (offsets nil) (state "tristate") (cycle "1") (termMap nil) (setup "2.0e-09") (hold "1.0e-09") (rise nil) (fall nil) (macroType nil) (voltage nil) (spice nil) (LEFDEFPinName nil) (LEFDEFPinType nil) (mappingTag nil))) (DiffInputPkg ((temperature "27") (bufferModelNonInverting "CDSDefaultInput_2p5v") (bufferModelInverting "CDSDefaultInput_2p5v") (threshInputHighMin "1.7 V") (threshInputHighTyp "1.7  V") (threshInputHighMax "1.7  V") (threshInputLowMin "0.7  V") (threshInputLowTyp "0.7  V") (threshInputLowMax "0.7  V") (mappingTagNonInverting nil) (mappingTagInverting nil) (cycle "1"))) (idlCircuit ((allDrivers "active") (ftsMode '("Typ")) (rcvrSelect "all") (simMode "Reflection") (tlineDelayMode "time") (userRevision "1.0") (autoSolve "On"))) (Inductor ((inductance "5 nH") (orientation "0"))) (DiffOutput ((temperature "27") (bufferModelNonInverting "CDSDefaultOutput_2p5v") (bufferModelInverting "CDSDefaultOutput_2p5v") (stimuli nil) (offsets nil) (state "tristate") (cycle "1") (termMap nil) (setup "0.9e-09") (hold "0.4e-09") (rise nil) (fall nil) (threshOutputHighMin "2.375  V") (threshOutputHighTyp "2.5  V") (threshOutputHighMax "2.625  V") (threshOutputLowMin "1.275  V") (threshOutputLowTyp "1.7  V") (threshOutputLowMax "1.985  V") (mappingTagNonInverting nil) (mappingTagInverting nil) (spice nil))) (HiClampTerm ((cutoffVoltage "0.7 V") (voltage "5 V") (maxDelay "0.1 ns"))) (Capacitor ((capacitance "10 pF") (orientation "0"))) (DiffOutputPkg ((temperature "27") (bufferModelNonInverting "CDSDefaultOutput_2p5v") (bufferModelInverting "CDSDefaultOutput_2p5v") (stimuli nil) (offsets nil) (state "tristate") (cycle "1") (termMap nil) (setup "0.9e-09") (hold "0.4e-09") (rise nil) (fall nil) (threshOutputHighMin "2.375  V") (threshOutputHighTyp "2.5  V") (threshOutputHighMax "2.625  V") (threshOutputLowMin "1.275  V") (threshOutputLowTyp "1.7  V") (threshOutputLowMax "1.985  V") (mappingTagNonInverting nil) (mappingTagInverting nil) (spice nil))) (DualClampTerm ((cutoffVoltageUp "0.7 V") (cutoffVoltageDown "0.7 V") (voltageUp "5 V") (voltageDown "0 V") (maxDelay "0.1 ns"))) (IbisOutput ((temperature "27") (bufferModel "CDSDefaultOutput_2p5v") (stimuli nil) (offsets nil) (state "tristate") (cycle "1") (termMap nil) (setup "2.0e-09") (hold "1.0e-09") (rise nil) (fall nil) (macroType nil) (voltage nil) (spice nil) (LEFDEFPinName nil) (LEFDEFPinType nil) (mappingTag nil))) (IbisIO ((temperature "27") (bufferModel "CDSDefaultIO_2p5v") (stimuli nil) (offsets nil) (state "tristate") (cycle "1") (termMap nil) (setup "2.0e-09") (hold "1.0e-09") (rise nil) (fall nil) (macroType nil) (voltage nil) (spice nil) (LEFDEFPinName nil) (LEFDEFPinType nil) (mappingTag nil))) (RLGC (length("1000 mil"))) (DiffIO ((temperature "27") (bufferModelNonInverting "CDSDefaultIO_2p5v") (bufferModelInverting "CDSDefaultIO_2p5v") (stimuli nil) (offsets nil) (state "tristate") (cycle "1") (termMap nil) (setup "0.9e-09") (hold "0.4e-09") (rise nil) (fall nil) (threshInputHighMin "1.7 V") (threshInputHighTyp "1.7  V") (threshInputHighMax "1.7  V") (threshInputLowMin "0.7  V") (threshInputLowTyp "0.7  V") (threshInputLowMax "0.7 ") (threshOutputHighMin "2.365  V") (threshOutputHighTyp "2.5  V") (threshOutputHighMax "2.625  V") (threshOutputLowMin "1.275  V") (threshOutputLowTyp "1.7  V") (threshOutputLowMax "1.985  V") (mappingTagNonInverting nil) (mappingTagInverting nil) (spice nil))) (Source ((voltage "5 V"))) (DiffIOPkg ((temperature "27") (bufferModelNonInverting "CDSDefaultIO_2p5v") (bufferModelInverting "CDSDefaultIO_2p5v") (stimuli nil) (offsets nil) (state "tristate") (cycle "1") (termMap nil) (setup "0.9e-09") (hold "0.4e-09") (rise nil) (fall nil) (threshInputHighMin "1.7 V") (threshInputHighTyp "1.7  V") (threshInputHighMax "1.7  V") (threshInputLowMin "0.7  V") (threshInputLowTyp "0.7  V") (threshInputLowMax "0.7 ") (threshOutputHighMin "2.365  V") (threshOutputHighTyp "2.5  V") (threshOutputHighMax "2.625  V") (threshOutputLowMin "1.275  V") (threshOutputLowTyp "1.7  V") (threshOutputLowMax "1.985  V") (mappingTagNonInverting nil) (mappingTagInverting nil) (spice nil))) (Diode ((cutoffVoltage "0.7 V"))) (ShuntTerm ((resistance "50 ohm") (voltage "5 V") (maxDelay "0.1 ns"))) (IbisIO_OpenPullDown ((temperature "27") (bufferModel "CDSDefaultIO_2p5v") (stimuli nil) (offsets nil) (state "tristate") (cycle "1") (termMap nil) (setup "2.0e-09") (hold "1.0e-09") (rise nil) (fall nil) (macroType nil) (voltage nil) (spice nil) (LEFDEFPinName nil) (LEFDEFPinType nil) (mappingTag nil))) (IbisIO_OpenPullUp ((temperature "27") (bufferModel "CDSDefaultIO_2p5v") (stimuli nil) (offsets nil) (state "tristate") (cycle "1") (termMap nil) (setup "2.0e-09") (hold "1.0e-09") (rise nil) (fall nil) (macroType nil) (voltage nil) (spice nil) (LEFDEFPinName nil) (LEFDEFPinType nil) (mappingTag nil))) (TheveninTerm ((resistanceUp "180 ohm") (resistanceDown "270 ohm") (voltageUp "5 V") (voltageDown "0 V") (maxDelay "0.1 ns"))) (Resistor ((resistance "50 ohm") (orientation "0"))) (RCTerm ((resistance "50 ohm") (capacitance "20 pF") (voltage "5 V") (maxDelay "0.1 ns"))) (DiffInput ((temperature "27") (bufferModelNonInverting "CDSDefaultInput_2p5v") (bufferModelInverting "CDSDefaultInput_2p5v") (threshInputHighMin "1.7 V") (threshInputHighTyp "1.7  V") (threshInputHighMax "1.7  V") (threshInputLowMin "0.7  V") (threshInputLowTyp "0.7  V") (threshInputLowMax "0.7  V") (mappingTagNonInverting nil) (mappingTagInverting nil) (cycle "1"))) (LowClampTerm ((cutoffVoltage "0.7 V") (voltage "0 V") (maxDelay "0.1 ns"))) (CPWSL ((d1Thickness "10 mil") (d1Constant "4.5") (d1LossTangent "0.035") (d2Thickness "0.72 mil") (d2Constant "4.5") (d2LossTangent "0.035") (d3Thickness "10 mil") (d3Constant "4.5") (d3LossTangent "0.035") length("1000 mil") (spacing "5 mil") (spacing2 "5 mil") (spacing3 "5 mil") (spacing4 "5 mil") (spacing5 "5 mil") (traceConductivity "595900 mho/cm") (traceGeometry "cpwms") (traceLayerName "") (traceThickness "0.72 mil") (traceType "single") (traceWidth "5.0 mil") (traceWidth2 "5.0 mil") (traceWidth3 "5.0 mil") (traceWidth4 "5.0 mil") (traceWidth5 "5.0 mil") (traceWidth6 "5.0 mil") (offset "0 mil") (traceCount "1") (impedance nil))) (Trace ((d1Thickness "10 mil") (d1Constant "4.5") (d1LossTangent "0.035") (d2Thickness "10 mil") (d2Constant "4.5") (d2LossTangent "0.035") (d3Thickness "0.0") (d3Constant "1.0") (d3LossTangent "0") length("1000 mil") (spacing "5 mil") (spacing2 "5 mil") (spacing3 "5 mil") (spacing4 "5 mil") (spacing5 "5 mil") (traceConductivity "595900 mho/cm") (traceGeometry "microstrip") (traceLayerName "") (traceThickness "0.72 mil") (traceType "single") (traceWidth "5.0 mil") (traceWidth2 "5.0 mil") (traceWidth3 "5.0 mil") (traceWidth4 "5.0 mil") (traceWidth5 "5.0 mil") (traceWidth6 "5.0 mil") (offset "0 mil") (traceCount "1") (impedance nil))) (CPWMS ((d1Thickness "10 mil") (d1Constant "4.5") (d1LossTangent "0.035") (d2Thickness "0.72 mil") (d2Constant "4.5") (d2LossTangent "0.035") (d3Thickness "0.0") (d3Constant "1") (d3LossTangent "0") length("1000 mil") (spacing "5 mil") (spacing2 "5 mil") (spacing3 "5 mil") (spacing4 "5 mil") (spacing5 "5 mil") (traceConductivity "595900 mho/cm") (traceGeometry "cpwms") (traceLayerName "") (traceThickness "0.72 mil") (traceType "single") (traceWidth "5.0 mil") (traceWidth2 "5.0 mil") (traceWidth3 "5.0 mil") (traceWidth4 "5.0 mil") (traceWidth5 "5.0 mil") (traceWidth6 "5.0 mil") (offset "0 mil") (traceCount "1") (impedance nil))) (CPW ((d1Thickness "10 mil") (d1Constant "4.5") (d1LossTangent "0.035") (d2Thickness "0.72 mil") (d2Constant "1") (d2LossTangent "0") (d3Thickness "0.0") (d3Constant "1") (d3LossTangent "0") length("1000 mil") (spacing "5 mil") (spacing2 "5 mil") (spacing3 "5 mil") (spacing4 "5 mil") (spacing5 "5 mil") (traceConductivity "595900 mho/cm") (traceGeometry "cpwms") (traceLayerName "") (traceThickness "0.72 mil") (traceType "single") (traceWidth "5.0 mil") (traceWidth2 "5.0 mil") (traceWidth3 "5.0 mil") (traceWidth4 "5.0 mil") (traceWidth5 "5.0 mil") (traceWidth6 "5.0 mil") (offset "0 mil") (traceCount "1") (impedance nil))) (async ((asyncTimePoints "") (asyncInitState "1"))) (IbisOutput_OpenPullUp ((temperature "27") (bufferModel "CDSDefaultOutput_2p5v") (stimuli nil) (offsets nil) (state "tristate") (cycle "1") (termMap nil) (setup "2.0e-09") (hold "1.0e-09") (rise nil) (fall nil) (macroType nil) (voltage nil) (spice nil) (LEFDEFPinName nil) (LEFDEFPinType nil) (mappingTag nil))) (Cable (length("1 m"))) (ESpiceDevice nil) (IbisInput ((temperature "27") (bufferModel "CDSDefaultInput_2p5v") (cycle "1") (LEFDEFPinName nil) (LEFDEFPinType nil) (mappingTag nil))) (SeriesTerm ((resistance "22 ohm") (maxDelay "0.1 ns"))) (IbisOutputPkg ((temperature "27") (bufferModel "CDSDefaultOutput_2p5v") (stimuli nil) (offsets nil) (state "tristate") (cycle "1") (termMap nil) (setup "2.0e-09") (hold "1.0e-09") (rise nil) (fall nil) (macroType nil) (voltage nil) (spice nil) (LEFDEFPinName nil) (LEFDEFPinType nil) (mappingTag nil))) (IbisIOPkg ((temperature "27") (bufferModel "CDSDefaultIO_2p5v") (stimuli nil) (offsets nil) (state "tristate") (cycle "1") (termMap nil) (setup "2.0e-09") (hold "1.0e-09") (rise nil) (fall nil) (macroType nil) (voltage nil) (spice nil) (LEFDEFPinName nil) (LEFDEFPinType nil) (mappingTag nil))) (CurrentProbe nil) (IbisInputPkg ((temperature "27") (bufferModel "CDSDefaultInput_2p5v") (cycle "1") (LEFDEFPinName nil) (LEFDEFPinType nil) (mappingTag nil))) (periodic ((periodicFreq "100e6") (periodicPattern "10") (periodicJitter "0"))) (clocked ((clockRise "1e-09") (clockFall "1e-09") (clockFreq "100e6") (clockInitState "0") (clockDutyCycle "0.5") (clockJitter "0"))) (Via ((model "Unknown") (viaOutputFormat "Unknown") (viaPadstack nil) (viaTopLayer nil) (viaBottomLayer nil) (viaIsPower nil) (viaIsGround nil)))))
				)
				( objectStatus "UPI_CPU0_CPU1_P1P1" )
			)
			( electricalCSet "@crescent_city_bb_fab1_lib.crescent_city_bb_fab1(sch_1):\KTI\"
				( groupRef "UPI_CPU0_CPU1_P0P0:MG_KTI_BUNDLE" )
				( groupRef "UPI_CPU0_CPU1_P0P0:MG_KTI_CPU0_CPU1_P0P0" )
				( pinPairRef "UPI_CPU0_CPU1_P0P0:U5D1.BH3:U2D1.AC10" )
				( attribute "DIFFP_GATHER_CONTROL" "IGNORE"
					( Origin gBackEnd )
				)
				( attribute "DIFFP_UNCOUPLED_LENGTH" "1000.00"
					( Origin gBackEnd )
				)
				( attribute "DIFFP_COUPLED_PLUS" "0.10"
					( Origin gBackEnd )
				)
				( attribute "DIFFP_COUPLED_MINUS" "0.10"
					( Origin gBackEnd )
				)
				( attribute "DIFFP_PHASE_TOL" "5 mil"
					( Units "uPhaseTol" "ns" 1.000000)
					( Origin gBackEnd )
				)
				( attribute "DIFFP_PHASE_MAX_LENGTH" "600.00"
					( Origin gBackEnd )
				)
				( attribute "DIFFP_PHASE_TOL_DYNAMIC" "50 mil"
					( Units "uPhaseTol" "mil" 1.000000)
					( Origin gBackEnd )
				)
				( attribute "DIFFP_MIN_SPACE" "4.00"
					( Origin gBackEnd )
				)
				( topologyData 22610
(SKIDL (Circuits ("MAIN" (Parts ("CRESCENT_CITY_089_20140807_B.@@U36.BH3" IbisIOPkg (xy (5528 4240)) (refDes "U5D1") (model "Unknown") (Props (_SXDesignName "CRESCENT_CITY_089_20140807_B") (brdx "12028.89 MIL") (brdy "2941.96 MIL") (bufferModel "CDSDefaultIO_2p5v") (cycle "1") (hold "1.0e-09") (mappingTag "") (offsets ("4" "0") ("5" "0")) (setup "2.0e-09") (state "tristate") (stimuli ("4" "local0") ("5" "local1")) (temperature "27") (termMap ("4" "Data") ("5" "Enable"))) (Terms ("CRESCENT_CITY_089_20140807_B.X1202889Y294196L2LRATS" "BH3"))) ("CRESCENT_CITY_089_20140807_B.@@U100.AC10" IbisIOPkg (xy (5502 4240)) (refDes "U2D1") (model "Unknown") (Props (_SXDesignName "CRESCENT_CITY_089_20140807_B") (brdx "5296.21 MIL") (brdy "2454.47 MIL") (bufferModel "CDSDefaultIO_2p5v") (cycle "1") (hold "1.0e-09") (mappingTag "") (offsets ("4" "0") ("5" "0")) (setup "2.0e-09") (state "tristate") (stimuli ("4" "local2") ("5" "local3")) (temperature "27") (termMap ("4" "Data") ("5" "Enable"))) (Terms ("CRESCENT_CITY_089_20140807_B.X529621Y245447L2LRATS" "AC10"))) ("CRESCENT_CITY_089_20140807_B.T@@RATS@@U36.BH3@@U100.AC10" TLine (xy (5513 4235)) (mirror x) (refDes "TL1") (Props (_SXDesignName "CRESCENT_CITY_089_20140807_B") (impedance "47.807 ohm") length("7220.16 MIL") (propDelay "1.29679 ns") (traceCount "1") (traceGeometry "Microstrip") (velocity "5567.72 mil/ns")) (Terms ("CRESCENT_CITY_089_20140807_B.X1202889Y294196L2LRATS" "1") ("CRESCENT_CITY_089_20140807_B.X529621Y245447L2LRATS" "2")))) (Nodes ("CRESCENT_CITY_089_20140807_B.X1202889Y294196L2LRATS" (terms "CRESCENT_CITY_089_20140807_B.T@@RATS@@U36.BH3@@U100.AC10.1" "CRESCENT_CITY_089_20140807_B.@@U36.BH3.1")) ("CRESCENT_CITY_089_20140807_B.X529621Y245447L2LRATS" (terms "CRESCENT_CITY_089_20140807_B.T@@RATS@@U36.BH3@@U100.AC10.2" "CRESCENT_CITY_089_20140807_B.@@U100.AC10.1"))) (Ports) (Stimuli ("local2" (scope local) (stimType periodic) (Props (periodicFreq "5e+007") (periodicJitter "0") (periodicPattern "1"))) ("local0" (scope local) (stimType periodic) (Props (periodicFreq "5e+007") (periodicJitter "0") (periodicPattern "1"))) ("local1" (scope local) (stimType periodic) (Props (periodicFreq "5e+007") (periodicJitter "0") (periodicPattern "1"))) ("local3" (scope local) (stimType periodic) (Props (periodicFreq "5e+007") (periodicJitter "0") (periodicPattern "1")))) (Notes) (Constraints ("DP_GATHER_CONTROL" "IGNORE") ("DP_MAX_UNCOUPLED_LENGTH" "0.000635") ("DP_MIN_LINE_SPACING" "0.0001016") ("DP_NEGATIVE_COUPLED_TOLERANCE" "2.54e-006") ("DP_PHASE_MAX_LENGTH" "0.01524") ("DP_PHASE_TOLERANCE" ("LENGTH" "0.000127")) ("DP_PHASE_TOLERANCE_DYNAMIC" ("LENGTH" "0.00127")) ("DP_POSITIVE_COUPLED_TOLERANCE" "2.54e-006") ("RELATIVE_PROPAGATION_DELAY" ("MG_KTI_BUNDLE" "CRESCENT_CITY_089_20140807_B U36.BH3" "CRESCENT_CITY_089_20140807_B U100.AC10" "NET GROUP" "LENGTH" "0.0127" "DELAY" "") ("MG_KTI_CPU0_CPU1_P0P0" "CRESCENT_CITY_089_20140807_B U36.BH3" "CRESCENT_CITY_089_20140807_B U100.AC10" "GLOBAL" "LENGTH" "0.026797" "LENGTH" "-0.026797"))) (MeasurementSets ("EMI" ("EMIStatus" status("on")) ("PeakEmission" status("on")) ("PeakFrequency" status("on")) ("PulseFreq" status("on")) ("RiseTime" status("on")) ("VoltageSwing" status("on"))) ("Reflection" ("BufferDelayFall" status("off")) ("BufferDelayRise" status("off")) ("EyeHeight" status("off")) ("EyeJitter" status("off")) ("EyeWidth" status("off")) ("FirstIncidentFall" status("off")) ("FirstIncidentRise" status("off")) ("Glitch" status("on")) ("GlitchFall" status("off")) ("GlitchRise" status("off")) ("Monotonic" status("on")) ("MonotonicFall" status("off")) ("MonotonicRise" status("off")) ("NoiseMargin" status("on")) ("NoiseMarginHigh" status("off")) ("NoiseMarginLow" status("off")) ("OvershootHigh" status("on")) ("OvershootLow" status("on")) ("PropDelay" status("on")) ("SettleDelay" status("on")) ("SettleDelayFall" status("off")) ("SettleDelayRise" status("off")) ("SwitchDelay" status("on")) ("SwitchDelayFall" status("off")) ("SwitchDelayRise" status("off"))) ("Crosstalk" ("Crosstalk" status("on"))) ("Custom")) (VectorSets) (Props (XnetName "KTI_CPU0_CPU1_P0P0_DP<0>") (allDrivers "active") (customSimType "Reflection") (ftsMode ("Typ")) (rcvrSelect "all") (tlineDelayMode "time") (userRevision "1.0")))) (Subckts) (CrossSections ("CRESCENT_CITY_089_20140807_B" (Props (SXDesignName "CRESCENT_CITY_089_20140807_B")) (Layers ("" (layerType "SURFACE") (material "AIR") (thickness "0 mil") (dielectricConstant "1.000000") (lossTangent "0") (etchFactor "0.000000") (elecCondVal "0 mho/cm") (thermCondVal "0 w/cm-degC")) ("" (layerType "DIELECTRIC") (material "CONFORMAL_COAT") (thickness "0.5 mil") (dielectricConstant "3.800000") (lossTangent "0.035") (etchFactor "0.000000") (elecCondVal "0 mho/cm") (thermCondVal "0.012 w/cm-degC")) ("TOP" (layerType "CONDUCTOR") (material "COPPER") (thickness "  1.800000 mil") (width "4.00 MIL") (dielectricConstant "4.500000") (lossTangent "0") (etchFactor "70.000000") (elecCondVal "595900.000000 mho/cm") (thermCondVal "0 w/cm-degC") (signalDieConstant "3.800000") (signalLossTangent "0.035")) ("" (layerType "DIELECTRIC") (material "FR-4") (thickness "  2.700000 mil") (dielectricConstant "4.000000") (lossTangent "0.035") (etchFactor "0.000000") (elecCondVal "0 mho/cm") (thermCondVal "0.012 w/cm-degC")) ("L2_GND1" (layerType "PLANE") (material "COPPER") (isShield t) (thickness "  1.200000 mil") (dielectricConstant "4.500000") (lossTangent "0.035") (etchFactor "90.000000") (elecCondVal "595900.000000 mho/cm") (thermCondVal "0.012 w/cm-degC")) ("" (layerType "DIELECTRIC") (material "FR-4") (thickness "  9.000000 mil") (dielectricConstant "4.100000") (lossTangent "0.035") (etchFactor "0.000000") (elecCondVal "0 mho/cm") (thermCondVal "0.012 w/cm-degC")) ("L3_SIG1" (layerType "CONDUCTOR") (material "COPPER") (thickness "  1.200000 mil") (width "4.00 MIL") (dielectricConstant "4.500000") (lossTangent "0.035") (etchFactor "90.000000") (elecCondVal "595900.000000 mho/cm") (thermCondVal "0.012 w/cm-degC") (signalDieConstant "4.100000") (signalLossTangent "0.035")) ("" (layerType "DIELECTRIC") (material "FR-4") (thickness "  3.300000 mil") (dielectricConstant "4.500000") (lossTangent "0.035") (etchFactor "0.000000") (elecCondVal "0 mho/cm") (thermCondVal "0 w/cm-degC")) ("L4_GND2" (layerType "PLANE") (material "COPPER") (isShield t) (thickness "  1.200000 mil") (dielectricConstant "4.500000") (lossTangent "0.035") (etchFactor "90.000000") (elecCondVal "595900.000000 mho/cm") (thermCondVal "0 w/cm-degC")) ("" (layerType "DIELECTRIC") (material "FR-4") (thickness "  9.000000 mil") (dielectricConstant "4.000000") (lossTangent "0.035") (etchFactor "0.000000") (elecCondVal "0 mho/cm") (thermCondVal "0.012 w/cm-degC")) ("L5_SIG2" (layerType "CONDUCTOR") (material "COPPER") (thickness "  1.200000 mil") (width "4.00 MIL") (dielectricConstant "4.500000") (lossTangent "0.035") (etchFactor "90.000000") (elecCondVal "595900.000000 mho/cm") (thermCondVal "0.012 w/cm-degC") (signalDieConstant "4.000000") (signalLossTangent "0.035")) ("" (layerType "DIELECTRIC") (material "FR-4") (thickness "  3.300000 mil") (dielectricConstant "4.500000") (lossTangent "0.035") (etchFactor "0.000000") (elecCondVal "0 mho/cm") (thermCondVal "0 w/cm-degC")) ("L6_GND3" (layerType "PLANE") (material "COPPER") (isShield t) (thickness "  1.200000 mil") (dielectricConstant "4.500000") (lossTangent "0.035") (etchFactor "90.000000") (elecCondVal "595900.000000 mho/cm") (thermCondVal "0 w/cm-degC")) ("" (layerType "DIELECTRIC") (material "FR-4") (thickness "  3.000000 mil") (dielectricConstant "4.100000") (lossTangent "0.035") (etchFactor "0.000000") (elecCondVal "0 mho/cm") (thermCondVal "0.012 w/cm-degC")) ("L7_PWR1-SIG" (layerType "PLANE") (material "COPPER") (isShield t) (thickness "  2.400000 mil") (dielectricConstant "4.500000") (lossTangent "0.035") (etchFactor "90.000000") (elecCondVal "595900.000000 mho/cm") (thermCondVal "0.012 w/cm-degC")) ("" (layerType "DIELECTRIC") (material "FR-4") (thickness "  6.600000 mil") (dielectricConstant "4.000000") (lossTangent "0.035") (etchFactor "0.000000") (elecCondVal "0 mho/cm") (thermCondVal "0.012 w/cm-degC")) ("L8_PWR2-SIG" (layerType "PLANE") (material "COPPER") (isShield t) (thickness "  2.400000 mil") (dielectricConstant "4.500000") (lossTangent "0.035") (etchFactor "90.000000") (elecCondVal "595900.000000 mho/cm") (thermCondVal "0.012 w/cm-degC")) ("" (layerType "DIELECTRIC") (material "FR-4") (thickness "  3.000000 mil") (dielectricConstant "4.500000") (lossTangent "0.035") (etchFactor "0.000000") (elecCondVal "0 mho/cm") (thermCondVal "0 w/cm-degC")) ("L9_GND4" (layerType "PLANE") (material "COPPER") (isShield t) (thickness "  1.200000 mil") (dielectricConstant "4.500000") (lossTangent "0.035") (etchFactor "90.000000") (elecCondVal "595900.000000 mho/cm") (thermCondVal "0 w/cm-degC")) ("" (layerType "DIELECTRIC") (material "FR-4") (thickness "  3.300000 mil") (dielectricConstant "4.100000") (lossTangent "0.035") (etchFactor "0.000000") (elecCondVal "0 mho/cm") (thermCondVal "0.012 w/cm-degC")) ("L10_SIG3" (layerType "CONDUCTOR") (material "COPPER") (thickness "  1.200000 mil") (width "4.00 MIL") (dielectricConstant "4.500000") (lossTangent "0.035") (etchFactor "90.000000") (elecCondVal "595900.000000 mho/cm") (thermCondVal "0.012 w/cm-degC") (signalDieConstant "4.100000") (signalLossTangent "0.035")) ("" (layerType "DIELECTRIC") (material "FR-4") (thickness "  9.000000 mil") (dielectricConstant "4.500000") (lossTangent "0.035") (etchFactor "0.000000") (elecCondVal "0 mho/cm") (thermCondVal "0 w/cm-degC")) ("L11_GND5" (layerType "PLANE") (material "COPPER") (isShield t) (thickness "  1.200000 mil") (dielectricConstant "4.500000") (lossTangent "0.035") (etchFactor "90.000000") (elecCondVal "595900.000000 mho/cm") (thermCondVal "0 w/cm-degC")) ("" (layerType "DIELECTRIC") (material "FR-4") (thickness "  3.300000 mil") (dielectricConstant "4.500000") (lossTangent "0.035") (etchFactor "0.000000") (elecCondVal "0 mho/cm") (thermCondVal "0.012 w/cm-degC")) ("L12_SIG4" (layerType "CONDUCTOR") (material "COPPER") (thickness "  1.200000 mil") (width "4.00 MIL") (dielectricConstant "4.500000") (lossTangent "0.035") (etchFactor "90.000000") (elecCondVal "595900.000000 mho/cm") (thermCondVal "0.012 w/cm-degC") (signalDieConstant "4.500000") (signalLossTangent "0.035")) ("" (layerType "DIELECTRIC") (material "FR-4") (thickness "  9.000000 mil") (dielectricConstant "4.500000") (lossTangent "0.035") (etchFactor "0.000000") (elecCondVal "0 mho/cm") (thermCondVal "0 w/cm-degC")) ("L13_GND6" (layerType "PLANE") (material "COPPER") (isShield t) (thickness "  1.200000 mil") (dielectricConstant "4.500000") (lossTangent "0.035") (etchFactor "90.000000") (elecCondVal "595900.000000 mho/cm") (thermCondVal "0.012 w/cm-degC")) ("" (layerType "DIELECTRIC") (material "FR-4") (thickness "  2.700000 mil") (dielectricConstant "4.500000") (lossTangent "0.035") (etchFactor "0.000000") (elecCondVal "0 mho/cm") (thermCondVal "0.012 w/cm-degC")) ("BOTTOM" (layerType "CONDUCTOR") (material "COPPER") (thickness "  1.800000 mil") (width "4.00 MIL") (dielectricConstant "4.500000") (lossTangent "0") (etchFactor "70.000000") (elecCondVal "595900.000000 mho/cm") (thermCondVal "0 w/cm-degC") (signalDieConstant "3.800000") (signalLossTangent "0.035")) ("" (layerType "DIELECTRIC") (material "CONFORMAL_COAT") (thickness "0.5 mil") (dielectricConstant "3.800000") (lossTangent "0.035") (etchFactor "0.000000") (elecCondVal "0 mho/cm") (thermCondVal "0.012 w/cm-degC")) ("" (layerType "SURFACE") (material "AIR") (thickness "0 mil") (dielectricConstant "1.000000") (lossTangent "0") (etchFactor "0.000000") (elecCondVal "0 mho/cm") (thermCondVal "0 w/cm-degC"))))) (Props (DesUnits "mils 2") (LayerStack ("DIELECTRIC" "DIELECTRIC" "BOTTOM" "DIELECTRIC" "L13_GND6" "DIELECTRIC" "L12_SIG4" "DIELECTRIC" "L11_GND5" "DIELECTRIC" "L10_SIG3" "DIELECTRIC" "L9_GND4" "DIELECTRIC" "L8_PWR2-SIG" "DIELECTRIC" "L7_PWR1-SIG" "DIELECTRIC" "L6_GND3" "DIELECTRIC" "L5_SIG2" "DIELECTRIC" "L4_GND2" "DIELECTRIC" "L3_SIG1" "DIELECTRIC" "L2_GND1" "DIELECTRIC" "TOP" "DIELECTRIC" "DIELECTRIC")) (Revision "16.600")) (Params (TLine ((diffImpedance "100ohm") (diffVelocity "1.4142e+08M/s") (impedance "60ohm") length("2800 mil") (propDelay "0.5 ns") (velocity "5600 mil/ns") (traceCount "1") (traceGeometry "Microstrip") (impedanceMin nil) (impedanceMax nil) (lengthMin nil) (lengthMax nil) (propDelayMin nil) (propDelayMax nil) (impedanceSweepCount nil) (propDelaySweepCount nil) (velocitySweepCount nil) (lengthSweepCount nil) (matchSetName nil))) (sync ((syncFreq "100e6") (syncInitState "1") (syncPattern "10") (syncEdgeSwitch "rise"))) (Connector nil) (IbisIOMacro ((temperature "27") (bufferModel "CDSDefaultIO_2p5v") (stimuli nil) (offsets nil) (state "tristate") (cycle "1") (termMap nil) (setup "2.0e-09") (hold "1.0e-09") (rise nil) (fall nil) (macroType nil) (voltage nil) (spice nil) (LEFDEFPinName nil) (LEFDEFPinType nil) (mappingTag nil))) (DiffInputPkg ((temperature "27") (bufferModelNonInverting "CDSDefaultInput_2p5v") (bufferModelInverting "CDSDefaultInput_2p5v") (threshInputHighMin "1.7 V") (threshInputHighTyp "1.7  V") (threshInputHighMax "1.7  V") (threshInputLowMin "0.7  V") (threshInputLowTyp "0.7  V") (threshInputLowMax "0.7  V") (mappingTagNonInverting nil) (mappingTagInverting nil) (cycle "1"))) (idlCircuit ((allDrivers "active") (ftsMode '("Typ")) (rcvrSelect "all") (simMode "Reflection") (tlineDelayMode "time") (userRevision "1.0") (autoSolve "On"))) (Inductor ((inductance "5 nH") (orientation "0"))) (DiffOutput ((temperature "27") (bufferModelNonInverting "CDSDefaultOutput_2p5v") (bufferModelInverting "CDSDefaultOutput_2p5v") (stimuli nil) (offsets nil) (state "tristate") (cycle "1") (termMap nil) (setup "0.9e-09") (hold "0.4e-09") (rise nil) (fall nil) (threshOutputHighMin "2.375  V") (threshOutputHighTyp "2.5  V") (threshOutputHighMax "2.625  V") (threshOutputLowMin "1.275  V") (threshOutputLowTyp "1.7  V") (threshOutputLowMax "1.985  V") (mappingTagNonInverting nil) (mappingTagInverting nil) (spice nil))) (HiClampTerm ((cutoffVoltage "0.7 V") (voltage "5 V") (maxDelay "0.1 ns"))) (Capacitor ((capacitance "10 pF") (orientation "0"))) (DiffOutputPkg ((temperature "27") (bufferModelNonInverting "CDSDefaultOutput_2p5v") (bufferModelInverting "CDSDefaultOutput_2p5v") (stimuli nil) (offsets nil) (state "tristate") (cycle "1") (termMap nil) (setup "0.9e-09") (hold "0.4e-09") (rise nil) (fall nil) (threshOutputHighMin "2.375  V") (threshOutputHighTyp "2.5  V") (threshOutputHighMax "2.625  V") (threshOutputLowMin "1.275  V") (threshOutputLowTyp "1.7  V") (threshOutputLowMax "1.985  V") (mappingTagNonInverting nil) (mappingTagInverting nil) (spice nil))) (DualClampTerm ((cutoffVoltageUp "0.7 V") (cutoffVoltageDown "0.7 V") (voltageUp "5 V") (voltageDown "0 V") (maxDelay "0.1 ns"))) (IbisOutput ((temperature "27") (bufferModel "CDSDefaultOutput_2p5v") (stimuli nil) (offsets nil) (state "tristate") (cycle "1") (termMap nil) (setup "2.0e-09") (hold "1.0e-09") (rise nil) (fall nil) (macroType nil) (voltage nil) (spice nil) (LEFDEFPinName nil) (LEFDEFPinType nil) (mappingTag nil))) (IbisIO ((temperature "27") (bufferModel "CDSDefaultIO_2p5v") (stimuli nil) (offsets nil) (state "tristate") (cycle "1") (termMap nil) (setup "2.0e-09") (hold "1.0e-09") (rise nil) (fall nil) (macroType nil) (voltage nil) (spice nil) (LEFDEFPinName nil) (LEFDEFPinType nil) (mappingTag nil))) (RLGC (length("1000 mil"))) (DiffIO ((temperature "27") (bufferModelNonInverting "CDSDefaultIO_2p5v") (bufferModelInverting "CDSDefaultIO_2p5v") (stimuli nil) (offsets nil) (state "tristate") (cycle "1") (termMap nil) (setup "0.9e-09") (hold "0.4e-09") (rise nil) (fall nil) (threshInputHighMin "1.7 V") (threshInputHighTyp "1.7  V") (threshInputHighMax "1.7  V") (threshInputLowMin "0.7  V") (threshInputLowTyp "0.7  V") (threshInputLowMax "0.7 ") (threshOutputHighMin "2.365  V") (threshOutputHighTyp "2.5  V") (threshOutputHighMax "2.625  V") (threshOutputLowMin "1.275  V") (threshOutputLowTyp "1.7  V") (threshOutputLowMax "1.985  V") (mappingTagNonInverting nil) (mappingTagInverting nil) (spice nil))) (Source ((voltage "5 V"))) (DiffIOPkg ((temperature "27") (bufferModelNonInverting "CDSDefaultIO_2p5v") (bufferModelInverting "CDSDefaultIO_2p5v") (stimuli nil) (offsets nil) (state "tristate") (cycle "1") (termMap nil) (setup "0.9e-09") (hold "0.4e-09") (rise nil) (fall nil) (threshInputHighMin "1.7 V") (threshInputHighTyp "1.7  V") (threshInputHighMax "1.7  V") (threshInputLowMin "0.7  V") (threshInputLowTyp "0.7  V") (threshInputLowMax "0.7 ") (threshOutputHighMin "2.365  V") (threshOutputHighTyp "2.5  V") (threshOutputHighMax "2.625  V") (threshOutputLowMin "1.275  V") (threshOutputLowTyp "1.7  V") (threshOutputLowMax "1.985  V") (mappingTagNonInverting nil) (mappingTagInverting nil) (spice nil))) (Diode ((cutoffVoltage "0.7 V"))) (ShuntTerm ((resistance "50 ohm") (voltage "5 V") (maxDelay "0.1 ns"))) (IbisIO_OpenPullDown ((temperature "27") (bufferModel "CDSDefaultIO_2p5v") (stimuli nil) (offsets nil) (state "tristate") (cycle "1") (termMap nil) (setup "2.0e-09") (hold "1.0e-09") (rise nil) (fall nil) (macroType nil) (voltage nil) (spice nil) (LEFDEFPinName nil) (LEFDEFPinType nil) (mappingTag nil))) (IbisIO_OpenPullUp ((temperature "27") (bufferModel "CDSDefaultIO_2p5v") (stimuli nil) (offsets nil) (state "tristate") (cycle "1") (termMap nil) (setup "2.0e-09") (hold "1.0e-09") (rise nil) (fall nil) (macroType nil) (voltage nil) (spice nil) (LEFDEFPinName nil) (LEFDEFPinType nil) (mappingTag nil))) (TheveninTerm ((resistanceUp "180 ohm") (resistanceDown "270 ohm") (voltageUp "5 V") (voltageDown "0 V") (maxDelay "0.1 ns"))) (Resistor ((resistance "50 ohm") (orientation "0"))) (RCTerm ((resistance "50 ohm") (capacitance "20 pF") (voltage "5 V") (maxDelay "0.1 ns"))) (DiffInput ((temperature "27") (bufferModelNonInverting "CDSDefaultInput_2p5v") (bufferModelInverting "CDSDefaultInput_2p5v") (threshInputHighMin "1.7 V") (threshInputHighTyp "1.7  V") (threshInputHighMax "1.7  V") (threshInputLowMin "0.7  V") (threshInputLowTyp "0.7  V") (threshInputLowMax "0.7  V") (mappingTagNonInverting nil) (mappingTagInverting nil) (cycle "1"))) (LowClampTerm ((cutoffVoltage "0.7 V") (voltage "0 V") (maxDelay "0.1 ns"))) (CPWSL ((d1Thickness "10 mil") (d1Constant "4.5") (d1LossTangent "0.035") (d2Thickness "0.72 mil") (d2Constant "4.5") (d2LossTangent "0.035") (d3Thickness "10 mil") (d3Constant "4.5") (d3LossTangent "0.035") length("1000 mil") (spacing "5 mil") (spacing2 "5 mil") (spacing3 "5 mil") (spacing4 "5 mil") (spacing5 "5 mil") (traceConductivity "595900 mho/cm") (traceGeometry "cpwms") (traceLayerName "") (traceThickness "0.72 mil") (traceType "single") (traceWidth "5.0 mil") (traceWidth2 "5.0 mil") (traceWidth3 "5.0 mil") (traceWidth4 "5.0 mil") (traceWidth5 "5.0 mil") (traceWidth6 "5.0 mil") (offset "0 mil") (traceCount "1") (impedance nil))) (Trace ((d1Thickness "10 mil") (d1Constant "4.5") (d1LossTangent "0.035") (d2Thickness "10 mil") (d2Constant "4.5") (d2LossTangent "0.035") (d3Thickness "0.0") (d3Constant "1.0") (d3LossTangent "0") length("1000 mil") (spacing "5 mil") (spacing2 "5 mil") (spacing3 "5 mil") (spacing4 "5 mil") (spacing5 "5 mil") (traceConductivity "595900 mho/cm") (traceGeometry "microstrip") (traceLayerName "") (traceThickness "0.72 mil") (traceType "single") (traceWidth "5.0 mil") (traceWidth2 "5.0 mil") (traceWidth3 "5.0 mil") (traceWidth4 "5.0 mil") (traceWidth5 "5.0 mil") (traceWidth6 "5.0 mil") (offset "0 mil") (traceCount "1") (impedance nil))) (CPWMS ((d1Thickness "10 mil") (d1Constant "4.5") (d1LossTangent "0.035") (d2Thickness "0.72 mil") (d2Constant "4.5") (d2LossTangent "0.035") (d3Thickness "0.0") (d3Constant "1") (d3LossTangent "0") length("1000 mil") (spacing "5 mil") (spacing2 "5 mil") (spacing3 "5 mil") (spacing4 "5 mil") (spacing5 "5 mil") (traceConductivity "595900 mho/cm") (traceGeometry "cpwms") (traceLayerName "") (traceThickness "0.72 mil") (traceType "single") (traceWidth "5.0 mil") (traceWidth2 "5.0 mil") (traceWidth3 "5.0 mil") (traceWidth4 "5.0 mil") (traceWidth5 "5.0 mil") (traceWidth6 "5.0 mil") (offset "0 mil") (traceCount "1") (impedance nil))) (CPW ((d1Thickness "10 mil") (d1Constant "4.5") (d1LossTangent "0.035") (d2Thickness "0.72 mil") (d2Constant "1") (d2LossTangent "0") (d3Thickness "0.0") (d3Constant "1") (d3LossTangent "0") length("1000 mil") (spacing "5 mil") (spacing2 "5 mil") (spacing3 "5 mil") (spacing4 "5 mil") (spacing5 "5 mil") (traceConductivity "595900 mho/cm") (traceGeometry "cpwms") (traceLayerName "") (traceThickness "0.72 mil") (traceType "single") (traceWidth "5.0 mil") (traceWidth2 "5.0 mil") (traceWidth3 "5.0 mil") (traceWidth4 "5.0 mil") (traceWidth5 "5.0 mil") (traceWidth6 "5.0 mil") (offset "0 mil") (traceCount "1") (impedance nil))) (async ((asyncTimePoints "") (asyncInitState "1"))) (IbisOutput_OpenPullUp ((temperature "27") (bufferModel "CDSDefaultOutput_2p5v") (stimuli nil) (offsets nil) (state "tristate") (cycle "1") (termMap nil) (setup "2.0e-09") (hold "1.0e-09") (rise nil) (fall nil) (macroType nil) (voltage nil) (spice nil) (LEFDEFPinName nil) (LEFDEFPinType nil) (mappingTag nil))) (Cable (length("1 m"))) (ESpiceDevice nil) (IbisInput ((temperature "27") (bufferModel "CDSDefaultInput_2p5v") (cycle "1") (LEFDEFPinName nil) (LEFDEFPinType nil) (mappingTag nil))) (SeriesTerm ((resistance "22 ohm") (maxDelay "0.1 ns"))) (IbisOutputPkg ((temperature "27") (bufferModel "CDSDefaultOutput_2p5v") (stimuli nil) (offsets nil) (state "tristate") (cycle "1") (termMap nil) (setup "2.0e-09") (hold "1.0e-09") (rise nil) (fall nil) (macroType nil) (voltage nil) (spice nil) (LEFDEFPinName nil) (LEFDEFPinType nil) (mappingTag nil))) (IbisIOPkg ((temperature "27") (bufferModel "CDSDefaultIO_2p5v") (stimuli nil) (offsets nil) (state "tristate") (cycle "1") (termMap nil) (setup "2.0e-09") (hold "1.0e-09") (rise nil) (fall nil) (macroType nil) (voltage nil) (spice nil) (LEFDEFPinName nil) (LEFDEFPinType nil) (mappingTag nil))) (CurrentProbe nil) (IbisInputPkg ((temperature "27") (bufferModel "CDSDefaultInput_2p5v") (cycle "1") (LEFDEFPinName nil) (LEFDEFPinType nil) (mappingTag nil))) (periodic ((periodicFreq "100e6") (periodicPattern "10") (periodicJitter "0"))) (clocked ((clockRise "1e-09") (clockFall "1e-09") (clockFreq "100e6") (clockInitState "0") (clockDutyCycle "0.5") (clockJitter "0"))) (Via ((model "Unknown") (viaOutputFormat "Unknown") (viaPadstack nil) (viaTopLayer nil) (viaBottomLayer nil) (viaIsPower nil) (viaIsGround nil)))))
				)
				( objectStatus "UPI_CPU0_CPU1_P0P0" )
			)
			( electricalCSet "@crescent_city_bb_fab1_lib.crescent_city_bb_fab1(sch_1):\DDR_CLK1\"
				( groupRef "DDR_CLK1:MG_DDR_NEAR_DIMM-CLK1" )
				( attribute "DIFFP_GATHER_CONTROL" "IGNORE"
					( Origin gBackEnd )
				)
				( attribute "DIFFP_UNCOUPLED_LENGTH" "500.00"
					( Origin gBackEnd )
				)
				( attribute "DIFFP_COUPLED_PLUS" "0.10"
					( Origin gBackEnd )
				)
				( attribute "DIFFP_COUPLED_MINUS" "0.10"
					( Origin gBackEnd )
				)
				( attribute "DIFFP_PHASE_TOL" "5 mil"
					( Units "uPhaseTol" "ns" 1.000000)
					( Origin gBackEnd )
				)
				( attribute "TOPOLOGY_TEMPLATE_REVISION" "1.0"
					( Origin gBackEnd )
				)
				( topologyData 22235
(SKIDL (Circuits ("MAIN" (Parts ("CRESCENT_CITY_083_20140728_C.@@J1.74" IbisIOPkg (xy (5522 4240)) (refDes "J4G1") (model "Unknown") (Props (_SXDesignName "CRESCENT_CITY_083_20140728_C") (brdx "10108.26 MIL") (brdy "607.23 MIL") (bufferModel "CDSDefaultIO_2p5v") (cycle "1") (hold "1.0e-09") (mappingTag "") (offsets ("4" "0") ("5" "0")) (setup "2.0e-09") (state "tristate") (stimuli ("4" "local7") ("5" "local8")) (temperature "27") (termMap ("4" "Data") ("5" "Enable"))) (Terms ("CRESCENT_CITY_083_20140728_C.X1010826Y60723L2LRATS" "74"))) ("CRESCENT_CITY_083_20140728_C.@@U36.D55" IbisIOPkg (xy (5502 4240)) (refDes "U5D1") (model "Unknown") (Props (_SXDesignName "CRESCENT_CITY_083_20140728_C") (brdx "10211.15 MIL") (brdy "2013.09 MIL") (bufferModel "CDSDefaultIO_2p5v") (cycle "1") (hold "1.0e-09") (mappingTag "") (offsets ("4" "0") ("5" "0")) (setup "2.0e-09") (state "tristate") (stimuli ("4" "local9") ("5" "local10")) (temperature "27") (termMap ("4" "Data") ("5" "Enable"))) (Terms ("CRESCENT_CITY_083_20140728_C.X1021115Y201309L2LRATS" "D55"))) ("CRESCENT_CITY_083_20140728_C.T@@RATS@@U36.D55@@J1.74" TLine (xy (5513 4235)) (refDes "TL1") (Props (_SXDesignName "CRESCENT_CITY_083_20140728_C") (impedance "53.474 ohm") length("1508.75 MIL") (propDelay "0.27098 ns") (traceCount "1") (traceGeometry "Microstrip") (velocity "5567.76 mil/ns")) (Terms ("CRESCENT_CITY_083_20140728_C.X1021115Y201309L2LRATS" "1") ("CRESCENT_CITY_083_20140728_C.X1010826Y60723L2LRATS" "2")))) (Nodes ("CRESCENT_CITY_083_20140728_C.X1021115Y201309L2LRATS" (terms "CRESCENT_CITY_083_20140728_C.T@@RATS@@U36.D55@@J1.74.1" "CRESCENT_CITY_083_20140728_C.@@U36.D55.1")) ("CRESCENT_CITY_083_20140728_C.X1010826Y60723L2LRATS" (terms "CRESCENT_CITY_083_20140728_C.T@@RATS@@U36.D55@@J1.74.2" "CRESCENT_CITY_083_20140728_C.@@J1.74.1"))) (Ports) (Stimuli ("local8" (scope local) (stimType periodic) (Props (periodicFreq "5e+007") (periodicJitter "0") (periodicPattern "1"))) ("local10" (scope local) (stimType periodic) (Props (periodicFreq "5e+007") (periodicJitter "0") (periodicPattern "1"))) ("local9" (scope local) (stimType periodic) (Props (periodicFreq "5e+007") (periodicJitter "0") (periodicPattern "1"))) ("local7" (scope local) (stimType periodic) (Props (periodicFreq "5e+007") (periodicJitter "0") (periodicPattern "1")))) (Notes) (Constraints ("DP_GATHER_CONTROL" "IGNORE") ("DP_MAX_UNCOUPLED_LENGTH" "0.0127") ("DP_NEGATIVE_COUPLED_TOLERANCE" "2.54e-006") ("DP_PHASE_TOLERANCE" ("LENGTH" "0.000127")) ("DP_POSITIVE_COUPLED_TOLERANCE" "2.54e-006") ("RELATIVE_PROPAGATION_DELAY" ("MG_DDR_FAR_DIMM-CLK0" "LONGEST" "LONGEST" "CLASS" "LENGTH" "0.000127" "LENGTH" "0"))) (MeasurementSets ("EMI" ("EMIStatus" status("on")) ("PeakEmission" status("on")) ("PeakFrequency" status("on")) ("PulseFreq" status("on")) ("RiseTime" status("on")) ("VoltageSwing" status("on"))) ("Reflection" ("BufferDelayFall" status("off")) ("BufferDelayRise" status("off")) ("EyeHeight" status("off")) ("EyeJitter" status("off")) ("EyeWidth" status("off")) ("FirstIncidentFall" status("off")) ("FirstIncidentRise" status("off")) ("Glitch" status("on")) ("GlitchFall" status("off")) ("GlitchRise" status("off")) ("Monotonic" status("on")) ("MonotonicFall" status("off")) ("MonotonicRise" status("off")) ("NoiseMargin" status("on")) ("NoiseMarginHigh" status("off")) ("NoiseMarginLow" status("off")) ("OvershootHigh" status("on")) ("OvershootLow" status("on")) ("PropDelay" status("on")) ("SettleDelay" status("on")) ("SettleDelayFall" status("off")) ("SettleDelayRise" status("off")) ("SwitchDelay" status("on")) ("SwitchDelayFall" status("off")) ("SwitchDelayRise" status("off"))) ("Crosstalk" ("Crosstalk" status("on"))) ("Custom")) (VectorSets) (Props (XnetName "M_A_CLK_DP<0>") (allDrivers "active") (customSimType "Reflection") (ftsMode ("Typ")) (rcvrSelect "all") (tlineDelayMode "time") (userRevision "1.0")))) (Subckts) (CrossSections ("CRESCENT_CITY_083_20140728_C" (Props (SXDesignName "CRESCENT_CITY_083_20140728_C")) (Layers ("" (layerType "SURFACE") (material "AIR") (thickness "0 mil") (dielectricConstant "1.000000") (lossTangent "0") (etchFactor "0.000000") (elecCondVal "0 mho/cm") (thermCondVal "0 w/cm-degC")) ("" (layerType "DIELECTRIC") (material "CONFORMAL_COAT") (thickness "0.5 mil") (dielectricConstant "3.800000") (lossTangent "0.035") (etchFactor "0.000000") (elecCondVal "0 mho/cm") (thermCondVal "0.012 w/cm-degC")) ("TOP" (layerType "CONDUCTOR") (material "COPPER") (thickness "  1.800000 mil") (width "4.00 MIL") (dielectricConstant "4.500000") (lossTangent "0") (etchFactor "70.000000") (elecCondVal "595900.000000 mho/cm") (thermCondVal "0 w/cm-degC") (signalDieConstant "3.800000") (signalLossTangent "0.035")) ("" (layerType "DIELECTRIC") (material "FR-4") (thickness "  2.700000 mil") (dielectricConstant "4.000000") (lossTangent "0.035") (etchFactor "0.000000") (elecCondVal "0 mho/cm") (thermCondVal "0.012 w/cm-degC")) ("L2_GND1" (layerType "PLANE") (material "COPPER") (isShield t) (thickness "  1.200000 mil") (dielectricConstant "4.500000") (lossTangent "0.035") (etchFactor "90.000000") (elecCondVal "595900.000000 mho/cm") (thermCondVal "0.012 w/cm-degC")) ("" (layerType "DIELECTRIC") (material "FR-4") (thickness "  9.900000 mil") (dielectricConstant "4.100000") (lossTangent "0.035") (etchFactor "0.000000") (elecCondVal "0 mho/cm") (thermCondVal "0.012 w/cm-degC")) ("L3_SIG1" (layerType "CONDUCTOR") (material "COPPER") (thickness "  1.200000 mil") (width "4.00 MIL") (dielectricConstant "4.500000") (lossTangent "0.035") (etchFactor "90.000000") (elecCondVal "595900.000000 mho/cm") (thermCondVal "0.012 w/cm-degC") (signalDieConstant "4.100000") (signalLossTangent "0.035")) ("" (layerType "DIELECTRIC") (material "FR-4") (thickness "  3.300000 mil") (dielectricConstant "4.500000") (lossTangent "0.035") (etchFactor "0.000000") (elecCondVal "0 mho/cm") (thermCondVal "0 w/cm-degC")) ("L4_GND2" (layerType "PLANE") (material "COPPER") (isShield t) (thickness "  1.200000 mil") (dielectricConstant "4.500000") (lossTangent "0.035") (etchFactor "90.000000") (elecCondVal "595900.000000 mho/cm") (thermCondVal "0 w/cm-degC")) ("" (layerType "DIELECTRIC") (material "FR-4") (thickness "  3.300000 mil") (dielectricConstant "4.000000") (lossTangent "0.035") (etchFactor "0.000000") (elecCondVal "0 mho/cm") (thermCondVal "0.012 w/cm-degC")) ("L5_SIG2" (layerType "CONDUCTOR") (material "COPPER") (thickness "  1.200000 mil") (width "4.00 MIL") (dielectricConstant "4.500000") (lossTangent "0.035") (etchFactor "90.000000") (elecCondVal "595900.000000 mho/cm") (thermCondVal "0.012 w/cm-degC") (signalDieConstant "4.000000") (signalLossTangent "0.035")) ("" (layerType "DIELECTRIC") (material "FR-4") (thickness "  9.900000 mil") (dielectricConstant "4.500000") (lossTangent "0.035") (etchFactor "0.000000") (elecCondVal "0 mho/cm") (thermCondVal "0 w/cm-degC")) ("L6_GND3" (layerType "PLANE") (material "COPPER") (isShield t) (thickness "  1.200000 mil") (dielectricConstant "4.500000") (lossTangent "0.035") (etchFactor "90.000000") (elecCondVal "595900.000000 mho/cm") (thermCondVal "0 w/cm-degC")) ("" (layerType "DIELECTRIC") (material "FR-4") (thickness "  3.300000 mil") (dielectricConstant "4.100000") (lossTangent "0.035") (etchFactor "0.000000") (elecCondVal "0 mho/cm") (thermCondVal "0.012 w/cm-degC")) ("L7_PWR1-SIG" (layerType "PLANE") (material "COPPER") (isShield t) (thickness "  1.200000 mil") (dielectricConstant "4.500000") (lossTangent "0.035") (etchFactor "90.000000") (elecCondVal "595900.000000 mho/cm") (thermCondVal "0.012 w/cm-degC")) ("" (layerType "DIELECTRIC") (material "FR-4") (thickness "  9.900000 mil") (dielectricConstant "4.000000") (lossTangent "0.035") (etchFactor "0.000000") (elecCondVal "0 mho/cm") (thermCondVal "0.012 w/cm-degC")) ("L8_PWR2-SIG" (layerType "PLANE") (material "COPPER") (isShield t) (thickness "  1.200000 mil") (dielectricConstant "4.500000") (lossTangent "0.035") (etchFactor "90.000000") (elecCondVal "595900.000000 mho/cm") (thermCondVal "0.012 w/cm-degC")) ("" (layerType "DIELECTRIC") (material "FR-4") (thickness "  3.300000 mil") (dielectricConstant "4.500000") (lossTangent "0.035") (etchFactor "0.000000") (elecCondVal "0 mho/cm") (thermCondVal "0 w/cm-degC")) ("L9_GND4" (layerType "PLANE") (material "COPPER") (isShield t) (thickness "  1.200000 mil") (dielectricConstant "4.500000") (lossTangent "0.035") (etchFactor "90.000000") (elecCondVal "595900.000000 mho/cm") (thermCondVal "0 w/cm-degC")) ("" (layerType "DIELECTRIC") (material "FR-4") (thickness "  9.900000 mil") (dielectricConstant "4.100000") (lossTangent "0.035") (etchFactor "0.000000") (elecCondVal "0 mho/cm") (thermCondVal "0.012 w/cm-degC")) ("L10_SIG3" (layerType "CONDUCTOR") (material "COPPER") (thickness "  1.200000 mil") (width "4.00 MIL") (dielectricConstant "4.500000") (lossTangent "0.035") (etchFactor "90.000000") (elecCondVal "595900.000000 mho/cm") (thermCondVal "0.012 w/cm-degC") (signalDieConstant "4.100000") (signalLossTangent "0.035")) ("" (layerType "DIELECTRIC") (material "FR-4") (thickness "  3.300000 mil") (dielectricConstant "4.500000") (lossTangent "0.035") (etchFactor "0.000000") (elecCondVal "0 mho/cm") (thermCondVal "0 w/cm-degC")) ("L11_GND5" (layerType "PLANE") (material "COPPER") (isShield t) (thickness "  1.200000 mil") (dielectricConstant "4.500000") (lossTangent "0.035") (etchFactor "90.000000") (elecCondVal "595900.000000 mho/cm") (thermCondVal "0 w/cm-degC")) ("" (layerType "DIELECTRIC") (material "FR-4") (thickness "  9.900000 mil") (dielectricConstant "4.500000") (lossTangent "0.035") (etchFactor "0.000000") (elecCondVal "0 mho/cm") (thermCondVal "0.012 w/cm-degC")) ("L12_SIG4" (layerType "CONDUCTOR") (material "COPPER") (thickness "  1.200000 mil") (width "4.00 MIL") (dielectricConstant "4.500000") (lossTangent "0.035") (etchFactor "90.000000") (elecCondVal "595900.000000 mho/cm") (thermCondVal "0.012 w/cm-degC") (signalDieConstant "4.500000") (signalLossTangent "0.035")) ("" (layerType "DIELECTRIC") (material "FR-4") (thickness "  3.300000 mil") (dielectricConstant "4.500000") (lossTangent "0.035") (etchFactor "0.000000") (elecCondVal "0 mho/cm") (thermCondVal "0 w/cm-degC")) ("L13_GND6" (layerType "PLANE") (material "COPPER") (isShield t) (thickness "  1.200000 mil") (dielectricConstant "4.500000") (lossTangent "0.035") (etchFactor "90.000000") (elecCondVal "595900.000000 mho/cm") (thermCondVal "0.012 w/cm-degC")) ("" (layerType "DIELECTRIC") (material "FR-4") (thickness "  2.700000 mil") (dielectricConstant "4.500000") (lossTangent "0.035") (etchFactor "0.000000") (elecCondVal "0 mho/cm") (thermCondVal "0.012 w/cm-degC")) ("BOTTOM" (layerType "CONDUCTOR") (material "COPPER") (thickness "  1.800000 mil") (width "4.00 MIL") (dielectricConstant "4.500000") (lossTangent "0") (etchFactor "70.000000") (elecCondVal "595900.000000 mho/cm") (thermCondVal "0 w/cm-degC") (signalDieConstant "3.800000") (signalLossTangent "0.035")) ("" (layerType "DIELECTRIC") (material "CONFORMAL_COAT") (thickness "0.5 mil") (dielectricConstant "3.800000") (lossTangent "0.035") (etchFactor "0.000000") (elecCondVal "0 mho/cm") (thermCondVal "0.012 w/cm-degC")) ("" (layerType "SURFACE") (material "AIR") (thickness "0 mil") (dielectricConstant "1.000000") (lossTangent "0") (etchFactor "0.000000") (elecCondVal "0 mho/cm") (thermCondVal "0 w/cm-degC"))))) (Props (DesUnits "mils 2") (LayerStack ("DIELECTRIC" "DIELECTRIC" "BOTTOM" "DIELECTRIC" "L13_GND6" "DIELECTRIC" "L12_SIG4" "DIELECTRIC" "L11_GND5" "DIELECTRIC" "L10_SIG3" "DIELECTRIC" "L9_GND4" "DIELECTRIC" "L8_PWR2-SIG" "DIELECTRIC" "L7_PWR1-SIG" "DIELECTRIC" "L6_GND3" "DIELECTRIC" "L5_SIG2" "DIELECTRIC" "L4_GND2" "DIELECTRIC" "L3_SIG1" "DIELECTRIC" "L2_GND1" "DIELECTRIC" "TOP" "DIELECTRIC" "DIELECTRIC")) (Revision "16.600")) (Params (ESpiceDevice nil) (Cable (length("1 m"))) (Via ((model "Unknown") (viaOutputFormat "Unknown") (viaPadstack nil) (viaTopLayer nil) (viaBottomLayer nil) (viaIsPower nil) (viaIsGround nil))) (Trace ((d1Thickness "10 mil") (d1Constant "4.5") (d1LossTangent "0.035") (d2Thickness "10 mil") (d2Constant "4.5") (d2LossTangent "0.035") (d3Thickness "0.0") (d3Constant "1.0") (d3LossTangent "0") length("1000 mil") (spacing "5 mil") (spacing2 "5 mil") (spacing3 "5 mil") (spacing4 "5 mil") (spacing5 "5 mil") (traceConductivity "595900 mho/cm") (traceGeometry "microstrip") (traceLayerName "") (traceThickness "0.72 mil") (traceType "single") (traceWidth "5.0 mil") (traceWidth2 "5.0 mil") (traceWidth3 "5.0 mil") (traceWidth4 "5.0 mil") (traceWidth5 "5.0 mil") (traceWidth6 "5.0 mil") (offset "0 mil") (traceCount "1") (impedance nil))) (IbisOutput_OpenPullUp ((temperature "27") (bufferModel "CDSDefaultOutput_2p5v") (stimuli nil) (offsets nil) (state "tristate") (cycle "1") (termMap nil) (setup "2.0e-09") (hold "1.0e-09") (rise nil) (fall nil) (macroType nil) (voltage nil) (spice nil) (LEFDEFPinName nil) (LEFDEFPinType nil) (mappingTag nil))) (IbisInput ((temperature "27") (bufferModel "CDSDefaultInput_2p5v") (cycle "1") (LEFDEFPinName nil) (LEFDEFPinType nil) (mappingTag nil))) (IbisIO_OpenPullUp ((temperature "27") (bufferModel "CDSDefaultIO_2p5v") (stimuli nil) (offsets nil) (state "tristate") (cycle "1") (termMap nil) (setup "2.0e-09") (hold "1.0e-09") (rise nil) (fall nil) (macroType nil) (voltage nil) (spice nil) (LEFDEFPinName nil) (LEFDEFPinType nil) (mappingTag nil))) (clocked ((clockRise "1e-09") (clockFall "1e-09") (clockFreq "100e6") (clockInitState "0") (clockDutyCycle "0.5") (clockJitter "0"))) (periodic ((periodicFreq "100e6") (periodicPattern "10") (periodicJitter "0"))) (IbisIO_OpenPullDown ((temperature "27") (bufferModel "CDSDefaultIO_2p5v") (stimuli nil) (offsets nil) (state "tristate") (cycle "1") (termMap nil) (setup "2.0e-09") (hold "1.0e-09") (rise nil) (fall nil) (macroType nil) (voltage nil) (spice nil) (LEFDEFPinName nil) (LEFDEFPinType nil) (mappingTag nil))) (RLGC (length("1000 mil"))) (DiffIO ((temperature "27") (bufferModelNonInverting "CDSDefaultIO_2p5v") (bufferModelInverting "CDSDefaultIO_2p5v") (stimuli nil) (offsets nil) (state "tristate") (cycle "1") (termMap nil) (setup "0.9e-09") (hold "0.4e-09") (rise nil) (fall nil) (threshInputHighMin "1.7 V") (threshInputHighTyp "1.7  V") (threshInputHighMax "1.7  V") (threshInputLowMin "0.7  V") (threshInputLowTyp "0.7  V") (threshInputLowMax "0.7 ") (threshOutputHighMin "2.365  V") (threshOutputHighTyp "2.5  V") (threshOutputHighMax "2.625  V") (threshOutputLowMin "1.275  V") (threshOutputLowTyp "1.7  V") (threshOutputLowMax "1.985  V") (mappingTagNonInverting nil) (mappingTagInverting nil) (spice nil))) (IbisOutput ((temperature "27") (bufferModel "CDSDefaultOutput_2p5v") (stimuli nil) (offsets nil) (state "tristate") (cycle "1") (termMap nil) (setup "2.0e-09") (hold "1.0e-09") (rise nil) (fall nil) (macroType nil) (voltage nil) (spice nil) (LEFDEFPinName nil) (LEFDEFPinType nil) (mappingTag nil))) (Source ((voltage "5 V"))) (Inductor ((inductance "5 nH") (orientation "0"))) (DiffIOPkg ((temperature "27") (bufferModelNonInverting "CDSDefaultIO_2p5v") (bufferModelInverting "CDSDefaultIO_2p5v") (stimuli nil) (offsets nil) (state "tristate") (cycle "1") (termMap nil) (setup "0.9e-09") (hold "0.4e-09") (rise nil) (fall nil) (threshInputHighMin "1.7 V") (threshInputHighTyp "1.7  V") (threshInputHighMax "1.7  V") (threshInputLowMin "0.7  V") (threshInputLowTyp "0.7  V") (threshInputLowMax "0.7 ") (threshOutputHighMin "2.365  V") (threshOutputHighTyp "2.5  V") (threshOutputHighMax "2.625  V") (threshOutputLowMin "1.275  V") (threshOutputLowTyp "1.7  V") (threshOutputLowMax "1.985  V") (mappingTagNonInverting nil) (mappingTagInverting nil) (spice nil))) (IbisIO ((temperature "27") (bufferModel "CDSDefaultIO_2p5v") (stimuli nil) (offsets nil) (state "tristate") (cycle "1") (termMap nil) (setup "2.0e-09") (hold "1.0e-09") (rise nil) (fall nil) (macroType nil) (voltage nil) (spice nil) (LEFDEFPinName nil) (LEFDEFPinType nil) (mappingTag nil))) (SeriesTerm ((resistance "22 ohm") (maxDelay "0.1 ns"))) (CPW ((d1Thickness "10 mil") (d1Constant "4.5") (d1LossTangent "0.035") (d2Thickness "0.72 mil") (d2Constant "1") (d2LossTangent "0") (d3Thickness "0.0") (d3Constant "1") (d3LossTangent "0") length("1000 mil") (spacing "5 mil") (spacing2 "5 mil") (spacing3 "5 mil") (spacing4 "5 mil") (spacing5 "5 mil") (traceConductivity "595900 mho/cm") (traceGeometry "cpwms") (traceLayerName "") (traceThickness "0.72 mil") (traceType "single") (traceWidth "5.0 mil") (traceWidth2 "5.0 mil") (traceWidth3 "5.0 mil") (traceWidth4 "5.0 mil") (traceWidth5 "5.0 mil") (traceWidth6 "5.0 mil") (offset "0 mil") (traceCount "1") (impedance nil))) (CPWMS ((d1Thickness "10 mil") (d1Constant "4.5") (d1LossTangent "0.035") (d2Thickness "0.72 mil") (d2Constant "4.5") (d2LossTangent "0.035") (d3Thickness "0.0") (d3Constant "1") (d3LossTangent "0") length("1000 mil") (spacing "5 mil") (spacing2 "5 mil") (spacing3 "5 mil") (spacing4 "5 mil") (spacing5 "5 mil") (traceConductivity "595900 mho/cm") (traceGeometry "cpwms") (traceLayerName "") (traceThickness "0.72 mil") (traceType "single") (traceWidth "5.0 mil") (traceWidth2 "5.0 mil") (traceWidth3 "5.0 mil") (traceWidth4 "5.0 mil") (traceWidth5 "5.0 mil") (traceWidth6 "5.0 mil") (offset "0 mil") (traceCount "1") (impedance nil))) (TLine ((diffImpedance "100ohm") (diffVelocity "1.4142e+08M/s") (impedance "60ohm") length("2800 mil") (propDelay "0.5 ns") (velocity "5600 mil/ns") (traceCount "1") (traceGeometry "Microstrip") (impedanceMin nil) (impedanceMax nil) (lengthMin nil) (lengthMax nil) (propDelayMin nil) (propDelayMax nil) (impedanceSweepCount nil) (propDelaySweepCount nil) (velocitySweepCount nil) (lengthSweepCount nil) (matchSetName nil))) (sync ((syncFreq "100e6") (syncInitState "1") (syncPattern "10") (syncEdgeSwitch "rise"))) (Connector nil) (Diode ((cutoffVoltage "0.7 V"))) (CurrentProbe nil) (CPWSL ((d1Thickness "10 mil") (d1Constant "4.5") (d1LossTangent "0.035") (d2Thickness "0.72 mil") (d2Constant "4.5") (d2LossTangent "0.035") (d3Thickness "10 mil") (d3Constant "4.5") (d3LossTangent "0.035") length("1000 mil") (spacing "5 mil") (spacing2 "5 mil") (spacing3 "5 mil") (spacing4 "5 mil") (spacing5 "5 mil") (traceConductivity "595900 mho/cm") (traceGeometry "cpwms") (traceLayerName "") (traceThickness "0.72 mil") (traceType "single") (traceWidth "5.0 mil") (traceWidth2 "5.0 mil") (traceWidth3 "5.0 mil") (traceWidth4 "5.0 mil") (traceWidth5 "5.0 mil") (traceWidth6 "5.0 mil") (offset "0 mil") (traceCount "1") (impedance nil))) (async ((asyncTimePoints "") (asyncInitState "1"))) (Capacitor ((capacitance "10 pF") (orientation "0"))) (DiffOutputPkg ((temperature "27") (bufferModelNonInverting "CDSDefaultOutput_2p5v") (bufferModelInverting "CDSDefaultOutput_2p5v") (stimuli nil) (offsets nil) (state "tristate") (cycle "1") (termMap nil) (setup "0.9e-09") (hold "0.4e-09") (rise nil) (fall nil) (threshOutputHighMin "2.375  V") (threshOutputHighTyp "2.5  V") (threshOutputHighMax "2.625  V") (threshOutputLowMin "1.275  V") (threshOutputLowTyp "1.7  V") (threshOutputLowMax "1.985  V") (mappingTagNonInverting nil) (mappingTagInverting nil) (spice nil))) (DiffOutput ((temperature "27") (bufferModelNonInverting "CDSDefaultOutput_2p5v") (bufferModelInverting "CDSDefaultOutput_2p5v") (stimuli nil) (offsets nil) (state "tristate") (cycle "1") (termMap nil) (setup "0.9e-09") (hold "0.4e-09") (rise nil) (fall nil) (threshOutputHighMin "2.375  V") (threshOutputHighTyp "2.5  V") (threshOutputHighMax "2.625  V") (threshOutputLowMin "1.275  V") (threshOutputLowTyp "1.7  V") (threshOutputLowMax "1.985  V") (mappingTagNonInverting nil) (mappingTagInverting nil) (spice nil))) (HiClampTerm ((cutoffVoltage "0.7 V") (voltage "5 V") (maxDelay "0.1 ns"))) (IbisInputPkg ((temperature "27") (bufferModel "CDSDefaultInput_2p5v") (cycle "1") (LEFDEFPinName nil) (LEFDEFPinType nil) (mappingTag nil))) (Resistor ((resistance "50 ohm") (orientation "0"))) (DiffInput ((temperature "27") (bufferModelNonInverting "CDSDefaultInput_2p5v") (bufferModelInverting "CDSDefaultInput_2p5v") (threshInputHighMin "1.7 V") (threshInputHighTyp "1.7  V") (threshInputHighMax "1.7  V") (threshInputLowMin "0.7  V") (threshInputLowTyp "0.7  V") (threshInputLowMax "0.7  V") (mappingTagNonInverting nil) (mappingTagInverting nil) (cycle "1"))) (DualClampTerm ((cutoffVoltageUp "0.7 V") (cutoffVoltageDown "0.7 V") (voltageUp "5 V") (voltageDown "0 V") (maxDelay "0.1 ns"))) (IbisOutputPkg ((temperature "27") (bufferModel "CDSDefaultOutput_2p5v") (stimuli nil) (offsets nil) (state "tristate") (cycle "1") (termMap nil) (setup "2.0e-09") (hold "1.0e-09") (rise nil) (fall nil) (macroType nil) (voltage nil) (spice nil) (LEFDEFPinName nil) (LEFDEFPinType nil) (mappingTag nil))) (IbisIOPkg ((temperature "27") (bufferModel "CDSDefaultIO_2p5v") (stimuli nil) (offsets nil) (state "tristate") (cycle "1") (termMap nil) (setup "2.0e-09") (hold "1.0e-09") (rise nil) (fall nil) (macroType nil) (voltage nil) (spice nil) (LEFDEFPinName nil) (LEFDEFPinType nil) (mappingTag nil))) (TheveninTerm ((resistanceUp "180 ohm") (resistanceDown "270 ohm") (voltageUp "5 V") (voltageDown "0 V") (maxDelay "0.1 ns"))) (IbisIOMacro ((temperature "27") (bufferModel "CDSDefaultIO_2p5v") (stimuli nil) (offsets nil) (state "tristate") (cycle "1") (termMap nil) (setup "2.0e-09") (hold "1.0e-09") (rise nil) (fall nil) (macroType nil) (voltage nil) (spice nil) (LEFDEFPinName nil) (LEFDEFPinType nil) (mappingTag nil))) (RCTerm ((resistance "50 ohm") (capacitance "20 pF") (voltage "5 V") (maxDelay "0.1 ns"))) (LowClampTerm ((cutoffVoltage "0.7 V") (voltage "0 V") (maxDelay "0.1 ns"))) (DiffInputPkg ((temperature "27") (bufferModelNonInverting "CDSDefaultInput_2p5v") (bufferModelInverting "CDSDefaultInput_2p5v") (threshInputHighMin "1.7 V") (threshInputHighTyp "1.7  V") (threshInputHighMax "1.7  V") (threshInputLowMin "0.7  V") (threshInputLowTyp "0.7  V") (threshInputLowMax "0.7  V") (mappingTagNonInverting nil) (mappingTagInverting nil) (cycle "1"))) (ShuntTerm ((resistance "50 ohm") (voltage "5 V") (maxDelay "0.1 ns"))) (idlCircuit ((allDrivers "active") (ftsMode '("Typ")) (rcvrSelect "all") (simMode "Reflection") (tlineDelayMode "time") (userRevision "1.0") (autoSolve "On")))))
				)
				( objectStatus "DDR_CLK1" )
			)
			( electricalCSet "@crescent_city_bb_fab1_lib.crescent_city_bb_fab1(sch_1):\M_A_CLK_DP_0_\"
				( groupRef "DDR_CLK0:MG_DDR_FAR_DIMM-CLK0" )
				( attribute "DIFFP_GATHER_CONTROL" "IGNORE"
					( Origin gBackEnd )
				)
				( attribute "DIFFP_UNCOUPLED_LENGTH" "500.00"
					( Origin gBackEnd )
				)
				( attribute "DIFFP_COUPLED_PLUS" "0.10"
					( Origin gBackEnd )
				)
				( attribute "DIFFP_COUPLED_MINUS" "0.10"
					( Origin gBackEnd )
				)
				( attribute "DIFFP_PHASE_TOL" "5 mil"
					( Units "uPhaseTol" "ns" 1.000000)
					( Origin gBackEnd )
				)
				( attribute "TOPOLOGY_TEMPLATE_REVISION" "1.0"
					( Origin gBackEnd )
				)
				( topologyData 22235
(SKIDL (Circuits ("MAIN" (Parts ("CRESCENT_CITY_083_20140728_C.@@J1.74" IbisIOPkg (xy (5522 4240)) (refDes "J4G1") (model "Unknown") (Props (_SXDesignName "CRESCENT_CITY_083_20140728_C") (brdx "10108.26 MIL") (brdy "607.23 MIL") (bufferModel "CDSDefaultIO_2p5v") (cycle "1") (hold "1.0e-09") (mappingTag "") (offsets ("4" "0") ("5" "0")) (setup "2.0e-09") (state "tristate") (stimuli ("4" "local7") ("5" "local8")) (temperature "27") (termMap ("4" "Data") ("5" "Enable"))) (Terms ("CRESCENT_CITY_083_20140728_C.X1010826Y60723L2LRATS" "74"))) ("CRESCENT_CITY_083_20140728_C.@@U36.D55" IbisIOPkg (xy (5502 4240)) (refDes "U5D1") (model "Unknown") (Props (_SXDesignName "CRESCENT_CITY_083_20140728_C") (brdx "10211.15 MIL") (brdy "2013.09 MIL") (bufferModel "CDSDefaultIO_2p5v") (cycle "1") (hold "1.0e-09") (mappingTag "") (offsets ("4" "0") ("5" "0")) (setup "2.0e-09") (state "tristate") (stimuli ("4" "local9") ("5" "local10")) (temperature "27") (termMap ("4" "Data") ("5" "Enable"))) (Terms ("CRESCENT_CITY_083_20140728_C.X1021115Y201309L2LRATS" "D55"))) ("CRESCENT_CITY_083_20140728_C.T@@RATS@@U36.D55@@J1.74" TLine (xy (5513 4235)) (refDes "TL1") (Props (_SXDesignName "CRESCENT_CITY_083_20140728_C") (impedance "53.474 ohm") length("1508.75 MIL") (propDelay "0.27098 ns") (traceCount "1") (traceGeometry "Microstrip") (velocity "5567.76 mil/ns")) (Terms ("CRESCENT_CITY_083_20140728_C.X1021115Y201309L2LRATS" "1") ("CRESCENT_CITY_083_20140728_C.X1010826Y60723L2LRATS" "2")))) (Nodes ("CRESCENT_CITY_083_20140728_C.X1021115Y201309L2LRATS" (terms "CRESCENT_CITY_083_20140728_C.T@@RATS@@U36.D55@@J1.74.1" "CRESCENT_CITY_083_20140728_C.@@U36.D55.1")) ("CRESCENT_CITY_083_20140728_C.X1010826Y60723L2LRATS" (terms "CRESCENT_CITY_083_20140728_C.T@@RATS@@U36.D55@@J1.74.2" "CRESCENT_CITY_083_20140728_C.@@J1.74.1"))) (Ports) (Stimuli ("local8" (scope local) (stimType periodic) (Props (periodicFreq "5e+007") (periodicJitter "0") (periodicPattern "1"))) ("local10" (scope local) (stimType periodic) (Props (periodicFreq "5e+007") (periodicJitter "0") (periodicPattern "1"))) ("local9" (scope local) (stimType periodic) (Props (periodicFreq "5e+007") (periodicJitter "0") (periodicPattern "1"))) ("local7" (scope local) (stimType periodic) (Props (periodicFreq "5e+007") (periodicJitter "0") (periodicPattern "1")))) (Notes) (Constraints ("DP_GATHER_CONTROL" "IGNORE") ("DP_MAX_UNCOUPLED_LENGTH" "0.0127") ("DP_NEGATIVE_COUPLED_TOLERANCE" "2.54e-006") ("DP_PHASE_TOLERANCE" ("LENGTH" "0.000127")) ("DP_POSITIVE_COUPLED_TOLERANCE" "2.54e-006") ("RELATIVE_PROPAGATION_DELAY" ("MG_DDR_FAR_DIMM-CLK0" "LONGEST" "LONGEST" "CLASS" "LENGTH" "0.000127" "LENGTH" "0"))) (MeasurementSets ("EMI" ("EMIStatus" status("on")) ("PeakEmission" status("on")) ("PeakFrequency" status("on")) ("PulseFreq" status("on")) ("RiseTime" status("on")) ("VoltageSwing" status("on"))) ("Reflection" ("BufferDelayFall" status("off")) ("BufferDelayRise" status("off")) ("EyeHeight" status("off")) ("EyeJitter" status("off")) ("EyeWidth" status("off")) ("FirstIncidentFall" status("off")) ("FirstIncidentRise" status("off")) ("Glitch" status("on")) ("GlitchFall" status("off")) ("GlitchRise" status("off")) ("Monotonic" status("on")) ("MonotonicFall" status("off")) ("MonotonicRise" status("off")) ("NoiseMargin" status("on")) ("NoiseMarginHigh" status("off")) ("NoiseMarginLow" status("off")) ("OvershootHigh" status("on")) ("OvershootLow" status("on")) ("PropDelay" status("on")) ("SettleDelay" status("on")) ("SettleDelayFall" status("off")) ("SettleDelayRise" status("off")) ("SwitchDelay" status("on")) ("SwitchDelayFall" status("off")) ("SwitchDelayRise" status("off"))) ("Crosstalk" ("Crosstalk" status("on"))) ("Custom")) (VectorSets) (Props (XnetName "M_A_CLK_DP<0>") (allDrivers "active") (customSimType "Reflection") (ftsMode ("Typ")) (rcvrSelect "all") (tlineDelayMode "time") (userRevision "1.0")))) (Subckts) (CrossSections ("CRESCENT_CITY_083_20140728_C" (Props (SXDesignName "CRESCENT_CITY_083_20140728_C")) (Layers ("" (layerType "SURFACE") (material "AIR") (thickness "0 mil") (dielectricConstant "1.000000") (lossTangent "0") (etchFactor "0.000000") (elecCondVal "0 mho/cm") (thermCondVal "0 w/cm-degC")) ("" (layerType "DIELECTRIC") (material "CONFORMAL_COAT") (thickness "0.5 mil") (dielectricConstant "3.800000") (lossTangent "0.035") (etchFactor "0.000000") (elecCondVal "0 mho/cm") (thermCondVal "0.012 w/cm-degC")) ("TOP" (layerType "CONDUCTOR") (material "COPPER") (thickness "  1.800000 mil") (width "4.00 MIL") (dielectricConstant "4.500000") (lossTangent "0") (etchFactor "70.000000") (elecCondVal "595900.000000 mho/cm") (thermCondVal "0 w/cm-degC") (signalDieConstant "3.800000") (signalLossTangent "0.035")) ("" (layerType "DIELECTRIC") (material "FR-4") (thickness "  2.700000 mil") (dielectricConstant "4.000000") (lossTangent "0.035") (etchFactor "0.000000") (elecCondVal "0 mho/cm") (thermCondVal "0.012 w/cm-degC")) ("L2_GND1" (layerType "PLANE") (material "COPPER") (isShield t) (thickness "  1.200000 mil") (dielectricConstant "4.500000") (lossTangent "0.035") (etchFactor "90.000000") (elecCondVal "595900.000000 mho/cm") (thermCondVal "0.012 w/cm-degC")) ("" (layerType "DIELECTRIC") (material "FR-4") (thickness "  9.900000 mil") (dielectricConstant "4.100000") (lossTangent "0.035") (etchFactor "0.000000") (elecCondVal "0 mho/cm") (thermCondVal "0.012 w/cm-degC")) ("L3_SIG1" (layerType "CONDUCTOR") (material "COPPER") (thickness "  1.200000 mil") (width "4.00 MIL") (dielectricConstant "4.500000") (lossTangent "0.035") (etchFactor "90.000000") (elecCondVal "595900.000000 mho/cm") (thermCondVal "0.012 w/cm-degC") (signalDieConstant "4.100000") (signalLossTangent "0.035")) ("" (layerType "DIELECTRIC") (material "FR-4") (thickness "  3.300000 mil") (dielectricConstant "4.500000") (lossTangent "0.035") (etchFactor "0.000000") (elecCondVal "0 mho/cm") (thermCondVal "0 w/cm-degC")) ("L4_GND2" (layerType "PLANE") (material "COPPER") (isShield t) (thickness "  1.200000 mil") (dielectricConstant "4.500000") (lossTangent "0.035") (etchFactor "90.000000") (elecCondVal "595900.000000 mho/cm") (thermCondVal "0 w/cm-degC")) ("" (layerType "DIELECTRIC") (material "FR-4") (thickness "  3.300000 mil") (dielectricConstant "4.000000") (lossTangent "0.035") (etchFactor "0.000000") (elecCondVal "0 mho/cm") (thermCondVal "0.012 w/cm-degC")) ("L5_SIG2" (layerType "CONDUCTOR") (material "COPPER") (thickness "  1.200000 mil") (width "4.00 MIL") (dielectricConstant "4.500000") (lossTangent "0.035") (etchFactor "90.000000") (elecCondVal "595900.000000 mho/cm") (thermCondVal "0.012 w/cm-degC") (signalDieConstant "4.000000") (signalLossTangent "0.035")) ("" (layerType "DIELECTRIC") (material "FR-4") (thickness "  9.900000 mil") (dielectricConstant "4.500000") (lossTangent "0.035") (etchFactor "0.000000") (elecCondVal "0 mho/cm") (thermCondVal "0 w/cm-degC")) ("L6_GND3" (layerType "PLANE") (material "COPPER") (isShield t) (thickness "  1.200000 mil") (dielectricConstant "4.500000") (lossTangent "0.035") (etchFactor "90.000000") (elecCondVal "595900.000000 mho/cm") (thermCondVal "0 w/cm-degC")) ("" (layerType "DIELECTRIC") (material "FR-4") (thickness "  3.300000 mil") (dielectricConstant "4.100000") (lossTangent "0.035") (etchFactor "0.000000") (elecCondVal "0 mho/cm") (thermCondVal "0.012 w/cm-degC")) ("L7_PWR1-SIG" (layerType "PLANE") (material "COPPER") (isShield t) (thickness "  1.200000 mil") (dielectricConstant "4.500000") (lossTangent "0.035") (etchFactor "90.000000") (elecCondVal "595900.000000 mho/cm") (thermCondVal "0.012 w/cm-degC")) ("" (layerType "DIELECTRIC") (material "FR-4") (thickness "  9.900000 mil") (dielectricConstant "4.000000") (lossTangent "0.035") (etchFactor "0.000000") (elecCondVal "0 mho/cm") (thermCondVal "0.012 w/cm-degC")) ("L8_PWR2-SIG" (layerType "PLANE") (material "COPPER") (isShield t) (thickness "  1.200000 mil") (dielectricConstant "4.500000") (lossTangent "0.035") (etchFactor "90.000000") (elecCondVal "595900.000000 mho/cm") (thermCondVal "0.012 w/cm-degC")) ("" (layerType "DIELECTRIC") (material "FR-4") (thickness "  3.300000 mil") (dielectricConstant "4.500000") (lossTangent "0.035") (etchFactor "0.000000") (elecCondVal "0 mho/cm") (thermCondVal "0 w/cm-degC")) ("L9_GND4" (layerType "PLANE") (material "COPPER") (isShield t) (thickness "  1.200000 mil") (dielectricConstant "4.500000") (lossTangent "0.035") (etchFactor "90.000000") (elecCondVal "595900.000000 mho/cm") (thermCondVal "0 w/cm-degC")) ("" (layerType "DIELECTRIC") (material "FR-4") (thickness "  9.900000 mil") (dielectricConstant "4.100000") (lossTangent "0.035") (etchFactor "0.000000") (elecCondVal "0 mho/cm") (thermCondVal "0.012 w/cm-degC")) ("L10_SIG3" (layerType "CONDUCTOR") (material "COPPER") (thickness "  1.200000 mil") (width "4.00 MIL") (dielectricConstant "4.500000") (lossTangent "0.035") (etchFactor "90.000000") (elecCondVal "595900.000000 mho/cm") (thermCondVal "0.012 w/cm-degC") (signalDieConstant "4.100000") (signalLossTangent "0.035")) ("" (layerType "DIELECTRIC") (material "FR-4") (thickness "  3.300000 mil") (dielectricConstant "4.500000") (lossTangent "0.035") (etchFactor "0.000000") (elecCondVal "0 mho/cm") (thermCondVal "0 w/cm-degC")) ("L11_GND5" (layerType "PLANE") (material "COPPER") (isShield t) (thickness "  1.200000 mil") (dielectricConstant "4.500000") (lossTangent "0.035") (etchFactor "90.000000") (elecCondVal "595900.000000 mho/cm") (thermCondVal "0 w/cm-degC")) ("" (layerType "DIELECTRIC") (material "FR-4") (thickness "  9.900000 mil") (dielectricConstant "4.500000") (lossTangent "0.035") (etchFactor "0.000000") (elecCondVal "0 mho/cm") (thermCondVal "0.012 w/cm-degC")) ("L12_SIG4" (layerType "CONDUCTOR") (material "COPPER") (thickness "  1.200000 mil") (width "4.00 MIL") (dielectricConstant "4.500000") (lossTangent "0.035") (etchFactor "90.000000") (elecCondVal "595900.000000 mho/cm") (thermCondVal "0.012 w/cm-degC") (signalDieConstant "4.500000") (signalLossTangent "0.035")) ("" (layerType "DIELECTRIC") (material "FR-4") (thickness "  3.300000 mil") (dielectricConstant "4.500000") (lossTangent "0.035") (etchFactor "0.000000") (elecCondVal "0 mho/cm") (thermCondVal "0 w/cm-degC")) ("L13_GND6" (layerType "PLANE") (material "COPPER") (isShield t) (thickness "  1.200000 mil") (dielectricConstant "4.500000") (lossTangent "0.035") (etchFactor "90.000000") (elecCondVal "595900.000000 mho/cm") (thermCondVal "0.012 w/cm-degC")) ("" (layerType "DIELECTRIC") (material "FR-4") (thickness "  2.700000 mil") (dielectricConstant "4.500000") (lossTangent "0.035") (etchFactor "0.000000") (elecCondVal "0 mho/cm") (thermCondVal "0.012 w/cm-degC")) ("BOTTOM" (layerType "CONDUCTOR") (material "COPPER") (thickness "  1.800000 mil") (width "4.00 MIL") (dielectricConstant "4.500000") (lossTangent "0") (etchFactor "70.000000") (elecCondVal "595900.000000 mho/cm") (thermCondVal "0 w/cm-degC") (signalDieConstant "3.800000") (signalLossTangent "0.035")) ("" (layerType "DIELECTRIC") (material "CONFORMAL_COAT") (thickness "0.5 mil") (dielectricConstant "3.800000") (lossTangent "0.035") (etchFactor "0.000000") (elecCondVal "0 mho/cm") (thermCondVal "0.012 w/cm-degC")) ("" (layerType "SURFACE") (material "AIR") (thickness "0 mil") (dielectricConstant "1.000000") (lossTangent "0") (etchFactor "0.000000") (elecCondVal "0 mho/cm") (thermCondVal "0 w/cm-degC"))))) (Props (DesUnits "mils 2") (LayerStack ("DIELECTRIC" "DIELECTRIC" "BOTTOM" "DIELECTRIC" "L13_GND6" "DIELECTRIC" "L12_SIG4" "DIELECTRIC" "L11_GND5" "DIELECTRIC" "L10_SIG3" "DIELECTRIC" "L9_GND4" "DIELECTRIC" "L8_PWR2-SIG" "DIELECTRIC" "L7_PWR1-SIG" "DIELECTRIC" "L6_GND3" "DIELECTRIC" "L5_SIG2" "DIELECTRIC" "L4_GND2" "DIELECTRIC" "L3_SIG1" "DIELECTRIC" "L2_GND1" "DIELECTRIC" "TOP" "DIELECTRIC" "DIELECTRIC")) (Revision "16.600")) (Params (ESpiceDevice nil) (Cable (length("1 m"))) (Via ((model "Unknown") (viaOutputFormat "Unknown") (viaPadstack nil) (viaTopLayer nil) (viaBottomLayer nil) (viaIsPower nil) (viaIsGround nil))) (Trace ((d1Thickness "10 mil") (d1Constant "4.5") (d1LossTangent "0.035") (d2Thickness "10 mil") (d2Constant "4.5") (d2LossTangent "0.035") (d3Thickness "0.0") (d3Constant "1.0") (d3LossTangent "0") length("1000 mil") (spacing "5 mil") (spacing2 "5 mil") (spacing3 "5 mil") (spacing4 "5 mil") (spacing5 "5 mil") (traceConductivity "595900 mho/cm") (traceGeometry "microstrip") (traceLayerName "") (traceThickness "0.72 mil") (traceType "single") (traceWidth "5.0 mil") (traceWidth2 "5.0 mil") (traceWidth3 "5.0 mil") (traceWidth4 "5.0 mil") (traceWidth5 "5.0 mil") (traceWidth6 "5.0 mil") (offset "0 mil") (traceCount "1") (impedance nil))) (IbisOutput_OpenPullUp ((temperature "27") (bufferModel "CDSDefaultOutput_2p5v") (stimuli nil) (offsets nil) (state "tristate") (cycle "1") (termMap nil) (setup "2.0e-09") (hold "1.0e-09") (rise nil) (fall nil) (macroType nil) (voltage nil) (spice nil) (LEFDEFPinName nil) (LEFDEFPinType nil) (mappingTag nil))) (IbisInput ((temperature "27") (bufferModel "CDSDefaultInput_2p5v") (cycle "1") (LEFDEFPinName nil) (LEFDEFPinType nil) (mappingTag nil))) (IbisIO_OpenPullUp ((temperature "27") (bufferModel "CDSDefaultIO_2p5v") (stimuli nil) (offsets nil) (state "tristate") (cycle "1") (termMap nil) (setup "2.0e-09") (hold "1.0e-09") (rise nil) (fall nil) (macroType nil) (voltage nil) (spice nil) (LEFDEFPinName nil) (LEFDEFPinType nil) (mappingTag nil))) (clocked ((clockRise "1e-09") (clockFall "1e-09") (clockFreq "100e6") (clockInitState "0") (clockDutyCycle "0.5") (clockJitter "0"))) (periodic ((periodicFreq "100e6") (periodicPattern "10") (periodicJitter "0"))) (IbisIO_OpenPullDown ((temperature "27") (bufferModel "CDSDefaultIO_2p5v") (stimuli nil) (offsets nil) (state "tristate") (cycle "1") (termMap nil) (setup "2.0e-09") (hold "1.0e-09") (rise nil) (fall nil) (macroType nil) (voltage nil) (spice nil) (LEFDEFPinName nil) (LEFDEFPinType nil) (mappingTag nil))) (RLGC (length("1000 mil"))) (DiffIO ((temperature "27") (bufferModelNonInverting "CDSDefaultIO_2p5v") (bufferModelInverting "CDSDefaultIO_2p5v") (stimuli nil) (offsets nil) (state "tristate") (cycle "1") (termMap nil) (setup "0.9e-09") (hold "0.4e-09") (rise nil) (fall nil) (threshInputHighMin "1.7 V") (threshInputHighTyp "1.7  V") (threshInputHighMax "1.7  V") (threshInputLowMin "0.7  V") (threshInputLowTyp "0.7  V") (threshInputLowMax "0.7 ") (threshOutputHighMin "2.365  V") (threshOutputHighTyp "2.5  V") (threshOutputHighMax "2.625  V") (threshOutputLowMin "1.275  V") (threshOutputLowTyp "1.7  V") (threshOutputLowMax "1.985  V") (mappingTagNonInverting nil) (mappingTagInverting nil) (spice nil))) (IbisOutput ((temperature "27") (bufferModel "CDSDefaultOutput_2p5v") (stimuli nil) (offsets nil) (state "tristate") (cycle "1") (termMap nil) (setup "2.0e-09") (hold "1.0e-09") (rise nil) (fall nil) (macroType nil) (voltage nil) (spice nil) (LEFDEFPinName nil) (LEFDEFPinType nil) (mappingTag nil))) (Source ((voltage "5 V"))) (Inductor ((inductance "5 nH") (orientation "0"))) (DiffIOPkg ((temperature "27") (bufferModelNonInverting "CDSDefaultIO_2p5v") (bufferModelInverting "CDSDefaultIO_2p5v") (stimuli nil) (offsets nil) (state "tristate") (cycle "1") (termMap nil) (setup "0.9e-09") (hold "0.4e-09") (rise nil) (fall nil) (threshInputHighMin "1.7 V") (threshInputHighTyp "1.7  V") (threshInputHighMax "1.7  V") (threshInputLowMin "0.7  V") (threshInputLowTyp "0.7  V") (threshInputLowMax "0.7 ") (threshOutputHighMin "2.365  V") (threshOutputHighTyp "2.5  V") (threshOutputHighMax "2.625  V") (threshOutputLowMin "1.275  V") (threshOutputLowTyp "1.7  V") (threshOutputLowMax "1.985  V") (mappingTagNonInverting nil) (mappingTagInverting nil) (spice nil))) (IbisIO ((temperature "27") (bufferModel "CDSDefaultIO_2p5v") (stimuli nil) (offsets nil) (state "tristate") (cycle "1") (termMap nil) (setup "2.0e-09") (hold "1.0e-09") (rise nil) (fall nil) (macroType nil) (voltage nil) (spice nil) (LEFDEFPinName nil) (LEFDEFPinType nil) (mappingTag nil))) (SeriesTerm ((resistance "22 ohm") (maxDelay "0.1 ns"))) (CPW ((d1Thickness "10 mil") (d1Constant "4.5") (d1LossTangent "0.035") (d2Thickness "0.72 mil") (d2Constant "1") (d2LossTangent "0") (d3Thickness "0.0") (d3Constant "1") (d3LossTangent "0") length("1000 mil") (spacing "5 mil") (spacing2 "5 mil") (spacing3 "5 mil") (spacing4 "5 mil") (spacing5 "5 mil") (traceConductivity "595900 mho/cm") (traceGeometry "cpwms") (traceLayerName "") (traceThickness "0.72 mil") (traceType "single") (traceWidth "5.0 mil") (traceWidth2 "5.0 mil") (traceWidth3 "5.0 mil") (traceWidth4 "5.0 mil") (traceWidth5 "5.0 mil") (traceWidth6 "5.0 mil") (offset "0 mil") (traceCount "1") (impedance nil))) (CPWMS ((d1Thickness "10 mil") (d1Constant "4.5") (d1LossTangent "0.035") (d2Thickness "0.72 mil") (d2Constant "4.5") (d2LossTangent "0.035") (d3Thickness "0.0") (d3Constant "1") (d3LossTangent "0") length("1000 mil") (spacing "5 mil") (spacing2 "5 mil") (spacing3 "5 mil") (spacing4 "5 mil") (spacing5 "5 mil") (traceConductivity "595900 mho/cm") (traceGeometry "cpwms") (traceLayerName "") (traceThickness "0.72 mil") (traceType "single") (traceWidth "5.0 mil") (traceWidth2 "5.0 mil") (traceWidth3 "5.0 mil") (traceWidth4 "5.0 mil") (traceWidth5 "5.0 mil") (traceWidth6 "5.0 mil") (offset "0 mil") (traceCount "1") (impedance nil))) (TLine ((diffImpedance "100ohm") (diffVelocity "1.4142e+08M/s") (impedance "60ohm") length("2800 mil") (propDelay "0.5 ns") (velocity "5600 mil/ns") (traceCount "1") (traceGeometry "Microstrip") (impedanceMin nil) (impedanceMax nil) (lengthMin nil) (lengthMax nil) (propDelayMin nil) (propDelayMax nil) (impedanceSweepCount nil) (propDelaySweepCount nil) (velocitySweepCount nil) (lengthSweepCount nil) (matchSetName nil))) (sync ((syncFreq "100e6") (syncInitState "1") (syncPattern "10") (syncEdgeSwitch "rise"))) (Connector nil) (Diode ((cutoffVoltage "0.7 V"))) (CurrentProbe nil) (CPWSL ((d1Thickness "10 mil") (d1Constant "4.5") (d1LossTangent "0.035") (d2Thickness "0.72 mil") (d2Constant "4.5") (d2LossTangent "0.035") (d3Thickness "10 mil") (d3Constant "4.5") (d3LossTangent "0.035") length("1000 mil") (spacing "5 mil") (spacing2 "5 mil") (spacing3 "5 mil") (spacing4 "5 mil") (spacing5 "5 mil") (traceConductivity "595900 mho/cm") (traceGeometry "cpwms") (traceLayerName "") (traceThickness "0.72 mil") (traceType "single") (traceWidth "5.0 mil") (traceWidth2 "5.0 mil") (traceWidth3 "5.0 mil") (traceWidth4 "5.0 mil") (traceWidth5 "5.0 mil") (traceWidth6 "5.0 mil") (offset "0 mil") (traceCount "1") (impedance nil))) (async ((asyncTimePoints "") (asyncInitState "1"))) (Capacitor ((capacitance "10 pF") (orientation "0"))) (DiffOutputPkg ((temperature "27") (bufferModelNonInverting "CDSDefaultOutput_2p5v") (bufferModelInverting "CDSDefaultOutput_2p5v") (stimuli nil) (offsets nil) (state "tristate") (cycle "1") (termMap nil) (setup "0.9e-09") (hold "0.4e-09") (rise nil) (fall nil) (threshOutputHighMin "2.375  V") (threshOutputHighTyp "2.5  V") (threshOutputHighMax "2.625  V") (threshOutputLowMin "1.275  V") (threshOutputLowTyp "1.7  V") (threshOutputLowMax "1.985  V") (mappingTagNonInverting nil) (mappingTagInverting nil) (spice nil))) (DiffOutput ((temperature "27") (bufferModelNonInverting "CDSDefaultOutput_2p5v") (bufferModelInverting "CDSDefaultOutput_2p5v") (stimuli nil) (offsets nil) (state "tristate") (cycle "1") (termMap nil) (setup "0.9e-09") (hold "0.4e-09") (rise nil) (fall nil) (threshOutputHighMin "2.375  V") (threshOutputHighTyp "2.5  V") (threshOutputHighMax "2.625  V") (threshOutputLowMin "1.275  V") (threshOutputLowTyp "1.7  V") (threshOutputLowMax "1.985  V") (mappingTagNonInverting nil) (mappingTagInverting nil) (spice nil))) (HiClampTerm ((cutoffVoltage "0.7 V") (voltage "5 V") (maxDelay "0.1 ns"))) (IbisInputPkg ((temperature "27") (bufferModel "CDSDefaultInput_2p5v") (cycle "1") (LEFDEFPinName nil) (LEFDEFPinType nil) (mappingTag nil))) (Resistor ((resistance "50 ohm") (orientation "0"))) (DiffInput ((temperature "27") (bufferModelNonInverting "CDSDefaultInput_2p5v") (bufferModelInverting "CDSDefaultInput_2p5v") (threshInputHighMin "1.7 V") (threshInputHighTyp "1.7  V") (threshInputHighMax "1.7  V") (threshInputLowMin "0.7  V") (threshInputLowTyp "0.7  V") (threshInputLowMax "0.7  V") (mappingTagNonInverting nil) (mappingTagInverting nil) (cycle "1"))) (DualClampTerm ((cutoffVoltageUp "0.7 V") (cutoffVoltageDown "0.7 V") (voltageUp "5 V") (voltageDown "0 V") (maxDelay "0.1 ns"))) (IbisOutputPkg ((temperature "27") (bufferModel "CDSDefaultOutput_2p5v") (stimuli nil) (offsets nil) (state "tristate") (cycle "1") (termMap nil) (setup "2.0e-09") (hold "1.0e-09") (rise nil) (fall nil) (macroType nil) (voltage nil) (spice nil) (LEFDEFPinName nil) (LEFDEFPinType nil) (mappingTag nil))) (IbisIOPkg ((temperature "27") (bufferModel "CDSDefaultIO_2p5v") (stimuli nil) (offsets nil) (state "tristate") (cycle "1") (termMap nil) (setup "2.0e-09") (hold "1.0e-09") (rise nil) (fall nil) (macroType nil) (voltage nil) (spice nil) (LEFDEFPinName nil) (LEFDEFPinType nil) (mappingTag nil))) (TheveninTerm ((resistanceUp "180 ohm") (resistanceDown "270 ohm") (voltageUp "5 V") (voltageDown "0 V") (maxDelay "0.1 ns"))) (IbisIOMacro ((temperature "27") (bufferModel "CDSDefaultIO_2p5v") (stimuli nil) (offsets nil) (state "tristate") (cycle "1") (termMap nil) (setup "2.0e-09") (hold "1.0e-09") (rise nil) (fall nil) (macroType nil) (voltage nil) (spice nil) (LEFDEFPinName nil) (LEFDEFPinType nil) (mappingTag nil))) (RCTerm ((resistance "50 ohm") (capacitance "20 pF") (voltage "5 V") (maxDelay "0.1 ns"))) (LowClampTerm ((cutoffVoltage "0.7 V") (voltage "0 V") (maxDelay "0.1 ns"))) (DiffInputPkg ((temperature "27") (bufferModelNonInverting "CDSDefaultInput_2p5v") (bufferModelInverting "CDSDefaultInput_2p5v") (threshInputHighMin "1.7 V") (threshInputHighTyp "1.7  V") (threshInputHighMax "1.7  V") (threshInputLowMin "0.7  V") (threshInputLowTyp "0.7  V") (threshInputLowMax "0.7  V") (mappingTagNonInverting nil) (mappingTagInverting nil) (cycle "1"))) (ShuntTerm ((resistance "50 ohm") (voltage "5 V") (maxDelay "0.1 ns"))) (idlCircuit ((allDrivers "active") (ftsMode '("Typ")) (rcvrSelect "all") (simMode "Reflection") (tlineDelayMode "time") (userRevision "1.0") (autoSolve "On")))))
				)
				( objectStatus "DDR_CLK0" )
			)
			( electricalCSet "@crescent_city_bb_fab1_lib.crescent_city_bb_fab1(sch_1):\DDR_CTRL_DLL14-19\"
				( groupRef "DDR_CTRL_DLL14-19:MG_DDR_CTRL" )
				( groupRef "DDR_CTRL_DLL14-19:MG_DDR_FAR_DIMM-CLK0" )
				( pinPairRef "DDR_CTRL_DLL14-19:U5D1.G52:J4G1.84" )
				( attribute "TOPOLOGY_TEMPLATE_REVISION" "1.0"
					( Origin gBackEnd )
				)
				( topologyData 22228
(SKIDL (Circuits ("MAIN" (Parts ("CRESCENT_CITY_083_20140725_A.@@J1.84" IbisIOPkg (xy (5528 4240)) (refDes "J4G1") (model "Unknown") (Props (_SXDesignName "CRESCENT_CITY_083_20140725_A") (brdx "10643.7 MIL") (brdy "607.23 MIL") (bufferModel "CDSDefaultIO_2p5v") (cycle "1") (hold "1.0e-09") (mappingTag "") (offsets ("4" "0") ("5" "0")) (setup "2.0e-09") (state "tristate") (stimuli ("4" "local3") ("5" "local4")) (temperature "27") (termMap ("4" "Data") ("5" "Enable"))) (Terms ("CRESCENT_CITY_083_20140725_A.X1064370Y60723L2LRATS" "84"))) ("CRESCENT_CITY_083_20140725_A.@@U36.G52" IbisIOPkg (xy (5502 4240)) (refDes "U5D1") (model "Unknown") (Props (_SXDesignName "CRESCENT_CITY_083_20140725_A") (brdx "10312.55 MIL") (brdy "2071.59 MIL") (bufferModel "CDSDefaultIO_2p5v") (cycle "1") (hold "1.0e-09") (mappingTag "") (offsets ("4" "0") ("5" "0")) (setup "2.0e-09") (state "tristate") (stimuli ("4" "local5") ("5" "local6")) (temperature "27") (termMap ("4" "Data") ("5" "Enable"))) (Terms ("CRESCENT_CITY_083_20140725_A.X1031255Y207159L2LRATS" "G52"))) ("CRESCENT_CITY_083_20140725_A.T@@RATS@@J1.84@@U36.G52" TLine (xy (5513 4235)) (mirror x) (refDes "TL1") (Props (_SXDesignName "CRESCENT_CITY_083_20140725_A") (impedance "47.779 ohm") length("1795.51 MIL") (propDelay "0.32249 ns") (traceCount "1") (traceGeometry "Microstrip") (velocity "5567.64 mil/ns")) (Terms ("CRESCENT_CITY_083_20140725_A.X1064370Y60723L2LRATS" "1") ("CRESCENT_CITY_083_20140725_A.X1031255Y207159L2LRATS" "2")))) (Nodes ("CRESCENT_CITY_083_20140725_A.X1031255Y207159L2LRATS" (terms "CRESCENT_CITY_083_20140725_A.T@@RATS@@J1.84@@U36.G52.2" "CRESCENT_CITY_083_20140725_A.@@U36.G52.1")) ("CRESCENT_CITY_083_20140725_A.X1064370Y60723L2LRATS" (terms "CRESCENT_CITY_083_20140725_A.T@@RATS@@J1.84@@U36.G52.1" "CRESCENT_CITY_083_20140725_A.@@J1.84.1"))) (Ports) (Stimuli ("local6" (scope local) (stimType periodic) (Props (periodicFreq "5e+007") (periodicJitter "0") (periodicPattern "1"))) ("local3" (scope local) (stimType periodic) (Props (periodicFreq "5e+007") (periodicJitter "0") (periodicPattern "1"))) ("local4" (scope local) (stimType periodic) (Props (periodicFreq "5e+007") (periodicJitter "0") (periodicPattern "1"))) ("local5" (scope local) (stimType periodic) (Props (periodicFreq "5e+007") (periodicJitter "0") (periodicPattern "1")))) (Notes) (Constraints ("RELATIVE_PROPAGATION_DELAY" ("MG_DDR_CTRL" "CRESCENT_CITY_083_20140725_A U36.G52" "CRESCENT_CITY_083_20140725_A J1.84" "NET GROUP" "LENGTH" "0.000635" "LENGTH" "0") ("MG_DDR_FAR_DIMM-CLK0" "CRESCENT_CITY_083_20140725_A U36.G52" "CRESCENT_CITY_083_20140725_A J1.84" "CLASS" "LENGTH" "0.00762" "LENGTH" "0"))) (MeasurementSets ("EMI" ("EMIStatus" status("on")) ("PeakEmission" status("on")) ("PeakFrequency" status("on")) ("PulseFreq" status("on")) ("RiseTime" status("on")) ("VoltageSwing" status("on"))) ("Reflection" ("BufferDelayFall" status("off")) ("BufferDelayRise" status("off")) ("EyeHeight" status("off")) ("EyeJitter" status("off")) ("EyeWidth" status("off")) ("FirstIncidentFall" status("off")) ("FirstIncidentRise" status("off")) ("Glitch" status("on")) ("GlitchFall" status("off")) ("GlitchRise" status("off")) ("Monotonic" status("on")) ("MonotonicFall" status("off")) ("MonotonicRise" status("off")) ("NoiseMargin" status("on")) ("NoiseMarginHigh" status("off")) ("NoiseMarginLow" status("off")) ("OvershootHigh" status("on")) ("OvershootLow" status("on")) ("PropDelay" status("on")) ("SettleDelay" status("on")) ("SettleDelayFall" status("off")) ("SettleDelayRise" status("off")) ("SwitchDelay" status("on")) ("SwitchDelayFall" status("off")) ("SwitchDelayRise" status("off"))) ("Crosstalk" ("Crosstalk" status("on"))) ("Custom")) (VectorSets) (Props (XnetName "M_A_CS_N<0>") (allDrivers "active") (customSimType "Reflection") (ftsMode ("Typ")) (rcvrSelect "all") (tlineDelayMode "time") (userRevision "1.0")))) (Subckts) (CrossSections ("CRESCENT_CITY_083_20140725_A" (Props (SXDesignName "CRESCENT_CITY_083_20140725_A")) (Layers ("" (layerType "SURFACE") (material "AIR") (thickness "0 mil") (dielectricConstant "1.000000") (lossTangent "0") (etchFactor "0.000000") (elecCondVal "0 mho/cm") (thermCondVal "0 w/cm-degC")) ("" (layerType "DIELECTRIC") (material "CONFORMAL_COAT") (thickness "0.5 mil") (dielectricConstant "3.800000") (lossTangent "0.035") (etchFactor "0.000000") (elecCondVal "0 mho/cm") (thermCondVal "0.012 w/cm-degC")) ("TOP" (layerType "CONDUCTOR") (material "COPPER") (thickness "  1.800000 mil") (width "4.00 MIL") (dielectricConstant "4.500000") (lossTangent "0") (etchFactor "70.000000") (elecCondVal "595900.000000 mho/cm") (thermCondVal "0 w/cm-degC") (signalDieConstant "3.800000") (signalLossTangent "0.035")) ("" (layerType "DIELECTRIC") (material "FR-4") (thickness "  2.700000 mil") (dielectricConstant "4.000000") (lossTangent "0.035") (etchFactor "0.000000") (elecCondVal "0 mho/cm") (thermCondVal "0.012 w/cm-degC")) ("L2_GND1" (layerType "PLANE") (material "COPPER") (isShield t) (thickness "  1.200000 mil") (dielectricConstant "4.500000") (lossTangent "0.035") (etchFactor "90.000000") (elecCondVal "595900.000000 mho/cm") (thermCondVal "0.012 w/cm-degC")) ("" (layerType "DIELECTRIC") (material "FR-4") (thickness "  9.900000 mil") (dielectricConstant "4.100000") (lossTangent "0.035") (etchFactor "0.000000") (elecCondVal "0 mho/cm") (thermCondVal "0.012 w/cm-degC")) ("L3_SIG1" (layerType "CONDUCTOR") (material "COPPER") (thickness "  1.200000 mil") (width "4.00 MIL") (dielectricConstant "4.500000") (lossTangent "0.035") (etchFactor "90.000000") (elecCondVal "595900.000000 mho/cm") (thermCondVal "0.012 w/cm-degC") (signalDieConstant "4.100000") (signalLossTangent "0.035")) ("" (layerType "DIELECTRIC") (material "FR-4") (thickness "  3.300000 mil") (dielectricConstant "4.500000") (lossTangent "0.035") (etchFactor "0.000000") (elecCondVal "0 mho/cm") (thermCondVal "0 w/cm-degC")) ("L4_GND2" (layerType "PLANE") (material "COPPER") (isShield t) (thickness "  1.200000 mil") (dielectricConstant "4.500000") (lossTangent "0.035") (etchFactor "90.000000") (elecCondVal "595900.000000 mho/cm") (thermCondVal "0 w/cm-degC")) ("" (layerType "DIELECTRIC") (material "FR-4") (thickness "  3.300000 mil") (dielectricConstant "4.000000") (lossTangent "0.035") (etchFactor "0.000000") (elecCondVal "0 mho/cm") (thermCondVal "0.012 w/cm-degC")) ("L5_SIG2" (layerType "CONDUCTOR") (material "COPPER") (thickness "  1.200000 mil") (width "4.00 MIL") (dielectricConstant "4.500000") (lossTangent "0.035") (etchFactor "90.000000") (elecCondVal "595900.000000 mho/cm") (thermCondVal "0.012 w/cm-degC") (signalDieConstant "4.000000") (signalLossTangent "0.035")) ("" (layerType "DIELECTRIC") (material "FR-4") (thickness "  9.900000 mil") (dielectricConstant "4.500000") (lossTangent "0.035") (etchFactor "0.000000") (elecCondVal "0 mho/cm") (thermCondVal "0 w/cm-degC")) ("L6_GND3" (layerType "PLANE") (material "COPPER") (isShield t) (thickness "  1.200000 mil") (dielectricConstant "4.500000") (lossTangent "0.035") (etchFactor "90.000000") (elecCondVal "595900.000000 mho/cm") (thermCondVal "0 w/cm-degC")) ("" (layerType "DIELECTRIC") (material "FR-4") (thickness "  3.300000 mil") (dielectricConstant "4.100000") (lossTangent "0.035") (etchFactor "0.000000") (elecCondVal "0 mho/cm") (thermCondVal "0.012 w/cm-degC")) ("L7_PWR1-SIG" (layerType "PLANE") (material "COPPER") (isShield t) (thickness "  1.200000 mil") (dielectricConstant "4.500000") (lossTangent "0.035") (etchFactor "90.000000") (elecCondVal "595900.000000 mho/cm") (thermCondVal "0.012 w/cm-degC")) ("" (layerType "DIELECTRIC") (material "FR-4") (thickness "  9.900000 mil") (dielectricConstant "4.000000") (lossTangent "0.035") (etchFactor "0.000000") (elecCondVal "0 mho/cm") (thermCondVal "0.012 w/cm-degC")) ("L8_PWR2-SIG" (layerType "PLANE") (material "COPPER") (isShield t) (thickness "  1.200000 mil") (dielectricConstant "4.500000") (lossTangent "0.035") (etchFactor "90.000000") (elecCondVal "595900.000000 mho/cm") (thermCondVal "0.012 w/cm-degC")) ("" (layerType "DIELECTRIC") (material "FR-4") (thickness "  3.300000 mil") (dielectricConstant "4.500000") (lossTangent "0.035") (etchFactor "0.000000") (elecCondVal "0 mho/cm") (thermCondVal "0 w/cm-degC")) ("L9_GND4" (layerType "PLANE") (material "COPPER") (isShield t) (thickness "  1.200000 mil") (dielectricConstant "4.500000") (lossTangent "0.035") (etchFactor "90.000000") (elecCondVal "595900.000000 mho/cm") (thermCondVal "0 w/cm-degC")) ("" (layerType "DIELECTRIC") (material "FR-4") (thickness "  9.900000 mil") (dielectricConstant "4.100000") (lossTangent "0.035") (etchFactor "0.000000") (elecCondVal "0 mho/cm") (thermCondVal "0.012 w/cm-degC")) ("L10_SIG3" (layerType "CONDUCTOR") (material "COPPER") (thickness "  1.200000 mil") (width "4.00 MIL") (dielectricConstant "4.500000") (lossTangent "0.035") (etchFactor "90.000000") (elecCondVal "595900.000000 mho/cm") (thermCondVal "0.012 w/cm-degC") (signalDieConstant "4.100000") (signalLossTangent "0.035")) ("" (layerType "DIELECTRIC") (material "FR-4") (thickness "  3.300000 mil") (dielectricConstant "4.500000") (lossTangent "0.035") (etchFactor "0.000000") (elecCondVal "0 mho/cm") (thermCondVal "0 w/cm-degC")) ("L11_GND5" (layerType "PLANE") (material "COPPER") (isShield t) (thickness "  1.200000 mil") (dielectricConstant "4.500000") (lossTangent "0.035") (etchFactor "90.000000") (elecCondVal "595900.000000 mho/cm") (thermCondVal "0 w/cm-degC")) ("" (layerType "DIELECTRIC") (material "FR-4") (thickness "  9.900000 mil") (dielectricConstant "4.500000") (lossTangent "0.035") (etchFactor "0.000000") (elecCondVal "0 mho/cm") (thermCondVal "0.012 w/cm-degC")) ("L12_SIG4" (layerType "CONDUCTOR") (material "COPPER") (thickness "  1.200000 mil") (width "4.00 MIL") (dielectricConstant "4.500000") (lossTangent "0.035") (etchFactor "90.000000") (elecCondVal "595900.000000 mho/cm") (thermCondVal "0.012 w/cm-degC") (signalDieConstant "4.500000") (signalLossTangent "0.035")) ("" (layerType "DIELECTRIC") (material "FR-4") (thickness "  3.300000 mil") (dielectricConstant "4.500000") (lossTangent "0.035") (etchFactor "0.000000") (elecCondVal "0 mho/cm") (thermCondVal "0 w/cm-degC")) ("L13_GND6" (layerType "PLANE") (material "COPPER") (isShield t) (thickness "  1.200000 mil") (dielectricConstant "4.500000") (lossTangent "0.035") (etchFactor "90.000000") (elecCondVal "595900.000000 mho/cm") (thermCondVal "0.012 w/cm-degC")) ("" (layerType "DIELECTRIC") (material "FR-4") (thickness "  2.700000 mil") (dielectricConstant "4.500000") (lossTangent "0.035") (etchFactor "0.000000") (elecCondVal "0 mho/cm") (thermCondVal "0.012 w/cm-degC")) ("BOTTOM" (layerType "CONDUCTOR") (material "COPPER") (thickness "  1.800000 mil") (width "4.00 MIL") (dielectricConstant "4.500000") (lossTangent "0") (etchFactor "70.000000") (elecCondVal "595900.000000 mho/cm") (thermCondVal "0 w/cm-degC") (signalDieConstant "3.800000") (signalLossTangent "0.035")) ("" (layerType "DIELECTRIC") (material "CONFORMAL_COAT") (thickness "0.5 mil") (dielectricConstant "3.800000") (lossTangent "0.035") (etchFactor "0.000000") (elecCondVal "0 mho/cm") (thermCondVal "0.012 w/cm-degC")) ("" (layerType "SURFACE") (material "AIR") (thickness "0 mil") (dielectricConstant "1.000000") (lossTangent "0") (etchFactor "0.000000") (elecCondVal "0 mho/cm") (thermCondVal "0 w/cm-degC"))))) (Props (DesUnits "mils 2") (LayerStack ("DIELECTRIC" "DIELECTRIC" "BOTTOM" "DIELECTRIC" "L13_GND6" "DIELECTRIC" "L12_SIG4" "DIELECTRIC" "L11_GND5" "DIELECTRIC" "L10_SIG3" "DIELECTRIC" "L9_GND4" "DIELECTRIC" "L8_PWR2-SIG" "DIELECTRIC" "L7_PWR1-SIG" "DIELECTRIC" "L6_GND3" "DIELECTRIC" "L5_SIG2" "DIELECTRIC" "L4_GND2" "DIELECTRIC" "L3_SIG1" "DIELECTRIC" "L2_GND1" "DIELECTRIC" "TOP" "DIELECTRIC" "DIELECTRIC")) (Revision "16.600")) (Params (ESpiceDevice nil) (Cable (length("1 m"))) (Via ((model "Unknown") (viaOutputFormat "Unknown") (viaPadstack nil) (viaTopLayer nil) (viaBottomLayer nil) (viaIsPower nil) (viaIsGround nil))) (Trace ((d1Thickness "10 mil") (d1Constant "4.5") (d1LossTangent "0.035") (d2Thickness "10 mil") (d2Constant "4.5") (d2LossTangent "0.035") (d3Thickness "0.0") (d3Constant "1.0") (d3LossTangent "0") length("1000 mil") (spacing "5 mil") (spacing2 "5 mil") (spacing3 "5 mil") (spacing4 "5 mil") (spacing5 "5 mil") (traceConductivity "595900 mho/cm") (traceGeometry "microstrip") (traceLayerName "") (traceThickness "0.72 mil") (traceType "single") (traceWidth "5.0 mil") (traceWidth2 "5.0 mil") (traceWidth3 "5.0 mil") (traceWidth4 "5.0 mil") (traceWidth5 "5.0 mil") (traceWidth6 "5.0 mil") (offset "0 mil") (traceCount "1") (impedance nil))) (IbisOutput_OpenPullUp ((temperature "27") (bufferModel "CDSDefaultOutput_2p5v") (stimuli nil) (offsets nil) (state "tristate") (cycle "1") (termMap nil) (setup "2.0e-09") (hold "1.0e-09") (rise nil) (fall nil) (macroType nil) (voltage nil) (spice nil) (LEFDEFPinName nil) (LEFDEFPinType nil) (mappingTag nil))) (IbisInput ((temperature "27") (bufferModel "CDSDefaultInput_2p5v") (cycle "1") (LEFDEFPinName nil) (LEFDEFPinType nil) (mappingTag nil))) (IbisIO_OpenPullUp ((temperature "27") (bufferModel "CDSDefaultIO_2p5v") (stimuli nil) (offsets nil) (state "tristate") (cycle "1") (termMap nil) (setup "2.0e-09") (hold "1.0e-09") (rise nil) (fall nil) (macroType nil) (voltage nil) (spice nil) (LEFDEFPinName nil) (LEFDEFPinType nil) (mappingTag nil))) (clocked ((clockRise "1e-09") (clockFall "1e-09") (clockFreq "100e6") (clockInitState "0") (clockDutyCycle "0.5") (clockJitter "0"))) (periodic ((periodicFreq "100e6") (periodicPattern "10") (periodicJitter "0"))) (IbisIO_OpenPullDown ((temperature "27") (bufferModel "CDSDefaultIO_2p5v") (stimuli nil) (offsets nil) (state "tristate") (cycle "1") (termMap nil) (setup "2.0e-09") (hold "1.0e-09") (rise nil) (fall nil) (macroType nil) (voltage nil) (spice nil) (LEFDEFPinName nil) (LEFDEFPinType nil) (mappingTag nil))) (RLGC (length("1000 mil"))) (DiffIO ((temperature "27") (bufferModelNonInverting "CDSDefaultIO_2p5v") (bufferModelInverting "CDSDefaultIO_2p5v") (stimuli nil) (offsets nil) (state "tristate") (cycle "1") (termMap nil) (setup "0.9e-09") (hold "0.4e-09") (rise nil) (fall nil) (threshInputHighMin "1.7 V") (threshInputHighTyp "1.7  V") (threshInputHighMax "1.7  V") (threshInputLowMin "0.7  V") (threshInputLowTyp "0.7  V") (threshInputLowMax "0.7 ") (threshOutputHighMin "2.365  V") (threshOutputHighTyp "2.5  V") (threshOutputHighMax "2.625  V") (threshOutputLowMin "1.275  V") (threshOutputLowTyp "1.7  V") (threshOutputLowMax "1.985  V") (mappingTagNonInverting nil) (mappingTagInverting nil) (spice nil))) (IbisOutput ((temperature "27") (bufferModel "CDSDefaultOutput_2p5v") (stimuli nil) (offsets nil) (state "tristate") (cycle "1") (termMap nil) (setup "2.0e-09") (hold "1.0e-09") (rise nil) (fall nil) (macroType nil) (voltage nil) (spice nil) (LEFDEFPinName nil) (LEFDEFPinType nil) (mappingTag nil))) (Source ((voltage "5 V"))) (Inductor ((inductance "5 nH") (orientation "0"))) (DiffIOPkg ((temperature "27") (bufferModelNonInverting "CDSDefaultIO_2p5v") (bufferModelInverting "CDSDefaultIO_2p5v") (stimuli nil) (offsets nil) (state "tristate") (cycle "1") (termMap nil) (setup "0.9e-09") (hold "0.4e-09") (rise nil) (fall nil) (threshInputHighMin "1.7 V") (threshInputHighTyp "1.7  V") (threshInputHighMax "1.7  V") (threshInputLowMin "0.7  V") (threshInputLowTyp "0.7  V") (threshInputLowMax "0.7 ") (threshOutputHighMin "2.365  V") (threshOutputHighTyp "2.5  V") (threshOutputHighMax "2.625  V") (threshOutputLowMin "1.275  V") (threshOutputLowTyp "1.7  V") (threshOutputLowMax "1.985  V") (mappingTagNonInverting nil) (mappingTagInverting nil) (spice nil))) (IbisIO ((temperature "27") (bufferModel "CDSDefaultIO_2p5v") (stimuli nil) (offsets nil) (state "tristate") (cycle "1") (termMap nil) (setup "2.0e-09") (hold "1.0e-09") (rise nil) (fall nil) (macroType nil) (voltage nil) (spice nil) (LEFDEFPinName nil) (LEFDEFPinType nil) (mappingTag nil))) (SeriesTerm ((resistance "22 ohm") (maxDelay "0.1 ns"))) (CPW ((d1Thickness "10 mil") (d1Constant "4.5") (d1LossTangent "0.035") (d2Thickness "0.72 mil") (d2Constant "1") (d2LossTangent "0") (d3Thickness "0.0") (d3Constant "1") (d3LossTangent "0") length("1000 mil") (spacing "5 mil") (spacing2 "5 mil") (spacing3 "5 mil") (spacing4 "5 mil") (spacing5 "5 mil") (traceConductivity "595900 mho/cm") (traceGeometry "cpwms") (traceLayerName "") (traceThickness "0.72 mil") (traceType "single") (traceWidth "5.0 mil") (traceWidth2 "5.0 mil") (traceWidth3 "5.0 mil") (traceWidth4 "5.0 mil") (traceWidth5 "5.0 mil") (traceWidth6 "5.0 mil") (offset "0 mil") (traceCount "1") (impedance nil))) (CPWMS ((d1Thickness "10 mil") (d1Constant "4.5") (d1LossTangent "0.035") (d2Thickness "0.72 mil") (d2Constant "4.5") (d2LossTangent "0.035") (d3Thickness "0.0") (d3Constant "1") (d3LossTangent "0") length("1000 mil") (spacing "5 mil") (spacing2 "5 mil") (spacing3 "5 mil") (spacing4 "5 mil") (spacing5 "5 mil") (traceConductivity "595900 mho/cm") (traceGeometry "cpwms") (traceLayerName "") (traceThickness "0.72 mil") (traceType "single") (traceWidth "5.0 mil") (traceWidth2 "5.0 mil") (traceWidth3 "5.0 mil") (traceWidth4 "5.0 mil") (traceWidth5 "5.0 mil") (traceWidth6 "5.0 mil") (offset "0 mil") (traceCount "1") (impedance nil))) (TLine ((diffImpedance "100ohm") (diffVelocity "1.4142e+08M/s") (impedance "60ohm") length("2800 mil") (propDelay "0.5 ns") (velocity "5600 mil/ns") (traceCount "1") (traceGeometry "Microstrip") (impedanceMin nil) (impedanceMax nil) (lengthMin nil) (lengthMax nil) (propDelayMin nil) (propDelayMax nil) (impedanceSweepCount nil) (propDelaySweepCount nil) (velocitySweepCount nil) (lengthSweepCount nil) (matchSetName nil))) (sync ((syncFreq "100e6") (syncInitState "1") (syncPattern "10") (syncEdgeSwitch "rise"))) (Connector nil) (Diode ((cutoffVoltage "0.7 V"))) (CurrentProbe nil) (CPWSL ((d1Thickness "10 mil") (d1Constant "4.5") (d1LossTangent "0.035") (d2Thickness "0.72 mil") (d2Constant "4.5") (d2LossTangent "0.035") (d3Thickness "10 mil") (d3Constant "4.5") (d3LossTangent "0.035") length("1000 mil") (spacing "5 mil") (spacing2 "5 mil") (spacing3 "5 mil") (spacing4 "5 mil") (spacing5 "5 mil") (traceConductivity "595900 mho/cm") (traceGeometry "cpwms") (traceLayerName "") (traceThickness "0.72 mil") (traceType "single") (traceWidth "5.0 mil") (traceWidth2 "5.0 mil") (traceWidth3 "5.0 mil") (traceWidth4 "5.0 mil") (traceWidth5 "5.0 mil") (traceWidth6 "5.0 mil") (offset "0 mil") (traceCount "1") (impedance nil))) (async ((asyncTimePoints "") (asyncInitState "1"))) (Capacitor ((capacitance "10 pF") (orientation "0"))) (DiffOutputPkg ((temperature "27") (bufferModelNonInverting "CDSDefaultOutput_2p5v") (bufferModelInverting "CDSDefaultOutput_2p5v") (stimuli nil) (offsets nil) (state "tristate") (cycle "1") (termMap nil) (setup "0.9e-09") (hold "0.4e-09") (rise nil) (fall nil) (threshOutputHighMin "2.375  V") (threshOutputHighTyp "2.5  V") (threshOutputHighMax "2.625  V") (threshOutputLowMin "1.275  V") (threshOutputLowTyp "1.7  V") (threshOutputLowMax "1.985  V") (mappingTagNonInverting nil) (mappingTagInverting nil) (spice nil))) (DiffOutput ((temperature "27") (bufferModelNonInverting "CDSDefaultOutput_2p5v") (bufferModelInverting "CDSDefaultOutput_2p5v") (stimuli nil) (offsets nil) (state "tristate") (cycle "1") (termMap nil) (setup "0.9e-09") (hold "0.4e-09") (rise nil) (fall nil) (threshOutputHighMin "2.375  V") (threshOutputHighTyp "2.5  V") (threshOutputHighMax "2.625  V") (threshOutputLowMin "1.275  V") (threshOutputLowTyp "1.7  V") (threshOutputLowMax "1.985  V") (mappingTagNonInverting nil) (mappingTagInverting nil) (spice nil))) (HiClampTerm ((cutoffVoltage "0.7 V") (voltage "5 V") (maxDelay "0.1 ns"))) (IbisInputPkg ((temperature "27") (bufferModel "CDSDefaultInput_2p5v") (cycle "1") (LEFDEFPinName nil) (LEFDEFPinType nil) (mappingTag nil))) (Resistor ((resistance "50 ohm") (orientation "0"))) (DiffInput ((temperature "27") (bufferModelNonInverting "CDSDefaultInput_2p5v") (bufferModelInverting "CDSDefaultInput_2p5v") (threshInputHighMin "1.7 V") (threshInputHighTyp "1.7  V") (threshInputHighMax "1.7  V") (threshInputLowMin "0.7  V") (threshInputLowTyp "0.7  V") (threshInputLowMax "0.7  V") (mappingTagNonInverting nil) (mappingTagInverting nil) (cycle "1"))) (DualClampTerm ((cutoffVoltageUp "0.7 V") (cutoffVoltageDown "0.7 V") (voltageUp "5 V") (voltageDown "0 V") (maxDelay "0.1 ns"))) (IbisOutputPkg ((temperature "27") (bufferModel "CDSDefaultOutput_2p5v") (stimuli nil) (offsets nil) (state "tristate") (cycle "1") (termMap nil) (setup "2.0e-09") (hold "1.0e-09") (rise nil) (fall nil) (macroType nil) (voltage nil) (spice nil) (LEFDEFPinName nil) (LEFDEFPinType nil) (mappingTag nil))) (IbisIOPkg ((temperature "27") (bufferModel "CDSDefaultIO_2p5v") (stimuli nil) (offsets nil) (state "tristate") (cycle "1") (termMap nil) (setup "2.0e-09") (hold "1.0e-09") (rise nil) (fall nil) (macroType nil) (voltage nil) (spice nil) (LEFDEFPinName nil) (LEFDEFPinType nil) (mappingTag nil))) (TheveninTerm ((resistanceUp "180 ohm") (resistanceDown "270 ohm") (voltageUp "5 V") (voltageDown "0 V") (maxDelay "0.1 ns"))) (IbisIOMacro ((temperature "27") (bufferModel "CDSDefaultIO_2p5v") (stimuli nil) (offsets nil) (state "tristate") (cycle "1") (termMap nil) (setup "2.0e-09") (hold "1.0e-09") (rise nil) (fall nil) (macroType nil) (voltage nil) (spice nil) (LEFDEFPinName nil) (LEFDEFPinType nil) (mappingTag nil))) (RCTerm ((resistance "50 ohm") (capacitance "20 pF") (voltage "5 V") (maxDelay "0.1 ns"))) (LowClampTerm ((cutoffVoltage "0.7 V") (voltage "0 V") (maxDelay "0.1 ns"))) (DiffInputPkg ((temperature "27") (bufferModelNonInverting "CDSDefaultInput_2p5v") (bufferModelInverting "CDSDefaultInput_2p5v") (threshInputHighMin "1.7 V") (threshInputHighTyp "1.7  V") (threshInputHighMax "1.7  V") (threshInputLowMin "0.7  V") (threshInputLowTyp "0.7  V") (threshInputLowMax "0.7  V") (mappingTagNonInverting nil) (mappingTagInverting nil) (cycle "1"))) (ShuntTerm ((resistance "50 ohm") (voltage "5 V") (maxDelay "0.1 ns"))) (idlCircuit ((allDrivers "active") (ftsMode '("Typ")) (rcvrSelect "all") (simMode "Reflection") (tlineDelayMode "time") (userRevision "1.0") (autoSolve "On")))))
				)
				( objectStatus "DDR_CTRL_DLL14-19" )
			)
			( electricalCSet "@crescent_city_bb_fab1_lib.crescent_city_bb_fab1(sch_1):\DDR_F_CMD_DLL1-13\"
				( groupRef "DDR_F_CMD_DLL1-13:MG_DDR_NEAR_DIMM-CLK1" )
				( groupRef "DDR_F_CMD_DLL1-13:MG_DDR_FAR_DIMM_CMD" )
				( groupRef "DDR_F_CMD_DLL1-13:MG_DDR_FAR_DIMM-CLK0" )
				( groupRef "DDR_F_CMD_DLL1-13:MG_DDR_CMD_NEAR_DIMM" )
				( pinPairRef "DDR_F_CMD_DLL1-13:U5D1.F51:J6L1.228" )
				( pinPairRef "DDR_F_CMD_DLL1-13:U5D1.F51:J4A1.228" )
				( attribute "TOPOLOGY_TEMPLATE_REVISION" "1.0"
					( Origin gBackEnd )
				)
				( topologyData 23953
(SKIDL (Circuits ("MAIN" (Parts ("CRESCENT_CITY_083_20140724_A.@@J1.228" IbisIOPkg (xy (5548 4240)) (refDes "J4A1") (model "Unknown") (Props (_SXDesignName "CRESCENT_CITY_083_20140724_A") (brdx "10643.7 MIL") (brdy "788.33 MIL") (bufferModel "CDSDefaultIO_2p5v") (cycle "1") (hold "1.0e-09") (mappingTag "") (offsets ("4" "0") ("5" "0")) (setup "2.0e-09") (state "tristate") (stimuli ("4" "local0") ("5" "local1")) (temperature "27") (termMap ("4" "Data") ("5" "Enable"))) (Terms ("CRESCENT_CITY_083_20140724_A.X1064370Y78833L2LRATS" "228"))) ("CRESCENT_CITY_083_20140724_A.@@J2.228" IbisIOPkg (xy (5528 4240)) (refDes "J6L1") (model "Unknown") (Props (_SXDesignName "CRESCENT_CITY_083_20140724_A") (brdx "10643.7 MIL") (brdy "796.23 MIL") (bufferModel "CDSDefaultIO_2p5v") (cycle "1") (hold "1.0e-09") (mappingTag "") (offsets ("4" "0") ("5" "0")) (setup "2.0e-09") (state "tristate") (stimuli ("4" "local2") ("5" "local15")) (temperature "27") (termMap ("4" "Data") ("5" "Enable"))) (Terms ("CRESCENT_CITY_083_20140724_A.X1064370Y79623L28LRATS" "228"))) ("CRESCENT_CITY_083_20140724_A.@@U36.F51" IbisIOPkg (xy (5502 4240)) (refDes "U5D1") (model "Unknown") (Props (_SXDesignName "CRESCENT_CITY_083_20140724_A") (brdx "10346.35 MIL") (brdy "2052.1 MIL") (bufferModel "CDSDefaultIO_2p5v") (cycle "1") (hold "1.0e-09") (mappingTag "") (offsets ("4" "0") ("5" "0")) (setup "2.0e-09") (state "tristate") (stimuli ("4" "local16") ("5" "local17")) (temperature "27") (termMap ("4" "Data") ("5" "Enable"))) (Terms ("CRESCENT_CITY_083_20140724_A.X1034635Y205210L2LRATS" "F51"))) ("CRESCENT_CITY_083_20140724_A.T@@RATS@@J2.228@@U36.F51" TLine (xy (5513 4235)) (mirror x) (refDes "TL1") (Props (_SXDesignName "CRESCENT_CITY_083_20140724_A") (impedance "53.474 ohm") length("1553.22 MIL") (propDelay "0.27897 ns") (traceCount "1") (traceGeometry "Microstrip") (velocity "5567.68 mil/ns")) (Terms ("CRESCENT_CITY_083_20140724_A.X1064370Y79623L28LRATS" "1") ("CRESCENT_CITY_083_20140724_A.X1034635Y205210L2LRATS" "2"))) ("CRESCENT_CITY_083_20140724_A.T@@RATS@@J2.228@@J1.228" TLine (xy (5539 4235)) (refDes "TL2") (Props (_SXDesignName "CRESCENT_CITY_083_20140724_A") (impedance "39.682 ohm") length("7.90 MIL") (propDelay "0.00142 ns") (traceCount "1") (traceGeometry "Microstrip") (velocity "5563.39 mil/ns")) (Terms ("CRESCENT_CITY_083_20140724_A.X1064370Y79623L28LRATS" "1") ("CRESCENT_CITY_083_20140724_A.X1064370Y78833L2LRATS" "2")))) (Nodes ("CRESCENT_CITY_083_20140724_A.X1034635Y205210L2LRATS" (terms "CRESCENT_CITY_083_20140724_A.T@@RATS@@J2.228@@U36.F51.2" "CRESCENT_CITY_083_20140724_A.@@U36.F51.1")) ("CRESCENT_CITY_083_20140724_A.X1064370Y78833L2LRATS" (terms "CRESCENT_CITY_083_20140724_A.T@@RATS@@J2.228@@J1.228.2" "CRESCENT_CITY_083_20140724_A.@@J1.228.1")) ("CRESCENT_CITY_083_20140724_A.X1064370Y79623L28LRATS" (terms "CRESCENT_CITY_083_20140724_A.T@@RATS@@J2.228@@J1.228.1" "CRESCENT_CITY_083_20140724_A.T@@RATS@@J2.228@@U36.F51.1" "CRESCENT_CITY_083_20140724_A.@@J2.228.1"))) (Ports) (Stimuli ("local2" (scope local) (stimType periodic) (Props (periodicFreq "5e+007") (periodicJitter "0") (periodicPattern "1"))) ("local15" (scope local) (stimType periodic) (Props (periodicFreq "5e+007") (periodicJitter "0") (periodicPattern "1"))) ("local0" (scope local) (stimType periodic) (Props (periodicFreq "5e+007") (periodicJitter "0") (periodicPattern "1"))) ("local16" (scope local) (stimType periodic) (Props (periodicFreq "5e+007") (periodicJitter "0") (periodicPattern "1"))) ("local1" (scope local) (stimType periodic) (Props (periodicFreq "5e+007") (periodicJitter "0") (periodicPattern "1"))) ("local17" (scope local) (stimType periodic) (Props (periodicFreq "5e+007") (periodicJitter "0") (periodicPattern "1")))) (Notes) (Constraints ("RELATIVE_PROPAGATION_DELAY" ("MG_DDR_NEAR_DIMM-CLK1" "CRESCENT_CITY_083_20140724_A U36.F51" "CRESCENT_CITY_083_20140724_A J12.228" "CLASS" "LENGTH" "0.01778" "LENGTH" "0") ("MG_DDR_FAR_DIMM_CMD" "CRESCENT_CITY_083_20140724_A U36.F51" "CRESCENT_CITY_083_20140724_A J11.228" "NET GROUP" "LENGTH" "0.000635" "LENGTH" "0") ("MG_DDR_FAR_DIMM-CLK0" "CRESCENT_CITY_083_20140724_A U36.F51" "CRESCENT_CITY_083_20140724_A J11.228" "CLASS" "LENGTH" "0.01778" "LENGTH" "0") ("MG_DDR_CMD_NEAR_DIMM" "CRESCENT_CITY_083_20140724_A U36.F51" "CRESCENT_CITY_083_20140724_A J12.228" "NET GROUP" "LENGTH" "0.000635" "LENGTH" "0"))) (MeasurementSets ("EMI" ("EMIStatus" status("on")) ("PeakEmission" status("on")) ("PeakFrequency" status("on")) ("PulseFreq" status("on")) ("RiseTime" status("on")) ("VoltageSwing" status("on"))) ("Reflection" ("BufferDelayFall" status("off")) ("BufferDelayRise" status("off")) ("EyeHeight" status("off")) ("EyeJitter" status("off")) ("EyeWidth" status("off")) ("FirstIncidentFall" status("off")) ("FirstIncidentRise" status("off")) ("Glitch" status("on")) ("GlitchFall" status("off")) ("GlitchRise" status("off")) ("Monotonic" status("on")) ("MonotonicFall" status("off")) ("MonotonicRise" status("off")) ("NoiseMargin" status("on")) ("NoiseMarginHigh" status("off")) ("NoiseMarginLow" status("off")) ("OvershootHigh" status("on")) ("OvershootLow" status("on")) ("PropDelay" status("on")) ("SettleDelay" status("on")) ("SettleDelayFall" status("off")) ("SettleDelayRise" status("off")) ("SwitchDelay" status("on")) ("SwitchDelayFall" status("off")) ("SwitchDelayRise" status("off"))) ("Crosstalk" ("Crosstalk" status("on"))) ("Custom")) (VectorSets) (Props (XnetName "M_A_MA<14>") (allDrivers "active") (autoSolve "Off") (customSimType "Reflection") (ftsMode ("Typ")) (rcvrSelect "all") (tlineDelayMode "time") (userRevision "1.0")))) (Subckts) (CrossSections ("CRESCENT_CITY_083_20140724_A" (Props (SXDesignName "CRESCENT_CITY_083_20140724_A")) (Layers ("" (layerType "SURFACE") (material "AIR") (thickness "0 mil") (dielectricConstant "1.000000") (lossTangent "0") (etchFactor "0.000000") (elecCondVal "0 mho/cm") (thermCondVal "0 w/cm-degC")) ("" (layerType "DIELECTRIC") (material "CONFORMAL_COAT") (thickness "0.5 mil") (dielectricConstant "3.800000") (lossTangent "0.035") (etchFactor "0.000000") (elecCondVal "0 mho/cm") (thermCondVal "0.012 w/cm-degC")) ("TOP" (layerType "CONDUCTOR") (material "COPPER") (thickness "  1.800000 mil") (width "4.00 MIL") (dielectricConstant "4.500000") (lossTangent "0") (etchFactor "70.000000") (elecCondVal "595900.000000 mho/cm") (thermCondVal "0 w/cm-degC") (signalDieConstant "3.800000") (signalLossTangent "0.035")) ("" (layerType "DIELECTRIC") (material "FR-4") (thickness "  2.700000 mil") (dielectricConstant "4.000000") (lossTangent "0.035") (etchFactor "0.000000") (elecCondVal "0 mho/cm") (thermCondVal "0.012 w/cm-degC")) ("L2_GND1" (layerType "PLANE") (material "COPPER") (isShield t) (thickness "  1.200000 mil") (dielectricConstant "4.500000") (lossTangent "0.035") (etchFactor "90.000000") (elecCondVal "595900.000000 mho/cm") (thermCondVal "0.012 w/cm-degC")) ("" (layerType "DIELECTRIC") (material "FR-4") (thickness "  9.900000 mil") (dielectricConstant "4.100000") (lossTangent "0.035") (etchFactor "0.000000") (elecCondVal "0 mho/cm") (thermCondVal "0.012 w/cm-degC")) ("L3_SIG1" (layerType "CONDUCTOR") (material "COPPER") (thickness "  1.200000 mil") (width "4.00 MIL") (dielectricConstant "4.500000") (lossTangent "0.035") (etchFactor "90.000000") (elecCondVal "595900.000000 mho/cm") (thermCondVal "0.012 w/cm-degC") (signalDieConstant "4.100000") (signalLossTangent "0.035")) ("" (layerType "DIELECTRIC") (material "FR-4") (thickness "  3.300000 mil") (dielectricConstant "4.500000") (lossTangent "0.035") (etchFactor "0.000000") (elecCondVal "0 mho/cm") (thermCondVal "0 w/cm-degC")) ("L4_GND2" (layerType "PLANE") (material "COPPER") (isShield t) (thickness "  1.200000 mil") (dielectricConstant "4.500000") (lossTangent "0.035") (etchFactor "90.000000") (elecCondVal "595900.000000 mho/cm") (thermCondVal "0 w/cm-degC")) ("" (layerType "DIELECTRIC") (material "FR-4") (thickness "  3.300000 mil") (dielectricConstant "4.000000") (lossTangent "0.035") (etchFactor "0.000000") (elecCondVal "0 mho/cm") (thermCondVal "0.012 w/cm-degC")) ("L5_SIG2" (layerType "CONDUCTOR") (material "COPPER") (thickness "  1.200000 mil") (width "4.00 MIL") (dielectricConstant "4.500000") (lossTangent "0.035") (etchFactor "90.000000") (elecCondVal "595900.000000 mho/cm") (thermCondVal "0.012 w/cm-degC") (signalDieConstant "4.000000") (signalLossTangent "0.035")) ("" (layerType "DIELECTRIC") (material "FR-4") (thickness "  9.900000 mil") (dielectricConstant "4.500000") (lossTangent "0.035") (etchFactor "0.000000") (elecCondVal "0 mho/cm") (thermCondVal "0 w/cm-degC")) ("L6_GND3" (layerType "PLANE") (material "COPPER") (isShield t) (thickness "  1.200000 mil") (dielectricConstant "4.500000") (lossTangent "0.035") (etchFactor "90.000000") (elecCondVal "595900.000000 mho/cm") (thermCondVal "0 w/cm-degC")) ("" (layerType "DIELECTRIC") (material "FR-4") (thickness "  3.300000 mil") (dielectricConstant "4.100000") (lossTangent "0.035") (etchFactor "0.000000") (elecCondVal "0 mho/cm") (thermCondVal "0.012 w/cm-degC")) ("L7_PWR1-SIG" (layerType "PLANE") (material "COPPER") (isShield t) (thickness "  1.200000 mil") (dielectricConstant "4.500000") (lossTangent "0.035") (etchFactor "90.000000") (elecCondVal "595900.000000 mho/cm") (thermCondVal "0.012 w/cm-degC")) ("" (layerType "DIELECTRIC") (material "FR-4") (thickness "  9.900000 mil") (dielectricConstant "4.000000") (lossTangent "0.035") (etchFactor "0.000000") (elecCondVal "0 mho/cm") (thermCondVal "0.012 w/cm-degC")) ("L8_PWR2-SIG" (layerType "PLANE") (material "COPPER") (isShield t) (thickness "  1.200000 mil") (dielectricConstant "4.500000") (lossTangent "0.035") (etchFactor "90.000000") (elecCondVal "595900.000000 mho/cm") (thermCondVal "0.012 w/cm-degC")) ("" (layerType "DIELECTRIC") (material "FR-4") (thickness "  3.300000 mil") (dielectricConstant "4.500000") (lossTangent "0.035") (etchFactor "0.000000") (elecCondVal "0 mho/cm") (thermCondVal "0 w/cm-degC")) ("L9_GND4" (layerType "PLANE") (material "COPPER") (isShield t) (thickness "  1.200000 mil") (dielectricConstant "4.500000") (lossTangent "0.035") (etchFactor "90.000000") (elecCondVal "595900.000000 mho/cm") (thermCondVal "0 w/cm-degC")) ("" (layerType "DIELECTRIC") (material "FR-4") (thickness "  9.900000 mil") (dielectricConstant "4.100000") (lossTangent "0.035") (etchFactor "0.000000") (elecCondVal "0 mho/cm") (thermCondVal "0.012 w/cm-degC")) ("L10_SIG3" (layerType "CONDUCTOR") (material "COPPER") (thickness "  1.200000 mil") (width "4.00 MIL") (dielectricConstant "4.500000") (lossTangent "0.035") (etchFactor "90.000000") (elecCondVal "595900.000000 mho/cm") (thermCondVal "0.012 w/cm-degC") (signalDieConstant "4.100000") (signalLossTangent "0.035")) ("" (layerType "DIELECTRIC") (material "FR-4") (thickness "  3.300000 mil") (dielectricConstant "4.500000") (lossTangent "0.035") (etchFactor "0.000000") (elecCondVal "0 mho/cm") (thermCondVal "0 w/cm-degC")) ("L11_GND5" (layerType "PLANE") (material "COPPER") (isShield t) (thickness "  1.200000 mil") (dielectricConstant "4.500000") (lossTangent "0.035") (etchFactor "90.000000") (elecCondVal "595900.000000 mho/cm") (thermCondVal "0 w/cm-degC")) ("" (layerType "DIELECTRIC") (material "FR-4") (thickness "  9.900000 mil") (dielectricConstant "4.500000") (lossTangent "0.035") (etchFactor "0.000000") (elecCondVal "0 mho/cm") (thermCondVal "0.012 w/cm-degC")) ("L12_SIG4" (layerType "CONDUCTOR") (material "COPPER") (thickness "  1.200000 mil") (width "4.00 MIL") (dielectricConstant "4.500000") (lossTangent "0.035") (etchFactor "90.000000") (elecCondVal "595900.000000 mho/cm") (thermCondVal "0.012 w/cm-degC") (signalDieConstant "4.500000") (signalLossTangent "0.035")) ("" (layerType "DIELECTRIC") (material "FR-4") (thickness "  3.300000 mil") (dielectricConstant "4.500000") (lossTangent "0.035") (etchFactor "0.000000") (elecCondVal "0 mho/cm") (thermCondVal "0 w/cm-degC")) ("L13_GND6" (layerType "PLANE") (material "COPPER") (isShield t) (thickness "  1.200000 mil") (dielectricConstant "4.500000") (lossTangent "0.035") (etchFactor "90.000000") (elecCondVal "595900.000000 mho/cm") (thermCondVal "0.012 w/cm-degC")) ("" (layerType "DIELECTRIC") (material "FR-4") (thickness "  2.700000 mil") (dielectricConstant "4.500000") (lossTangent "0.035") (etchFactor "0.000000") (elecCondVal "0 mho/cm") (thermCondVal "0.012 w/cm-degC")) ("BOTTOM" (layerType "CONDUCTOR") (material "COPPER") (thickness "  1.800000 mil") (width "4.00 MIL") (dielectricConstant "4.500000") (lossTangent "0") (etchFactor "70.000000") (elecCondVal "595900.000000 mho/cm") (thermCondVal "0 w/cm-degC") (signalDieConstant "3.800000") (signalLossTangent "0.035")) ("" (layerType "DIELECTRIC") (material "CONFORMAL_COAT") (thickness "0.5 mil") (dielectricConstant "3.800000") (lossTangent "0.035") (etchFactor "0.000000") (elecCondVal "0 mho/cm") (thermCondVal "0.012 w/cm-degC")) ("" (layerType "SURFACE") (material "AIR") (thickness "0 mil") (dielectricConstant "1.000000") (lossTangent "0") (etchFactor "0.000000") (elecCondVal "0 mho/cm") (thermCondVal "0 w/cm-degC"))))) (Props (DesUnits "mils 2") (LayerStack ("DIELECTRIC" "DIELECTRIC" "BOTTOM" "DIELECTRIC" "L13_GND6" "DIELECTRIC" "L12_SIG4" "DIELECTRIC" "L11_GND5" "DIELECTRIC" "L10_SIG3" "DIELECTRIC" "L9_GND4" "DIELECTRIC" "L8_PWR2-SIG" "DIELECTRIC" "L7_PWR1-SIG" "DIELECTRIC" "L6_GND3" "DIELECTRIC" "L5_SIG2" "DIELECTRIC" "L4_GND2" "DIELECTRIC" "L3_SIG1" "DIELECTRIC" "L2_GND1" "DIELECTRIC" "TOP" "DIELECTRIC" "DIELECTRIC")) (Revision "16.600")) (Params (TheveninTerm ((resistanceUp "180 ohm") (resistanceDown "270 ohm") (voltageUp "5 V") (voltageDown "0 V") (maxDelay "0.1 ns"))) (ShuntTerm ((resistance "50 ohm") (voltage "5 V") (maxDelay "0.1 ns"))) (SeriesTerm ((resistance "22 ohm") (maxDelay "0.1 ns"))) (LowClampTerm ((cutoffVoltage "0.7 V") (voltage "0 V") (maxDelay "0.1 ns"))) (IbisIO_OpenPullDown ((temperature "27") (bufferModel "CDSDefaultIO_2p5v") (stimuli nil) (offsets nil) (state "tristate") (cycle "1") (termMap nil) (setup "2.0e-09") (hold "1.0e-09") (rise nil) (fall nil) (macroType nil) (voltage nil) (spice nil) (LEFDEFPinName nil) (LEFDEFPinType nil) (mappingTag nil))) (IbisIO_OpenPullUp ((temperature "27") (bufferModel "CDSDefaultIO_2p5v") (stimuli nil) (offsets nil) (state "tristate") (cycle "1") (termMap nil) (setup "2.0e-09") (hold "1.0e-09") (rise nil) (fall nil) (macroType nil) (voltage nil) (spice nil) (LEFDEFPinName nil) (LEFDEFPinType nil) (mappingTag nil))) (clocked ((clockRise "1e-09") (clockFall "1e-09") (clockFreq "100e6") (clockInitState "0") (clockDutyCycle "0.5") (clockJitter "0"))) (RCTerm ((resistance "50 ohm") (capacitance "20 pF") (voltage "5 V") (maxDelay "0.1 ns"))) (periodic ((periodicFreq "100e6") (periodicPattern "10") (periodicJitter "0"))) (Via ((model "Unknown") (viaOutputFormat "Unknown") (viaPadstack nil) (viaTopLayer nil) (viaBottomLayer nil) (viaIsPower nil) (viaIsGround nil))) (DualClampTerm ((cutoffVoltageUp "0.7 V") (cutoffVoltageDown "0.7 V") (voltageUp "5 V") (voltageDown "0 V") (maxDelay "0.1 ns"))) (IbisIOPkg ((temperature "27") (bufferModel "CDSDefaultIO_2p5v") (stimuli nil) (offsets nil) (state "tristate") (cycle "1") (termMap nil) (setup "2.0e-09") (hold "1.0e-09") (rise nil) (fall nil) (macroType nil) (voltage nil) (spice nil) (LEFDEFPinName nil) (LEFDEFPinType nil) (mappingTag nil))) (CurrentProbe nil) (HiClampTerm ((cutoffVoltage "0.7 V") (voltage "5 V") (maxDelay "0.1 ns"))) (IbisOutputPkg ((temperature "27") (bufferModel "CDSDefaultOutput_2p5v") (stimuli nil) (offsets nil) (state "tristate") (cycle "1") (termMap nil) (setup "2.0e-09") (hold "1.0e-09") (rise nil) (fall nil) (macroType nil) (voltage nil) (spice nil) (LEFDEFPinName nil) (LEFDEFPinType nil) (mappingTag nil))) (Diode ((cutoffVoltage "0.7 V"))) (IbisInputPkg ((temperature "27") (bufferModel "CDSDefaultInput_2p5v") (cycle "1") (LEFDEFPinName nil) (LEFDEFPinType nil) (mappingTag nil))) (async ((asyncTimePoints "") (asyncInitState "1"))) (ESpiceDevice nil) (IbisInput ((temperature "27") (bufferModel "CDSDefaultInput_2p5v") (cycle "1") (LEFDEFPinName nil) (LEFDEFPinType nil) (mappingTag nil))) (Trace ((d1Thickness "10 mil") (d1Constant "4.5") (d1LossTangent "0.035") (d2Thickness "10 mil") (d2Constant "4.5") (d2LossTangent "0.035") (d3Thickness "0.0") (d3Constant "1.0") (d3LossTangent "0") length("1000 mil") (spacing "5 mil") (spacing2 "5 mil") (spacing3 "5 mil") (spacing4 "5 mil") (spacing5 "5 mil") (traceConductivity "595900 mho/cm") (traceGeometry "microstrip") (traceLayerName "") (traceThickness "0.72 mil") (traceType "single") (traceWidth "5.0 mil") (traceWidth2 "5.0 mil") (traceWidth3 "5.0 mil") (traceWidth4 "5.0 mil") (traceWidth5 "5.0 mil") (traceWidth6 "5.0 mil") (offset "0 mil") (traceCount "1") (impedance nil))) (Cable (length("1 m"))) (Resistor ((resistance "50 ohm") (orientation "0"))) (DiffInput ((temperature "27") (bufferModelNonInverting "CDSDefaultInput_2p5v") (bufferModelInverting "CDSDefaultInput_2p5v") (threshInputHighMin "1.7 V") (threshInputHighTyp "1.7  V") (threshInputHighMax "1.7  V") (threshInputLowMin "0.7  V") (threshInputLowTyp "0.7  V") (threshInputLowMax "0.7  V") (mappingTagNonInverting nil) (mappingTagInverting nil) (cycle "1"))) (Source ((voltage "5 V"))) (DiffIOPkg ((temperature "27") (bufferModelNonInverting "CDSDefaultIO_2p5v") (bufferModelInverting "CDSDefaultIO_2p5v") (stimuli nil) (offsets nil) (state "tristate") (cycle "1") (termMap nil) (setup "0.9e-09") (hold "0.4e-09") (rise nil) (fall nil) (threshInputHighMin "1.7 V") (threshInputHighTyp "1.7  V") (threshInputHighMax "1.7  V") (threshInputLowMin "0.7  V") (threshInputLowTyp "0.7  V") (threshInputLowMax "0.7 ") (threshOutputHighMin "2.365  V") (threshOutputHighTyp "2.5  V") (threshOutputHighMax "2.625  V") (threshOutputLowMin "1.275  V") (threshOutputLowTyp "1.7  V") (threshOutputLowMax "1.985  V") (mappingTagNonInverting nil) (mappingTagInverting nil) (spice nil))) (IbisOutput ((temperature "27") (bufferModel "CDSDefaultOutput_2p5v") (stimuli nil) (offsets nil) (state "tristate") (cycle "1") (termMap nil) (setup "2.0e-09") (hold "1.0e-09") (rise nil) (fall nil) (macroType nil) (voltage nil) (spice nil) (LEFDEFPinName nil) (LEFDEFPinType nil) (mappingTag nil))) (IbisIO ((temperature "27") (bufferModel "CDSDefaultIO_2p5v") (stimuli nil) (offsets nil) (state "tristate") (cycle "1") (termMap nil) (setup "2.0e-09") (hold "1.0e-09") (rise nil) (fall nil) (macroType nil) (voltage nil) (spice nil) (LEFDEFPinName nil) (LEFDEFPinType nil) (mappingTag nil))) (RLGC (length("1000 mil"))) (DiffIO ((temperature "27") (bufferModelNonInverting "CDSDefaultIO_2p5v") (bufferModelInverting "CDSDefaultIO_2p5v") (stimuli nil) (offsets nil) (state "tristate") (cycle "1") (termMap nil) (setup "0.9e-09") (hold "0.4e-09") (rise nil) (fall nil) (threshInputHighMin "1.7 V") (threshInputHighTyp "1.7  V") (threshInputHighMax "1.7  V") (threshInputLowMin "0.7  V") (threshInputLowTyp "0.7  V") (threshInputLowMax "0.7 ") (threshOutputHighMin "2.365  V") (threshOutputHighTyp "2.5  V") (threshOutputHighMax "2.625  V") (threshOutputLowMin "1.275  V") (threshOutputLowTyp "1.7  V") (threshOutputLowMax "1.985  V") (mappingTagNonInverting nil) (mappingTagInverting nil) (spice nil))) (Capacitor ((capacitance "10 pF") (orientation "0"))) (DiffOutputPkg ((temperature "27") (bufferModelNonInverting "CDSDefaultOutput_2p5v") (bufferModelInverting "CDSDefaultOutput_2p5v") (stimuli nil) (offsets nil) (state "tristate") (cycle "1") (termMap nil) (setup "0.9e-09") (hold "0.4e-09") (rise nil) (fall nil) (threshOutputHighMin "2.375  V") (threshOutputHighTyp "2.5  V") (threshOutputHighMax "2.625  V") (threshOutputLowMin "1.275  V") (threshOutputLowTyp "1.7  V") (threshOutputLowMax "1.985  V") (mappingTagNonInverting nil) (mappingTagInverting nil) (spice nil))) (Inductor ((inductance "5 nH") (orientation "0"))) (DiffOutput ((temperature "27") (bufferModelNonInverting "CDSDefaultOutput_2p5v") (bufferModelInverting "CDSDefaultOutput_2p5v") (stimuli nil) (offsets nil) (state "tristate") (cycle "1") (termMap nil) (setup "0.9e-09") (hold "0.4e-09") (rise nil) (fall nil) (threshOutputHighMin "2.375  V") (threshOutputHighTyp "2.5  V") (threshOutputHighMax "2.625  V") (threshOutputLowMin "1.275  V") (threshOutputLowTyp "1.7  V") (threshOutputLowMax "1.985  V") (mappingTagNonInverting nil) (mappingTagInverting nil) (spice nil))) (CPWMS ((d1Thickness "10 mil") (d1Constant "4.5") (d1LossTangent "0.035") (d2Thickness "0.72 mil") (d2Constant "4.5") (d2LossTangent "0.035") (d3Thickness "0.0") (d3Constant "1") (d3LossTangent "0") length("1000 mil") (spacing "5 mil") (spacing2 "5 mil") (spacing3 "5 mil") (spacing4 "5 mil") (spacing5 "5 mil") (traceConductivity "595900 mho/cm") (traceGeometry "cpwms") (traceLayerName "") (traceThickness "0.72 mil") (traceType "single") (traceWidth "5.0 mil") (traceWidth2 "5.0 mil") (traceWidth3 "5.0 mil") (traceWidth4 "5.0 mil") (traceWidth5 "5.0 mil") (traceWidth6 "5.0 mil") (offset "0 mil") (traceCount "1") (impedance nil))) (CPW ((d1Thickness "10 mil") (d1Constant "4.5") (d1LossTangent "0.035") (d2Thickness "0.72 mil") (d2Constant "1") (d2LossTangent "0") (d3Thickness "0.0") (d3Constant "1") (d3LossTangent "0") length("1000 mil") (spacing "5 mil") (spacing2 "5 mil") (spacing3 "5 mil") (spacing4 "5 mil") (spacing5 "5 mil") (traceConductivity "595900 mho/cm") (traceGeometry "cpwms") (traceLayerName "") (traceThickness "0.72 mil") (traceType "single") (traceWidth "5.0 mil") (traceWidth2 "5.0 mil") (traceWidth3 "5.0 mil") (traceWidth4 "5.0 mil") (traceWidth5 "5.0 mil") (traceWidth6 "5.0 mil") (offset "0 mil") (traceCount "1") (impedance nil))) (idlCircuit ((allDrivers "active") (ftsMode '("Typ")) (rcvrSelect "all") (simMode "Reflection") (tlineDelayMode "time") (userRevision "1.0") (autoSolve "On"))) (CPWSL ((d1Thickness "10 mil") (d1Constant "4.5") (d1LossTangent "0.035") (d2Thickness "0.72 mil") (d2Constant "4.5") (d2LossTangent "0.035") (d3Thickness "10 mil") (d3Constant "4.5") (d3LossTangent "0.035") length("1000 mil") (spacing "5 mil") (spacing2 "5 mil") (spacing3 "5 mil") (spacing4 "5 mil") (spacing5 "5 mil") (traceConductivity "595900 mho/cm") (traceGeometry "cpwms") (traceLayerName "") (traceThickness "0.72 mil") (traceType "single") (traceWidth "5.0 mil") (traceWidth2 "5.0 mil") (traceWidth3 "5.0 mil") (traceWidth4 "5.0 mil") (traceWidth5 "5.0 mil") (traceWidth6 "5.0 mil") (offset "0 mil") (traceCount "1") (impedance nil))) (DiffInputPkg ((temperature "27") (bufferModelNonInverting "CDSDefaultInput_2p5v") (bufferModelInverting "CDSDefaultInput_2p5v") (threshInputHighMin "1.7 V") (threshInputHighTyp "1.7  V") (threshInputHighMax "1.7  V") (threshInputLowMin "0.7  V") (threshInputLowTyp "0.7  V") (threshInputLowMax "0.7  V") (mappingTagNonInverting nil) (mappingTagInverting nil) (cycle "1"))) (IbisIOMacro ((temperature "27") (bufferModel "CDSDefaultIO_2p5v") (stimuli nil) (offsets nil) (state "tristate") (cycle "1") (termMap nil) (setup "2.0e-09") (hold "1.0e-09") (rise nil) (fall nil) (macroType nil) (voltage nil) (spice nil) (LEFDEFPinName nil) (LEFDEFPinType nil) (mappingTag nil))) (IbisOutput_OpenPullUp ((temperature "27") (bufferModel "CDSDefaultOutput_2p5v") (stimuli nil) (offsets nil) (state "tristate") (cycle "1") (termMap nil) (setup "2.0e-09") (hold "1.0e-09") (rise nil) (fall nil) (macroType nil) (voltage nil) (spice nil) (LEFDEFPinName nil) (LEFDEFPinType nil) (mappingTag nil))) (Connector nil) (TLine ((diffImpedance "100ohm") (diffVelocity "1.4142e+08M/s") (impedance "60ohm") length("2800 mil") (propDelay "0.5 ns") (velocity "5600 mil/ns") (traceCount "1") (traceGeometry "Microstrip") (impedanceMin nil) (impedanceMax nil) (lengthMin nil) (lengthMax nil) (propDelayMin nil) (propDelayMax nil) (impedanceSweepCount nil) (propDelaySweepCount nil) (velocitySweepCount nil) (lengthSweepCount nil) (matchSetName nil))) (sync ((syncFreq "100e6") (syncInitState "1") (syncPattern "10") (syncEdgeSwitch "rise")))))
				)
				( objectStatus "DDR_F_CMD_DLL1-13" )
			)
			( electricalCSet "@crescent_city_bb_fab1_lib.crescent_city_bb_fab1(sch_1):\DDR_E_CMD_DLL1-13\"
				( groupRef "DDR_E_CMD_DLL1-13:MG_DDR_NEAR_DIMM-CLK1" )
				( groupRef "DDR_E_CMD_DLL1-13:MG_DDR_FAR_DIMM_CMD" )
				( groupRef "DDR_E_CMD_DLL1-13:MG_DDR_FAR_DIMM-CLK0" )
				( groupRef "DDR_E_CMD_DLL1-13:MG_DDR_CMD_NEAR_DIMM" )
				( pinPairRef "DDR_E_CMD_DLL1-13:U5D1.F51:J6L2.228" )
				( pinPairRef "DDR_E_CMD_DLL1-13:U5D1.F51:J4A2.228" )
				( attribute "TOPOLOGY_TEMPLATE_REVISION" "1.0"
					( Origin gBackEnd )
				)
				( topologyData 23951
(SKIDL (Circuits ("MAIN" (Parts ("CRESCENT_CITY_083_20140724_A.@@J1.228" IbisIOPkg (xy (5548 4240)) (refDes "J4A2") (model "Unknown") (Props (_SXDesignName "CRESCENT_CITY_083_20140724_A") (brdx "10643.7 MIL") (brdy "788.33 MIL") (bufferModel "CDSDefaultIO_2p5v") (cycle "1") (hold "1.0e-09") (mappingTag "") (offsets ("4" "0") ("5" "0")) (setup "2.0e-09") (state "tristate") (stimuli ("4" "local0") ("5" "local1")) (temperature "27") (termMap ("4" "Data") ("5" "Enable"))) (Terms ("CRESCENT_CITY_083_20140724_A.X1064370Y78833L2LRATS" "228"))) ("CRESCENT_CITY_083_20140724_A.@@J2.228" IbisIOPkg (xy (5528 4240)) (refDes "J6L2") (model "Unknown") (Props (_SXDesignName "CRESCENT_CITY_083_20140724_A") (brdx "10643.7 MIL") (brdy "796.23 MIL") (bufferModel "CDSDefaultIO_2p5v") (cycle "1") (hold "1.0e-09") (mappingTag "") (offsets ("4" "0") ("5" "0")) (setup "2.0e-09") (state "tristate") (stimuli ("4" "local2") ("5" "local15")) (temperature "27") (termMap ("4" "Data") ("5" "Enable"))) (Terms ("CRESCENT_CITY_083_20140724_A.X1064370Y79623L28LRATS" "228"))) ("CRESCENT_CITY_083_20140724_A.@@U36.F51" IbisIOPkg (xy (5502 4240)) (refDes "U5D1") (model "Unknown") (Props (_SXDesignName "CRESCENT_CITY_083_20140724_A") (brdx "10346.35 MIL") (brdy "2052.1 MIL") (bufferModel "CDSDefaultIO_2p5v") (cycle "1") (hold "1.0e-09") (mappingTag "") (offsets ("4" "0") ("5" "0")) (setup "2.0e-09") (state "tristate") (stimuli ("4" "local16") ("5" "local17")) (temperature "27") (termMap ("4" "Data") ("5" "Enable"))) (Terms ("CRESCENT_CITY_083_20140724_A.X1034635Y205210L2LRATS" "F51"))) ("CRESCENT_CITY_083_20140724_A.T@@RATS@@J2.228@@U36.F51" TLine (xy (5513 4235)) (mirror x) (refDes "TL1") (Props (_SXDesignName "CRESCENT_CITY_083_20140724_A") (impedance "53.474 ohm") length("1553.22 MIL") (propDelay "0.27897 ns") (traceCount "1") (traceGeometry "Microstrip") (velocity "5567.68 mil/ns")) (Terms ("CRESCENT_CITY_083_20140724_A.X1064370Y79623L28LRATS" "1") ("CRESCENT_CITY_083_20140724_A.X1034635Y205210L2LRATS" "2"))) ("CRESCENT_CITY_083_20140724_A.T@@RATS@@J2.228@@J1.228" TLine (xy (5539 4235)) (refDes "TL2") (Props (_SXDesignName "CRESCENT_CITY_083_20140724_A") (impedance "39.682 ohm") length("7.90 MIL") (propDelay "0.00142 ns") (traceCount "1") (traceGeometry "Microstrip") (velocity "5563.39 mil/ns")) (Terms ("CRESCENT_CITY_083_20140724_A.X1064370Y79623L28LRATS" "1") ("CRESCENT_CITY_083_20140724_A.X1064370Y78833L2LRATS" "2")))) (Nodes ("CRESCENT_CITY_083_20140724_A.X1034635Y205210L2LRATS" (terms "CRESCENT_CITY_083_20140724_A.T@@RATS@@J2.228@@U36.F51.2" "CRESCENT_CITY_083_20140724_A.@@U36.F51.1")) ("CRESCENT_CITY_083_20140724_A.X1064370Y78833L2LRATS" (terms "CRESCENT_CITY_083_20140724_A.T@@RATS@@J2.228@@J1.228.2" "CRESCENT_CITY_083_20140724_A.@@J1.228.1")) ("CRESCENT_CITY_083_20140724_A.X1064370Y79623L28LRATS" (terms "CRESCENT_CITY_083_20140724_A.T@@RATS@@J2.228@@J1.228.1" "CRESCENT_CITY_083_20140724_A.T@@RATS@@J2.228@@U36.F51.1" "CRESCENT_CITY_083_20140724_A.@@J2.228.1"))) (Ports) (Stimuli ("local2" (scope local) (stimType periodic) (Props (periodicFreq "5e+007") (periodicJitter "0") (periodicPattern "1"))) ("local15" (scope local) (stimType periodic) (Props (periodicFreq "5e+007") (periodicJitter "0") (periodicPattern "1"))) ("local0" (scope local) (stimType periodic) (Props (periodicFreq "5e+007") (periodicJitter "0") (periodicPattern "1"))) ("local16" (scope local) (stimType periodic) (Props (periodicFreq "5e+007") (periodicJitter "0") (periodicPattern "1"))) ("local1" (scope local) (stimType periodic) (Props (periodicFreq "5e+007") (periodicJitter "0") (periodicPattern "1"))) ("local17" (scope local) (stimType periodic) (Props (periodicFreq "5e+007") (periodicJitter "0") (periodicPattern "1")))) (Notes) (Constraints ("RELATIVE_PROPAGATION_DELAY" ("MG_DDR_NEAR_DIMM-CLK1" "CRESCENT_CITY_083_20140724_A U36.F51" "CRESCENT_CITY_083_20140724_A J10.228" "CLASS" "LENGTH" "0.01778" "LENGTH" "0") ("MG_DDR_FAR_DIMM_CMD" "CRESCENT_CITY_083_20140724_A U36.F51" "CRESCENT_CITY_083_20140724_A J9.228" "NET GROUP" "LENGTH" "0.000635" "LENGTH" "0") ("MG_DDR_FAR_DIMM-CLK0" "CRESCENT_CITY_083_20140724_A U36.F51" "CRESCENT_CITY_083_20140724_A J9.228" "CLASS" "LENGTH" "0.01778" "LENGTH" "0") ("MG_DDR_CMD_NEAR_DIMM" "CRESCENT_CITY_083_20140724_A U36.F51" "CRESCENT_CITY_083_20140724_A J10.228" "NET GROUP" "LENGTH" "0.000635" "LENGTH" "0"))) (MeasurementSets ("EMI" ("EMIStatus" status("on")) ("PeakEmission" status("on")) ("PeakFrequency" status("on")) ("PulseFreq" status("on")) ("RiseTime" status("on")) ("VoltageSwing" status("on"))) ("Reflection" ("BufferDelayFall" status("off")) ("BufferDelayRise" status("off")) ("EyeHeight" status("off")) ("EyeJitter" status("off")) ("EyeWidth" status("off")) ("FirstIncidentFall" status("off")) ("FirstIncidentRise" status("off")) ("Glitch" status("on")) ("GlitchFall" status("off")) ("GlitchRise" status("off")) ("Monotonic" status("on")) ("MonotonicFall" status("off")) ("MonotonicRise" status("off")) ("NoiseMargin" status("on")) ("NoiseMarginHigh" status("off")) ("NoiseMarginLow" status("off")) ("OvershootHigh" status("on")) ("OvershootLow" status("on")) ("PropDelay" status("on")) ("SettleDelay" status("on")) ("SettleDelayFall" status("off")) ("SettleDelayRise" status("off")) ("SwitchDelay" status("on")) ("SwitchDelayFall" status("off")) ("SwitchDelayRise" status("off"))) ("Crosstalk" ("Crosstalk" status("on"))) ("Custom")) (VectorSets) (Props (XnetName "M_A_MA<14>") (allDrivers "active") (autoSolve "Off") (customSimType "Reflection") (ftsMode ("Typ")) (rcvrSelect "all") (tlineDelayMode "time") (userRevision "1.0")))) (Subckts) (CrossSections ("CRESCENT_CITY_083_20140724_A" (Props (SXDesignName "CRESCENT_CITY_083_20140724_A")) (Layers ("" (layerType "SURFACE") (material "AIR") (thickness "0 mil") (dielectricConstant "1.000000") (lossTangent "0") (etchFactor "0.000000") (elecCondVal "0 mho/cm") (thermCondVal "0 w/cm-degC")) ("" (layerType "DIELECTRIC") (material "CONFORMAL_COAT") (thickness "0.5 mil") (dielectricConstant "3.800000") (lossTangent "0.035") (etchFactor "0.000000") (elecCondVal "0 mho/cm") (thermCondVal "0.012 w/cm-degC")) ("TOP" (layerType "CONDUCTOR") (material "COPPER") (thickness "  1.800000 mil") (width "4.00 MIL") (dielectricConstant "4.500000") (lossTangent "0") (etchFactor "70.000000") (elecCondVal "595900.000000 mho/cm") (thermCondVal "0 w/cm-degC") (signalDieConstant "3.800000") (signalLossTangent "0.035")) ("" (layerType "DIELECTRIC") (material "FR-4") (thickness "  2.700000 mil") (dielectricConstant "4.000000") (lossTangent "0.035") (etchFactor "0.000000") (elecCondVal "0 mho/cm") (thermCondVal "0.012 w/cm-degC")) ("L2_GND1" (layerType "PLANE") (material "COPPER") (isShield t) (thickness "  1.200000 mil") (dielectricConstant "4.500000") (lossTangent "0.035") (etchFactor "90.000000") (elecCondVal "595900.000000 mho/cm") (thermCondVal "0.012 w/cm-degC")) ("" (layerType "DIELECTRIC") (material "FR-4") (thickness "  9.900000 mil") (dielectricConstant "4.100000") (lossTangent "0.035") (etchFactor "0.000000") (elecCondVal "0 mho/cm") (thermCondVal "0.012 w/cm-degC")) ("L3_SIG1" (layerType "CONDUCTOR") (material "COPPER") (thickness "  1.200000 mil") (width "4.00 MIL") (dielectricConstant "4.500000") (lossTangent "0.035") (etchFactor "90.000000") (elecCondVal "595900.000000 mho/cm") (thermCondVal "0.012 w/cm-degC") (signalDieConstant "4.100000") (signalLossTangent "0.035")) ("" (layerType "DIELECTRIC") (material "FR-4") (thickness "  3.300000 mil") (dielectricConstant "4.500000") (lossTangent "0.035") (etchFactor "0.000000") (elecCondVal "0 mho/cm") (thermCondVal "0 w/cm-degC")) ("L4_GND2" (layerType "PLANE") (material "COPPER") (isShield t) (thickness "  1.200000 mil") (dielectricConstant "4.500000") (lossTangent "0.035") (etchFactor "90.000000") (elecCondVal "595900.000000 mho/cm") (thermCondVal "0 w/cm-degC")) ("" (layerType "DIELECTRIC") (material "FR-4") (thickness "  3.300000 mil") (dielectricConstant "4.000000") (lossTangent "0.035") (etchFactor "0.000000") (elecCondVal "0 mho/cm") (thermCondVal "0.012 w/cm-degC")) ("L5_SIG2" (layerType "CONDUCTOR") (material "COPPER") (thickness "  1.200000 mil") (width "4.00 MIL") (dielectricConstant "4.500000") (lossTangent "0.035") (etchFactor "90.000000") (elecCondVal "595900.000000 mho/cm") (thermCondVal "0.012 w/cm-degC") (signalDieConstant "4.000000") (signalLossTangent "0.035")) ("" (layerType "DIELECTRIC") (material "FR-4") (thickness "  9.900000 mil") (dielectricConstant "4.500000") (lossTangent "0.035") (etchFactor "0.000000") (elecCondVal "0 mho/cm") (thermCondVal "0 w/cm-degC")) ("L6_GND3" (layerType "PLANE") (material "COPPER") (isShield t) (thickness "  1.200000 mil") (dielectricConstant "4.500000") (lossTangent "0.035") (etchFactor "90.000000") (elecCondVal "595900.000000 mho/cm") (thermCondVal "0 w/cm-degC")) ("" (layerType "DIELECTRIC") (material "FR-4") (thickness "  3.300000 mil") (dielectricConstant "4.100000") (lossTangent "0.035") (etchFactor "0.000000") (elecCondVal "0 mho/cm") (thermCondVal "0.012 w/cm-degC")) ("L7_PWR1-SIG" (layerType "PLANE") (material "COPPER") (isShield t) (thickness "  1.200000 mil") (dielectricConstant "4.500000") (lossTangent "0.035") (etchFactor "90.000000") (elecCondVal "595900.000000 mho/cm") (thermCondVal "0.012 w/cm-degC")) ("" (layerType "DIELECTRIC") (material "FR-4") (thickness "  9.900000 mil") (dielectricConstant "4.000000") (lossTangent "0.035") (etchFactor "0.000000") (elecCondVal "0 mho/cm") (thermCondVal "0.012 w/cm-degC")) ("L8_PWR2-SIG" (layerType "PLANE") (material "COPPER") (isShield t) (thickness "  1.200000 mil") (dielectricConstant "4.500000") (lossTangent "0.035") (etchFactor "90.000000") (elecCondVal "595900.000000 mho/cm") (thermCondVal "0.012 w/cm-degC")) ("" (layerType "DIELECTRIC") (material "FR-4") (thickness "  3.300000 mil") (dielectricConstant "4.500000") (lossTangent "0.035") (etchFactor "0.000000") (elecCondVal "0 mho/cm") (thermCondVal "0 w/cm-degC")) ("L9_GND4" (layerType "PLANE") (material "COPPER") (isShield t) (thickness "  1.200000 mil") (dielectricConstant "4.500000") (lossTangent "0.035") (etchFactor "90.000000") (elecCondVal "595900.000000 mho/cm") (thermCondVal "0 w/cm-degC")) ("" (layerType "DIELECTRIC") (material "FR-4") (thickness "  9.900000 mil") (dielectricConstant "4.100000") (lossTangent "0.035") (etchFactor "0.000000") (elecCondVal "0 mho/cm") (thermCondVal "0.012 w/cm-degC")) ("L10_SIG3" (layerType "CONDUCTOR") (material "COPPER") (thickness "  1.200000 mil") (width "4.00 MIL") (dielectricConstant "4.500000") (lossTangent "0.035") (etchFactor "90.000000") (elecCondVal "595900.000000 mho/cm") (thermCondVal "0.012 w/cm-degC") (signalDieConstant "4.100000") (signalLossTangent "0.035")) ("" (layerType "DIELECTRIC") (material "FR-4") (thickness "  3.300000 mil") (dielectricConstant "4.500000") (lossTangent "0.035") (etchFactor "0.000000") (elecCondVal "0 mho/cm") (thermCondVal "0 w/cm-degC")) ("L11_GND5" (layerType "PLANE") (material "COPPER") (isShield t) (thickness "  1.200000 mil") (dielectricConstant "4.500000") (lossTangent "0.035") (etchFactor "90.000000") (elecCondVal "595900.000000 mho/cm") (thermCondVal "0 w/cm-degC")) ("" (layerType "DIELECTRIC") (material "FR-4") (thickness "  9.900000 mil") (dielectricConstant "4.500000") (lossTangent "0.035") (etchFactor "0.000000") (elecCondVal "0 mho/cm") (thermCondVal "0.012 w/cm-degC")) ("L12_SIG4" (layerType "CONDUCTOR") (material "COPPER") (thickness "  1.200000 mil") (width "4.00 MIL") (dielectricConstant "4.500000") (lossTangent "0.035") (etchFactor "90.000000") (elecCondVal "595900.000000 mho/cm") (thermCondVal "0.012 w/cm-degC") (signalDieConstant "4.500000") (signalLossTangent "0.035")) ("" (layerType "DIELECTRIC") (material "FR-4") (thickness "  3.300000 mil") (dielectricConstant "4.500000") (lossTangent "0.035") (etchFactor "0.000000") (elecCondVal "0 mho/cm") (thermCondVal "0 w/cm-degC")) ("L13_GND6" (layerType "PLANE") (material "COPPER") (isShield t) (thickness "  1.200000 mil") (dielectricConstant "4.500000") (lossTangent "0.035") (etchFactor "90.000000") (elecCondVal "595900.000000 mho/cm") (thermCondVal "0.012 w/cm-degC")) ("" (layerType "DIELECTRIC") (material "FR-4") (thickness "  2.700000 mil") (dielectricConstant "4.500000") (lossTangent "0.035") (etchFactor "0.000000") (elecCondVal "0 mho/cm") (thermCondVal "0.012 w/cm-degC")) ("BOTTOM" (layerType "CONDUCTOR") (material "COPPER") (thickness "  1.800000 mil") (width "4.00 MIL") (dielectricConstant "4.500000") (lossTangent "0") (etchFactor "70.000000") (elecCondVal "595900.000000 mho/cm") (thermCondVal "0 w/cm-degC") (signalDieConstant "3.800000") (signalLossTangent "0.035")) ("" (layerType "DIELECTRIC") (material "CONFORMAL_COAT") (thickness "0.5 mil") (dielectricConstant "3.800000") (lossTangent "0.035") (etchFactor "0.000000") (elecCondVal "0 mho/cm") (thermCondVal "0.012 w/cm-degC")) ("" (layerType "SURFACE") (material "AIR") (thickness "0 mil") (dielectricConstant "1.000000") (lossTangent "0") (etchFactor "0.000000") (elecCondVal "0 mho/cm") (thermCondVal "0 w/cm-degC"))))) (Props (DesUnits "mils 2") (LayerStack ("DIELECTRIC" "DIELECTRIC" "BOTTOM" "DIELECTRIC" "L13_GND6" "DIELECTRIC" "L12_SIG4" "DIELECTRIC" "L11_GND5" "DIELECTRIC" "L10_SIG3" "DIELECTRIC" "L9_GND4" "DIELECTRIC" "L8_PWR2-SIG" "DIELECTRIC" "L7_PWR1-SIG" "DIELECTRIC" "L6_GND3" "DIELECTRIC" "L5_SIG2" "DIELECTRIC" "L4_GND2" "DIELECTRIC" "L3_SIG1" "DIELECTRIC" "L2_GND1" "DIELECTRIC" "TOP" "DIELECTRIC" "DIELECTRIC")) (Revision "16.600")) (Params (TheveninTerm ((resistanceUp "180 ohm") (resistanceDown "270 ohm") (voltageUp "5 V") (voltageDown "0 V") (maxDelay "0.1 ns"))) (ShuntTerm ((resistance "50 ohm") (voltage "5 V") (maxDelay "0.1 ns"))) (SeriesTerm ((resistance "22 ohm") (maxDelay "0.1 ns"))) (LowClampTerm ((cutoffVoltage "0.7 V") (voltage "0 V") (maxDelay "0.1 ns"))) (IbisIO_OpenPullDown ((temperature "27") (bufferModel "CDSDefaultIO_2p5v") (stimuli nil) (offsets nil) (state "tristate") (cycle "1") (termMap nil) (setup "2.0e-09") (hold "1.0e-09") (rise nil) (fall nil) (macroType nil) (voltage nil) (spice nil) (LEFDEFPinName nil) (LEFDEFPinType nil) (mappingTag nil))) (IbisIO_OpenPullUp ((temperature "27") (bufferModel "CDSDefaultIO_2p5v") (stimuli nil) (offsets nil) (state "tristate") (cycle "1") (termMap nil) (setup "2.0e-09") (hold "1.0e-09") (rise nil) (fall nil) (macroType nil) (voltage nil) (spice nil) (LEFDEFPinName nil) (LEFDEFPinType nil) (mappingTag nil))) (clocked ((clockRise "1e-09") (clockFall "1e-09") (clockFreq "100e6") (clockInitState "0") (clockDutyCycle "0.5") (clockJitter "0"))) (RCTerm ((resistance "50 ohm") (capacitance "20 pF") (voltage "5 V") (maxDelay "0.1 ns"))) (periodic ((periodicFreq "100e6") (periodicPattern "10") (periodicJitter "0"))) (Via ((model "Unknown") (viaOutputFormat "Unknown") (viaPadstack nil) (viaTopLayer nil) (viaBottomLayer nil) (viaIsPower nil) (viaIsGround nil))) (DualClampTerm ((cutoffVoltageUp "0.7 V") (cutoffVoltageDown "0.7 V") (voltageUp "5 V") (voltageDown "0 V") (maxDelay "0.1 ns"))) (IbisIOPkg ((temperature "27") (bufferModel "CDSDefaultIO_2p5v") (stimuli nil) (offsets nil) (state "tristate") (cycle "1") (termMap nil) (setup "2.0e-09") (hold "1.0e-09") (rise nil) (fall nil) (macroType nil) (voltage nil) (spice nil) (LEFDEFPinName nil) (LEFDEFPinType nil) (mappingTag nil))) (CurrentProbe nil) (HiClampTerm ((cutoffVoltage "0.7 V") (voltage "5 V") (maxDelay "0.1 ns"))) (IbisOutputPkg ((temperature "27") (bufferModel "CDSDefaultOutput_2p5v") (stimuli nil) (offsets nil) (state "tristate") (cycle "1") (termMap nil) (setup "2.0e-09") (hold "1.0e-09") (rise nil) (fall nil) (macroType nil) (voltage nil) (spice nil) (LEFDEFPinName nil) (LEFDEFPinType nil) (mappingTag nil))) (Diode ((cutoffVoltage "0.7 V"))) (IbisInputPkg ((temperature "27") (bufferModel "CDSDefaultInput_2p5v") (cycle "1") (LEFDEFPinName nil) (LEFDEFPinType nil) (mappingTag nil))) (async ((asyncTimePoints "") (asyncInitState "1"))) (ESpiceDevice nil) (IbisInput ((temperature "27") (bufferModel "CDSDefaultInput_2p5v") (cycle "1") (LEFDEFPinName nil) (LEFDEFPinType nil) (mappingTag nil))) (Trace ((d1Thickness "10 mil") (d1Constant "4.5") (d1LossTangent "0.035") (d2Thickness "10 mil") (d2Constant "4.5") (d2LossTangent "0.035") (d3Thickness "0.0") (d3Constant "1.0") (d3LossTangent "0") length("1000 mil") (spacing "5 mil") (spacing2 "5 mil") (spacing3 "5 mil") (spacing4 "5 mil") (spacing5 "5 mil") (traceConductivity "595900 mho/cm") (traceGeometry "microstrip") (traceLayerName "") (traceThickness "0.72 mil") (traceType "single") (traceWidth "5.0 mil") (traceWidth2 "5.0 mil") (traceWidth3 "5.0 mil") (traceWidth4 "5.0 mil") (traceWidth5 "5.0 mil") (traceWidth6 "5.0 mil") (offset "0 mil") (traceCount "1") (impedance nil))) (Cable (length("1 m"))) (Resistor ((resistance "50 ohm") (orientation "0"))) (DiffInput ((temperature "27") (bufferModelNonInverting "CDSDefaultInput_2p5v") (bufferModelInverting "CDSDefaultInput_2p5v") (threshInputHighMin "1.7 V") (threshInputHighTyp "1.7  V") (threshInputHighMax "1.7  V") (threshInputLowMin "0.7  V") (threshInputLowTyp "0.7  V") (threshInputLowMax "0.7  V") (mappingTagNonInverting nil) (mappingTagInverting nil) (cycle "1"))) (Source ((voltage "5 V"))) (DiffIOPkg ((temperature "27") (bufferModelNonInverting "CDSDefaultIO_2p5v") (bufferModelInverting "CDSDefaultIO_2p5v") (stimuli nil) (offsets nil) (state "tristate") (cycle "1") (termMap nil) (setup "0.9e-09") (hold "0.4e-09") (rise nil) (fall nil) (threshInputHighMin "1.7 V") (threshInputHighTyp "1.7  V") (threshInputHighMax "1.7  V") (threshInputLowMin "0.7  V") (threshInputLowTyp "0.7  V") (threshInputLowMax "0.7 ") (threshOutputHighMin "2.365  V") (threshOutputHighTyp "2.5  V") (threshOutputHighMax "2.625  V") (threshOutputLowMin "1.275  V") (threshOutputLowTyp "1.7  V") (threshOutputLowMax "1.985  V") (mappingTagNonInverting nil) (mappingTagInverting nil) (spice nil))) (IbisOutput ((temperature "27") (bufferModel "CDSDefaultOutput_2p5v") (stimuli nil) (offsets nil) (state "tristate") (cycle "1") (termMap nil) (setup "2.0e-09") (hold "1.0e-09") (rise nil) (fall nil) (macroType nil) (voltage nil) (spice nil) (LEFDEFPinName nil) (LEFDEFPinType nil) (mappingTag nil))) (IbisIO ((temperature "27") (bufferModel "CDSDefaultIO_2p5v") (stimuli nil) (offsets nil) (state "tristate") (cycle "1") (termMap nil) (setup "2.0e-09") (hold "1.0e-09") (rise nil) (fall nil) (macroType nil) (voltage nil) (spice nil) (LEFDEFPinName nil) (LEFDEFPinType nil) (mappingTag nil))) (RLGC (length("1000 mil"))) (DiffIO ((temperature "27") (bufferModelNonInverting "CDSDefaultIO_2p5v") (bufferModelInverting "CDSDefaultIO_2p5v") (stimuli nil) (offsets nil) (state "tristate") (cycle "1") (termMap nil) (setup "0.9e-09") (hold "0.4e-09") (rise nil) (fall nil) (threshInputHighMin "1.7 V") (threshInputHighTyp "1.7  V") (threshInputHighMax "1.7  V") (threshInputLowMin "0.7  V") (threshInputLowTyp "0.7  V") (threshInputLowMax "0.7 ") (threshOutputHighMin "2.365  V") (threshOutputHighTyp "2.5  V") (threshOutputHighMax "2.625  V") (threshOutputLowMin "1.275  V") (threshOutputLowTyp "1.7  V") (threshOutputLowMax "1.985  V") (mappingTagNonInverting nil) (mappingTagInverting nil) (spice nil))) (Capacitor ((capacitance "10 pF") (orientation "0"))) (DiffOutputPkg ((temperature "27") (bufferModelNonInverting "CDSDefaultOutput_2p5v") (bufferModelInverting "CDSDefaultOutput_2p5v") (stimuli nil) (offsets nil) (state "tristate") (cycle "1") (termMap nil) (setup "0.9e-09") (hold "0.4e-09") (rise nil) (fall nil) (threshOutputHighMin "2.375  V") (threshOutputHighTyp "2.5  V") (threshOutputHighMax "2.625  V") (threshOutputLowMin "1.275  V") (threshOutputLowTyp "1.7  V") (threshOutputLowMax "1.985  V") (mappingTagNonInverting nil) (mappingTagInverting nil) (spice nil))) (Inductor ((inductance "5 nH") (orientation "0"))) (DiffOutput ((temperature "27") (bufferModelNonInverting "CDSDefaultOutput_2p5v") (bufferModelInverting "CDSDefaultOutput_2p5v") (stimuli nil) (offsets nil) (state "tristate") (cycle "1") (termMap nil) (setup "0.9e-09") (hold "0.4e-09") (rise nil) (fall nil) (threshOutputHighMin "2.375  V") (threshOutputHighTyp "2.5  V") (threshOutputHighMax "2.625  V") (threshOutputLowMin "1.275  V") (threshOutputLowTyp "1.7  V") (threshOutputLowMax "1.985  V") (mappingTagNonInverting nil) (mappingTagInverting nil) (spice nil))) (CPWMS ((d1Thickness "10 mil") (d1Constant "4.5") (d1LossTangent "0.035") (d2Thickness "0.72 mil") (d2Constant "4.5") (d2LossTangent "0.035") (d3Thickness "0.0") (d3Constant "1") (d3LossTangent "0") length("1000 mil") (spacing "5 mil") (spacing2 "5 mil") (spacing3 "5 mil") (spacing4 "5 mil") (spacing5 "5 mil") (traceConductivity "595900 mho/cm") (traceGeometry "cpwms") (traceLayerName "") (traceThickness "0.72 mil") (traceType "single") (traceWidth "5.0 mil") (traceWidth2 "5.0 mil") (traceWidth3 "5.0 mil") (traceWidth4 "5.0 mil") (traceWidth5 "5.0 mil") (traceWidth6 "5.0 mil") (offset "0 mil") (traceCount "1") (impedance nil))) (CPW ((d1Thickness "10 mil") (d1Constant "4.5") (d1LossTangent "0.035") (d2Thickness "0.72 mil") (d2Constant "1") (d2LossTangent "0") (d3Thickness "0.0") (d3Constant "1") (d3LossTangent "0") length("1000 mil") (spacing "5 mil") (spacing2 "5 mil") (spacing3 "5 mil") (spacing4 "5 mil") (spacing5 "5 mil") (traceConductivity "595900 mho/cm") (traceGeometry "cpwms") (traceLayerName "") (traceThickness "0.72 mil") (traceType "single") (traceWidth "5.0 mil") (traceWidth2 "5.0 mil") (traceWidth3 "5.0 mil") (traceWidth4 "5.0 mil") (traceWidth5 "5.0 mil") (traceWidth6 "5.0 mil") (offset "0 mil") (traceCount "1") (impedance nil))) (idlCircuit ((allDrivers "active") (ftsMode '("Typ")) (rcvrSelect "all") (simMode "Reflection") (tlineDelayMode "time") (userRevision "1.0") (autoSolve "On"))) (CPWSL ((d1Thickness "10 mil") (d1Constant "4.5") (d1LossTangent "0.035") (d2Thickness "0.72 mil") (d2Constant "4.5") (d2LossTangent "0.035") (d3Thickness "10 mil") (d3Constant "4.5") (d3LossTangent "0.035") length("1000 mil") (spacing "5 mil") (spacing2 "5 mil") (spacing3 "5 mil") (spacing4 "5 mil") (spacing5 "5 mil") (traceConductivity "595900 mho/cm") (traceGeometry "cpwms") (traceLayerName "") (traceThickness "0.72 mil") (traceType "single") (traceWidth "5.0 mil") (traceWidth2 "5.0 mil") (traceWidth3 "5.0 mil") (traceWidth4 "5.0 mil") (traceWidth5 "5.0 mil") (traceWidth6 "5.0 mil") (offset "0 mil") (traceCount "1") (impedance nil))) (DiffInputPkg ((temperature "27") (bufferModelNonInverting "CDSDefaultInput_2p5v") (bufferModelInverting "CDSDefaultInput_2p5v") (threshInputHighMin "1.7 V") (threshInputHighTyp "1.7  V") (threshInputHighMax "1.7  V") (threshInputLowMin "0.7  V") (threshInputLowTyp "0.7  V") (threshInputLowMax "0.7  V") (mappingTagNonInverting nil) (mappingTagInverting nil) (cycle "1"))) (IbisIOMacro ((temperature "27") (bufferModel "CDSDefaultIO_2p5v") (stimuli nil) (offsets nil) (state "tristate") (cycle "1") (termMap nil) (setup "2.0e-09") (hold "1.0e-09") (rise nil) (fall nil) (macroType nil) (voltage nil) (spice nil) (LEFDEFPinName nil) (LEFDEFPinType nil) (mappingTag nil))) (IbisOutput_OpenPullUp ((temperature "27") (bufferModel "CDSDefaultOutput_2p5v") (stimuli nil) (offsets nil) (state "tristate") (cycle "1") (termMap nil) (setup "2.0e-09") (hold "1.0e-09") (rise nil) (fall nil) (macroType nil) (voltage nil) (spice nil) (LEFDEFPinName nil) (LEFDEFPinType nil) (mappingTag nil))) (Connector nil) (TLine ((diffImpedance "100ohm") (diffVelocity "1.4142e+08M/s") (impedance "60ohm") length("2800 mil") (propDelay "0.5 ns") (velocity "5600 mil/ns") (traceCount "1") (traceGeometry "Microstrip") (impedanceMin nil) (impedanceMax nil) (lengthMin nil) (lengthMax nil) (propDelayMin nil) (propDelayMax nil) (impedanceSweepCount nil) (propDelaySweepCount nil) (velocitySweepCount nil) (lengthSweepCount nil) (matchSetName nil))) (sync ((syncFreq "100e6") (syncInitState "1") (syncPattern "10") (syncEdgeSwitch "rise")))))
				)
				( objectStatus "DDR_E_CMD_DLL1-13" )
			)
			( electricalCSet "@crescent_city_bb_fab1_lib.crescent_city_bb_fab1(sch_1):\DDR_D_CMD_DLL1-13\"
				( groupRef "DDR_D_CMD_DLL1-13:MG_DDR_NEAR_DIMM-CLK1" )
				( groupRef "DDR_D_CMD_DLL1-13:MG_DDR_FAR_DIMM_CMD" )
				( groupRef "DDR_D_CMD_DLL1-13:MG_DDR_FAR_DIMM-CLK0" )
				( groupRef "DDR_D_CMD_DLL1-13:MG_DDR_CMD_NEAR_DIMM" )
				( pinPairRef "DDR_D_CMD_DLL1-13:U5D1.F51:J6M1.228" )
				( pinPairRef "DDR_D_CMD_DLL1-13:U5D1.F51:J4B1.228" )
				( attribute "TOPOLOGY_TEMPLATE_REVISION" "1.0"
					( Origin gBackEnd )
				)
				( topologyData 23949
(SKIDL (Circuits ("MAIN" (Parts ("CRESCENT_CITY_083_20140724_A.@@J1.228" IbisIOPkg (xy (5548 4240)) (refDes "J4B1") (model "Unknown") (Props (_SXDesignName "CRESCENT_CITY_083_20140724_A") (brdx "10643.7 MIL") (brdy "788.33 MIL") (bufferModel "CDSDefaultIO_2p5v") (cycle "1") (hold "1.0e-09") (mappingTag "") (offsets ("4" "0") ("5" "0")) (setup "2.0e-09") (state "tristate") (stimuli ("4" "local0") ("5" "local1")) (temperature "27") (termMap ("4" "Data") ("5" "Enable"))) (Terms ("CRESCENT_CITY_083_20140724_A.X1064370Y78833L2LRATS" "228"))) ("CRESCENT_CITY_083_20140724_A.@@J2.228" IbisIOPkg (xy (5528 4240)) (refDes "J6M1") (model "Unknown") (Props (_SXDesignName "CRESCENT_CITY_083_20140724_A") (brdx "10643.7 MIL") (brdy "796.23 MIL") (bufferModel "CDSDefaultIO_2p5v") (cycle "1") (hold "1.0e-09") (mappingTag "") (offsets ("4" "0") ("5" "0")) (setup "2.0e-09") (state "tristate") (stimuli ("4" "local2") ("5" "local15")) (temperature "27") (termMap ("4" "Data") ("5" "Enable"))) (Terms ("CRESCENT_CITY_083_20140724_A.X1064370Y79623L28LRATS" "228"))) ("CRESCENT_CITY_083_20140724_A.@@U36.F51" IbisIOPkg (xy (5502 4240)) (refDes "U5D1") (model "Unknown") (Props (_SXDesignName "CRESCENT_CITY_083_20140724_A") (brdx "10346.35 MIL") (brdy "2052.1 MIL") (bufferModel "CDSDefaultIO_2p5v") (cycle "1") (hold "1.0e-09") (mappingTag "") (offsets ("4" "0") ("5" "0")) (setup "2.0e-09") (state "tristate") (stimuli ("4" "local16") ("5" "local17")) (temperature "27") (termMap ("4" "Data") ("5" "Enable"))) (Terms ("CRESCENT_CITY_083_20140724_A.X1034635Y205210L2LRATS" "F51"))) ("CRESCENT_CITY_083_20140724_A.T@@RATS@@J2.228@@U36.F51" TLine (xy (5513 4235)) (mirror x) (refDes "TL1") (Props (_SXDesignName "CRESCENT_CITY_083_20140724_A") (impedance "53.474 ohm") length("1553.22 MIL") (propDelay "0.27897 ns") (traceCount "1") (traceGeometry "Microstrip") (velocity "5567.68 mil/ns")) (Terms ("CRESCENT_CITY_083_20140724_A.X1064370Y79623L28LRATS" "1") ("CRESCENT_CITY_083_20140724_A.X1034635Y205210L2LRATS" "2"))) ("CRESCENT_CITY_083_20140724_A.T@@RATS@@J2.228@@J1.228" TLine (xy (5539 4235)) (refDes "TL2") (Props (_SXDesignName "CRESCENT_CITY_083_20140724_A") (impedance "39.682 ohm") length("7.90 MIL") (propDelay "0.00142 ns") (traceCount "1") (traceGeometry "Microstrip") (velocity "5563.39 mil/ns")) (Terms ("CRESCENT_CITY_083_20140724_A.X1064370Y79623L28LRATS" "1") ("CRESCENT_CITY_083_20140724_A.X1064370Y78833L2LRATS" "2")))) (Nodes ("CRESCENT_CITY_083_20140724_A.X1034635Y205210L2LRATS" (terms "CRESCENT_CITY_083_20140724_A.T@@RATS@@J2.228@@U36.F51.2" "CRESCENT_CITY_083_20140724_A.@@U36.F51.1")) ("CRESCENT_CITY_083_20140724_A.X1064370Y78833L2LRATS" (terms "CRESCENT_CITY_083_20140724_A.T@@RATS@@J2.228@@J1.228.2" "CRESCENT_CITY_083_20140724_A.@@J1.228.1")) ("CRESCENT_CITY_083_20140724_A.X1064370Y79623L28LRATS" (terms "CRESCENT_CITY_083_20140724_A.T@@RATS@@J2.228@@J1.228.1" "CRESCENT_CITY_083_20140724_A.T@@RATS@@J2.228@@U36.F51.1" "CRESCENT_CITY_083_20140724_A.@@J2.228.1"))) (Ports) (Stimuli ("local2" (scope local) (stimType periodic) (Props (periodicFreq "5e+007") (periodicJitter "0") (periodicPattern "1"))) ("local15" (scope local) (stimType periodic) (Props (periodicFreq "5e+007") (periodicJitter "0") (periodicPattern "1"))) ("local0" (scope local) (stimType periodic) (Props (periodicFreq "5e+007") (periodicJitter "0") (periodicPattern "1"))) ("local16" (scope local) (stimType periodic) (Props (periodicFreq "5e+007") (periodicJitter "0") (periodicPattern "1"))) ("local1" (scope local) (stimType periodic) (Props (periodicFreq "5e+007") (periodicJitter "0") (periodicPattern "1"))) ("local17" (scope local) (stimType periodic) (Props (periodicFreq "5e+007") (periodicJitter "0") (periodicPattern "1")))) (Notes) (Constraints ("RELATIVE_PROPAGATION_DELAY" ("MG_DDR_NEAR_DIMM-CLK1" "CRESCENT_CITY_083_20140724_A U36.F51" "CRESCENT_CITY_083_20140724_A J8.228" "CLASS" "LENGTH" "0.01778" "LENGTH" "0") ("MG_DDR_FAR_DIMM_CMD" "CRESCENT_CITY_083_20140724_A U36.F51" "CRESCENT_CITY_083_20140724_A J7.228" "NET GROUP" "LENGTH" "0.000635" "LENGTH" "0") ("MG_DDR_FAR_DIMM-CLK0" "CRESCENT_CITY_083_20140724_A U36.F51" "CRESCENT_CITY_083_20140724_A J7.228" "CLASS" "LENGTH" "0.01778" "LENGTH" "0") ("MG_DDR_CMD_NEAR_DIMM" "CRESCENT_CITY_083_20140724_A U36.F51" "CRESCENT_CITY_083_20140724_A J8.228" "NET GROUP" "LENGTH" "0.000635" "LENGTH" "0"))) (MeasurementSets ("EMI" ("EMIStatus" status("on")) ("PeakEmission" status("on")) ("PeakFrequency" status("on")) ("PulseFreq" status("on")) ("RiseTime" status("on")) ("VoltageSwing" status("on"))) ("Reflection" ("BufferDelayFall" status("off")) ("BufferDelayRise" status("off")) ("EyeHeight" status("off")) ("EyeJitter" status("off")) ("EyeWidth" status("off")) ("FirstIncidentFall" status("off")) ("FirstIncidentRise" status("off")) ("Glitch" status("on")) ("GlitchFall" status("off")) ("GlitchRise" status("off")) ("Monotonic" status("on")) ("MonotonicFall" status("off")) ("MonotonicRise" status("off")) ("NoiseMargin" status("on")) ("NoiseMarginHigh" status("off")) ("NoiseMarginLow" status("off")) ("OvershootHigh" status("on")) ("OvershootLow" status("on")) ("PropDelay" status("on")) ("SettleDelay" status("on")) ("SettleDelayFall" status("off")) ("SettleDelayRise" status("off")) ("SwitchDelay" status("on")) ("SwitchDelayFall" status("off")) ("SwitchDelayRise" status("off"))) ("Crosstalk" ("Crosstalk" status("on"))) ("Custom")) (VectorSets) (Props (XnetName "M_A_MA<14>") (allDrivers "active") (autoSolve "Off") (customSimType "Reflection") (ftsMode ("Typ")) (rcvrSelect "all") (tlineDelayMode "time") (userRevision "1.0")))) (Subckts) (CrossSections ("CRESCENT_CITY_083_20140724_A" (Props (SXDesignName "CRESCENT_CITY_083_20140724_A")) (Layers ("" (layerType "SURFACE") (material "AIR") (thickness "0 mil") (dielectricConstant "1.000000") (lossTangent "0") (etchFactor "0.000000") (elecCondVal "0 mho/cm") (thermCondVal "0 w/cm-degC")) ("" (layerType "DIELECTRIC") (material "CONFORMAL_COAT") (thickness "0.5 mil") (dielectricConstant "3.800000") (lossTangent "0.035") (etchFactor "0.000000") (elecCondVal "0 mho/cm") (thermCondVal "0.012 w/cm-degC")) ("TOP" (layerType "CONDUCTOR") (material "COPPER") (thickness "  1.800000 mil") (width "4.00 MIL") (dielectricConstant "4.500000") (lossTangent "0") (etchFactor "70.000000") (elecCondVal "595900.000000 mho/cm") (thermCondVal "0 w/cm-degC") (signalDieConstant "3.800000") (signalLossTangent "0.035")) ("" (layerType "DIELECTRIC") (material "FR-4") (thickness "  2.700000 mil") (dielectricConstant "4.000000") (lossTangent "0.035") (etchFactor "0.000000") (elecCondVal "0 mho/cm") (thermCondVal "0.012 w/cm-degC")) ("L2_GND1" (layerType "PLANE") (material "COPPER") (isShield t) (thickness "  1.200000 mil") (dielectricConstant "4.500000") (lossTangent "0.035") (etchFactor "90.000000") (elecCondVal "595900.000000 mho/cm") (thermCondVal "0.012 w/cm-degC")) ("" (layerType "DIELECTRIC") (material "FR-4") (thickness "  9.900000 mil") (dielectricConstant "4.100000") (lossTangent "0.035") (etchFactor "0.000000") (elecCondVal "0 mho/cm") (thermCondVal "0.012 w/cm-degC")) ("L3_SIG1" (layerType "CONDUCTOR") (material "COPPER") (thickness "  1.200000 mil") (width "4.00 MIL") (dielectricConstant "4.500000") (lossTangent "0.035") (etchFactor "90.000000") (elecCondVal "595900.000000 mho/cm") (thermCondVal "0.012 w/cm-degC") (signalDieConstant "4.100000") (signalLossTangent "0.035")) ("" (layerType "DIELECTRIC") (material "FR-4") (thickness "  3.300000 mil") (dielectricConstant "4.500000") (lossTangent "0.035") (etchFactor "0.000000") (elecCondVal "0 mho/cm") (thermCondVal "0 w/cm-degC")) ("L4_GND2" (layerType "PLANE") (material "COPPER") (isShield t) (thickness "  1.200000 mil") (dielectricConstant "4.500000") (lossTangent "0.035") (etchFactor "90.000000") (elecCondVal "595900.000000 mho/cm") (thermCondVal "0 w/cm-degC")) ("" (layerType "DIELECTRIC") (material "FR-4") (thickness "  3.300000 mil") (dielectricConstant "4.000000") (lossTangent "0.035") (etchFactor "0.000000") (elecCondVal "0 mho/cm") (thermCondVal "0.012 w/cm-degC")) ("L5_SIG2" (layerType "CONDUCTOR") (material "COPPER") (thickness "  1.200000 mil") (width "4.00 MIL") (dielectricConstant "4.500000") (lossTangent "0.035") (etchFactor "90.000000") (elecCondVal "595900.000000 mho/cm") (thermCondVal "0.012 w/cm-degC") (signalDieConstant "4.000000") (signalLossTangent "0.035")) ("" (layerType "DIELECTRIC") (material "FR-4") (thickness "  9.900000 mil") (dielectricConstant "4.500000") (lossTangent "0.035") (etchFactor "0.000000") (elecCondVal "0 mho/cm") (thermCondVal "0 w/cm-degC")) ("L6_GND3" (layerType "PLANE") (material "COPPER") (isShield t) (thickness "  1.200000 mil") (dielectricConstant "4.500000") (lossTangent "0.035") (etchFactor "90.000000") (elecCondVal "595900.000000 mho/cm") (thermCondVal "0 w/cm-degC")) ("" (layerType "DIELECTRIC") (material "FR-4") (thickness "  3.300000 mil") (dielectricConstant "4.100000") (lossTangent "0.035") (etchFactor "0.000000") (elecCondVal "0 mho/cm") (thermCondVal "0.012 w/cm-degC")) ("L7_PWR1-SIG" (layerType "PLANE") (material "COPPER") (isShield t) (thickness "  1.200000 mil") (dielectricConstant "4.500000") (lossTangent "0.035") (etchFactor "90.000000") (elecCondVal "595900.000000 mho/cm") (thermCondVal "0.012 w/cm-degC")) ("" (layerType "DIELECTRIC") (material "FR-4") (thickness "  9.900000 mil") (dielectricConstant "4.000000") (lossTangent "0.035") (etchFactor "0.000000") (elecCondVal "0 mho/cm") (thermCondVal "0.012 w/cm-degC")) ("L8_PWR2-SIG" (layerType "PLANE") (material "COPPER") (isShield t) (thickness "  1.200000 mil") (dielectricConstant "4.500000") (lossTangent "0.035") (etchFactor "90.000000") (elecCondVal "595900.000000 mho/cm") (thermCondVal "0.012 w/cm-degC")) ("" (layerType "DIELECTRIC") (material "FR-4") (thickness "  3.300000 mil") (dielectricConstant "4.500000") (lossTangent "0.035") (etchFactor "0.000000") (elecCondVal "0 mho/cm") (thermCondVal "0 w/cm-degC")) ("L9_GND4" (layerType "PLANE") (material "COPPER") (isShield t) (thickness "  1.200000 mil") (dielectricConstant "4.500000") (lossTangent "0.035") (etchFactor "90.000000") (elecCondVal "595900.000000 mho/cm") (thermCondVal "0 w/cm-degC")) ("" (layerType "DIELECTRIC") (material "FR-4") (thickness "  9.900000 mil") (dielectricConstant "4.100000") (lossTangent "0.035") (etchFactor "0.000000") (elecCondVal "0 mho/cm") (thermCondVal "0.012 w/cm-degC")) ("L10_SIG3" (layerType "CONDUCTOR") (material "COPPER") (thickness "  1.200000 mil") (width "4.00 MIL") (dielectricConstant "4.500000") (lossTangent "0.035") (etchFactor "90.000000") (elecCondVal "595900.000000 mho/cm") (thermCondVal "0.012 w/cm-degC") (signalDieConstant "4.100000") (signalLossTangent "0.035")) ("" (layerType "DIELECTRIC") (material "FR-4") (thickness "  3.300000 mil") (dielectricConstant "4.500000") (lossTangent "0.035") (etchFactor "0.000000") (elecCondVal "0 mho/cm") (thermCondVal "0 w/cm-degC")) ("L11_GND5" (layerType "PLANE") (material "COPPER") (isShield t) (thickness "  1.200000 mil") (dielectricConstant "4.500000") (lossTangent "0.035") (etchFactor "90.000000") (elecCondVal "595900.000000 mho/cm") (thermCondVal "0 w/cm-degC")) ("" (layerType "DIELECTRIC") (material "FR-4") (thickness "  9.900000 mil") (dielectricConstant "4.500000") (lossTangent "0.035") (etchFactor "0.000000") (elecCondVal "0 mho/cm") (thermCondVal "0.012 w/cm-degC")) ("L12_SIG4" (layerType "CONDUCTOR") (material "COPPER") (thickness "  1.200000 mil") (width "4.00 MIL") (dielectricConstant "4.500000") (lossTangent "0.035") (etchFactor "90.000000") (elecCondVal "595900.000000 mho/cm") (thermCondVal "0.012 w/cm-degC") (signalDieConstant "4.500000") (signalLossTangent "0.035")) ("" (layerType "DIELECTRIC") (material "FR-4") (thickness "  3.300000 mil") (dielectricConstant "4.500000") (lossTangent "0.035") (etchFactor "0.000000") (elecCondVal "0 mho/cm") (thermCondVal "0 w/cm-degC")) ("L13_GND6" (layerType "PLANE") (material "COPPER") (isShield t) (thickness "  1.200000 mil") (dielectricConstant "4.500000") (lossTangent "0.035") (etchFactor "90.000000") (elecCondVal "595900.000000 mho/cm") (thermCondVal "0.012 w/cm-degC")) ("" (layerType "DIELECTRIC") (material "FR-4") (thickness "  2.700000 mil") (dielectricConstant "4.500000") (lossTangent "0.035") (etchFactor "0.000000") (elecCondVal "0 mho/cm") (thermCondVal "0.012 w/cm-degC")) ("BOTTOM" (layerType "CONDUCTOR") (material "COPPER") (thickness "  1.800000 mil") (width "4.00 MIL") (dielectricConstant "4.500000") (lossTangent "0") (etchFactor "70.000000") (elecCondVal "595900.000000 mho/cm") (thermCondVal "0 w/cm-degC") (signalDieConstant "3.800000") (signalLossTangent "0.035")) ("" (layerType "DIELECTRIC") (material "CONFORMAL_COAT") (thickness "0.5 mil") (dielectricConstant "3.800000") (lossTangent "0.035") (etchFactor "0.000000") (elecCondVal "0 mho/cm") (thermCondVal "0.012 w/cm-degC")) ("" (layerType "SURFACE") (material "AIR") (thickness "0 mil") (dielectricConstant "1.000000") (lossTangent "0") (etchFactor "0.000000") (elecCondVal "0 mho/cm") (thermCondVal "0 w/cm-degC"))))) (Props (DesUnits "mils 2") (LayerStack ("DIELECTRIC" "DIELECTRIC" "BOTTOM" "DIELECTRIC" "L13_GND6" "DIELECTRIC" "L12_SIG4" "DIELECTRIC" "L11_GND5" "DIELECTRIC" "L10_SIG3" "DIELECTRIC" "L9_GND4" "DIELECTRIC" "L8_PWR2-SIG" "DIELECTRIC" "L7_PWR1-SIG" "DIELECTRIC" "L6_GND3" "DIELECTRIC" "L5_SIG2" "DIELECTRIC" "L4_GND2" "DIELECTRIC" "L3_SIG1" "DIELECTRIC" "L2_GND1" "DIELECTRIC" "TOP" "DIELECTRIC" "DIELECTRIC")) (Revision "16.600")) (Params (TheveninTerm ((resistanceUp "180 ohm") (resistanceDown "270 ohm") (voltageUp "5 V") (voltageDown "0 V") (maxDelay "0.1 ns"))) (ShuntTerm ((resistance "50 ohm") (voltage "5 V") (maxDelay "0.1 ns"))) (SeriesTerm ((resistance "22 ohm") (maxDelay "0.1 ns"))) (LowClampTerm ((cutoffVoltage "0.7 V") (voltage "0 V") (maxDelay "0.1 ns"))) (IbisIO_OpenPullDown ((temperature "27") (bufferModel "CDSDefaultIO_2p5v") (stimuli nil) (offsets nil) (state "tristate") (cycle "1") (termMap nil) (setup "2.0e-09") (hold "1.0e-09") (rise nil) (fall nil) (macroType nil) (voltage nil) (spice nil) (LEFDEFPinName nil) (LEFDEFPinType nil) (mappingTag nil))) (IbisIO_OpenPullUp ((temperature "27") (bufferModel "CDSDefaultIO_2p5v") (stimuli nil) (offsets nil) (state "tristate") (cycle "1") (termMap nil) (setup "2.0e-09") (hold "1.0e-09") (rise nil) (fall nil) (macroType nil) (voltage nil) (spice nil) (LEFDEFPinName nil) (LEFDEFPinType nil) (mappingTag nil))) (clocked ((clockRise "1e-09") (clockFall "1e-09") (clockFreq "100e6") (clockInitState "0") (clockDutyCycle "0.5") (clockJitter "0"))) (RCTerm ((resistance "50 ohm") (capacitance "20 pF") (voltage "5 V") (maxDelay "0.1 ns"))) (periodic ((periodicFreq "100e6") (periodicPattern "10") (periodicJitter "0"))) (Via ((model "Unknown") (viaOutputFormat "Unknown") (viaPadstack nil) (viaTopLayer nil) (viaBottomLayer nil) (viaIsPower nil) (viaIsGround nil))) (DualClampTerm ((cutoffVoltageUp "0.7 V") (cutoffVoltageDown "0.7 V") (voltageUp "5 V") (voltageDown "0 V") (maxDelay "0.1 ns"))) (IbisIOPkg ((temperature "27") (bufferModel "CDSDefaultIO_2p5v") (stimuli nil) (offsets nil) (state "tristate") (cycle "1") (termMap nil) (setup "2.0e-09") (hold "1.0e-09") (rise nil) (fall nil) (macroType nil) (voltage nil) (spice nil) (LEFDEFPinName nil) (LEFDEFPinType nil) (mappingTag nil))) (CurrentProbe nil) (HiClampTerm ((cutoffVoltage "0.7 V") (voltage "5 V") (maxDelay "0.1 ns"))) (IbisOutputPkg ((temperature "27") (bufferModel "CDSDefaultOutput_2p5v") (stimuli nil) (offsets nil) (state "tristate") (cycle "1") (termMap nil) (setup "2.0e-09") (hold "1.0e-09") (rise nil) (fall nil) (macroType nil) (voltage nil) (spice nil) (LEFDEFPinName nil) (LEFDEFPinType nil) (mappingTag nil))) (Diode ((cutoffVoltage "0.7 V"))) (IbisInputPkg ((temperature "27") (bufferModel "CDSDefaultInput_2p5v") (cycle "1") (LEFDEFPinName nil) (LEFDEFPinType nil) (mappingTag nil))) (async ((asyncTimePoints "") (asyncInitState "1"))) (ESpiceDevice nil) (IbisInput ((temperature "27") (bufferModel "CDSDefaultInput_2p5v") (cycle "1") (LEFDEFPinName nil) (LEFDEFPinType nil) (mappingTag nil))) (Trace ((d1Thickness "10 mil") (d1Constant "4.5") (d1LossTangent "0.035") (d2Thickness "10 mil") (d2Constant "4.5") (d2LossTangent "0.035") (d3Thickness "0.0") (d3Constant "1.0") (d3LossTangent "0") length("1000 mil") (spacing "5 mil") (spacing2 "5 mil") (spacing3 "5 mil") (spacing4 "5 mil") (spacing5 "5 mil") (traceConductivity "595900 mho/cm") (traceGeometry "microstrip") (traceLayerName "") (traceThickness "0.72 mil") (traceType "single") (traceWidth "5.0 mil") (traceWidth2 "5.0 mil") (traceWidth3 "5.0 mil") (traceWidth4 "5.0 mil") (traceWidth5 "5.0 mil") (traceWidth6 "5.0 mil") (offset "0 mil") (traceCount "1") (impedance nil))) (Cable (length("1 m"))) (Resistor ((resistance "50 ohm") (orientation "0"))) (DiffInput ((temperature "27") (bufferModelNonInverting "CDSDefaultInput_2p5v") (bufferModelInverting "CDSDefaultInput_2p5v") (threshInputHighMin "1.7 V") (threshInputHighTyp "1.7  V") (threshInputHighMax "1.7  V") (threshInputLowMin "0.7  V") (threshInputLowTyp "0.7  V") (threshInputLowMax "0.7  V") (mappingTagNonInverting nil) (mappingTagInverting nil) (cycle "1"))) (Source ((voltage "5 V"))) (DiffIOPkg ((temperature "27") (bufferModelNonInverting "CDSDefaultIO_2p5v") (bufferModelInverting "CDSDefaultIO_2p5v") (stimuli nil) (offsets nil) (state "tristate") (cycle "1") (termMap nil) (setup "0.9e-09") (hold "0.4e-09") (rise nil) (fall nil) (threshInputHighMin "1.7 V") (threshInputHighTyp "1.7  V") (threshInputHighMax "1.7  V") (threshInputLowMin "0.7  V") (threshInputLowTyp "0.7  V") (threshInputLowMax "0.7 ") (threshOutputHighMin "2.365  V") (threshOutputHighTyp "2.5  V") (threshOutputHighMax "2.625  V") (threshOutputLowMin "1.275  V") (threshOutputLowTyp "1.7  V") (threshOutputLowMax "1.985  V") (mappingTagNonInverting nil) (mappingTagInverting nil) (spice nil))) (IbisOutput ((temperature "27") (bufferModel "CDSDefaultOutput_2p5v") (stimuli nil) (offsets nil) (state "tristate") (cycle "1") (termMap nil) (setup "2.0e-09") (hold "1.0e-09") (rise nil) (fall nil) (macroType nil) (voltage nil) (spice nil) (LEFDEFPinName nil) (LEFDEFPinType nil) (mappingTag nil))) (IbisIO ((temperature "27") (bufferModel "CDSDefaultIO_2p5v") (stimuli nil) (offsets nil) (state "tristate") (cycle "1") (termMap nil) (setup "2.0e-09") (hold "1.0e-09") (rise nil) (fall nil) (macroType nil) (voltage nil) (spice nil) (LEFDEFPinName nil) (LEFDEFPinType nil) (mappingTag nil))) (RLGC (length("1000 mil"))) (DiffIO ((temperature "27") (bufferModelNonInverting "CDSDefaultIO_2p5v") (bufferModelInverting "CDSDefaultIO_2p5v") (stimuli nil) (offsets nil) (state "tristate") (cycle "1") (termMap nil) (setup "0.9e-09") (hold "0.4e-09") (rise nil) (fall nil) (threshInputHighMin "1.7 V") (threshInputHighTyp "1.7  V") (threshInputHighMax "1.7  V") (threshInputLowMin "0.7  V") (threshInputLowTyp "0.7  V") (threshInputLowMax "0.7 ") (threshOutputHighMin "2.365  V") (threshOutputHighTyp "2.5  V") (threshOutputHighMax "2.625  V") (threshOutputLowMin "1.275  V") (threshOutputLowTyp "1.7  V") (threshOutputLowMax "1.985  V") (mappingTagNonInverting nil) (mappingTagInverting nil) (spice nil))) (Capacitor ((capacitance "10 pF") (orientation "0"))) (DiffOutputPkg ((temperature "27") (bufferModelNonInverting "CDSDefaultOutput_2p5v") (bufferModelInverting "CDSDefaultOutput_2p5v") (stimuli nil) (offsets nil) (state "tristate") (cycle "1") (termMap nil) (setup "0.9e-09") (hold "0.4e-09") (rise nil) (fall nil) (threshOutputHighMin "2.375  V") (threshOutputHighTyp "2.5  V") (threshOutputHighMax "2.625  V") (threshOutputLowMin "1.275  V") (threshOutputLowTyp "1.7  V") (threshOutputLowMax "1.985  V") (mappingTagNonInverting nil) (mappingTagInverting nil) (spice nil))) (Inductor ((inductance "5 nH") (orientation "0"))) (DiffOutput ((temperature "27") (bufferModelNonInverting "CDSDefaultOutput_2p5v") (bufferModelInverting "CDSDefaultOutput_2p5v") (stimuli nil) (offsets nil) (state "tristate") (cycle "1") (termMap nil) (setup "0.9e-09") (hold "0.4e-09") (rise nil) (fall nil) (threshOutputHighMin "2.375  V") (threshOutputHighTyp "2.5  V") (threshOutputHighMax "2.625  V") (threshOutputLowMin "1.275  V") (threshOutputLowTyp "1.7  V") (threshOutputLowMax "1.985  V") (mappingTagNonInverting nil) (mappingTagInverting nil) (spice nil))) (CPWMS ((d1Thickness "10 mil") (d1Constant "4.5") (d1LossTangent "0.035") (d2Thickness "0.72 mil") (d2Constant "4.5") (d2LossTangent "0.035") (d3Thickness "0.0") (d3Constant "1") (d3LossTangent "0") length("1000 mil") (spacing "5 mil") (spacing2 "5 mil") (spacing3 "5 mil") (spacing4 "5 mil") (spacing5 "5 mil") (traceConductivity "595900 mho/cm") (traceGeometry "cpwms") (traceLayerName "") (traceThickness "0.72 mil") (traceType "single") (traceWidth "5.0 mil") (traceWidth2 "5.0 mil") (traceWidth3 "5.0 mil") (traceWidth4 "5.0 mil") (traceWidth5 "5.0 mil") (traceWidth6 "5.0 mil") (offset "0 mil") (traceCount "1") (impedance nil))) (CPW ((d1Thickness "10 mil") (d1Constant "4.5") (d1LossTangent "0.035") (d2Thickness "0.72 mil") (d2Constant "1") (d2LossTangent "0") (d3Thickness "0.0") (d3Constant "1") (d3LossTangent "0") length("1000 mil") (spacing "5 mil") (spacing2 "5 mil") (spacing3 "5 mil") (spacing4 "5 mil") (spacing5 "5 mil") (traceConductivity "595900 mho/cm") (traceGeometry "cpwms") (traceLayerName "") (traceThickness "0.72 mil") (traceType "single") (traceWidth "5.0 mil") (traceWidth2 "5.0 mil") (traceWidth3 "5.0 mil") (traceWidth4 "5.0 mil") (traceWidth5 "5.0 mil") (traceWidth6 "5.0 mil") (offset "0 mil") (traceCount "1") (impedance nil))) (idlCircuit ((allDrivers "active") (ftsMode '("Typ")) (rcvrSelect "all") (simMode "Reflection") (tlineDelayMode "time") (userRevision "1.0") (autoSolve "On"))) (CPWSL ((d1Thickness "10 mil") (d1Constant "4.5") (d1LossTangent "0.035") (d2Thickness "0.72 mil") (d2Constant "4.5") (d2LossTangent "0.035") (d3Thickness "10 mil") (d3Constant "4.5") (d3LossTangent "0.035") length("1000 mil") (spacing "5 mil") (spacing2 "5 mil") (spacing3 "5 mil") (spacing4 "5 mil") (spacing5 "5 mil") (traceConductivity "595900 mho/cm") (traceGeometry "cpwms") (traceLayerName "") (traceThickness "0.72 mil") (traceType "single") (traceWidth "5.0 mil") (traceWidth2 "5.0 mil") (traceWidth3 "5.0 mil") (traceWidth4 "5.0 mil") (traceWidth5 "5.0 mil") (traceWidth6 "5.0 mil") (offset "0 mil") (traceCount "1") (impedance nil))) (DiffInputPkg ((temperature "27") (bufferModelNonInverting "CDSDefaultInput_2p5v") (bufferModelInverting "CDSDefaultInput_2p5v") (threshInputHighMin "1.7 V") (threshInputHighTyp "1.7  V") (threshInputHighMax "1.7  V") (threshInputLowMin "0.7  V") (threshInputLowTyp "0.7  V") (threshInputLowMax "0.7  V") (mappingTagNonInverting nil) (mappingTagInverting nil) (cycle "1"))) (IbisIOMacro ((temperature "27") (bufferModel "CDSDefaultIO_2p5v") (stimuli nil) (offsets nil) (state "tristate") (cycle "1") (termMap nil) (setup "2.0e-09") (hold "1.0e-09") (rise nil) (fall nil) (macroType nil) (voltage nil) (spice nil) (LEFDEFPinName nil) (LEFDEFPinType nil) (mappingTag nil))) (IbisOutput_OpenPullUp ((temperature "27") (bufferModel "CDSDefaultOutput_2p5v") (stimuli nil) (offsets nil) (state "tristate") (cycle "1") (termMap nil) (setup "2.0e-09") (hold "1.0e-09") (rise nil) (fall nil) (macroType nil) (voltage nil) (spice nil) (LEFDEFPinName nil) (LEFDEFPinType nil) (mappingTag nil))) (Connector nil) (TLine ((diffImpedance "100ohm") (diffVelocity "1.4142e+08M/s") (impedance "60ohm") length("2800 mil") (propDelay "0.5 ns") (velocity "5600 mil/ns") (traceCount "1") (traceGeometry "Microstrip") (impedanceMin nil) (impedanceMax nil) (lengthMin nil) (lengthMax nil) (propDelayMin nil) (propDelayMax nil) (impedanceSweepCount nil) (propDelaySweepCount nil) (velocitySweepCount nil) (lengthSweepCount nil) (matchSetName nil))) (sync ((syncFreq "100e6") (syncInitState "1") (syncPattern "10") (syncEdgeSwitch "rise")))))
				)
				( objectStatus "DDR_D_CMD_DLL1-13" )
			)
			( electricalCSet "@crescent_city_bb_fab1_lib.crescent_city_bb_fab1(sch_1):\DDR_DQS_A\"
				( groupRef "DDR_DQS:MG_DQ-DQS_FAR_DIMM" )
				( groupRef "DDR_DQS:MG_DQ-DQS_NEAR_DIMM" )
				( pinPairRef "DDR_DQS:U5D1.AJ84:J4G1.152" )
				( pinPairRef "DDR_DQS:U5D1.AJ84:J6T1.152" )
				( attribute "DIFFP_GATHER_CONTROL" "IGNORE"
					( Origin gBackEnd )
				)
				( attribute "DIFFP_UNCOUPLED_LENGTH" "1300.00"
					( Origin gBackEnd )
				)
				( attribute "DIFFP_COUPLED_PLUS" "0.10"
					( Origin gBackEnd )
				)
				( attribute "DIFFP_COUPLED_MINUS" "0.20"
					( Origin gBackEnd )
				)
				( attribute "DIFFP_PHASE_TOL" "5 mil"
					( Units "uPhaseTol" "ns" 1.000000)
					( Origin gBackEnd )
				)
				( attribute "DIFFP_PHASE_MAX_LENGTH" "600.00"
					( Origin gBackEnd )
				)
				( attribute "DIFFP_PHASE_TOL_DYNAMIC" "600 mil"
					( Units "uPhaseTol" "mil" 1.000000)
					( Origin gBackEnd )
				)
				( attribute "TOPOLOGY_TEMPLATE_REVISION" "1.0"
					( Origin gBackEnd )
				)
				( topologyData 21521
(SKIDL (Circuits ("MAIN" (Parts ("CRESCENT_CITY_065_20140613_B.@@J2.152" IbisIOPkg (xy (5522 4240)) (refDes "J6T1") (model "Unknown") (Props (_SXDesignName "CRESCENT_CITY_065_20140613_B") (brdx "12417.32 MIL") (brdy "5231.33 MIL") (bufferModel "CDSDefaultIO_2p5v") (cycle "1") (hold "1.0e-09") (offsets ("4" "0") ("5" "0")) (setup "2.0e-09") (state "tristate") (stimuli ("5" "local4") ("4" "local3")) (temperature "27") (termMap ("4" "Data") ("5" "Enable"))) (Terms ("CRESCENT_CITY_065_20140613_B.X1241732Y523133L20LRATS" "152"))) ("CRESCENT_CITY_065_20140613_B.@@U36.AJ84" IbisIOPkg (xy (5542 4240)) (refDes "U5D1") (model "Unknown") (Props (_SXDesignName "CRESCENT_CITY_065_20140613_B") (brdx "11085.95 MIL") (brdy "3526.96 MIL") (bufferModel "CDSDefaultIO_2p5v") (cycle "1") (hold "1.0e-09") (offsets ("4" "0") ("5" "0")) (setup "2.0e-09") (state "tristate") (stimuli ("5" "local6") ("4" "local5")) (temperature "27") (termMap ("4" "Data") ("5" "Enable"))) (Terms ("CRESCENT_CITY_065_20140613_B.X1108595Y352696L2LRATS" "AJ84"))) ("CRESCENT_CITY_065_20140613_B.@@J1.152" IbisIOPkg (xy (5502 4240)) (refDes "J4G1") (model "Unknown") (Props (_SXDesignName "CRESCENT_CITY_065_20140613_B") (brdx "12417.32 MIL") (brdy "5239.23 MIL") (bufferModel "CDSDefaultIO_2p5v") (cycle "1") (hold "1.0e-09") (offsets ("4" "0") ("5" "0")) (setup "2.0e-09") (state "tristate") (stimuli ("5" "local8") ("4" "local7")) (temperature "27") (termMap ("4" "Data") ("5" "Enable"))) (Terms ("CRESCENT_CITY_065_20140613_B.X1241732Y523923L2LRATS" "152"))) ("CRESCENT_CITY_065_20140613_B.T@@RATS@@J2.152@@U36.AJ84" TLine (xy (5533 4235)) (refDes "TL1") (Props (_SXDesignName "CRESCENT_CITY_065_20140613_B") (impedance "55.247 ohm") length("3035.74 MIL") (propDelay "0.54524 ns") (traceCount "1") (traceGeometry "Microstrip") (velocity "5567.72 mil/ns")) (Terms ("CRESCENT_CITY_065_20140613_B.X1241732Y523133L20LRATS" "1") ("CRESCENT_CITY_065_20140613_B.X1108595Y352696L2LRATS" "2"))) ("CRESCENT_CITY_065_20140613_B.T@@RATS@@J1.152@@J2.152" TLine (xy (5513 4235)) (refDes "TL2") (Props (_SXDesignName "CRESCENT_CITY_065_20140613_B") (impedance "39.475 ohm") length("7.90 MIL") (propDelay "0.00142 ns") (traceCount "1") (traceGeometry "Microstrip") (velocity "5563.39 mil/ns")) (Terms ("CRESCENT_CITY_065_20140613_B.X1241732Y523923L2LRATS" "1") ("CRESCENT_CITY_065_20140613_B.X1241732Y523133L20LRATS" "2")))) (Nodes ("CRESCENT_CITY_065_20140613_B.X1241732Y523133L20LRATS" (terms "CRESCENT_CITY_065_20140613_B.T@@RATS@@J1.152@@J2.152.2" "CRESCENT_CITY_065_20140613_B.T@@RATS@@J2.152@@U36.AJ84.1" "CRESCENT_CITY_065_20140613_B.@@J2.152.1")) ("CRESCENT_CITY_065_20140613_B.X1241732Y523923L2LRATS" (terms "CRESCENT_CITY_065_20140613_B.T@@RATS@@J1.152@@J2.152.1" "CRESCENT_CITY_065_20140613_B.@@J1.152.1")) ("CRESCENT_CITY_065_20140613_B.X1108595Y352696L2LRATS" (terms "CRESCENT_CITY_065_20140613_B.T@@RATS@@J2.152@@U36.AJ84.2" "CRESCENT_CITY_065_20140613_B.@@U36.AJ84.1"))) (Ports) (Stimuli ("local6" (scope local) (stimType periodic) (Props (periodicFreq "5e+007") (periodicJitter "0") (periodicPattern "1"))) ("local8" (scope local) (stimType periodic) (Props (periodicFreq "5e+007") (periodicJitter "0") (periodicPattern "1"))) ("local7" (scope local) (stimType periodic) (Props (periodicFreq "5e+007") (periodicJitter "0") (periodicPattern "1"))) ("local3" (scope local) (stimType periodic) (Props (periodicFreq "5e+007") (periodicJitter "0") (periodicPattern "1"))) ("local4" (scope local) (stimType periodic) (Props (periodicFreq "5e+007") (periodicJitter "0") (periodicPattern "1"))) ("local5" (scope local) (stimType periodic) (Props (periodicFreq "5e+007") (periodicJitter "0") (periodicPattern "1")))) (Notes) (Constraints ("DP_GATHER_CONTROL" "IGNORE") ("DP_MAX_UNCOUPLED_LENGTH" "0.00127") ("DP_MIN_LINE_SPACING" "0.0001016") ("DP_NEGATIVE_COUPLED_TOLERANCE" "2.54e-006") ("DP_PHASE_MAX_LENGTH" "0.01524") ("DP_PHASE_TOLERANCE" ("LENGTH" "5.08e-005")) ("DP_PHASE_TOLERANCE_DYNAMIC" ("LENGTH" "0.00508")) ("DP_POSITIVE_COUPLED_TOLERANCE" "2.54e-006") ("RELATIVE_PROPAGATION_DELAY" ("MG_DQ-DQS_FAR_DIMM" "CRESCENT_CITY_065_20140613_B U36.AJ84" "CRESCENT_CITY_065_20140613_B J1.152" "NET GROUP" "LENGTH" "0.000127" "LENGTH" "") ("MG_DQ-DQS_NEAR_DIMM" "CRESCENT_CITY_065_20140613_B U36.AJ84" "CRESCENT_CITY_065_20140613_B J2.152" "NET GROUP" "LENGTH" "0.000127" "LENGTH" ""))) (MeasurementSets ("EMI" ("EMIStatus" status("on")) ("PeakEmission" status("on")) ("PeakFrequency" status("on")) ("PulseFreq" status("on")) ("RiseTime" status("on")) ("VoltageSwing" status("on"))) ("Reflection" ("BufferDelayFall" status("off")) ("BufferDelayRise" status("off")) ("EyeHeight" status("off")) ("EyeJitter" status("off")) ("EyeWidth" status("off")) ("FirstIncidentFall" status("off")) ("FirstIncidentRise" status("off")) ("Glitch" status("on")) ("GlitchFall" status("off")) ("GlitchRise" status("off")) ("Monotonic" status("on")) ("MonotonicFall" status("off")) ("MonotonicRise" status("off")) ("NoiseMargin" status("on")) ("NoiseMarginHigh" status("off")) ("NoiseMarginLow" status("off")) ("OvershootHigh" status("on")) ("OvershootLow" status("on")) ("PropDelay" status("on")) ("SettleDelay" status("on")) ("SettleDelayFall" status("off")) ("SettleDelayRise" status("off")) ("SwitchDelay" status("on")) ("SwitchDelayFall" status("off")) ("SwitchDelayRise" status("off"))) ("Crosstalk" ("Crosstalk" status("on"))) ("Custom")) (VectorSets) (Props (XnetName "M_A_DQS_DN<0>") (allDrivers "active") (customSimType "Reflection") (ftsMode ("Typ")) (rcvrSelect "all") (tlineDelayMode "time") (userRevision "1.0")))) (Subckts) (CrossSections ("CRESCENT_CITY_065_20140613_B" (Props (SXDesignName "CRESCENT_CITY_065_20140613_B")) (Layers ("" (layerType "SURFACE") (material "AIR") (thickness "0 mil") (dielectricConstant "1.000000") (lossTangent "0") (etchFactor "0.000000") (elecCondVal "0 mho/cm") (thermCondVal "0 w/cm-degC")) ("" (layerType "DIELECTRIC") (material "CONFORMAL_COAT") (thickness "0.5 mil") (dielectricConstant "3.800000") (lossTangent "0.035") (etchFactor "0.000000") (elecCondVal "0 mho/cm") (thermCondVal "0.012 w/cm-degC")) ("TOP" (layerType "CONDUCTOR") (material "COPPER") (thickness "  2.000000 mil") (width "4.00 MIL") (dielectricConstant "4.500000") (lossTangent "0") (etchFactor "70.000000") (elecCondVal "595900.000000 mho/cm") (thermCondVal "0 w/cm-degC") (signalDieConstant "3.800000") (signalLossTangent "0.035")) ("" (layerType "DIELECTRIC") (material "FR-4") (thickness "  2.700000 mil") (dielectricConstant "4.000000") (lossTangent "0.035") (etchFactor "0.000000") (elecCondVal "0 mho/cm") (thermCondVal "0.012 w/cm-degC")) ("L2_GND1" (layerType "PLANE") (material "COPPER") (isShield t) (thickness "  1.300000 mil") (dielectricConstant "4.500000") (lossTangent "0.035") (etchFactor "90.000000") (elecCondVal "595900.000000 mho/cm") (thermCondVal "0.012 w/cm-degC")) ("" (layerType "DIELECTRIC") (material "FR-4") (thickness "  4.000000 mil") (dielectricConstant "4.100000") (lossTangent "0.035") (etchFactor "0.000000") (elecCondVal "0 mho/cm") (thermCondVal "0.012 w/cm-degC")) ("L3_SIG1" (layerType "CONDUCTOR") (material "COPPER") (thickness "  1.300000 mil") (width "4.00 MIL") (dielectricConstant "4.500000") (lossTangent "0.035") (etchFactor "90.000000") (elecCondVal "595900.000000 mho/cm") (thermCondVal "0.012 w/cm-degC") (signalDieConstant "4.100000") (signalLossTangent "0.035")) ("" (layerType "DIELECTRIC") (material "FR-4") (thickness " 21.000000 mil") (dielectricConstant "4.000000") (lossTangent "0.035") (etchFactor "0.000000") (elecCondVal "0 mho/cm") (thermCondVal "0.012 w/cm-degC")) ("L4_SIG2" (layerType "CONDUCTOR") (material "COPPER") (thickness "  1.300000 mil") (width "4.00 MIL") (dielectricConstant "4.500000") (lossTangent "0.035") (etchFactor "90.000000") (elecCondVal "595900.000000 mho/cm") (thermCondVal "0.012 w/cm-degC") (signalDieConstant "4.000000") (signalLossTangent "0.035")) ("" (layerType "DIELECTRIC") (material "FR-4") (thickness "  4.000000 mil") (dielectricConstant "4.100000") (lossTangent "0.035") (etchFactor "0.000000") (elecCondVal "0 mho/cm") (thermCondVal "0.012 w/cm-degC")) ("L5_PWR1" (layerType "PLANE") (material "COPPER") (isShield t) (thickness "  2.600000 mil") (dielectricConstant "4.500000") (lossTangent "0.035") (etchFactor "90.000000") (elecCondVal "595900.000000 mho/cm") (thermCondVal "0.012 w/cm-degC")) ("" (layerType "DIELECTRIC") (material "FR-4") (thickness "  4.000000 mil") (dielectricConstant "4.000000") (lossTangent "0.035") (etchFactor "0.000000") (elecCondVal "0 mho/cm") (thermCondVal "0.012 w/cm-degC")) ("L6_PWR2" (layerType "PLANE") (material "COPPER") (isShield t) (thickness "  2.600000 mil") (dielectricConstant "4.500000") (lossTangent "0.035") (etchFactor "90.000000") (elecCondVal "595900.000000 mho/cm") (thermCondVal "0.012 w/cm-degC")) ("" (layerType "DIELECTRIC") (material "FR-4") (thickness "  4.000000 mil") (dielectricConstant "4.100000") (lossTangent "0.035") (etchFactor "0.000000") (elecCondVal "0 mho/cm") (thermCondVal "0.012 w/cm-degC")) ("L7_SIG3" (layerType "CONDUCTOR") (material "COPPER") (thickness "  1.300000 mil") (width "4.00 MIL") (dielectricConstant "4.500000") (lossTangent "0.035") (etchFactor "90.000000") (elecCondVal "595900.000000 mho/cm") (thermCondVal "0.012 w/cm-degC") (signalDieConstant "4.100000") (signalLossTangent "0.035")) ("" (layerType "DIELECTRIC") (material "FR-4") (thickness " 21.000000 mil") (dielectricConstant "4.500000") (lossTangent "0.035") (etchFactor "0.000000") (elecCondVal "0 mho/cm") (thermCondVal "0.012 w/cm-degC")) ("L8_SIG4" (layerType "CONDUCTOR") (material "COPPER") (thickness "  1.300000 mil") (width "4.00 MIL") (dielectricConstant "4.500000") (lossTangent "0.035") (etchFactor "90.000000") (elecCondVal "595900.000000 mho/cm") (thermCondVal "0.012 w/cm-degC") (signalDieConstant "4.500000") (signalLossTangent "0.035")) ("" (layerType "DIELECTRIC") (material "FR-4") (thickness "  8.000000 mil") (dielectricConstant "4.500000") (lossTangent "0.035") (etchFactor "0.000000") (elecCondVal "0 mho/cm") (thermCondVal "0 w/cm-degC")) ("L9_GND4" (layerType "PLANE") (material "COPPER") (isShield t) (thickness "  1.300000 mil") (dielectricConstant "4.500000") (lossTangent "0.035") (etchFactor "90.000000") (elecCondVal "595900.000000 mho/cm") (thermCondVal "0.012 w/cm-degC")) ("" (layerType "DIELECTRIC") (material "FR-4") (thickness "  2.700000 mil") (dielectricConstant "4.500000") (lossTangent "0.035") (etchFactor "0.000000") (elecCondVal "0 mho/cm") (thermCondVal "0.012 w/cm-degC")) ("BOTTOM" (layerType "CONDUCTOR") (material "COPPER") (thickness "  2.000000 mil") (width "4.00 MIL") (dielectricConstant "4.500000") (lossTangent "0") (etchFactor "70.000000") (elecCondVal "595900.000000 mho/cm") (thermCondVal "0 w/cm-degC") (signalDieConstant "3.800000") (signalLossTangent "0.035")) ("" (layerType "DIELECTRIC") (material "CONFORMAL_COAT") (thickness "0.5 mil") (dielectricConstant "3.800000") (lossTangent "0.035") (etchFactor "0.000000") (elecCondVal "0 mho/cm") (thermCondVal "0.012 w/cm-degC")) ("" (layerType "SURFACE") (material "AIR") (thickness "0 mil") (dielectricConstant "1.000000") (lossTangent "0") (etchFactor "0.000000") (elecCondVal "0 mho/cm") (thermCondVal "0 w/cm-degC"))))) (Props (DesUnits "mils 2") (LayerStack ("DIELECTRIC" "DIELECTRIC" "BOTTOM" "DIELECTRIC" "L9_GND4" "DIELECTRIC" "L8_SIG4" "DIELECTRIC" "L7_SIG3" "DIELECTRIC" "L6_PWR2" "DIELECTRIC" "L5_PWR1" "DIELECTRIC" "L4_SIG2" "DIELECTRIC" "L3_SIG1" "DIELECTRIC" "L2_GND1" "DIELECTRIC" "TOP" "DIELECTRIC" "DIELECTRIC")) (Revision "16.600")) (Params (CPWMS ((d1Thickness "10 mil") (d1Constant "4.5") (d1LossTangent "0.035") (d2Thickness "0.72 mil") (d2Constant "4.5") (d2LossTangent "0.035") (d3Thickness "0.0") (d3Constant "1") (d3LossTangent "0") length("1000 mil") (spacing "5 mil") (spacing2 "5 mil") (spacing3 "5 mil") (spacing4 "5 mil") (spacing5 "5 mil") (traceConductivity "595900 mho/cm") (traceGeometry "cpwms") (traceLayerName "") (traceThickness "0.72 mil") (traceType "single") (traceWidth "5.0 mil") (traceWidth2 "5.0 mil") (traceWidth3 "5.0 mil") (traceWidth4 "5.0 mil") (traceWidth5 "5.0 mil") (traceWidth6 "5.0 mil") (offset "0 mil") (traceCount "1") (impedance nil))) (CPWSL ((d1Thickness "10 mil") (d1Constant "4.5") (d1LossTangent "0.035") (d2Thickness "0.72 mil") (d2Constant "4.5") (d2LossTangent "0.035") (d3Thickness "10 mil") (d3Constant "4.5") (d3LossTangent "0.035") length("1000 mil") (spacing "5 mil") (spacing2 "5 mil") (spacing3 "5 mil") (spacing4 "5 mil") (spacing5 "5 mil") (traceConductivity "595900 mho/cm") (traceGeometry "cpwms") (traceLayerName "") (traceThickness "0.72 mil") (traceType "single") (traceWidth "5.0 mil") (traceWidth2 "5.0 mil") (traceWidth3 "5.0 mil") (traceWidth4 "5.0 mil") (traceWidth5 "5.0 mil") (traceWidth6 "5.0 mil") (offset "0 mil") (traceCount "1") (impedance nil))) (CurrentProbe nil) (HiClampTerm ((cutoffVoltage "0.7 V") (voltage "5 V") (maxDelay "0.1 ns"))) (CPW ((d1Thickness "10 mil") (d1Constant "4.5") (d1LossTangent "0.035") (d2Thickness "0.72 mil") (d2Constant "1") (d2LossTangent "0") (d3Thickness "0.0") (d3Constant "1") (d3LossTangent "0") length("1000 mil") (spacing "5 mil") (spacing2 "5 mil") (spacing3 "5 mil") (spacing4 "5 mil") (spacing5 "5 mil") (traceConductivity "595900 mho/cm") (traceGeometry "cpwms") (traceLayerName "") (traceThickness "0.72 mil") (traceType "single") (traceWidth "5.0 mil") (traceWidth2 "5.0 mil") (traceWidth3 "5.0 mil") (traceWidth4 "5.0 mil") (traceWidth5 "5.0 mil") (traceWidth6 "5.0 mil") (offset "0 mil") (traceCount "1") (impedance nil))) (LowClampTerm ((cutoffVoltage "0.7 V") (voltage "0 V") (maxDelay "0.1 ns"))) (idlCircuit ((allDrivers "active") (ftsMode '("Typ")) (rcvrSelect "all") (simMode "Reflection") (tlineDelayMode "time") (userRevision "1.0") (autoSolve "On"))) (sync ((syncFreq "100e6") (syncInitState "1") (syncPattern "10") (syncEdgeSwitch "rise"))) (DiffInput ((temperature "27") (bufferModelNonInverting "CDSDefaultInput_2p5v") (bufferModelInverting "CDSDefaultInput_2p5v") (threshInputHighMin "1.7 V") (threshInputHighTyp "1.7  V") (threshInputHighMax "1.7  V") (threshInputLowMin "0.7  V") (threshInputLowTyp "0.7  V") (threshInputLowMax "0.7  V") (cycle "1"))) (DiffInputPkg ((temperature "27") (bufferModelNonInverting "CDSDefaultInput_2p5v") (bufferModelInverting "CDSDefaultInput_2p5v") (threshInputHighMin "1.7 V") (threshInputHighTyp "1.7  V") (threshInputHighMax "1.7  V") (threshInputLowMin "0.7  V") (threshInputLowTyp "0.7  V") (threshInputLowMax "0.7  V") (cycle "1"))) (DiffIO ((temperature "27") (bufferModelNonInverting "CDSDefaultIO_2p5v") (bufferModelInverting "CDSDefaultIO_2p5v") (stimuli nil) (offsets nil) (state "tristate") (cycle "1") (termMap nil) (setup "0.9e-09") (hold "0.4e-09") (rise nil) (fall nil) (threshInputHighMin "1.7 V") (threshInputHighTyp "1.7  V") (threshInputHighMax "1.7  V") (threshInputLowMin "0.7  V") (threshInputLowTyp "0.7  V") (threshInputLowMax "0.7 ") (threshOutputHighMin "2.365  V") (threshOutputHighTyp "2.5  V") (threshOutputHighMax "2.625  V") (threshOutputLowMin "1.275  V") (threshOutputLowTyp "1.7  V") (threshOutputLowMax "1.985  V") (spice nil))) (periodic ((periodicFreq "100e6") (periodicPattern "10") (periodicJitter "0"))) (Cable (length("1 m"))) (DiffOutput ((temperature "27") (bufferModelNonInverting "CDSDefaultOutput_2p5v") (bufferModelInverting "CDSDefaultOutput_2p5v") (stimuli nil) (offsets nil) (state "tristate") (cycle "1") (termMap nil) (setup "0.9e-09") (hold "0.4e-09") (rise nil) (fall nil) (threshOutputHighMin "2.375  V") (threshOutputHighTyp "2.5  V") (threshOutputHighMax "2.625  V") (threshOutputLowMin "1.275  V") (threshOutputLowTyp "1.7  V") (threshOutputLowMax "1.985  V") (spice nil))) (Via ((model "Unknown") (viaOutputFormat "Unknown") (viaPadstack nil) (viaTopLayer nil) (viaBottomLayer nil) (viaIsPower nil) (viaIsGround nil))) (Source ((voltage "5 V"))) (DiffOutputPkg ((temperature "27") (bufferModelNonInverting "CDSDefaultOutput_2p5v") (bufferModelInverting "CDSDefaultOutput_2p5v") (stimuli nil) (offsets nil) (state "tristate") (cycle "1") (termMap nil) (setup "0.9e-09") (hold "0.4e-09") (rise nil) (fall nil) (threshOutputHighMin "2.375  V") (threshOutputHighTyp "2.5  V") (threshOutputHighMax "2.625  V") (threshOutputLowMin "1.275  V") (threshOutputLowTyp "1.7  V") (threshOutputLowMax "1.985  V") (spice nil))) (IbisOutput ((temperature "27") (bufferModel "CDSDefaultOutput_2p5v") (stimuli nil) (offsets nil) (state "tristate") (cycle "1") (termMap nil) (setup "2.0e-09") (hold "1.0e-09") (rise nil) (fall nil) (macroType nil) (voltage nil) (spice nil) (LEFDEFPinName nil) (LEFDEFPinType nil))) (async ((asyncTimePoints "") (asyncInitState "1"))) (TLine ((diffImpedance "100ohm") (diffVelocity "1.4142e+08M/s") (impedance "60ohm") length("2800 mil") (propDelay "0.5 ns") (velocity "5600 mil/ns") (traceCount "1") (traceGeometry "Microstrip") (impedanceMin nil) (impedanceMax nil) (lengthMin nil) (lengthMax nil) (propDelayMin nil) (propDelayMax nil) (impedanceSweepCount nil) (propDelaySweepCount nil) (velocitySweepCount nil) (lengthSweepCount nil) (matchSetName nil))) (TheveninTerm ((resistanceUp "180 ohm") (resistanceDown "270 ohm") (voltageUp "5 V") (voltageDown "0 V") (maxDelay "0.1 ns"))) (IbisInputPkg ((temperature "27") (bufferModel "CDSDefaultInput_2p5v") (cycle "1") (LEFDEFPinName nil) (LEFDEFPinType nil))) (IbisIO_OpenPullDown ((temperature "27") (bufferModel "CDSDefaultIO_2p5v") (stimuli nil) (offsets nil) (state "tristate") (cycle "1") (termMap nil) (setup "2.0e-09") (hold "1.0e-09") (rise nil) (fall nil) (macroType nil) (voltage nil) (spice nil) (LEFDEFPinName nil) (LEFDEFPinType nil))) (IbisInput ((temperature "27") (bufferModel "CDSDefaultInput_2p5v") (cycle "1") (LEFDEFPinName nil) (LEFDEFPinType nil))) (SeriesTerm ((resistance "22 ohm") (maxDelay "0.1 ns"))) (Connector nil) (clocked ((clockRise "1e-09") (clockFall "1e-09") (clockFreq "100e6") (clockInitState "0") (clockDutyCycle "0.5") (clockJitter "0"))) (IbisOutput_OpenPullUp ((temperature "27") (bufferModel "CDSDefaultOutput_2p5v") (stimuli nil) (offsets nil) (state "tristate") (cycle "1") (termMap nil) (setup "2.0e-09") (hold "1.0e-09") (rise nil) (fall nil) (macroType nil) (voltage nil) (spice nil) (LEFDEFPinName nil) (LEFDEFPinType nil))) (DiffIOPkg ((temperature "27") (bufferModelNonInverting "CDSDefaultIO_2p5v") (bufferModelInverting "CDSDefaultIO_2p5v") (stimuli nil) (offsets nil) (state "tristate") (cycle "1") (termMap nil) (setup "0.9e-09") (hold "0.4e-09") (rise nil) (fall nil) (threshInputHighMin "1.7 V") (threshInputHighTyp "1.7  V") (threshInputHighMax "1.7  V") (threshInputLowMin "0.7  V") (threshInputLowTyp "0.7  V") (threshInputLowMax "0.7 ") (threshOutputHighMin "2.365  V") (threshOutputHighTyp "2.5  V") (threshOutputHighMax "2.625  V") (threshOutputLowMin "1.275  V") (threshOutputLowTyp "1.7  V") (threshOutputLowMax "1.985  V") (spice nil))) (IbisIO ((temperature "27") (bufferModel "CDSDefaultIO_2p5v") (stimuli nil) (offsets nil) (state "tristate") (cycle "1") (termMap nil) (setup "2.0e-09") (hold "1.0e-09") (rise nil) (fall nil) (macroType nil) (voltage nil) (spice nil) (LEFDEFPinName nil) (LEFDEFPinType nil))) (IbisIO_OpenPullUp ((temperature "27") (bufferModel "CDSDefaultIO_2p5v") (stimuli nil) (offsets nil) (state "tristate") (cycle "1") (termMap nil) (setup "2.0e-09") (hold "1.0e-09") (rise nil) (fall nil) (macroType nil) (voltage nil) (spice nil) (LEFDEFPinName nil) (LEFDEFPinType nil))) (IbisIOMacro ((temperature "27") (bufferModel "CDSDefaultIO_2p5v") (stimuli nil) (offsets nil) (state "tristate") (cycle "1") (termMap nil) (setup "2.0e-09") (hold "1.0e-09") (rise nil) (fall nil) (macroType nil) (voltage nil) (spice nil) (LEFDEFPinName nil) (LEFDEFPinType nil))) (DualClampTerm ((cutoffVoltageUp "0.7 V") (cutoffVoltageDown "0.7 V") (voltageUp "5 V") (voltageDown "0 V") (maxDelay "0.1 ns"))) (ESpiceDevice nil) (RCTerm ((resistance "50 ohm") (capacitance "20 pF") (voltage "5 V") (maxDelay "0.1 ns"))) (Inductor ((inductance "5 nH") (orientation "0"))) (Trace ((d1Thickness "10 mil") (d1Constant "4.5") (d1LossTangent "0.035") (d2Thickness "10 mil") (d2Constant "4.5") (d2LossTangent "0.035") (d3Thickness "0.0") (d3Constant "1.0") (d3LossTangent "0") length("1000 mil") (spacing "5 mil") (spacing2 "5 mil") (spacing3 "5 mil") (spacing4 "5 mil") (spacing5 "5 mil") (traceConductivity "595900 mho/cm") (traceGeometry "microstrip") (traceLayerName "") (traceThickness "0.72 mil") (traceType "single") (traceWidth "5.0 mil") (traceWidth2 "5.0 mil") (traceWidth3 "5.0 mil") (traceWidth4 "5.0 mil") (traceWidth5 "5.0 mil") (traceWidth6 "5.0 mil") (offset "0 mil") (traceCount "1") (impedance nil))) (Diode ((cutoffVoltage "0.7 V"))) (IbisOutputPkg ((temperature "27") (bufferModel "CDSDefaultOutput_2p5v") (stimuli nil) (offsets nil) (state "tristate") (cycle "1") (termMap nil) (setup "2.0e-09") (hold "1.0e-09") (rise nil) (fall nil) (macroType nil) (voltage nil) (spice nil) (LEFDEFPinName nil) (LEFDEFPinType nil))) (Capacitor ((capacitance "10 pF") (orientation "0"))) (IbisIOPkg ((temperature "27") (bufferModel "CDSDefaultIO_2p5v") (stimuli nil) (offsets nil) (state "tristate") (cycle "1") (termMap nil) (setup "2.0e-09") (hold "1.0e-09") (rise nil) (fall nil) (macroType nil) (voltage nil) (spice nil) (LEFDEFPinName nil) (LEFDEFPinType nil))) (ShuntTerm ((resistance "50 ohm") (voltage "5 V") (maxDelay "0.1 ns"))) (RLGC (length("1000 mil"))) (Resistor ((resistance "50 ohm") (orientation "0")))))
				)
				( objectStatus "DDR_DQS" )
			)
			( electricalCSet "@crescent_city_bb_fab1_lib.crescent_city_bb_fab1(sch_1):\M_A_MA_14_\"
				( groupRef "DDR_A_CMD_DLL1-13:MG_DDR_CMD_NEAR_DIMM" )
				( groupRef "DDR_A_CMD_DLL1-13:MG_DDR_FAR_DIMM-CLK0" )
				( groupRef "DDR_A_CMD_DLL1-13:MG_DDR_FAR_DIMM_CMD" )
				( groupRef "DDR_A_CMD_DLL1-13:MG_DDR_NEAR_DIMM-CLK1" )
				( pinPairRef "DDR_A_CMD_DLL1-13:U5D1.F51:J6T1.228" )
				( pinPairRef "DDR_A_CMD_DLL1-13:U5D1.F51:J4G1.228" )
				( attribute "TOPOLOGY_TEMPLATE_REVISION" "1.0"
					( Origin gBackEnd )
				)
				( topologyData 23931
(SKIDL (Circuits ("MAIN" (Parts ("CRESCENT_CITY_083_20140724_A.@@J1.228" IbisIOPkg (xy (5548 4240)) (refDes "J4G1") (model "Unknown") (Props (_SXDesignName "CRESCENT_CITY_083_20140724_A") (brdx "10643.7 MIL") (brdy "788.33 MIL") (bufferModel "CDSDefaultIO_2p5v") (cycle "1") (hold "1.0e-09") (mappingTag "") (offsets ("4" "0") ("5" "0")) (setup "2.0e-09") (state "tristate") (stimuli ("4" "local0") ("5" "local1")) (temperature "27") (termMap ("4" "Data") ("5" "Enable"))) (Terms ("CRESCENT_CITY_083_20140724_A.X1064370Y78833L2LRATS" "228"))) ("CRESCENT_CITY_083_20140724_A.@@J2.228" IbisIOPkg (xy (5528 4240)) (refDes "J6T1") (model "Unknown") (Props (_SXDesignName "CRESCENT_CITY_083_20140724_A") (brdx "10643.7 MIL") (brdy "796.23 MIL") (bufferModel "CDSDefaultIO_2p5v") (cycle "1") (hold "1.0e-09") (mappingTag "") (offsets ("4" "0") ("5" "0")) (setup "2.0e-09") (state "tristate") (stimuli ("4" "local2") ("5" "local15")) (temperature "27") (termMap ("4" "Data") ("5" "Enable"))) (Terms ("CRESCENT_CITY_083_20140724_A.X1064370Y79623L28LRATS" "228"))) ("CRESCENT_CITY_083_20140724_A.@@U36.F51" IbisIOPkg (xy (5502 4240)) (refDes "U5D1") (model "Unknown") (Props (_SXDesignName "CRESCENT_CITY_083_20140724_A") (brdx "10346.35 MIL") (brdy "2052.1 MIL") (bufferModel "CDSDefaultIO_2p5v") (cycle "1") (hold "1.0e-09") (mappingTag "") (offsets ("4" "0") ("5" "0")) (setup "2.0e-09") (state "tristate") (stimuli ("4" "local16") ("5" "local17")) (temperature "27") (termMap ("4" "Data") ("5" "Enable"))) (Terms ("CRESCENT_CITY_083_20140724_A.X1034635Y205210L2LRATS" "F51"))) ("CRESCENT_CITY_083_20140724_A.T@@RATS@@J2.228@@U36.F51" TLine (xy (5513 4235)) (mirror x) (refDes "TL1") (Props (_SXDesignName "CRESCENT_CITY_083_20140724_A") (impedance "53.474 ohm") length("1553.22 MIL") (propDelay "0.27897 ns") (traceCount "1") (traceGeometry "Microstrip") (velocity "5567.68 mil/ns")) (Terms ("CRESCENT_CITY_083_20140724_A.X1064370Y79623L28LRATS" "1") ("CRESCENT_CITY_083_20140724_A.X1034635Y205210L2LRATS" "2"))) ("CRESCENT_CITY_083_20140724_A.T@@RATS@@J2.228@@J1.228" TLine (xy (5539 4235)) (refDes "TL2") (Props (_SXDesignName "CRESCENT_CITY_083_20140724_A") (impedance "39.682 ohm") length("7.90 MIL") (propDelay "0.00142 ns") (traceCount "1") (traceGeometry "Microstrip") (velocity "5563.39 mil/ns")) (Terms ("CRESCENT_CITY_083_20140724_A.X1064370Y79623L28LRATS" "1") ("CRESCENT_CITY_083_20140724_A.X1064370Y78833L2LRATS" "2")))) (Nodes ("CRESCENT_CITY_083_20140724_A.X1034635Y205210L2LRATS" (terms "CRESCENT_CITY_083_20140724_A.T@@RATS@@J2.228@@U36.F51.2" "CRESCENT_CITY_083_20140724_A.@@U36.F51.1")) ("CRESCENT_CITY_083_20140724_A.X1064370Y78833L2LRATS" (terms "CRESCENT_CITY_083_20140724_A.T@@RATS@@J2.228@@J1.228.2" "CRESCENT_CITY_083_20140724_A.@@J1.228.1")) ("CRESCENT_CITY_083_20140724_A.X1064370Y79623L28LRATS" (terms "CRESCENT_CITY_083_20140724_A.T@@RATS@@J2.228@@J1.228.1" "CRESCENT_CITY_083_20140724_A.T@@RATS@@J2.228@@U36.F51.1" "CRESCENT_CITY_083_20140724_A.@@J2.228.1"))) (Ports) (Stimuli ("local2" (scope local) (stimType periodic) (Props (periodicFreq "5e+007") (periodicJitter "0") (periodicPattern "1"))) ("local15" (scope local) (stimType periodic) (Props (periodicFreq "5e+007") (periodicJitter "0") (periodicPattern "1"))) ("local0" (scope local) (stimType periodic) (Props (periodicFreq "5e+007") (periodicJitter "0") (periodicPattern "1"))) ("local16" (scope local) (stimType periodic) (Props (periodicFreq "5e+007") (periodicJitter "0") (periodicPattern "1"))) ("local1" (scope local) (stimType periodic) (Props (periodicFreq "5e+007") (periodicJitter "0") (periodicPattern "1"))) ("local17" (scope local) (stimType periodic) (Props (periodicFreq "5e+007") (periodicJitter "0") (periodicPattern "1")))) (Notes) (Constraints ("RELATIVE_PROPAGATION_DELAY" ("MG_DDR_CMD_NEAR_DIMM" "CRESCENT_CITY_083_20140724_A U36.F51" "CRESCENT_CITY_083_20140724_A J2.228" "NET GROUP" "LENGTH" "0.000635" "LENGTH" "0") ("MG_DDR_FAR_DIMM-CLK0" "CRESCENT_CITY_083_20140724_A U36.F51" "CRESCENT_CITY_083_20140724_A J1.228" "CLASS" "LENGTH" "0.01778" "LENGTH" "0") ("MG_DDR_FAR_DIMM_CMD" "CRESCENT_CITY_083_20140724_A U36.F51" "CRESCENT_CITY_083_20140724_A J1.228" "NET GROUP" "LENGTH" "0.000635" "LENGTH" "0") ("MG_DDR_NEAR_DIMM-CLK1" "CRESCENT_CITY_083_20140724_A U36.F51" "CRESCENT_CITY_083_20140724_A J2.228" "CLASS" "LENGTH" "0.01778" "LENGTH" "0"))) (MeasurementSets ("EMI" ("EMIStatus" status("on")) ("PeakEmission" status("on")) ("PeakFrequency" status("on")) ("PulseFreq" status("on")) ("RiseTime" status("on")) ("VoltageSwing" status("on"))) ("Reflection" ("BufferDelayFall" status("off")) ("BufferDelayRise" status("off")) ("EyeHeight" status("off")) ("EyeJitter" status("off")) ("EyeWidth" status("off")) ("FirstIncidentFall" status("off")) ("FirstIncidentRise" status("off")) ("Glitch" status("on")) ("GlitchFall" status("off")) ("GlitchRise" status("off")) ("Monotonic" status("on")) ("MonotonicFall" status("off")) ("MonotonicRise" status("off")) ("NoiseMargin" status("on")) ("NoiseMarginHigh" status("off")) ("NoiseMarginLow" status("off")) ("OvershootHigh" status("on")) ("OvershootLow" status("on")) ("PropDelay" status("on")) ("SettleDelay" status("on")) ("SettleDelayFall" status("off")) ("SettleDelayRise" status("off")) ("SwitchDelay" status("on")) ("SwitchDelayFall" status("off")) ("SwitchDelayRise" status("off"))) ("Crosstalk" ("Crosstalk" status("on"))) ("Custom")) (VectorSets) (Props (XnetName "M_A_MA<14>") (allDrivers "active") (customSimType "Reflection") (ftsMode ("Typ")) (rcvrSelect "all") (tlineDelayMode "time") (userRevision "1.0")))) (Subckts) (CrossSections ("CRESCENT_CITY_083_20140724_A" (Props (SXDesignName "CRESCENT_CITY_083_20140724_A")) (Layers ("" (layerType "SURFACE") (material "AIR") (thickness "0 mil") (dielectricConstant "1.000000") (lossTangent "0") (etchFactor "0.000000") (elecCondVal "0 mho/cm") (thermCondVal "0 w/cm-degC")) ("" (layerType "DIELECTRIC") (material "CONFORMAL_COAT") (thickness "0.5 mil") (dielectricConstant "3.800000") (lossTangent "0.035") (etchFactor "0.000000") (elecCondVal "0 mho/cm") (thermCondVal "0.012 w/cm-degC")) ("TOP" (layerType "CONDUCTOR") (material "COPPER") (thickness "  1.800000 mil") (width "4.00 MIL") (dielectricConstant "4.500000") (lossTangent "0") (etchFactor "70.000000") (elecCondVal "595900.000000 mho/cm") (thermCondVal "0 w/cm-degC") (signalDieConstant "3.800000") (signalLossTangent "0.035")) ("" (layerType "DIELECTRIC") (material "FR-4") (thickness "  2.700000 mil") (dielectricConstant "4.000000") (lossTangent "0.035") (etchFactor "0.000000") (elecCondVal "0 mho/cm") (thermCondVal "0.012 w/cm-degC")) ("L2_GND1" (layerType "PLANE") (material "COPPER") (isShield t) (thickness "  1.200000 mil") (dielectricConstant "4.500000") (lossTangent "0.035") (etchFactor "90.000000") (elecCondVal "595900.000000 mho/cm") (thermCondVal "0.012 w/cm-degC")) ("" (layerType "DIELECTRIC") (material "FR-4") (thickness "  9.900000 mil") (dielectricConstant "4.100000") (lossTangent "0.035") (etchFactor "0.000000") (elecCondVal "0 mho/cm") (thermCondVal "0.012 w/cm-degC")) ("L3_SIG1" (layerType "CONDUCTOR") (material "COPPER") (thickness "  1.200000 mil") (width "4.00 MIL") (dielectricConstant "4.500000") (lossTangent "0.035") (etchFactor "90.000000") (elecCondVal "595900.000000 mho/cm") (thermCondVal "0.012 w/cm-degC") (signalDieConstant "4.100000") (signalLossTangent "0.035")) ("" (layerType "DIELECTRIC") (material "FR-4") (thickness "  3.300000 mil") (dielectricConstant "4.500000") (lossTangent "0.035") (etchFactor "0.000000") (elecCondVal "0 mho/cm") (thermCondVal "0 w/cm-degC")) ("L4_GND2" (layerType "PLANE") (material "COPPER") (isShield t) (thickness "  1.200000 mil") (dielectricConstant "4.500000") (lossTangent "0.035") (etchFactor "90.000000") (elecCondVal "595900.000000 mho/cm") (thermCondVal "0 w/cm-degC")) ("" (layerType "DIELECTRIC") (material "FR-4") (thickness "  3.300000 mil") (dielectricConstant "4.000000") (lossTangent "0.035") (etchFactor "0.000000") (elecCondVal "0 mho/cm") (thermCondVal "0.012 w/cm-degC")) ("L5_SIG2" (layerType "CONDUCTOR") (material "COPPER") (thickness "  1.200000 mil") (width "4.00 MIL") (dielectricConstant "4.500000") (lossTangent "0.035") (etchFactor "90.000000") (elecCondVal "595900.000000 mho/cm") (thermCondVal "0.012 w/cm-degC") (signalDieConstant "4.000000") (signalLossTangent "0.035")) ("" (layerType "DIELECTRIC") (material "FR-4") (thickness "  9.900000 mil") (dielectricConstant "4.500000") (lossTangent "0.035") (etchFactor "0.000000") (elecCondVal "0 mho/cm") (thermCondVal "0 w/cm-degC")) ("L6_GND3" (layerType "PLANE") (material "COPPER") (isShield t) (thickness "  1.200000 mil") (dielectricConstant "4.500000") (lossTangent "0.035") (etchFactor "90.000000") (elecCondVal "595900.000000 mho/cm") (thermCondVal "0 w/cm-degC")) ("" (layerType "DIELECTRIC") (material "FR-4") (thickness "  3.300000 mil") (dielectricConstant "4.100000") (lossTangent "0.035") (etchFactor "0.000000") (elecCondVal "0 mho/cm") (thermCondVal "0.012 w/cm-degC")) ("L7_PWR1-SIG" (layerType "PLANE") (material "COPPER") (isShield t) (thickness "  1.200000 mil") (dielectricConstant "4.500000") (lossTangent "0.035") (etchFactor "90.000000") (elecCondVal "595900.000000 mho/cm") (thermCondVal "0.012 w/cm-degC")) ("" (layerType "DIELECTRIC") (material "FR-4") (thickness "  9.900000 mil") (dielectricConstant "4.000000") (lossTangent "0.035") (etchFactor "0.000000") (elecCondVal "0 mho/cm") (thermCondVal "0.012 w/cm-degC")) ("L8_PWR2-SIG" (layerType "PLANE") (material "COPPER") (isShield t) (thickness "  1.200000 mil") (dielectricConstant "4.500000") (lossTangent "0.035") (etchFactor "90.000000") (elecCondVal "595900.000000 mho/cm") (thermCondVal "0.012 w/cm-degC")) ("" (layerType "DIELECTRIC") (material "FR-4") (thickness "  3.300000 mil") (dielectricConstant "4.500000") (lossTangent "0.035") (etchFactor "0.000000") (elecCondVal "0 mho/cm") (thermCondVal "0 w/cm-degC")) ("L9_GND4" (layerType "PLANE") (material "COPPER") (isShield t) (thickness "  1.200000 mil") (dielectricConstant "4.500000") (lossTangent "0.035") (etchFactor "90.000000") (elecCondVal "595900.000000 mho/cm") (thermCondVal "0 w/cm-degC")) ("" (layerType "DIELECTRIC") (material "FR-4") (thickness "  9.900000 mil") (dielectricConstant "4.100000") (lossTangent "0.035") (etchFactor "0.000000") (elecCondVal "0 mho/cm") (thermCondVal "0.012 w/cm-degC")) ("L10_SIG3" (layerType "CONDUCTOR") (material "COPPER") (thickness "  1.200000 mil") (width "4.00 MIL") (dielectricConstant "4.500000") (lossTangent "0.035") (etchFactor "90.000000") (elecCondVal "595900.000000 mho/cm") (thermCondVal "0.012 w/cm-degC") (signalDieConstant "4.100000") (signalLossTangent "0.035")) ("" (layerType "DIELECTRIC") (material "FR-4") (thickness "  3.300000 mil") (dielectricConstant "4.500000") (lossTangent "0.035") (etchFactor "0.000000") (elecCondVal "0 mho/cm") (thermCondVal "0 w/cm-degC")) ("L11_GND5" (layerType "PLANE") (material "COPPER") (isShield t) (thickness "  1.200000 mil") (dielectricConstant "4.500000") (lossTangent "0.035") (etchFactor "90.000000") (elecCondVal "595900.000000 mho/cm") (thermCondVal "0 w/cm-degC")) ("" (layerType "DIELECTRIC") (material "FR-4") (thickness "  9.900000 mil") (dielectricConstant "4.500000") (lossTangent "0.035") (etchFactor "0.000000") (elecCondVal "0 mho/cm") (thermCondVal "0.012 w/cm-degC")) ("L12_SIG4" (layerType "CONDUCTOR") (material "COPPER") (thickness "  1.200000 mil") (width "4.00 MIL") (dielectricConstant "4.500000") (lossTangent "0.035") (etchFactor "90.000000") (elecCondVal "595900.000000 mho/cm") (thermCondVal "0.012 w/cm-degC") (signalDieConstant "4.500000") (signalLossTangent "0.035")) ("" (layerType "DIELECTRIC") (material "FR-4") (thickness "  3.300000 mil") (dielectricConstant "4.500000") (lossTangent "0.035") (etchFactor "0.000000") (elecCondVal "0 mho/cm") (thermCondVal "0 w/cm-degC")) ("L13_GND6" (layerType "PLANE") (material "COPPER") (isShield t) (thickness "  1.200000 mil") (dielectricConstant "4.500000") (lossTangent "0.035") (etchFactor "90.000000") (elecCondVal "595900.000000 mho/cm") (thermCondVal "0.012 w/cm-degC")) ("" (layerType "DIELECTRIC") (material "FR-4") (thickness "  2.700000 mil") (dielectricConstant "4.500000") (lossTangent "0.035") (etchFactor "0.000000") (elecCondVal "0 mho/cm") (thermCondVal "0.012 w/cm-degC")) ("BOTTOM" (layerType "CONDUCTOR") (material "COPPER") (thickness "  1.800000 mil") (width "4.00 MIL") (dielectricConstant "4.500000") (lossTangent "0") (etchFactor "70.000000") (elecCondVal "595900.000000 mho/cm") (thermCondVal "0 w/cm-degC") (signalDieConstant "3.800000") (signalLossTangent "0.035")) ("" (layerType "DIELECTRIC") (material "CONFORMAL_COAT") (thickness "0.5 mil") (dielectricConstant "3.800000") (lossTangent "0.035") (etchFactor "0.000000") (elecCondVal "0 mho/cm") (thermCondVal "0.012 w/cm-degC")) ("" (layerType "SURFACE") (material "AIR") (thickness "0 mil") (dielectricConstant "1.000000") (lossTangent "0") (etchFactor "0.000000") (elecCondVal "0 mho/cm") (thermCondVal "0 w/cm-degC"))))) (Props (DesUnits "mils 2") (LayerStack ("DIELECTRIC" "DIELECTRIC" "BOTTOM" "DIELECTRIC" "L13_GND6" "DIELECTRIC" "L12_SIG4" "DIELECTRIC" "L11_GND5" "DIELECTRIC" "L10_SIG3" "DIELECTRIC" "L9_GND4" "DIELECTRIC" "L8_PWR2-SIG" "DIELECTRIC" "L7_PWR1-SIG" "DIELECTRIC" "L6_GND3" "DIELECTRIC" "L5_SIG2" "DIELECTRIC" "L4_GND2" "DIELECTRIC" "L3_SIG1" "DIELECTRIC" "L2_GND1" "DIELECTRIC" "TOP" "DIELECTRIC" "DIELECTRIC")) (Revision "16.600")) (Params (ESpiceDevice nil) (Cable (length("1 m"))) (Via ((model "Unknown") (viaOutputFormat "Unknown") (viaPadstack nil) (viaTopLayer nil) (viaBottomLayer nil) (viaIsPower nil) (viaIsGround nil))) (Trace ((d1Thickness "10 mil") (d1Constant "4.5") (d1LossTangent "0.035") (d2Thickness "10 mil") (d2Constant "4.5") (d2LossTangent "0.035") (d3Thickness "0.0") (d3Constant "1.0") (d3LossTangent "0") length("1000 mil") (spacing "5 mil") (spacing2 "5 mil") (spacing3 "5 mil") (spacing4 "5 mil") (spacing5 "5 mil") (traceConductivity "595900 mho/cm") (traceGeometry "microstrip") (traceLayerName "") (traceThickness "0.72 mil") (traceType "single") (traceWidth "5.0 mil") (traceWidth2 "5.0 mil") (traceWidth3 "5.0 mil") (traceWidth4 "5.0 mil") (traceWidth5 "5.0 mil") (traceWidth6 "5.0 mil") (offset "0 mil") (traceCount "1") (impedance nil))) (IbisOutput_OpenPullUp ((temperature "27") (bufferModel "CDSDefaultOutput_2p5v") (stimuli nil) (offsets nil) (state "tristate") (cycle "1") (termMap nil) (setup "2.0e-09") (hold "1.0e-09") (rise nil) (fall nil) (macroType nil) (voltage nil) (spice nil) (LEFDEFPinName nil) (LEFDEFPinType nil) (mappingTag nil))) (IbisInput ((temperature "27") (bufferModel "CDSDefaultInput_2p5v") (cycle "1") (LEFDEFPinName nil) (LEFDEFPinType nil) (mappingTag nil))) (IbisIO_OpenPullUp ((temperature "27") (bufferModel "CDSDefaultIO_2p5v") (stimuli nil) (offsets nil) (state "tristate") (cycle "1") (termMap nil) (setup "2.0e-09") (hold "1.0e-09") (rise nil) (fall nil) (macroType nil) (voltage nil) (spice nil) (LEFDEFPinName nil) (LEFDEFPinType nil) (mappingTag nil))) (clocked ((clockRise "1e-09") (clockFall "1e-09") (clockFreq "100e6") (clockInitState "0") (clockDutyCycle "0.5") (clockJitter "0"))) (periodic ((periodicFreq "100e6") (periodicPattern "10") (periodicJitter "0"))) (IbisIO_OpenPullDown ((temperature "27") (bufferModel "CDSDefaultIO_2p5v") (stimuli nil) (offsets nil) (state "tristate") (cycle "1") (termMap nil) (setup "2.0e-09") (hold "1.0e-09") (rise nil) (fall nil) (macroType nil) (voltage nil) (spice nil) (LEFDEFPinName nil) (LEFDEFPinType nil) (mappingTag nil))) (RLGC (length("1000 mil"))) (DiffIO ((temperature "27") (bufferModelNonInverting "CDSDefaultIO_2p5v") (bufferModelInverting "CDSDefaultIO_2p5v") (stimuli nil) (offsets nil) (state "tristate") (cycle "1") (termMap nil) (setup "0.9e-09") (hold "0.4e-09") (rise nil) (fall nil) (threshInputHighMin "1.7 V") (threshInputHighTyp "1.7  V") (threshInputHighMax "1.7  V") (threshInputLowMin "0.7  V") (threshInputLowTyp "0.7  V") (threshInputLowMax "0.7 ") (threshOutputHighMin "2.365  V") (threshOutputHighTyp "2.5  V") (threshOutputHighMax "2.625  V") (threshOutputLowMin "1.275  V") (threshOutputLowTyp "1.7  V") (threshOutputLowMax "1.985  V") (mappingTagNonInverting nil) (mappingTagInverting nil) (spice nil))) (IbisOutput ((temperature "27") (bufferModel "CDSDefaultOutput_2p5v") (stimuli nil) (offsets nil) (state "tristate") (cycle "1") (termMap nil) (setup "2.0e-09") (hold "1.0e-09") (rise nil) (fall nil) (macroType nil) (voltage nil) (spice nil) (LEFDEFPinName nil) (LEFDEFPinType nil) (mappingTag nil))) (Source ((voltage "5 V"))) (Inductor ((inductance "5 nH") (orientation "0"))) (DiffIOPkg ((temperature "27") (bufferModelNonInverting "CDSDefaultIO_2p5v") (bufferModelInverting "CDSDefaultIO_2p5v") (stimuli nil) (offsets nil) (state "tristate") (cycle "1") (termMap nil) (setup "0.9e-09") (hold "0.4e-09") (rise nil) (fall nil) (threshInputHighMin "1.7 V") (threshInputHighTyp "1.7  V") (threshInputHighMax "1.7  V") (threshInputLowMin "0.7  V") (threshInputLowTyp "0.7  V") (threshInputLowMax "0.7 ") (threshOutputHighMin "2.365  V") (threshOutputHighTyp "2.5  V") (threshOutputHighMax "2.625  V") (threshOutputLowMin "1.275  V") (threshOutputLowTyp "1.7  V") (threshOutputLowMax "1.985  V") (mappingTagNonInverting nil) (mappingTagInverting nil) (spice nil))) (IbisIO ((temperature "27") (bufferModel "CDSDefaultIO_2p5v") (stimuli nil) (offsets nil) (state "tristate") (cycle "1") (termMap nil) (setup "2.0e-09") (hold "1.0e-09") (rise nil) (fall nil) (macroType nil) (voltage nil) (spice nil) (LEFDEFPinName nil) (LEFDEFPinType nil) (mappingTag nil))) (SeriesTerm ((resistance "22 ohm") (maxDelay "0.1 ns"))) (CPW ((d1Thickness "10 mil") (d1Constant "4.5") (d1LossTangent "0.035") (d2Thickness "0.72 mil") (d2Constant "1") (d2LossTangent "0") (d3Thickness "0.0") (d3Constant "1") (d3LossTangent "0") length("1000 mil") (spacing "5 mil") (spacing2 "5 mil") (spacing3 "5 mil") (spacing4 "5 mil") (spacing5 "5 mil") (traceConductivity "595900 mho/cm") (traceGeometry "cpwms") (traceLayerName "") (traceThickness "0.72 mil") (traceType "single") (traceWidth "5.0 mil") (traceWidth2 "5.0 mil") (traceWidth3 "5.0 mil") (traceWidth4 "5.0 mil") (traceWidth5 "5.0 mil") (traceWidth6 "5.0 mil") (offset "0 mil") (traceCount "1") (impedance nil))) (CPWMS ((d1Thickness "10 mil") (d1Constant "4.5") (d1LossTangent "0.035") (d2Thickness "0.72 mil") (d2Constant "4.5") (d2LossTangent "0.035") (d3Thickness "0.0") (d3Constant "1") (d3LossTangent "0") length("1000 mil") (spacing "5 mil") (spacing2 "5 mil") (spacing3 "5 mil") (spacing4 "5 mil") (spacing5 "5 mil") (traceConductivity "595900 mho/cm") (traceGeometry "cpwms") (traceLayerName "") (traceThickness "0.72 mil") (traceType "single") (traceWidth "5.0 mil") (traceWidth2 "5.0 mil") (traceWidth3 "5.0 mil") (traceWidth4 "5.0 mil") (traceWidth5 "5.0 mil") (traceWidth6 "5.0 mil") (offset "0 mil") (traceCount "1") (impedance nil))) (TLine ((diffImpedance "100ohm") (diffVelocity "1.4142e+08M/s") (impedance "60ohm") length("2800 mil") (propDelay "0.5 ns") (velocity "5600 mil/ns") (traceCount "1") (traceGeometry "Microstrip") (impedanceMin nil) (impedanceMax nil) (lengthMin nil) (lengthMax nil) (propDelayMin nil) (propDelayMax nil) (impedanceSweepCount nil) (propDelaySweepCount nil) (velocitySweepCount nil) (lengthSweepCount nil) (matchSetName nil))) (sync ((syncFreq "100e6") (syncInitState "1") (syncPattern "10") (syncEdgeSwitch "rise"))) (Connector nil) (Diode ((cutoffVoltage "0.7 V"))) (CurrentProbe nil) (CPWSL ((d1Thickness "10 mil") (d1Constant "4.5") (d1LossTangent "0.035") (d2Thickness "0.72 mil") (d2Constant "4.5") (d2LossTangent "0.035") (d3Thickness "10 mil") (d3Constant "4.5") (d3LossTangent "0.035") length("1000 mil") (spacing "5 mil") (spacing2 "5 mil") (spacing3 "5 mil") (spacing4 "5 mil") (spacing5 "5 mil") (traceConductivity "595900 mho/cm") (traceGeometry "cpwms") (traceLayerName "") (traceThickness "0.72 mil") (traceType "single") (traceWidth "5.0 mil") (traceWidth2 "5.0 mil") (traceWidth3 "5.0 mil") (traceWidth4 "5.0 mil") (traceWidth5 "5.0 mil") (traceWidth6 "5.0 mil") (offset "0 mil") (traceCount "1") (impedance nil))) (async ((asyncTimePoints "") (asyncInitState "1"))) (Capacitor ((capacitance "10 pF") (orientation "0"))) (DiffOutputPkg ((temperature "27") (bufferModelNonInverting "CDSDefaultOutput_2p5v") (bufferModelInverting "CDSDefaultOutput_2p5v") (stimuli nil) (offsets nil) (state "tristate") (cycle "1") (termMap nil) (setup "0.9e-09") (hold "0.4e-09") (rise nil) (fall nil) (threshOutputHighMin "2.375  V") (threshOutputHighTyp "2.5  V") (threshOutputHighMax "2.625  V") (threshOutputLowMin "1.275  V") (threshOutputLowTyp "1.7  V") (threshOutputLowMax "1.985  V") (mappingTagNonInverting nil) (mappingTagInverting nil) (spice nil))) (DiffOutput ((temperature "27") (bufferModelNonInverting "CDSDefaultOutput_2p5v") (bufferModelInverting "CDSDefaultOutput_2p5v") (stimuli nil) (offsets nil) (state "tristate") (cycle "1") (termMap nil) (setup "0.9e-09") (hold "0.4e-09") (rise nil) (fall nil) (threshOutputHighMin "2.375  V") (threshOutputHighTyp "2.5  V") (threshOutputHighMax "2.625  V") (threshOutputLowMin "1.275  V") (threshOutputLowTyp "1.7  V") (threshOutputLowMax "1.985  V") (mappingTagNonInverting nil) (mappingTagInverting nil) (spice nil))) (HiClampTerm ((cutoffVoltage "0.7 V") (voltage "5 V") (maxDelay "0.1 ns"))) (IbisInputPkg ((temperature "27") (bufferModel "CDSDefaultInput_2p5v") (cycle "1") (LEFDEFPinName nil) (LEFDEFPinType nil) (mappingTag nil))) (Resistor ((resistance "50 ohm") (orientation "0"))) (DiffInput ((temperature "27") (bufferModelNonInverting "CDSDefaultInput_2p5v") (bufferModelInverting "CDSDefaultInput_2p5v") (threshInputHighMin "1.7 V") (threshInputHighTyp "1.7  V") (threshInputHighMax "1.7  V") (threshInputLowMin "0.7  V") (threshInputLowTyp "0.7  V") (threshInputLowMax "0.7  V") (mappingTagNonInverting nil) (mappingTagInverting nil) (cycle "1"))) (DualClampTerm ((cutoffVoltageUp "0.7 V") (cutoffVoltageDown "0.7 V") (voltageUp "5 V") (voltageDown "0 V") (maxDelay "0.1 ns"))) (IbisOutputPkg ((temperature "27") (bufferModel "CDSDefaultOutput_2p5v") (stimuli nil) (offsets nil) (state "tristate") (cycle "1") (termMap nil) (setup "2.0e-09") (hold "1.0e-09") (rise nil) (fall nil) (macroType nil) (voltage nil) (spice nil) (LEFDEFPinName nil) (LEFDEFPinType nil) (mappingTag nil))) (IbisIOPkg ((temperature "27") (bufferModel "CDSDefaultIO_2p5v") (stimuli nil) (offsets nil) (state "tristate") (cycle "1") (termMap nil) (setup "2.0e-09") (hold "1.0e-09") (rise nil) (fall nil) (macroType nil) (voltage nil) (spice nil) (LEFDEFPinName nil) (LEFDEFPinType nil) (mappingTag nil))) (TheveninTerm ((resistanceUp "180 ohm") (resistanceDown "270 ohm") (voltageUp "5 V") (voltageDown "0 V") (maxDelay "0.1 ns"))) (IbisIOMacro ((temperature "27") (bufferModel "CDSDefaultIO_2p5v") (stimuli nil) (offsets nil) (state "tristate") (cycle "1") (termMap nil) (setup "2.0e-09") (hold "1.0e-09") (rise nil) (fall nil) (macroType nil) (voltage nil) (spice nil) (LEFDEFPinName nil) (LEFDEFPinType nil) (mappingTag nil))) (RCTerm ((resistance "50 ohm") (capacitance "20 pF") (voltage "5 V") (maxDelay "0.1 ns"))) (LowClampTerm ((cutoffVoltage "0.7 V") (voltage "0 V") (maxDelay "0.1 ns"))) (DiffInputPkg ((temperature "27") (bufferModelNonInverting "CDSDefaultInput_2p5v") (bufferModelInverting "CDSDefaultInput_2p5v") (threshInputHighMin "1.7 V") (threshInputHighTyp "1.7  V") (threshInputHighMax "1.7  V") (threshInputLowMin "0.7  V") (threshInputLowTyp "0.7  V") (threshInputLowMax "0.7  V") (mappingTagNonInverting nil) (mappingTagInverting nil) (cycle "1"))) (ShuntTerm ((resistance "50 ohm") (voltage "5 V") (maxDelay "0.1 ns"))) (idlCircuit ((allDrivers "active") (ftsMode '("Typ")) (rcvrSelect "all") (simMode "Reflection") (tlineDelayMode "time") (userRevision "1.0") (autoSolve "On")))))
				)
				( objectStatus "DDR_A_CMD_DLL1-13" )
			)
			( electricalCSet "@crescent_city_bb_fab1_lib.crescent_city_bb_fab1(sch_1):\DDR_DQ_A\"
				( groupRef "DDR_DQ_NEW:MG_DQ_NEAR_DIMM" )
				( groupRef "DDR_DQ_NEW:MG_DQ_FAR_DIMM" )
				( groupRef "DDR_DQ_NEW:MG_DQ-DQS_NEAR_DIMM" )
				( groupRef "DDR_DQ_NEW:MG_DQ-DQS_FAR_DIMM" )
				( pinPairRef "DDR_DQ_NEW:U5D1.AN86:J6T1.5" )
				( pinPairRef "DDR_DQ_NEW:U5D1.AN86:J4G1.5" )
				( attribute "TOPOLOGY_TEMPLATE_REVISION" "1.0"
					( Origin gBackEnd )
				)
				( topologyData 22009
(SKIDL (Circuits ("MAIN" (Parts ("CRESCENT_CITY_065_20140613_B.@@J2.5" IbisIOPkg (xy (5522 4240)) (refDes "J6T1") (model "Unknown") (Props (_SXDesignName "CRESCENT_CITY_065_20140613_B") (brdx "12517.71 MIL") (brdy "5050.23 MIL") (bufferModel "CDSDefaultIO_2p5v") (cycle "1") (hold "1.0e-09") (mappingTag "") (offsets ("4" "0") ("5" "0")) (setup "2.0e-09") (state "tristate") (stimuli ("4" "local9") ("5" "local10")) (temperature "27") (termMap ("4" "Data") ("5" "Enable"))) (Terms ("CRESCENT_CITY_065_20140613_B.X1251771Y505023L20LRATS" "5"))) ("CRESCENT_CITY_065_20140613_B.@@U36.AN86" IbisIOPkg (xy (5542 4240)) (refDes "U5D1") (model "Unknown") (Props (_SXDesignName "CRESCENT_CITY_065_20140613_B") (brdx "11153.55 MIL") (brdy "3448.96 MIL") (bufferModel "CDSDefaultIO_2p5v") (cycle "1") (hold "1.0e-09") (mappingTag "") (offsets ("4" "0") ("5" "0")) (setup "2.0e-09") (state "tristate") (stimuli ("4" "local11") ("5" "local12")) (temperature "27") (termMap ("4" "Data") ("5" "Enable"))) (Terms ("CRESCENT_CITY_065_20140613_B.X1115355Y344896L2LRATS" "AN86"))) ("CRESCENT_CITY_065_20140613_B.@@J1.5" IbisIOPkg (xy (5502 4240)) (refDes "J4G1") (model "Unknown") (Props (_SXDesignName "CRESCENT_CITY_065_20140613_B") (brdx "12517.71 MIL") (brdy "5420.33 MIL") (bufferModel "CDSDefaultIO_2p5v") (cycle "1") (hold "1.0e-09") (mappingTag "") (offsets ("4" "0") ("5" "0")) (setup "2.0e-09") (state "tristate") (stimuli ("4" "local13") ("5" "local14")) (temperature "27") (termMap ("4" "Data") ("5" "Enable"))) (Terms ("CRESCENT_CITY_065_20140613_B.X1251771Y542033L2LRATS" "5"))) ("CRESCENT_CITY_065_20140613_B.T@@RATS@@J1.5@@J2.5" TLine (xy (5513 4235)) (refDes "TL3") (Props (_SXDesignName "CRESCENT_CITY_065_20140613_B") (impedance "39.475 ohm") length("370.10 MIL") (propDelay "0.06647 ns") (traceCount "1") (traceGeometry "Microstrip") (velocity "5567.91 mil/ns")) (Terms ("CRESCENT_CITY_065_20140613_B.X1251771Y542033L2LRATS" "1") ("CRESCENT_CITY_065_20140613_B.X1251771Y505023L20LRATS" "2"))) ("CRESCENT_CITY_065_20140613_B.T@@RATS@@J2.5@@U36.AN86" TLine (xy (5533 4235)) (refDes "TL4") (Props (_SXDesignName "CRESCENT_CITY_065_20140613_B") (impedance "55.247 ohm") length("2965.43 MIL") (propDelay "0.53261 ns") (traceCount "1") (traceGeometry "Microstrip") (velocity "5567.72 mil/ns")) (Terms ("CRESCENT_CITY_065_20140613_B.X1251771Y505023L20LRATS" "1") ("CRESCENT_CITY_065_20140613_B.X1115355Y344896L2LRATS" "2")))) (Nodes ("CRESCENT_CITY_065_20140613_B.X1251771Y542033L2LRATS" (terms "CRESCENT_CITY_065_20140613_B.T@@RATS@@J1.5@@J2.5.1" "CRESCENT_CITY_065_20140613_B.@@J1.5.1")) ("CRESCENT_CITY_065_20140613_B.X1251771Y505023L20LRATS" (terms "CRESCENT_CITY_065_20140613_B.T@@RATS@@J2.5@@U36.AN86.1" "CRESCENT_CITY_065_20140613_B.T@@RATS@@J1.5@@J2.5.2" "CRESCENT_CITY_065_20140613_B.@@J2.5.1")) ("CRESCENT_CITY_065_20140613_B.X1115355Y344896L2LRATS" (terms "CRESCENT_CITY_065_20140613_B.T@@RATS@@J2.5@@U36.AN86.2" "CRESCENT_CITY_065_20140613_B.@@U36.AN86.1"))) (Ports) (Stimuli ("local10" (scope local) (stimType periodic) (Props (periodicFreq "5e+007") (periodicJitter "0") (periodicPattern "1"))) ("local9" (scope local) (stimType periodic) (Props (periodicFreq "5e+007") (periodicJitter "0") (periodicPattern "1"))) ("local13" (scope local) (stimType periodic) (Props (periodicFreq "5e+007") (periodicJitter "0") (periodicPattern "1"))) ("local14" (scope local) (stimType periodic) (Props (periodicFreq "5e+007") (periodicJitter "0") (periodicPattern "1"))) ("local11" (scope local) (stimType periodic) (Props (periodicFreq "5e+007") (periodicJitter "0") (periodicPattern "1"))) ("local12" (scope local) (stimType periodic) (Props (periodicFreq "5e+007") (periodicJitter "0") (periodicPattern "1")))) (Notes) (Constraints ("RELATIVE_PROPAGATION_DELAY" ("MG_DQ_NEAR_DIMM" "CRESCENT_CITY_065_20140613_B U36.AN86" "CRESCENT_CITY_065_20140613_B J2.5" "NET GROUP" "LENGTH" "0.00127" "LENGTH" "-0.00127") ("MG_DQ_FAR_DIMM" "CRESCENT_CITY_065_20140613_B U36.AN86" "CRESCENT_CITY_065_20140613_B J1.5" "NET GROUP" "LENGTH" "0.00127" "LENGTH" "-0.00127") ("MG_DQ-DQS_NEAR_DIMM" "CRESCENT_CITY_065_20140613_B U36.AN86" "CRESCENT_CITY_065_20140613_B J2.5" "NET GROUP" "LENGTH" "0.004953" "LENGTH" "0") ("MG_DQ-DQS_FAR_DIMM" "CRESCENT_CITY_065_20140613_B U36.AN86" "CRESCENT_CITY_065_20140613_B J1.5" "NET GROUP" "LENGTH" "0.004953" "LENGTH" "0"))) (MeasurementSets ("EMI" ("EMIStatus" status("on")) ("PeakEmission" status("on")) ("PeakFrequency" status("on")) ("PulseFreq" status("on")) ("RiseTime" status("on")) ("VoltageSwing" status("on"))) ("Reflection" ("BufferDelayFall" status("off")) ("BufferDelayRise" status("off")) ("EyeHeight" status("off")) ("EyeJitter" status("off")) ("EyeWidth" status("off")) ("FirstIncidentFall" status("off")) ("FirstIncidentRise" status("off")) ("Glitch" status("on")) ("GlitchFall" status("off")) ("GlitchRise" status("off")) ("Monotonic" status("on")) ("MonotonicFall" status("off")) ("MonotonicRise" status("off")) ("NoiseMargin" status("on")) ("NoiseMarginHigh" status("off")) ("NoiseMarginLow" status("off")) ("OvershootHigh" status("on")) ("OvershootLow" status("on")) ("PropDelay" status("on")) ("SettleDelay" status("on")) ("SettleDelayFall" status("off")) ("SettleDelayRise" status("off")) ("SwitchDelay" status("on")) ("SwitchDelayFall" status("off")) ("SwitchDelayRise" status("off"))) ("Crosstalk" ("Crosstalk" status("on"))) ("Custom")) (VectorSets) (Props (XnetName "M_A_DQ<0>") (allDrivers "active") (customSimType "Reflection") (ftsMode ("Typ")) (rcvrSelect "all") (tlineDelayMode "time") (userRevision "1.0")))) (Subckts) (CrossSections ("CRESCENT_CITY_065_20140613_B" (Props (SXDesignName "CRESCENT_CITY_065_20140613_B")) (Layers ("" (layerType "SURFACE") (material "AIR") (thickness "0 mil") (dielectricConstant "1.000000") (lossTangent "0") (etchFactor "0.000000") (elecCondVal "0 mho/cm") (thermCondVal "0 w/cm-degC")) ("" (layerType "DIELECTRIC") (material "CONFORMAL_COAT") (thickness "0.5 mil") (dielectricConstant "3.800000") (lossTangent "0.035") (etchFactor "0.000000") (elecCondVal "0 mho/cm") (thermCondVal "0.012 w/cm-degC")) ("TOP" (layerType "CONDUCTOR") (material "COPPER") (thickness "  2.000000 mil") (width "4.00 MIL") (dielectricConstant "4.500000") (lossTangent "0") (etchFactor "70.000000") (elecCondVal "595900.000000 mho/cm") (thermCondVal "0 w/cm-degC") (signalDieConstant "3.800000") (signalLossTangent "0.035")) ("" (layerType "DIELECTRIC") (material "FR-4") (thickness "  2.700000 mil") (dielectricConstant "4.000000") (lossTangent "0.035") (etchFactor "0.000000") (elecCondVal "0 mho/cm") (thermCondVal "0.012 w/cm-degC")) ("L2_GND1" (layerType "PLANE") (material "COPPER") (isShield t) (thickness "  1.300000 mil") (dielectricConstant "4.500000") (lossTangent "0.035") (etchFactor "90.000000") (elecCondVal "595900.000000 mho/cm") (thermCondVal "0.012 w/cm-degC")) ("" (layerType "DIELECTRIC") (material "FR-4") (thickness "  4.000000 mil") (dielectricConstant "4.100000") (lossTangent "0.035") (etchFactor "0.000000") (elecCondVal "0 mho/cm") (thermCondVal "0.012 w/cm-degC")) ("L3_SIG1" (layerType "CONDUCTOR") (material "COPPER") (thickness "  1.300000 mil") (width "4.00 MIL") (dielectricConstant "4.500000") (lossTangent "0.035") (etchFactor "90.000000") (elecCondVal "595900.000000 mho/cm") (thermCondVal "0.012 w/cm-degC") (signalDieConstant "4.100000") (signalLossTangent "0.035")) ("" (layerType "DIELECTRIC") (material "FR-4") (thickness " 21.000000 mil") (dielectricConstant "4.000000") (lossTangent "0.035") (etchFactor "0.000000") (elecCondVal "0 mho/cm") (thermCondVal "0.012 w/cm-degC")) ("L4_SIG2" (layerType "CONDUCTOR") (material "COPPER") (thickness "  1.300000 mil") (width "4.00 MIL") (dielectricConstant "4.500000") (lossTangent "0.035") (etchFactor "90.000000") (elecCondVal "595900.000000 mho/cm") (thermCondVal "0.012 w/cm-degC") (signalDieConstant "4.000000") (signalLossTangent "0.035")) ("" (layerType "DIELECTRIC") (material "FR-4") (thickness "  4.000000 mil") (dielectricConstant "4.100000") (lossTangent "0.035") (etchFactor "0.000000") (elecCondVal "0 mho/cm") (thermCondVal "0.012 w/cm-degC")) ("L5_PWR1" (layerType "PLANE") (material "COPPER") (isShield t) (thickness "  2.600000 mil") (dielectricConstant "4.500000") (lossTangent "0.035") (etchFactor "90.000000") (elecCondVal "595900.000000 mho/cm") (thermCondVal "0.012 w/cm-degC")) ("" (layerType "DIELECTRIC") (material "FR-4") (thickness "  4.000000 mil") (dielectricConstant "4.000000") (lossTangent "0.035") (etchFactor "0.000000") (elecCondVal "0 mho/cm") (thermCondVal "0.012 w/cm-degC")) ("L6_PWR2" (layerType "PLANE") (material "COPPER") (isShield t) (thickness "  2.600000 mil") (dielectricConstant "4.500000") (lossTangent "0.035") (etchFactor "90.000000") (elecCondVal "595900.000000 mho/cm") (thermCondVal "0.012 w/cm-degC")) ("" (layerType "DIELECTRIC") (material "FR-4") (thickness "  4.000000 mil") (dielectricConstant "4.100000") (lossTangent "0.035") (etchFactor "0.000000") (elecCondVal "0 mho/cm") (thermCondVal "0.012 w/cm-degC")) ("L7_SIG3" (layerType "CONDUCTOR") (material "COPPER") (thickness "  1.300000 mil") (width "4.00 MIL") (dielectricConstant "4.500000") (lossTangent "0.035") (etchFactor "90.000000") (elecCondVal "595900.000000 mho/cm") (thermCondVal "0.012 w/cm-degC") (signalDieConstant "4.100000") (signalLossTangent "0.035")) ("" (layerType "DIELECTRIC") (material "FR-4") (thickness " 21.000000 mil") (dielectricConstant "4.500000") (lossTangent "0.035") (etchFactor "0.000000") (elecCondVal "0 mho/cm") (thermCondVal "0.012 w/cm-degC")) ("L8_SIG4" (layerType "CONDUCTOR") (material "COPPER") (thickness "  1.300000 mil") (width "4.00 MIL") (dielectricConstant "4.500000") (lossTangent "0.035") (etchFactor "90.000000") (elecCondVal "595900.000000 mho/cm") (thermCondVal "0.012 w/cm-degC") (signalDieConstant "4.500000") (signalLossTangent "0.035")) ("" (layerType "DIELECTRIC") (material "FR-4") (thickness "  8.000000 mil") (dielectricConstant "4.500000") (lossTangent "0.035") (etchFactor "0.000000") (elecCondVal "0 mho/cm") (thermCondVal "0 w/cm-degC")) ("L9_GND4" (layerType "PLANE") (material "COPPER") (isShield t) (thickness "  1.300000 mil") (dielectricConstant "4.500000") (lossTangent "0.035") (etchFactor "90.000000") (elecCondVal "595900.000000 mho/cm") (thermCondVal "0.012 w/cm-degC")) ("" (layerType "DIELECTRIC") (material "FR-4") (thickness "  2.700000 mil") (dielectricConstant "4.500000") (lossTangent "0.035") (etchFactor "0.000000") (elecCondVal "0 mho/cm") (thermCondVal "0.012 w/cm-degC")) ("BOTTOM" (layerType "CONDUCTOR") (material "COPPER") (thickness "  2.000000 mil") (width "4.00 MIL") (dielectricConstant "4.500000") (lossTangent "0") (etchFactor "70.000000") (elecCondVal "595900.000000 mho/cm") (thermCondVal "0 w/cm-degC") (signalDieConstant "3.800000") (signalLossTangent "0.035")) ("" (layerType "DIELECTRIC") (material "CONFORMAL_COAT") (thickness "0.5 mil") (dielectricConstant "3.800000") (lossTangent "0.035") (etchFactor "0.000000") (elecCondVal "0 mho/cm") (thermCondVal "0.012 w/cm-degC")) ("" (layerType "SURFACE") (material "AIR") (thickness "0 mil") (dielectricConstant "1.000000") (lossTangent "0") (etchFactor "0.000000") (elecCondVal "0 mho/cm") (thermCondVal "0 w/cm-degC"))))) (Props (DesUnits "mils 2") (LayerStack ("DIELECTRIC" "DIELECTRIC" "BOTTOM" "DIELECTRIC" "L9_GND4" "DIELECTRIC" "L8_SIG4" "DIELECTRIC" "L7_SIG3" "DIELECTRIC" "L6_PWR2" "DIELECTRIC" "L5_PWR1" "DIELECTRIC" "L4_SIG2" "DIELECTRIC" "L3_SIG1" "DIELECTRIC" "L2_GND1" "DIELECTRIC" "TOP" "DIELECTRIC" "DIELECTRIC")) (Revision "16.600")) (Params (Resistor ((resistance "50 ohm") (orientation "0"))) (DiffOutputPkg ((mappingTagInverting nil) (mappingTagNonInverting nil) (temperature "27") (bufferModelNonInverting "CDSDefaultOutput_2p5v") (bufferModelInverting "CDSDefaultOutput_2p5v") (stimuli nil) (offsets nil) (state "tristate") (cycle "1") (termMap nil) (setup "0.9e-09") (hold "0.4e-09") (rise nil) (fall nil) (threshOutputHighMin "2.375  V") (threshOutputHighTyp "2.5  V") (threshOutputHighMax "2.625  V") (threshOutputLowMin "1.275  V") (threshOutputLowTyp "1.7  V") (threshOutputLowMax "1.985  V") (spice nil))) (DiffOutput ((mappingTagInverting nil) (mappingTagNonInverting nil) (temperature "27") (bufferModelNonInverting "CDSDefaultOutput_2p5v") (bufferModelInverting "CDSDefaultOutput_2p5v") (stimuli nil) (offsets nil) (state "tristate") (cycle "1") (termMap nil) (setup "0.9e-09") (hold "0.4e-09") (rise nil) (fall nil) (threshOutputHighMin "2.375  V") (threshOutputHighTyp "2.5  V") (threshOutputHighMax "2.625  V") (threshOutputLowMin "1.275  V") (threshOutputLowTyp "1.7  V") (threshOutputLowMax "1.985  V") (spice nil))) (Inductor ((inductance "5 nH") (orientation "0"))) (Capacitor ((capacitance "10 pF") (orientation "0"))) (DiffIOPkg ((mappingTagInverting nil) (mappingTagNonInverting nil) (temperature "27") (bufferModelNonInverting "CDSDefaultIO_2p5v") (bufferModelInverting "CDSDefaultIO_2p5v") (stimuli nil) (offsets nil) (state "tristate") (cycle "1") (termMap nil) (setup "0.9e-09") (hold "0.4e-09") (rise nil) (fall nil) (threshInputHighMin "1.7 V") (threshInputHighTyp "1.7  V") (threshInputHighMax "1.7  V") (threshInputLowMin "0.7  V") (threshInputLowTyp "0.7  V") (threshInputLowMax "0.7 ") (threshOutputHighMin "2.365  V") (threshOutputHighTyp "2.5  V") (threshOutputHighMax "2.625  V") (threshOutputLowMin "1.275  V") (threshOutputLowTyp "1.7  V") (threshOutputLowMax "1.985  V") (spice nil))) (Source ((voltage "5 V"))) (DiffIO ((mappingTagInverting nil) (mappingTagNonInverting nil) (temperature "27") (bufferModelNonInverting "CDSDefaultIO_2p5v") (bufferModelInverting "CDSDefaultIO_2p5v") (stimuli nil) (offsets nil) (state "tristate") (cycle "1") (termMap nil) (setup "0.9e-09") (hold "0.4e-09") (rise nil) (fall nil) (threshInputHighMin "1.7 V") (threshInputHighTyp "1.7  V") (threshInputHighMax "1.7  V") (threshInputLowMin "0.7  V") (threshInputLowTyp "0.7  V") (threshInputLowMax "0.7 ") (threshOutputHighMin "2.365  V") (threshOutputHighTyp "2.5  V") (threshOutputHighMax "2.625  V") (threshOutputLowMin "1.275  V") (threshOutputLowTyp "1.7  V") (threshOutputLowMax "1.985  V") (spice nil))) (IbisIO ((mappingTag nil) (temperature "27") (bufferModel "CDSDefaultIO_2p5v") (stimuli nil) (offsets nil) (state "tristate") (cycle "1") (termMap nil) (setup "2.0e-09") (hold "1.0e-09") (rise nil) (fall nil) (macroType nil) (voltage nil) (spice nil) (LEFDEFPinName nil) (LEFDEFPinType nil))) (RLGC (length("1000 mil"))) (IbisOutput ((mappingTag nil) (temperature "27") (bufferModel "CDSDefaultOutput_2p5v") (stimuli nil) (offsets nil) (state "tristate") (cycle "1") (termMap nil) (setup "2.0e-09") (hold "1.0e-09") (rise nil) (fall nil) (macroType nil) (voltage nil) (spice nil) (LEFDEFPinName nil) (LEFDEFPinType nil))) (IbisInput ((mappingTag nil) (temperature "27") (bufferModel "CDSDefaultInput_2p5v") (cycle "1") (LEFDEFPinName nil) (LEFDEFPinType nil))) (DiffInput ((mappingTagInverting nil) (mappingTagNonInverting nil) (temperature "27") (bufferModelNonInverting "CDSDefaultInput_2p5v") (bufferModelInverting "CDSDefaultInput_2p5v") (threshInputHighMin "1.7 V") (threshInputHighTyp "1.7  V") (threshInputHighMax "1.7  V") (threshInputLowMin "0.7  V") (threshInputLowTyp "0.7  V") (threshInputLowMax "0.7  V") (cycle "1"))) (ESpiceDevice nil) (TLine ((diffImpedance "100ohm") (diffVelocity "1.4142e+08M/s") (impedance "60ohm") length("2800 mil") (propDelay "0.5 ns") (velocity "5600 mil/ns") (traceCount "1") (traceGeometry "Microstrip") (impedanceMin nil) (impedanceMax nil) (lengthMin nil) (lengthMax nil) (propDelayMin nil) (propDelayMax nil) (impedanceSweepCount nil) (propDelaySweepCount nil) (velocitySweepCount nil) (lengthSweepCount nil) (matchSetName nil))) (Connector nil) (DiffInputPkg ((mappingTagInverting nil) (mappingTagNonInverting nil) (temperature "27") (bufferModelNonInverting "CDSDefaultInput_2p5v") (bufferModelInverting "CDSDefaultInput_2p5v") (threshInputHighMin "1.7 V") (threshInputHighTyp "1.7  V") (threshInputHighMax "1.7  V") (threshInputLowMin "0.7  V") (threshInputLowTyp "0.7  V") (threshInputLowMax "0.7  V") (cycle "1"))) (IbisIO_OpenPullUp ((mappingTag nil) (temperature "27") (bufferModel "CDSDefaultIO_2p5v") (stimuli nil) (offsets nil) (state "tristate") (cycle "1") (termMap nil) (setup "2.0e-09") (hold "1.0e-09") (rise nil) (fall nil) (macroType nil) (voltage nil) (spice nil) (LEFDEFPinName nil) (LEFDEFPinType nil))) (TheveninTerm ((resistanceUp "180 ohm") (resistanceDown "270 ohm") (voltageUp "5 V") (voltageDown "0 V") (maxDelay "0.1 ns"))) (sync ((syncFreq "100e6") (syncInitState "1") (syncPattern "10") (syncEdgeSwitch "rise"))) (idlCircuit ((allDrivers "active") (ftsMode '("Typ")) (rcvrSelect "all") (simMode "Reflection") (tlineDelayMode "time") (userRevision "1.0") (autoSolve "On"))) (IbisOutput_OpenPullUp ((mappingTag nil) (temperature "27") (bufferModel "CDSDefaultOutput_2p5v") (stimuli nil) (offsets nil) (state "tristate") (cycle "1") (termMap nil) (setup "2.0e-09") (hold "1.0e-09") (rise nil) (fall nil) (macroType nil) (voltage nil) (spice nil) (LEFDEFPinName nil) (LEFDEFPinType nil))) (ShuntTerm ((resistance "50 ohm") (voltage "5 V") (maxDelay "0.1 ns"))) (LowClampTerm ((cutoffVoltage "0.7 V") (voltage "0 V") (maxDelay "0.1 ns"))) (RCTerm ((resistance "50 ohm") (capacitance "20 pF") (voltage "5 V") (maxDelay "0.1 ns"))) (IbisInputPkg ((mappingTag nil) (temperature "27") (bufferModel "CDSDefaultInput_2p5v") (cycle "1") (LEFDEFPinName nil) (LEFDEFPinType nil))) (IbisOutputPkg ((mappingTag nil) (temperature "27") (bufferModel "CDSDefaultOutput_2p5v") (stimuli nil) (offsets nil) (state "tristate") (cycle "1") (termMap nil) (setup "2.0e-09") (hold "1.0e-09") (rise nil) (fall nil) (macroType nil) (voltage nil) (spice nil) (LEFDEFPinName nil) (LEFDEFPinType nil))) (IbisIOPkg ((mappingTag nil) (temperature "27") (bufferModel "CDSDefaultIO_2p5v") (stimuli nil) (offsets nil) (state "tristate") (cycle "1") (termMap nil) (setup "2.0e-09") (hold "1.0e-09") (rise nil) (fall nil) (macroType nil) (voltage nil) (spice nil) (LEFDEFPinName nil) (LEFDEFPinType nil))) (IbisIOMacro ((mappingTag nil) (temperature "27") (bufferModel "CDSDefaultIO_2p5v") (stimuli nil) (offsets nil) (state "tristate") (cycle "1") (termMap nil) (setup "2.0e-09") (hold "1.0e-09") (rise nil) (fall nil) (macroType nil) (voltage nil) (spice nil) (LEFDEFPinName nil) (LEFDEFPinType nil))) (IbisIO_OpenPullDown ((mappingTag nil) (temperature "27") (bufferModel "CDSDefaultIO_2p5v") (stimuli nil) (offsets nil) (state "tristate") (cycle "1") (termMap nil) (setup "2.0e-09") (hold "1.0e-09") (rise nil) (fall nil) (macroType nil) (voltage nil) (spice nil) (LEFDEFPinName nil) (LEFDEFPinType nil))) (DualClampTerm ((cutoffVoltageUp "0.7 V") (cutoffVoltageDown "0.7 V") (voltageUp "5 V") (voltageDown "0 V") (maxDelay "0.1 ns"))) (HiClampTerm ((cutoffVoltage "0.7 V") (voltage "5 V") (maxDelay "0.1 ns"))) (CPWSL ((d1Thickness "10 mil") (d1Constant "4.5") (d1LossTangent "0.035") (d2Thickness "0.72 mil") (d2Constant "4.5") (d2LossTangent "0.035") (d3Thickness "10 mil") (d3Constant "4.5") (d3LossTangent "0.035") length("1000 mil") (spacing "5 mil") (spacing2 "5 mil") (spacing3 "5 mil") (spacing4 "5 mil") (spacing5 "5 mil") (traceConductivity "595900 mho/cm") (traceGeometry "cpwms") (traceLayerName "") (traceThickness "0.72 mil") (traceType "single") (traceWidth "5.0 mil") (traceWidth2 "5.0 mil") (traceWidth3 "5.0 mil") (traceWidth4 "5.0 mil") (traceWidth5 "5.0 mil") (traceWidth6 "5.0 mil") (offset "0 mil") (traceCount "1") (impedance nil))) (CPWMS ((d1Thickness "10 mil") (d1Constant "4.5") (d1LossTangent "0.035") (d2Thickness "0.72 mil") (d2Constant "4.5") (d2LossTangent "0.035") (d3Thickness "0.0") (d3Constant "1") (d3LossTangent "0") length("1000 mil") (spacing "5 mil") (spacing2 "5 mil") (spacing3 "5 mil") (spacing4 "5 mil") (spacing5 "5 mil") (traceConductivity "595900 mho/cm") (traceGeometry "cpwms") (traceLayerName "") (traceThickness "0.72 mil") (traceType "single") (traceWidth "5.0 mil") (traceWidth2 "5.0 mil") (traceWidth3 "5.0 mil") (traceWidth4 "5.0 mil") (traceWidth5 "5.0 mil") (traceWidth6 "5.0 mil") (offset "0 mil") (traceCount "1") (impedance nil))) (CurrentProbe nil) (Diode ((cutoffVoltage "0.7 V"))) (clocked ((clockRise "1e-09") (clockFall "1e-09") (clockFreq "100e6") (clockInitState "0") (clockDutyCycle "0.5") (clockJitter "0"))) (periodic ((periodicFreq "100e6") (periodicPattern "10") (periodicJitter "0"))) (CPW ((d1Thickness "10 mil") (d1Constant "4.5") (d1LossTangent "0.035") (d2Thickness "0.72 mil") (d2Constant "1") (d2LossTangent "0") (d3Thickness "0.0") (d3Constant "1") (d3LossTangent "0") length("1000 mil") (spacing "5 mil") (spacing2 "5 mil") (spacing3 "5 mil") (spacing4 "5 mil") (spacing5 "5 mil") (traceConductivity "595900 mho/cm") (traceGeometry "cpwms") (traceLayerName "") (traceThickness "0.72 mil") (traceType "single") (traceWidth "5.0 mil") (traceWidth2 "5.0 mil") (traceWidth3 "5.0 mil") (traceWidth4 "5.0 mil") (traceWidth5 "5.0 mil") (traceWidth6 "5.0 mil") (offset "0 mil") (traceCount "1") (impedance nil))) (Trace ((d1Thickness "10 mil") (d1Constant "4.5") (d1LossTangent "0.035") (d2Thickness "10 mil") (d2Constant "4.5") (d2LossTangent "0.035") (d3Thickness "0.0") (d3Constant "1.0") (d3LossTangent "0") length("1000 mil") (spacing "5 mil") (spacing2 "5 mil") (spacing3 "5 mil") (spacing4 "5 mil") (spacing5 "5 mil") (traceConductivity "595900 mho/cm") (traceGeometry "microstrip") (traceLayerName "") (traceThickness "0.72 mil") (traceType "single") (traceWidth "5.0 mil") (traceWidth2 "5.0 mil") (traceWidth3 "5.0 mil") (traceWidth4 "5.0 mil") (traceWidth5 "5.0 mil") (traceWidth6 "5.0 mil") (offset "0 mil") (traceCount "1") (impedance nil))) (Cable (length("1 m"))) (Via ((model "Unknown") (viaOutputFormat "Unknown") (viaPadstack nil) (viaTopLayer nil) (viaBottomLayer nil) (viaIsPower nil) (viaIsGround nil))) (SeriesTerm ((resistance "22 ohm") (maxDelay "0.1 ns"))) (async ((asyncTimePoints "") (asyncInitState "1")))))
				)
				( objectStatus "DDR_DQ_NEW" )
			)
			( electricalCSet "@crescent_city_bb_fab1_lib.crescent_city_bb_fab1(sch_1):\DDR_CTRL_DLL20-14\"
				( groupRef "DDR_CTRL_DLL20-24:MG_DDR_CTRL" )
				( groupRef "DDR_CTRL_DLL20-24:MG_DDR_NEAR_DIMM-CLK1" )
				( pinPairRef "DDR_CTRL_DLL20-24:U5D1.B51:J6T1.84" )
				( attribute "TOPOLOGY_TEMPLATE_REVISION" "1.0"
					( Origin gBackEnd )
				)
				( topologyData 22229
(SKIDL (Circuits ("MAIN" (Parts ("CRESCENT_CITY_083_20140725_A.@@J2.84" IbisIOPkg (xy (5522 4240)) (refDes "J6T1") (model "Unknown") (Props (_SXDesignName "CRESCENT_CITY_083_20140725_A") (brdx "10643.7 MIL") (brdy "977.33 MIL") (bufferModel "CDSDefaultIO_2p5v") (cycle "1") (hold "1.0e-09") (mappingTag "") (offsets ("4" "0") ("5" "0")) (setup "2.0e-09") (state "tristate") (stimuli ("4" "local11") ("5" "local12")) (temperature "27") (termMap ("4" "Data") ("5" "Enable"))) (Terms ("CRESCENT_CITY_083_20140725_A.X1064370Y97733L28LRATS" "84"))) ("CRESCENT_CITY_083_20140725_A.@@U36.B51" IbisIOPkg (xy (5502 4240)) (refDes "U5D1") (model "Unknown") (Props (_SXDesignName "CRESCENT_CITY_083_20140725_A") (brdx "10346.35 MIL") (brdy "1974.09 MIL") (bufferModel "CDSDefaultIO_2p5v") (cycle "1") (hold "1.0e-09") (mappingTag "") (offsets ("4" "0") ("5" "0")) (setup "2.0e-09") (state "tristate") (stimuli ("4" "local13") ("5" "local14")) (temperature "27") (termMap ("4" "Data") ("5" "Enable"))) (Terms ("CRESCENT_CITY_083_20140725_A.X1034635Y197409L2LRATS" "B51"))) ("CRESCENT_CITY_083_20140725_A.T@@RATS@@U36.B51@@J2.84" TLine (xy (5513 4235)) (refDes "TL3") (Props (_SXDesignName "CRESCENT_CITY_083_20140725_A") (impedance "50.518 ohm") length("1294.11 MIL") (propDelay "0.23243 ns") (traceCount "1") (traceGeometry "Microstrip") (velocity "5567.76 mil/ns")) (Terms ("CRESCENT_CITY_083_20140725_A.X1034635Y197409L2LRATS" "1") ("CRESCENT_CITY_083_20140725_A.X1064370Y97733L28LRATS" "2")))) (Nodes ("CRESCENT_CITY_083_20140725_A.X1064370Y97733L28LRATS" (terms "CRESCENT_CITY_083_20140725_A.T@@RATS@@U36.B51@@J2.84.2" "CRESCENT_CITY_083_20140725_A.@@J2.84.1")) ("CRESCENT_CITY_083_20140725_A.X1034635Y197409L2LRATS" (terms "CRESCENT_CITY_083_20140725_A.T@@RATS@@U36.B51@@J2.84.1" "CRESCENT_CITY_083_20140725_A.@@U36.B51.1"))) (Ports) (Stimuli ("local13" (scope local) (stimType periodic) (Props (periodicFreq "5e+007") (periodicJitter "0") (periodicPattern "1"))) ("local14" (scope local) (stimType periodic) (Props (periodicFreq "5e+007") (periodicJitter "0") (periodicPattern "1"))) ("local11" (scope local) (stimType periodic) (Props (periodicFreq "5e+007") (periodicJitter "0") (periodicPattern "1"))) ("local12" (scope local) (stimType periodic) (Props (periodicFreq "5e+007") (periodicJitter "0") (periodicPattern "1")))) (Notes) (Constraints ("RELATIVE_PROPAGATION_DELAY" ("MG_DDR_CTRL" "CRESCENT_CITY_083_20140725_A U36.B51" "CRESCENT_CITY_083_20140725_A J2.84" "NET GROUP" "LENGTH" "0.000635" "LENGTH" "0") ("MG_DDR_NEAR_DIMM-CLK1" "CRESCENT_CITY_083_20140725_A U36.B51" "CRESCENT_CITY_083_20140725_A J2.84" "CLASS" "LENGTH" "0.00762" "LENGTH" "0"))) (MeasurementSets ("EMI" ("EMIStatus" status("on")) ("PeakEmission" status("on")) ("PeakFrequency" status("on")) ("PulseFreq" status("on")) ("RiseTime" status("on")) ("VoltageSwing" status("on"))) ("Reflection" ("BufferDelayFall" status("off")) ("BufferDelayRise" status("off")) ("EyeHeight" status("off")) ("EyeJitter" status("off")) ("EyeWidth" status("off")) ("FirstIncidentFall" status("off")) ("FirstIncidentRise" status("off")) ("Glitch" status("on")) ("GlitchFall" status("off")) ("GlitchRise" status("off")) ("Monotonic" status("on")) ("MonotonicFall" status("off")) ("MonotonicRise" status("off")) ("NoiseMargin" status("on")) ("NoiseMarginHigh" status("off")) ("NoiseMarginLow" status("off")) ("OvershootHigh" status("on")) ("OvershootLow" status("on")) ("PropDelay" status("on")) ("SettleDelay" status("on")) ("SettleDelayFall" status("off")) ("SettleDelayRise" status("off")) ("SwitchDelay" status("on")) ("SwitchDelayFall" status("off")) ("SwitchDelayRise" status("off"))) ("Crosstalk" ("Crosstalk" status("on"))) ("Custom")) (VectorSets) (Props (XnetName "M_A_CS_N<4>") (allDrivers "active") (customSimType "Reflection") (ftsMode ("Typ")) (rcvrSelect "all") (tlineDelayMode "time") (userRevision "1.0")))) (Subckts) (CrossSections ("CRESCENT_CITY_083_20140725_A" (Props (SXDesignName "CRESCENT_CITY_083_20140725_A")) (Layers ("" (layerType "SURFACE") (material "AIR") (thickness "0 mil") (dielectricConstant "1.000000") (lossTangent "0") (etchFactor "0.000000") (elecCondVal "0 mho/cm") (thermCondVal "0 w/cm-degC")) ("" (layerType "DIELECTRIC") (material "CONFORMAL_COAT") (thickness "0.5 mil") (dielectricConstant "3.800000") (lossTangent "0.035") (etchFactor "0.000000") (elecCondVal "0 mho/cm") (thermCondVal "0.012 w/cm-degC")) ("TOP" (layerType "CONDUCTOR") (material "COPPER") (thickness "  1.800000 mil") (width "4.00 MIL") (dielectricConstant "4.500000") (lossTangent "0") (etchFactor "70.000000") (elecCondVal "595900.000000 mho/cm") (thermCondVal "0 w/cm-degC") (signalDieConstant "3.800000") (signalLossTangent "0.035")) ("" (layerType "DIELECTRIC") (material "FR-4") (thickness "  2.700000 mil") (dielectricConstant "4.000000") (lossTangent "0.035") (etchFactor "0.000000") (elecCondVal "0 mho/cm") (thermCondVal "0.012 w/cm-degC")) ("L2_GND1" (layerType "PLANE") (material "COPPER") (isShield t) (thickness "  1.200000 mil") (dielectricConstant "4.500000") (lossTangent "0.035") (etchFactor "90.000000") (elecCondVal "595900.000000 mho/cm") (thermCondVal "0.012 w/cm-degC")) ("" (layerType "DIELECTRIC") (material "FR-4") (thickness "  9.900000 mil") (dielectricConstant "4.100000") (lossTangent "0.035") (etchFactor "0.000000") (elecCondVal "0 mho/cm") (thermCondVal "0.012 w/cm-degC")) ("L3_SIG1" (layerType "CONDUCTOR") (material "COPPER") (thickness "  1.200000 mil") (width "4.00 MIL") (dielectricConstant "4.500000") (lossTangent "0.035") (etchFactor "90.000000") (elecCondVal "595900.000000 mho/cm") (thermCondVal "0.012 w/cm-degC") (signalDieConstant "4.100000") (signalLossTangent "0.035")) ("" (layerType "DIELECTRIC") (material "FR-4") (thickness "  3.300000 mil") (dielectricConstant "4.500000") (lossTangent "0.035") (etchFactor "0.000000") (elecCondVal "0 mho/cm") (thermCondVal "0 w/cm-degC")) ("L4_GND2" (layerType "PLANE") (material "COPPER") (isShield t) (thickness "  1.200000 mil") (dielectricConstant "4.500000") (lossTangent "0.035") (etchFactor "90.000000") (elecCondVal "595900.000000 mho/cm") (thermCondVal "0 w/cm-degC")) ("" (layerType "DIELECTRIC") (material "FR-4") (thickness "  3.300000 mil") (dielectricConstant "4.000000") (lossTangent "0.035") (etchFactor "0.000000") (elecCondVal "0 mho/cm") (thermCondVal "0.012 w/cm-degC")) ("L5_SIG2" (layerType "CONDUCTOR") (material "COPPER") (thickness "  1.200000 mil") (width "4.00 MIL") (dielectricConstant "4.500000") (lossTangent "0.035") (etchFactor "90.000000") (elecCondVal "595900.000000 mho/cm") (thermCondVal "0.012 w/cm-degC") (signalDieConstant "4.000000") (signalLossTangent "0.035")) ("" (layerType "DIELECTRIC") (material "FR-4") (thickness "  9.900000 mil") (dielectricConstant "4.500000") (lossTangent "0.035") (etchFactor "0.000000") (elecCondVal "0 mho/cm") (thermCondVal "0 w/cm-degC")) ("L6_GND3" (layerType "PLANE") (material "COPPER") (isShield t) (thickness "  1.200000 mil") (dielectricConstant "4.500000") (lossTangent "0.035") (etchFactor "90.000000") (elecCondVal "595900.000000 mho/cm") (thermCondVal "0 w/cm-degC")) ("" (layerType "DIELECTRIC") (material "FR-4") (thickness "  3.300000 mil") (dielectricConstant "4.100000") (lossTangent "0.035") (etchFactor "0.000000") (elecCondVal "0 mho/cm") (thermCondVal "0.012 w/cm-degC")) ("L7_PWR1-SIG" (layerType "PLANE") (material "COPPER") (isShield t) (thickness "  1.200000 mil") (dielectricConstant "4.500000") (lossTangent "0.035") (etchFactor "90.000000") (elecCondVal "595900.000000 mho/cm") (thermCondVal "0.012 w/cm-degC")) ("" (layerType "DIELECTRIC") (material "FR-4") (thickness "  9.900000 mil") (dielectricConstant "4.000000") (lossTangent "0.035") (etchFactor "0.000000") (elecCondVal "0 mho/cm") (thermCondVal "0.012 w/cm-degC")) ("L8_PWR2-SIG" (layerType "PLANE") (material "COPPER") (isShield t) (thickness "  1.200000 mil") (dielectricConstant "4.500000") (lossTangent "0.035") (etchFactor "90.000000") (elecCondVal "595900.000000 mho/cm") (thermCondVal "0.012 w/cm-degC")) ("" (layerType "DIELECTRIC") (material "FR-4") (thickness "  3.300000 mil") (dielectricConstant "4.500000") (lossTangent "0.035") (etchFactor "0.000000") (elecCondVal "0 mho/cm") (thermCondVal "0 w/cm-degC")) ("L9_GND4" (layerType "PLANE") (material "COPPER") (isShield t) (thickness "  1.200000 mil") (dielectricConstant "4.500000") (lossTangent "0.035") (etchFactor "90.000000") (elecCondVal "595900.000000 mho/cm") (thermCondVal "0 w/cm-degC")) ("" (layerType "DIELECTRIC") (material "FR-4") (thickness "  9.900000 mil") (dielectricConstant "4.100000") (lossTangent "0.035") (etchFactor "0.000000") (elecCondVal "0 mho/cm") (thermCondVal "0.012 w/cm-degC")) ("L10_SIG3" (layerType "CONDUCTOR") (material "COPPER") (thickness "  1.200000 mil") (width "4.00 MIL") (dielectricConstant "4.500000") (lossTangent "0.035") (etchFactor "90.000000") (elecCondVal "595900.000000 mho/cm") (thermCondVal "0.012 w/cm-degC") (signalDieConstant "4.100000") (signalLossTangent "0.035")) ("" (layerType "DIELECTRIC") (material "FR-4") (thickness "  3.300000 mil") (dielectricConstant "4.500000") (lossTangent "0.035") (etchFactor "0.000000") (elecCondVal "0 mho/cm") (thermCondVal "0 w/cm-degC")) ("L11_GND5" (layerType "PLANE") (material "COPPER") (isShield t) (thickness "  1.200000 mil") (dielectricConstant "4.500000") (lossTangent "0.035") (etchFactor "90.000000") (elecCondVal "595900.000000 mho/cm") (thermCondVal "0 w/cm-degC")) ("" (layerType "DIELECTRIC") (material "FR-4") (thickness "  9.900000 mil") (dielectricConstant "4.500000") (lossTangent "0.035") (etchFactor "0.000000") (elecCondVal "0 mho/cm") (thermCondVal "0.012 w/cm-degC")) ("L12_SIG4" (layerType "CONDUCTOR") (material "COPPER") (thickness "  1.200000 mil") (width "4.00 MIL") (dielectricConstant "4.500000") (lossTangent "0.035") (etchFactor "90.000000") (elecCondVal "595900.000000 mho/cm") (thermCondVal "0.012 w/cm-degC") (signalDieConstant "4.500000") (signalLossTangent "0.035")) ("" (layerType "DIELECTRIC") (material "FR-4") (thickness "  3.300000 mil") (dielectricConstant "4.500000") (lossTangent "0.035") (etchFactor "0.000000") (elecCondVal "0 mho/cm") (thermCondVal "0 w/cm-degC")) ("L13_GND6" (layerType "PLANE") (material "COPPER") (isShield t) (thickness "  1.200000 mil") (dielectricConstant "4.500000") (lossTangent "0.035") (etchFactor "90.000000") (elecCondVal "595900.000000 mho/cm") (thermCondVal "0.012 w/cm-degC")) ("" (layerType "DIELECTRIC") (material "FR-4") (thickness "  2.700000 mil") (dielectricConstant "4.500000") (lossTangent "0.035") (etchFactor "0.000000") (elecCondVal "0 mho/cm") (thermCondVal "0.012 w/cm-degC")) ("BOTTOM" (layerType "CONDUCTOR") (material "COPPER") (thickness "  1.800000 mil") (width "4.00 MIL") (dielectricConstant "4.500000") (lossTangent "0") (etchFactor "70.000000") (elecCondVal "595900.000000 mho/cm") (thermCondVal "0 w/cm-degC") (signalDieConstant "3.800000") (signalLossTangent "0.035")) ("" (layerType "DIELECTRIC") (material "CONFORMAL_COAT") (thickness "0.5 mil") (dielectricConstant "3.800000") (lossTangent "0.035") (etchFactor "0.000000") (elecCondVal "0 mho/cm") (thermCondVal "0.012 w/cm-degC")) ("" (layerType "SURFACE") (material "AIR") (thickness "0 mil") (dielectricConstant "1.000000") (lossTangent "0") (etchFactor "0.000000") (elecCondVal "0 mho/cm") (thermCondVal "0 w/cm-degC"))))) (Props (DesUnits "mils 2") (LayerStack ("DIELECTRIC" "DIELECTRIC" "BOTTOM" "DIELECTRIC" "L13_GND6" "DIELECTRIC" "L12_SIG4" "DIELECTRIC" "L11_GND5" "DIELECTRIC" "L10_SIG3" "DIELECTRIC" "L9_GND4" "DIELECTRIC" "L8_PWR2-SIG" "DIELECTRIC" "L7_PWR1-SIG" "DIELECTRIC" "L6_GND3" "DIELECTRIC" "L5_SIG2" "DIELECTRIC" "L4_GND2" "DIELECTRIC" "L3_SIG1" "DIELECTRIC" "L2_GND1" "DIELECTRIC" "TOP" "DIELECTRIC" "DIELECTRIC")) (Revision "16.600")) (Params (ESpiceDevice nil) (Cable (length("1 m"))) (Via ((model "Unknown") (viaOutputFormat "Unknown") (viaPadstack nil) (viaTopLayer nil) (viaBottomLayer nil) (viaIsPower nil) (viaIsGround nil))) (Trace ((d1Thickness "10 mil") (d1Constant "4.5") (d1LossTangent "0.035") (d2Thickness "10 mil") (d2Constant "4.5") (d2LossTangent "0.035") (d3Thickness "0.0") (d3Constant "1.0") (d3LossTangent "0") length("1000 mil") (spacing "5 mil") (spacing2 "5 mil") (spacing3 "5 mil") (spacing4 "5 mil") (spacing5 "5 mil") (traceConductivity "595900 mho/cm") (traceGeometry "microstrip") (traceLayerName "") (traceThickness "0.72 mil") (traceType "single") (traceWidth "5.0 mil") (traceWidth2 "5.0 mil") (traceWidth3 "5.0 mil") (traceWidth4 "5.0 mil") (traceWidth5 "5.0 mil") (traceWidth6 "5.0 mil") (offset "0 mil") (traceCount "1") (impedance nil))) (IbisOutput_OpenPullUp ((temperature "27") (bufferModel "CDSDefaultOutput_2p5v") (stimuli nil) (offsets nil) (state "tristate") (cycle "1") (termMap nil) (setup "2.0e-09") (hold "1.0e-09") (rise nil) (fall nil) (macroType nil) (voltage nil) (spice nil) (LEFDEFPinName nil) (LEFDEFPinType nil) (mappingTag nil))) (IbisInput ((temperature "27") (bufferModel "CDSDefaultInput_2p5v") (cycle "1") (LEFDEFPinName nil) (LEFDEFPinType nil) (mappingTag nil))) (IbisIO_OpenPullUp ((temperature "27") (bufferModel "CDSDefaultIO_2p5v") (stimuli nil) (offsets nil) (state "tristate") (cycle "1") (termMap nil) (setup "2.0e-09") (hold "1.0e-09") (rise nil) (fall nil) (macroType nil) (voltage nil) (spice nil) (LEFDEFPinName nil) (LEFDEFPinType nil) (mappingTag nil))) (clocked ((clockRise "1e-09") (clockFall "1e-09") (clockFreq "100e6") (clockInitState "0") (clockDutyCycle "0.5") (clockJitter "0"))) (periodic ((periodicFreq "100e6") (periodicPattern "10") (periodicJitter "0"))) (IbisIO_OpenPullDown ((temperature "27") (bufferModel "CDSDefaultIO_2p5v") (stimuli nil) (offsets nil) (state "tristate") (cycle "1") (termMap nil) (setup "2.0e-09") (hold "1.0e-09") (rise nil) (fall nil) (macroType nil) (voltage nil) (spice nil) (LEFDEFPinName nil) (LEFDEFPinType nil) (mappingTag nil))) (RLGC (length("1000 mil"))) (DiffIO ((temperature "27") (bufferModelNonInverting "CDSDefaultIO_2p5v") (bufferModelInverting "CDSDefaultIO_2p5v") (stimuli nil) (offsets nil) (state "tristate") (cycle "1") (termMap nil) (setup "0.9e-09") (hold "0.4e-09") (rise nil) (fall nil) (threshInputHighMin "1.7 V") (threshInputHighTyp "1.7  V") (threshInputHighMax "1.7  V") (threshInputLowMin "0.7  V") (threshInputLowTyp "0.7  V") (threshInputLowMax "0.7 ") (threshOutputHighMin "2.365  V") (threshOutputHighTyp "2.5  V") (threshOutputHighMax "2.625  V") (threshOutputLowMin "1.275  V") (threshOutputLowTyp "1.7  V") (threshOutputLowMax "1.985  V") (mappingTagNonInverting nil) (mappingTagInverting nil) (spice nil))) (IbisOutput ((temperature "27") (bufferModel "CDSDefaultOutput_2p5v") (stimuli nil) (offsets nil) (state "tristate") (cycle "1") (termMap nil) (setup "2.0e-09") (hold "1.0e-09") (rise nil) (fall nil) (macroType nil) (voltage nil) (spice nil) (LEFDEFPinName nil) (LEFDEFPinType nil) (mappingTag nil))) (Source ((voltage "5 V"))) (Inductor ((inductance "5 nH") (orientation "0"))) (DiffIOPkg ((temperature "27") (bufferModelNonInverting "CDSDefaultIO_2p5v") (bufferModelInverting "CDSDefaultIO_2p5v") (stimuli nil) (offsets nil) (state "tristate") (cycle "1") (termMap nil) (setup "0.9e-09") (hold "0.4e-09") (rise nil) (fall nil) (threshInputHighMin "1.7 V") (threshInputHighTyp "1.7  V") (threshInputHighMax "1.7  V") (threshInputLowMin "0.7  V") (threshInputLowTyp "0.7  V") (threshInputLowMax "0.7 ") (threshOutputHighMin "2.365  V") (threshOutputHighTyp "2.5  V") (threshOutputHighMax "2.625  V") (threshOutputLowMin "1.275  V") (threshOutputLowTyp "1.7  V") (threshOutputLowMax "1.985  V") (mappingTagNonInverting nil) (mappingTagInverting nil) (spice nil))) (IbisIO ((temperature "27") (bufferModel "CDSDefaultIO_2p5v") (stimuli nil) (offsets nil) (state "tristate") (cycle "1") (termMap nil) (setup "2.0e-09") (hold "1.0e-09") (rise nil) (fall nil) (macroType nil) (voltage nil) (spice nil) (LEFDEFPinName nil) (LEFDEFPinType nil) (mappingTag nil))) (SeriesTerm ((resistance "22 ohm") (maxDelay "0.1 ns"))) (CPW ((d1Thickness "10 mil") (d1Constant "4.5") (d1LossTangent "0.035") (d2Thickness "0.72 mil") (d2Constant "1") (d2LossTangent "0") (d3Thickness "0.0") (d3Constant "1") (d3LossTangent "0") length("1000 mil") (spacing "5 mil") (spacing2 "5 mil") (spacing3 "5 mil") (spacing4 "5 mil") (spacing5 "5 mil") (traceConductivity "595900 mho/cm") (traceGeometry "cpwms") (traceLayerName "") (traceThickness "0.72 mil") (traceType "single") (traceWidth "5.0 mil") (traceWidth2 "5.0 mil") (traceWidth3 "5.0 mil") (traceWidth4 "5.0 mil") (traceWidth5 "5.0 mil") (traceWidth6 "5.0 mil") (offset "0 mil") (traceCount "1") (impedance nil))) (CPWMS ((d1Thickness "10 mil") (d1Constant "4.5") (d1LossTangent "0.035") (d2Thickness "0.72 mil") (d2Constant "4.5") (d2LossTangent "0.035") (d3Thickness "0.0") (d3Constant "1") (d3LossTangent "0") length("1000 mil") (spacing "5 mil") (spacing2 "5 mil") (spacing3 "5 mil") (spacing4 "5 mil") (spacing5 "5 mil") (traceConductivity "595900 mho/cm") (traceGeometry "cpwms") (traceLayerName "") (traceThickness "0.72 mil") (traceType "single") (traceWidth "5.0 mil") (traceWidth2 "5.0 mil") (traceWidth3 "5.0 mil") (traceWidth4 "5.0 mil") (traceWidth5 "5.0 mil") (traceWidth6 "5.0 mil") (offset "0 mil") (traceCount "1") (impedance nil))) (TLine ((diffImpedance "100ohm") (diffVelocity "1.4142e+08M/s") (impedance "60ohm") length("2800 mil") (propDelay "0.5 ns") (velocity "5600 mil/ns") (traceCount "1") (traceGeometry "Microstrip") (impedanceMin nil) (impedanceMax nil) (lengthMin nil) (lengthMax nil) (propDelayMin nil) (propDelayMax nil) (impedanceSweepCount nil) (propDelaySweepCount nil) (velocitySweepCount nil) (lengthSweepCount nil) (matchSetName nil))) (sync ((syncFreq "100e6") (syncInitState "1") (syncPattern "10") (syncEdgeSwitch "rise"))) (Connector nil) (Diode ((cutoffVoltage "0.7 V"))) (CurrentProbe nil) (CPWSL ((d1Thickness "10 mil") (d1Constant "4.5") (d1LossTangent "0.035") (d2Thickness "0.72 mil") (d2Constant "4.5") (d2LossTangent "0.035") (d3Thickness "10 mil") (d3Constant "4.5") (d3LossTangent "0.035") length("1000 mil") (spacing "5 mil") (spacing2 "5 mil") (spacing3 "5 mil") (spacing4 "5 mil") (spacing5 "5 mil") (traceConductivity "595900 mho/cm") (traceGeometry "cpwms") (traceLayerName "") (traceThickness "0.72 mil") (traceType "single") (traceWidth "5.0 mil") (traceWidth2 "5.0 mil") (traceWidth3 "5.0 mil") (traceWidth4 "5.0 mil") (traceWidth5 "5.0 mil") (traceWidth6 "5.0 mil") (offset "0 mil") (traceCount "1") (impedance nil))) (async ((asyncTimePoints "") (asyncInitState "1"))) (Capacitor ((capacitance "10 pF") (orientation "0"))) (DiffOutputPkg ((temperature "27") (bufferModelNonInverting "CDSDefaultOutput_2p5v") (bufferModelInverting "CDSDefaultOutput_2p5v") (stimuli nil) (offsets nil) (state "tristate") (cycle "1") (termMap nil) (setup "0.9e-09") (hold "0.4e-09") (rise nil) (fall nil) (threshOutputHighMin "2.375  V") (threshOutputHighTyp "2.5  V") (threshOutputHighMax "2.625  V") (threshOutputLowMin "1.275  V") (threshOutputLowTyp "1.7  V") (threshOutputLowMax "1.985  V") (mappingTagNonInverting nil) (mappingTagInverting nil) (spice nil))) (DiffOutput ((temperature "27") (bufferModelNonInverting "CDSDefaultOutput_2p5v") (bufferModelInverting "CDSDefaultOutput_2p5v") (stimuli nil) (offsets nil) (state "tristate") (cycle "1") (termMap nil) (setup "0.9e-09") (hold "0.4e-09") (rise nil) (fall nil) (threshOutputHighMin "2.375  V") (threshOutputHighTyp "2.5  V") (threshOutputHighMax "2.625  V") (threshOutputLowMin "1.275  V") (threshOutputLowTyp "1.7  V") (threshOutputLowMax "1.985  V") (mappingTagNonInverting nil) (mappingTagInverting nil) (spice nil))) (HiClampTerm ((cutoffVoltage "0.7 V") (voltage "5 V") (maxDelay "0.1 ns"))) (IbisInputPkg ((temperature "27") (bufferModel "CDSDefaultInput_2p5v") (cycle "1") (LEFDEFPinName nil) (LEFDEFPinType nil) (mappingTag nil))) (Resistor ((resistance "50 ohm") (orientation "0"))) (DiffInput ((temperature "27") (bufferModelNonInverting "CDSDefaultInput_2p5v") (bufferModelInverting "CDSDefaultInput_2p5v") (threshInputHighMin "1.7 V") (threshInputHighTyp "1.7  V") (threshInputHighMax "1.7  V") (threshInputLowMin "0.7  V") (threshInputLowTyp "0.7  V") (threshInputLowMax "0.7  V") (mappingTagNonInverting nil) (mappingTagInverting nil) (cycle "1"))) (DualClampTerm ((cutoffVoltageUp "0.7 V") (cutoffVoltageDown "0.7 V") (voltageUp "5 V") (voltageDown "0 V") (maxDelay "0.1 ns"))) (IbisOutputPkg ((temperature "27") (bufferModel "CDSDefaultOutput_2p5v") (stimuli nil) (offsets nil) (state "tristate") (cycle "1") (termMap nil) (setup "2.0e-09") (hold "1.0e-09") (rise nil) (fall nil) (macroType nil) (voltage nil) (spice nil) (LEFDEFPinName nil) (LEFDEFPinType nil) (mappingTag nil))) (IbisIOPkg ((temperature "27") (bufferModel "CDSDefaultIO_2p5v") (stimuli nil) (offsets nil) (state "tristate") (cycle "1") (termMap nil) (setup "2.0e-09") (hold "1.0e-09") (rise nil) (fall nil) (macroType nil) (voltage nil) (spice nil) (LEFDEFPinName nil) (LEFDEFPinType nil) (mappingTag nil))) (TheveninTerm ((resistanceUp "180 ohm") (resistanceDown "270 ohm") (voltageUp "5 V") (voltageDown "0 V") (maxDelay "0.1 ns"))) (IbisIOMacro ((temperature "27") (bufferModel "CDSDefaultIO_2p5v") (stimuli nil) (offsets nil) (state "tristate") (cycle "1") (termMap nil) (setup "2.0e-09") (hold "1.0e-09") (rise nil) (fall nil) (macroType nil) (voltage nil) (spice nil) (LEFDEFPinName nil) (LEFDEFPinType nil) (mappingTag nil))) (RCTerm ((resistance "50 ohm") (capacitance "20 pF") (voltage "5 V") (maxDelay "0.1 ns"))) (LowClampTerm ((cutoffVoltage "0.7 V") (voltage "0 V") (maxDelay "0.1 ns"))) (DiffInputPkg ((temperature "27") (bufferModelNonInverting "CDSDefaultInput_2p5v") (bufferModelInverting "CDSDefaultInput_2p5v") (threshInputHighMin "1.7 V") (threshInputHighTyp "1.7  V") (threshInputHighMax "1.7  V") (threshInputLowMin "0.7  V") (threshInputLowTyp "0.7  V") (threshInputLowMax "0.7  V") (mappingTagNonInverting nil) (mappingTagInverting nil) (cycle "1"))) (ShuntTerm ((resistance "50 ohm") (voltage "5 V") (maxDelay "0.1 ns"))) (idlCircuit ((allDrivers "active") (ftsMode '("Typ")) (rcvrSelect "all") (simMode "Reflection") (tlineDelayMode "time") (userRevision "1.0") (autoSolve "On")))))
				)
				( objectStatus "DDR_CTRL_DLL20-24" )
			)
			( electricalCSet "@crescent_city_bb_fab1_lib.crescent_city_bb_fab1(sch_1):\DDR_B_CMD_DLL1-13\"
				( groupRef "DDR_B_CMD_DLL1-13:MG_DDR_NEAR_DIMM-CLK1" )
				( groupRef "DDR_B_CMD_DLL1-13:MG_DDR_FAR_DIMM_CMD" )
				( groupRef "DDR_B_CMD_DLL1-13:MG_DDR_FAR_DIMM-CLK0" )
				( groupRef "DDR_B_CMD_DLL1-13:MG_DDR_CMD_NEAR_DIMM" )
				( pinPairRef "DDR_B_CMD_DLL1-13:U5D1.F51:J6U1.228" )
				( pinPairRef "DDR_B_CMD_DLL1-13:U5D1.F51:J4G2.228" )
				( attribute "TOPOLOGY_TEMPLATE_REVISION" "1.0"
					( Origin gBackEnd )
				)
				( topologyData 23949
(SKIDL (Circuits ("MAIN" (Parts ("CRESCENT_CITY_083_20140724_A.@@J1.228" IbisIOPkg (xy (5548 4240)) (refDes "J4G2") (model "Unknown") (Props (_SXDesignName "CRESCENT_CITY_083_20140724_A") (brdx "10643.7 MIL") (brdy "788.33 MIL") (bufferModel "CDSDefaultIO_2p5v") (cycle "1") (hold "1.0e-09") (mappingTag "") (offsets ("4" "0") ("5" "0")) (setup "2.0e-09") (state "tristate") (stimuli ("4" "local0") ("5" "local1")) (temperature "27") (termMap ("4" "Data") ("5" "Enable"))) (Terms ("CRESCENT_CITY_083_20140724_A.X1064370Y78833L2LRATS" "228"))) ("CRESCENT_CITY_083_20140724_A.@@J2.228" IbisIOPkg (xy (5528 4240)) (refDes "J6U1") (model "Unknown") (Props (_SXDesignName "CRESCENT_CITY_083_20140724_A") (brdx "10643.7 MIL") (brdy "796.23 MIL") (bufferModel "CDSDefaultIO_2p5v") (cycle "1") (hold "1.0e-09") (mappingTag "") (offsets ("4" "0") ("5" "0")) (setup "2.0e-09") (state "tristate") (stimuli ("4" "local2") ("5" "local15")) (temperature "27") (termMap ("4" "Data") ("5" "Enable"))) (Terms ("CRESCENT_CITY_083_20140724_A.X1064370Y79623L28LRATS" "228"))) ("CRESCENT_CITY_083_20140724_A.@@U36.F51" IbisIOPkg (xy (5502 4240)) (refDes "U5D1") (model "Unknown") (Props (_SXDesignName "CRESCENT_CITY_083_20140724_A") (brdx "10346.35 MIL") (brdy "2052.1 MIL") (bufferModel "CDSDefaultIO_2p5v") (cycle "1") (hold "1.0e-09") (mappingTag "") (offsets ("4" "0") ("5" "0")) (setup "2.0e-09") (state "tristate") (stimuli ("4" "local16") ("5" "local17")) (temperature "27") (termMap ("4" "Data") ("5" "Enable"))) (Terms ("CRESCENT_CITY_083_20140724_A.X1034635Y205210L2LRATS" "F51"))) ("CRESCENT_CITY_083_20140724_A.T@@RATS@@J2.228@@U36.F51" TLine (xy (5513 4235)) (mirror x) (refDes "TL1") (Props (_SXDesignName "CRESCENT_CITY_083_20140724_A") (impedance "53.474 ohm") length("1553.22 MIL") (propDelay "0.27897 ns") (traceCount "1") (traceGeometry "Microstrip") (velocity "5567.68 mil/ns")) (Terms ("CRESCENT_CITY_083_20140724_A.X1064370Y79623L28LRATS" "1") ("CRESCENT_CITY_083_20140724_A.X1034635Y205210L2LRATS" "2"))) ("CRESCENT_CITY_083_20140724_A.T@@RATS@@J2.228@@J1.228" TLine (xy (5539 4235)) (refDes "TL2") (Props (_SXDesignName "CRESCENT_CITY_083_20140724_A") (impedance "39.682 ohm") length("7.90 MIL") (propDelay "0.00142 ns") (traceCount "1") (traceGeometry "Microstrip") (velocity "5563.39 mil/ns")) (Terms ("CRESCENT_CITY_083_20140724_A.X1064370Y79623L28LRATS" "1") ("CRESCENT_CITY_083_20140724_A.X1064370Y78833L2LRATS" "2")))) (Nodes ("CRESCENT_CITY_083_20140724_A.X1034635Y205210L2LRATS" (terms "CRESCENT_CITY_083_20140724_A.T@@RATS@@J2.228@@U36.F51.2" "CRESCENT_CITY_083_20140724_A.@@U36.F51.1")) ("CRESCENT_CITY_083_20140724_A.X1064370Y78833L2LRATS" (terms "CRESCENT_CITY_083_20140724_A.T@@RATS@@J2.228@@J1.228.2" "CRESCENT_CITY_083_20140724_A.@@J1.228.1")) ("CRESCENT_CITY_083_20140724_A.X1064370Y79623L28LRATS" (terms "CRESCENT_CITY_083_20140724_A.T@@RATS@@J2.228@@J1.228.1" "CRESCENT_CITY_083_20140724_A.T@@RATS@@J2.228@@U36.F51.1" "CRESCENT_CITY_083_20140724_A.@@J2.228.1"))) (Ports) (Stimuli ("local2" (scope local) (stimType periodic) (Props (periodicFreq "5e+007") (periodicJitter "0") (periodicPattern "1"))) ("local15" (scope local) (stimType periodic) (Props (periodicFreq "5e+007") (periodicJitter "0") (periodicPattern "1"))) ("local0" (scope local) (stimType periodic) (Props (periodicFreq "5e+007") (periodicJitter "0") (periodicPattern "1"))) ("local16" (scope local) (stimType periodic) (Props (periodicFreq "5e+007") (periodicJitter "0") (periodicPattern "1"))) ("local1" (scope local) (stimType periodic) (Props (periodicFreq "5e+007") (periodicJitter "0") (periodicPattern "1"))) ("local17" (scope local) (stimType periodic) (Props (periodicFreq "5e+007") (periodicJitter "0") (periodicPattern "1")))) (Notes) (Constraints ("RELATIVE_PROPAGATION_DELAY" ("MG_DDR_NEAR_DIMM-CLK1" "CRESCENT_CITY_083_20140724_A U36.F51" "CRESCENT_CITY_083_20140724_A J4.228" "CLASS" "LENGTH" "0.01778" "LENGTH" "0") ("MG_DDR_FAR_DIMM_CMD" "CRESCENT_CITY_083_20140724_A U36.F51" "CRESCENT_CITY_083_20140724_A J3.228" "NET GROUP" "LENGTH" "0.000635" "LENGTH" "0") ("MG_DDR_FAR_DIMM-CLK0" "CRESCENT_CITY_083_20140724_A U36.F51" "CRESCENT_CITY_083_20140724_A J3.228" "CLASS" "LENGTH" "0.01778" "LENGTH" "0") ("MG_DDR_CMD_NEAR_DIMM" "CRESCENT_CITY_083_20140724_A U36.F51" "CRESCENT_CITY_083_20140724_A J4.228" "NET GROUP" "LENGTH" "0.000635" "LENGTH" "0"))) (MeasurementSets ("EMI" ("EMIStatus" status("on")) ("PeakEmission" status("on")) ("PeakFrequency" status("on")) ("PulseFreq" status("on")) ("RiseTime" status("on")) ("VoltageSwing" status("on"))) ("Reflection" ("BufferDelayFall" status("off")) ("BufferDelayRise" status("off")) ("EyeHeight" status("off")) ("EyeJitter" status("off")) ("EyeWidth" status("off")) ("FirstIncidentFall" status("off")) ("FirstIncidentRise" status("off")) ("Glitch" status("on")) ("GlitchFall" status("off")) ("GlitchRise" status("off")) ("Monotonic" status("on")) ("MonotonicFall" status("off")) ("MonotonicRise" status("off")) ("NoiseMargin" status("on")) ("NoiseMarginHigh" status("off")) ("NoiseMarginLow" status("off")) ("OvershootHigh" status("on")) ("OvershootLow" status("on")) ("PropDelay" status("on")) ("SettleDelay" status("on")) ("SettleDelayFall" status("off")) ("SettleDelayRise" status("off")) ("SwitchDelay" status("on")) ("SwitchDelayFall" status("off")) ("SwitchDelayRise" status("off"))) ("Crosstalk" ("Crosstalk" status("on"))) ("Custom")) (VectorSets) (Props (XnetName "M_A_MA<14>") (allDrivers "active") (autoSolve "Off") (customSimType "Reflection") (ftsMode ("Typ")) (rcvrSelect "all") (tlineDelayMode "time") (userRevision "1.0")))) (Subckts) (CrossSections ("CRESCENT_CITY_083_20140724_A" (Props (SXDesignName "CRESCENT_CITY_083_20140724_A")) (Layers ("" (layerType "SURFACE") (material "AIR") (thickness "0 mil") (dielectricConstant "1.000000") (lossTangent "0") (etchFactor "0.000000") (elecCondVal "0 mho/cm") (thermCondVal "0 w/cm-degC")) ("" (layerType "DIELECTRIC") (material "CONFORMAL_COAT") (thickness "0.5 mil") (dielectricConstant "3.800000") (lossTangent "0.035") (etchFactor "0.000000") (elecCondVal "0 mho/cm") (thermCondVal "0.012 w/cm-degC")) ("TOP" (layerType "CONDUCTOR") (material "COPPER") (thickness "  1.800000 mil") (width "4.00 MIL") (dielectricConstant "4.500000") (lossTangent "0") (etchFactor "70.000000") (elecCondVal "595900.000000 mho/cm") (thermCondVal "0 w/cm-degC") (signalDieConstant "3.800000") (signalLossTangent "0.035")) ("" (layerType "DIELECTRIC") (material "FR-4") (thickness "  2.700000 mil") (dielectricConstant "4.000000") (lossTangent "0.035") (etchFactor "0.000000") (elecCondVal "0 mho/cm") (thermCondVal "0.012 w/cm-degC")) ("L2_GND1" (layerType "PLANE") (material "COPPER") (isShield t) (thickness "  1.200000 mil") (dielectricConstant "4.500000") (lossTangent "0.035") (etchFactor "90.000000") (elecCondVal "595900.000000 mho/cm") (thermCondVal "0.012 w/cm-degC")) ("" (layerType "DIELECTRIC") (material "FR-4") (thickness "  9.900000 mil") (dielectricConstant "4.100000") (lossTangent "0.035") (etchFactor "0.000000") (elecCondVal "0 mho/cm") (thermCondVal "0.012 w/cm-degC")) ("L3_SIG1" (layerType "CONDUCTOR") (material "COPPER") (thickness "  1.200000 mil") (width "4.00 MIL") (dielectricConstant "4.500000") (lossTangent "0.035") (etchFactor "90.000000") (elecCondVal "595900.000000 mho/cm") (thermCondVal "0.012 w/cm-degC") (signalDieConstant "4.100000") (signalLossTangent "0.035")) ("" (layerType "DIELECTRIC") (material "FR-4") (thickness "  3.300000 mil") (dielectricConstant "4.500000") (lossTangent "0.035") (etchFactor "0.000000") (elecCondVal "0 mho/cm") (thermCondVal "0 w/cm-degC")) ("L4_GND2" (layerType "PLANE") (material "COPPER") (isShield t) (thickness "  1.200000 mil") (dielectricConstant "4.500000") (lossTangent "0.035") (etchFactor "90.000000") (elecCondVal "595900.000000 mho/cm") (thermCondVal "0 w/cm-degC")) ("" (layerType "DIELECTRIC") (material "FR-4") (thickness "  3.300000 mil") (dielectricConstant "4.000000") (lossTangent "0.035") (etchFactor "0.000000") (elecCondVal "0 mho/cm") (thermCondVal "0.012 w/cm-degC")) ("L5_SIG2" (layerType "CONDUCTOR") (material "COPPER") (thickness "  1.200000 mil") (width "4.00 MIL") (dielectricConstant "4.500000") (lossTangent "0.035") (etchFactor "90.000000") (elecCondVal "595900.000000 mho/cm") (thermCondVal "0.012 w/cm-degC") (signalDieConstant "4.000000") (signalLossTangent "0.035")) ("" (layerType "DIELECTRIC") (material "FR-4") (thickness "  9.900000 mil") (dielectricConstant "4.500000") (lossTangent "0.035") (etchFactor "0.000000") (elecCondVal "0 mho/cm") (thermCondVal "0 w/cm-degC")) ("L6_GND3" (layerType "PLANE") (material "COPPER") (isShield t) (thickness "  1.200000 mil") (dielectricConstant "4.500000") (lossTangent "0.035") (etchFactor "90.000000") (elecCondVal "595900.000000 mho/cm") (thermCondVal "0 w/cm-degC")) ("" (layerType "DIELECTRIC") (material "FR-4") (thickness "  3.300000 mil") (dielectricConstant "4.100000") (lossTangent "0.035") (etchFactor "0.000000") (elecCondVal "0 mho/cm") (thermCondVal "0.012 w/cm-degC")) ("L7_PWR1-SIG" (layerType "PLANE") (material "COPPER") (isShield t) (thickness "  1.200000 mil") (dielectricConstant "4.500000") (lossTangent "0.035") (etchFactor "90.000000") (elecCondVal "595900.000000 mho/cm") (thermCondVal "0.012 w/cm-degC")) ("" (layerType "DIELECTRIC") (material "FR-4") (thickness "  9.900000 mil") (dielectricConstant "4.000000") (lossTangent "0.035") (etchFactor "0.000000") (elecCondVal "0 mho/cm") (thermCondVal "0.012 w/cm-degC")) ("L8_PWR2-SIG" (layerType "PLANE") (material "COPPER") (isShield t) (thickness "  1.200000 mil") (dielectricConstant "4.500000") (lossTangent "0.035") (etchFactor "90.000000") (elecCondVal "595900.000000 mho/cm") (thermCondVal "0.012 w/cm-degC")) ("" (layerType "DIELECTRIC") (material "FR-4") (thickness "  3.300000 mil") (dielectricConstant "4.500000") (lossTangent "0.035") (etchFactor "0.000000") (elecCondVal "0 mho/cm") (thermCondVal "0 w/cm-degC")) ("L9_GND4" (layerType "PLANE") (material "COPPER") (isShield t) (thickness "  1.200000 mil") (dielectricConstant "4.500000") (lossTangent "0.035") (etchFactor "90.000000") (elecCondVal "595900.000000 mho/cm") (thermCondVal "0 w/cm-degC")) ("" (layerType "DIELECTRIC") (material "FR-4") (thickness "  9.900000 mil") (dielectricConstant "4.100000") (lossTangent "0.035") (etchFactor "0.000000") (elecCondVal "0 mho/cm") (thermCondVal "0.012 w/cm-degC")) ("L10_SIG3" (layerType "CONDUCTOR") (material "COPPER") (thickness "  1.200000 mil") (width "4.00 MIL") (dielectricConstant "4.500000") (lossTangent "0.035") (etchFactor "90.000000") (elecCondVal "595900.000000 mho/cm") (thermCondVal "0.012 w/cm-degC") (signalDieConstant "4.100000") (signalLossTangent "0.035")) ("" (layerType "DIELECTRIC") (material "FR-4") (thickness "  3.300000 mil") (dielectricConstant "4.500000") (lossTangent "0.035") (etchFactor "0.000000") (elecCondVal "0 mho/cm") (thermCondVal "0 w/cm-degC")) ("L11_GND5" (layerType "PLANE") (material "COPPER") (isShield t) (thickness "  1.200000 mil") (dielectricConstant "4.500000") (lossTangent "0.035") (etchFactor "90.000000") (elecCondVal "595900.000000 mho/cm") (thermCondVal "0 w/cm-degC")) ("" (layerType "DIELECTRIC") (material "FR-4") (thickness "  9.900000 mil") (dielectricConstant "4.500000") (lossTangent "0.035") (etchFactor "0.000000") (elecCondVal "0 mho/cm") (thermCondVal "0.012 w/cm-degC")) ("L12_SIG4" (layerType "CONDUCTOR") (material "COPPER") (thickness "  1.200000 mil") (width "4.00 MIL") (dielectricConstant "4.500000") (lossTangent "0.035") (etchFactor "90.000000") (elecCondVal "595900.000000 mho/cm") (thermCondVal "0.012 w/cm-degC") (signalDieConstant "4.500000") (signalLossTangent "0.035")) ("" (layerType "DIELECTRIC") (material "FR-4") (thickness "  3.300000 mil") (dielectricConstant "4.500000") (lossTangent "0.035") (etchFactor "0.000000") (elecCondVal "0 mho/cm") (thermCondVal "0 w/cm-degC")) ("L13_GND6" (layerType "PLANE") (material "COPPER") (isShield t) (thickness "  1.200000 mil") (dielectricConstant "4.500000") (lossTangent "0.035") (etchFactor "90.000000") (elecCondVal "595900.000000 mho/cm") (thermCondVal "0.012 w/cm-degC")) ("" (layerType "DIELECTRIC") (material "FR-4") (thickness "  2.700000 mil") (dielectricConstant "4.500000") (lossTangent "0.035") (etchFactor "0.000000") (elecCondVal "0 mho/cm") (thermCondVal "0.012 w/cm-degC")) ("BOTTOM" (layerType "CONDUCTOR") (material "COPPER") (thickness "  1.800000 mil") (width "4.00 MIL") (dielectricConstant "4.500000") (lossTangent "0") (etchFactor "70.000000") (elecCondVal "595900.000000 mho/cm") (thermCondVal "0 w/cm-degC") (signalDieConstant "3.800000") (signalLossTangent "0.035")) ("" (layerType "DIELECTRIC") (material "CONFORMAL_COAT") (thickness "0.5 mil") (dielectricConstant "3.800000") (lossTangent "0.035") (etchFactor "0.000000") (elecCondVal "0 mho/cm") (thermCondVal "0.012 w/cm-degC")) ("" (layerType "SURFACE") (material "AIR") (thickness "0 mil") (dielectricConstant "1.000000") (lossTangent "0") (etchFactor "0.000000") (elecCondVal "0 mho/cm") (thermCondVal "0 w/cm-degC"))))) (Props (DesUnits "mils 2") (LayerStack ("DIELECTRIC" "DIELECTRIC" "BOTTOM" "DIELECTRIC" "L13_GND6" "DIELECTRIC" "L12_SIG4" "DIELECTRIC" "L11_GND5" "DIELECTRIC" "L10_SIG3" "DIELECTRIC" "L9_GND4" "DIELECTRIC" "L8_PWR2-SIG" "DIELECTRIC" "L7_PWR1-SIG" "DIELECTRIC" "L6_GND3" "DIELECTRIC" "L5_SIG2" "DIELECTRIC" "L4_GND2" "DIELECTRIC" "L3_SIG1" "DIELECTRIC" "L2_GND1" "DIELECTRIC" "TOP" "DIELECTRIC" "DIELECTRIC")) (Revision "16.600")) (Params (LowClampTerm ((cutoffVoltage "0.7 V") (voltage "0 V") (maxDelay "0.1 ns"))) (RCTerm ((resistance "50 ohm") (capacitance "20 pF") (voltage "5 V") (maxDelay "0.1 ns"))) (TheveninTerm ((resistanceUp "180 ohm") (resistanceDown "270 ohm") (voltageUp "5 V") (voltageDown "0 V") (maxDelay "0.1 ns"))) (DiffInputPkg ((temperature "27") (bufferModelNonInverting "CDSDefaultInput_2p5v") (bufferModelInverting "CDSDefaultInput_2p5v") (threshInputHighMin "1.7 V") (threshInputHighTyp "1.7  V") (threshInputHighMax "1.7  V") (threshInputLowMin "0.7  V") (threshInputLowTyp "0.7  V") (threshInputLowMax "0.7  V") (mappingTagNonInverting nil) (mappingTagInverting nil) (cycle "1"))) (ShuntTerm ((resistance "50 ohm") (voltage "5 V") (maxDelay "0.1 ns"))) (IbisOutput_OpenPullUp ((temperature "27") (bufferModel "CDSDefaultOutput_2p5v") (stimuli nil) (offsets nil) (state "tristate") (cycle "1") (termMap nil) (setup "2.0e-09") (hold "1.0e-09") (rise nil) (fall nil) (macroType nil) (voltage nil) (spice nil) (LEFDEFPinName nil) (LEFDEFPinType nil) (mappingTag nil))) (TLine ((diffImpedance "100ohm") (diffVelocity "1.4142e+08M/s") (impedance "60ohm") length("2800 mil") (propDelay "0.5 ns") (velocity "5600 mil/ns") (traceCount "1") (traceGeometry "Microstrip") (impedanceMin nil) (impedanceMax nil) (lengthMin nil) (lengthMax nil) (propDelayMin nil) (propDelayMax nil) (impedanceSweepCount nil) (propDelaySweepCount nil) (velocitySweepCount nil) (lengthSweepCount nil) (matchSetName nil))) (IbisIO_OpenPullDown ((temperature "27") (bufferModel "CDSDefaultIO_2p5v") (stimuli nil) (offsets nil) (state "tristate") (cycle "1") (termMap nil) (setup "2.0e-09") (hold "1.0e-09") (rise nil) (fall nil) (macroType nil) (voltage nil) (spice nil) (LEFDEFPinName nil) (LEFDEFPinType nil) (mappingTag nil))) (IbisIO_OpenPullUp ((temperature "27") (bufferModel "CDSDefaultIO_2p5v") (stimuli nil) (offsets nil) (state "tristate") (cycle "1") (termMap nil) (setup "2.0e-09") (hold "1.0e-09") (rise nil) (fall nil) (macroType nil) (voltage nil) (spice nil) (LEFDEFPinName nil) (LEFDEFPinType nil) (mappingTag nil))) (idlCircuit ((allDrivers "active") (ftsMode '("Typ")) (rcvrSelect "all") (simMode "Reflection") (tlineDelayMode "time") (userRevision "1.0") (autoSolve "On"))) (Via ((model "Unknown") (viaOutputFormat "Unknown") (viaPadstack nil) (viaTopLayer nil) (viaBottomLayer nil) (viaIsPower nil) (viaIsGround nil))) (CurrentProbe nil) (Diode ((cutoffVoltage "0.7 V"))) (DiffInput ((temperature "27") (bufferModelNonInverting "CDSDefaultInput_2p5v") (bufferModelInverting "CDSDefaultInput_2p5v") (threshInputHighMin "1.7 V") (threshInputHighTyp "1.7  V") (threshInputHighMax "1.7  V") (threshInputLowMin "0.7  V") (threshInputLowTyp "0.7  V") (threshInputLowMax "0.7  V") (mappingTagNonInverting nil) (mappingTagInverting nil) (cycle "1"))) (sync ((syncFreq "100e6") (syncInitState "1") (syncPattern "10") (syncEdgeSwitch "rise"))) (DualClampTerm ((cutoffVoltageUp "0.7 V") (cutoffVoltageDown "0.7 V") (voltageUp "5 V") (voltageDown "0 V") (maxDelay "0.1 ns"))) (IbisInput ((temperature "27") (bufferModel "CDSDefaultInput_2p5v") (cycle "1") (LEFDEFPinName nil) (LEFDEFPinType nil) (mappingTag nil))) (Connector nil) (ESpiceDevice nil) (HiClampTerm ((cutoffVoltage "0.7 V") (voltage "5 V") (maxDelay "0.1 ns"))) (DiffIOPkg ((temperature "27") (bufferModelNonInverting "CDSDefaultIO_2p5v") (bufferModelInverting "CDSDefaultIO_2p5v") (stimuli nil) (offsets nil) (state "tristate") (cycle "1") (termMap nil) (setup "0.9e-09") (hold "0.4e-09") (rise nil) (fall nil) (threshInputHighMin "1.7 V") (threshInputHighTyp "1.7  V") (threshInputHighMax "1.7  V") (threshInputLowMin "0.7  V") (threshInputLowTyp "0.7  V") (threshInputLowMax "0.7 ") (threshOutputHighMin "2.365  V") (threshOutputHighTyp "2.5  V") (threshOutputHighMax "2.625  V") (threshOutputLowMin "1.275  V") (threshOutputLowTyp "1.7  V") (threshOutputLowMax "1.985  V") (mappingTagNonInverting nil) (mappingTagInverting nil) (spice nil))) (SeriesTerm ((resistance "22 ohm") (maxDelay "0.1 ns"))) (Resistor ((resistance "50 ohm") (orientation "0"))) (DiffIO ((temperature "27") (bufferModelNonInverting "CDSDefaultIO_2p5v") (bufferModelInverting "CDSDefaultIO_2p5v") (stimuli nil) (offsets nil) (state "tristate") (cycle "1") (termMap nil) (setup "0.9e-09") (hold "0.4e-09") (rise nil) (fall nil) (threshInputHighMin "1.7 V") (threshInputHighTyp "1.7  V") (threshInputHighMax "1.7  V") (threshInputLowMin "0.7  V") (threshInputLowTyp "0.7  V") (threshInputLowMax "0.7 ") (threshOutputHighMin "2.365  V") (threshOutputHighTyp "2.5  V") (threshOutputHighMax "2.625  V") (threshOutputLowMin "1.275  V") (threshOutputLowTyp "1.7  V") (threshOutputLowMax "1.985  V") (mappingTagNonInverting nil) (mappingTagInverting nil) (spice nil))) (DiffOutputPkg ((temperature "27") (bufferModelNonInverting "CDSDefaultOutput_2p5v") (bufferModelInverting "CDSDefaultOutput_2p5v") (stimuli nil) (offsets nil) (state "tristate") (cycle "1") (termMap nil) (setup "0.9e-09") (hold "0.4e-09") (rise nil) (fall nil) (threshOutputHighMin "2.375  V") (threshOutputHighTyp "2.5  V") (threshOutputHighMax "2.625  V") (threshOutputLowMin "1.275  V") (threshOutputLowTyp "1.7  V") (threshOutputLowMax "1.985  V") (mappingTagNonInverting nil) (mappingTagInverting nil) (spice nil))) (IbisIO ((temperature "27") (bufferModel "CDSDefaultIO_2p5v") (stimuli nil) (offsets nil) (state "tristate") (cycle "1") (termMap nil) (setup "2.0e-09") (hold "1.0e-09") (rise nil) (fall nil) (macroType nil) (voltage nil) (spice nil) (LEFDEFPinName nil) (LEFDEFPinType nil) (mappingTag nil))) (Trace ((d1Thickness "10 mil") (d1Constant "4.5") (d1LossTangent "0.035") (d2Thickness "10 mil") (d2Constant "4.5") (d2LossTangent "0.035") (d3Thickness "0.0") (d3Constant "1.0") (d3LossTangent "0") length("1000 mil") (spacing "5 mil") (spacing2 "5 mil") (spacing3 "5 mil") (spacing4 "5 mil") (spacing5 "5 mil") (traceConductivity "595900 mho/cm") (traceGeometry "microstrip") (traceLayerName "") (traceThickness "0.72 mil") (traceType "single") (traceWidth "5.0 mil") (traceWidth2 "5.0 mil") (traceWidth3 "5.0 mil") (traceWidth4 "5.0 mil") (traceWidth5 "5.0 mil") (traceWidth6 "5.0 mil") (offset "0 mil") (traceCount "1") (impedance nil))) (DiffOutput ((temperature "27") (bufferModelNonInverting "CDSDefaultOutput_2p5v") (bufferModelInverting "CDSDefaultOutput_2p5v") (stimuli nil) (offsets nil) (state "tristate") (cycle "1") (termMap nil) (setup "0.9e-09") (hold "0.4e-09") (rise nil) (fall nil) (threshOutputHighMin "2.375  V") (threshOutputHighTyp "2.5  V") (threshOutputHighMax "2.625  V") (threshOutputLowMin "1.275  V") (threshOutputLowTyp "1.7  V") (threshOutputLowMax "1.985  V") (mappingTagNonInverting nil) (mappingTagInverting nil) (spice nil))) (IbisOutput ((temperature "27") (bufferModel "CDSDefaultOutput_2p5v") (stimuli nil) (offsets nil) (state "tristate") (cycle "1") (termMap nil) (setup "2.0e-09") (hold "1.0e-09") (rise nil) (fall nil) (macroType nil) (voltage nil) (spice nil) (LEFDEFPinName nil) (LEFDEFPinType nil) (mappingTag nil))) (CPWSL ((d1Thickness "10 mil") (d1Constant "4.5") (d1LossTangent "0.035") (d2Thickness "0.72 mil") (d2Constant "4.5") (d2LossTangent "0.035") (d3Thickness "10 mil") (d3Constant "4.5") (d3LossTangent "0.035") length("1000 mil") (spacing "5 mil") (spacing2 "5 mil") (spacing3 "5 mil") (spacing4 "5 mil") (spacing5 "5 mil") (traceConductivity "595900 mho/cm") (traceGeometry "cpwms") (traceLayerName "") (traceThickness "0.72 mil") (traceType "single") (traceWidth "5.0 mil") (traceWidth2 "5.0 mil") (traceWidth3 "5.0 mil") (traceWidth4 "5.0 mil") (traceWidth5 "5.0 mil") (traceWidth6 "5.0 mil") (offset "0 mil") (traceCount "1") (impedance nil))) (Source ((voltage "5 V"))) (RLGC (length("1000 mil"))) (async ((asyncTimePoints "") (asyncInitState "1"))) (Cable (length("1 m"))) (Capacitor ((capacitance "10 pF") (orientation "0"))) (Inductor ((inductance "5 nH") (orientation "0"))) (CPW ((d1Thickness "10 mil") (d1Constant "4.5") (d1LossTangent "0.035") (d2Thickness "0.72 mil") (d2Constant "1") (d2LossTangent "0") (d3Thickness "0.0") (d3Constant "1") (d3LossTangent "0") length("1000 mil") (spacing "5 mil") (spacing2 "5 mil") (spacing3 "5 mil") (spacing4 "5 mil") (spacing5 "5 mil") (traceConductivity "595900 mho/cm") (traceGeometry "cpwms") (traceLayerName "") (traceThickness "0.72 mil") (traceType "single") (traceWidth "5.0 mil") (traceWidth2 "5.0 mil") (traceWidth3 "5.0 mil") (traceWidth4 "5.0 mil") (traceWidth5 "5.0 mil") (traceWidth6 "5.0 mil") (offset "0 mil") (traceCount "1") (impedance nil))) (CPWMS ((d1Thickness "10 mil") (d1Constant "4.5") (d1LossTangent "0.035") (d2Thickness "0.72 mil") (d2Constant "4.5") (d2LossTangent "0.035") (d3Thickness "0.0") (d3Constant "1") (d3LossTangent "0") length("1000 mil") (spacing "5 mil") (spacing2 "5 mil") (spacing3 "5 mil") (spacing4 "5 mil") (spacing5 "5 mil") (traceConductivity "595900 mho/cm") (traceGeometry "cpwms") (traceLayerName "") (traceThickness "0.72 mil") (traceType "single") (traceWidth "5.0 mil") (traceWidth2 "5.0 mil") (traceWidth3 "5.0 mil") (traceWidth4 "5.0 mil") (traceWidth5 "5.0 mil") (traceWidth6 "5.0 mil") (offset "0 mil") (traceCount "1") (impedance nil))) (IbisIOPkg ((temperature "27") (bufferModel "CDSDefaultIO_2p5v") (stimuli nil) (offsets nil) (state "tristate") (cycle "1") (termMap nil) (setup "2.0e-09") (hold "1.0e-09") (rise nil) (fall nil) (macroType nil) (voltage nil) (spice nil) (LEFDEFPinName nil) (LEFDEFPinType nil) (mappingTag nil))) (IbisIOMacro ((temperature "27") (bufferModel "CDSDefaultIO_2p5v") (stimuli nil) (offsets nil) (state "tristate") (cycle "1") (termMap nil) (setup "2.0e-09") (hold "1.0e-09") (rise nil) (fall nil) (macroType nil) (voltage nil) (spice nil) (LEFDEFPinName nil) (LEFDEFPinType nil) (mappingTag nil))) (clocked ((clockRise "1e-09") (clockFall "1e-09") (clockFreq "100e6") (clockInitState "0") (clockDutyCycle "0.5") (clockJitter "0"))) (IbisInputPkg ((temperature "27") (bufferModel "CDSDefaultInput_2p5v") (cycle "1") (LEFDEFPinName nil) (LEFDEFPinType nil) (mappingTag nil))) (periodic ((periodicFreq "100e6") (periodicPattern "10") (periodicJitter "0"))) (IbisOutputPkg ((temperature "27") (bufferModel "CDSDefaultOutput_2p5v") (stimuli nil) (offsets nil) (state "tristate") (cycle "1") (termMap nil) (setup "2.0e-09") (hold "1.0e-09") (rise nil) (fall nil) (macroType nil) (voltage nil) (spice nil) (LEFDEFPinName nil) (LEFDEFPinType nil) (mappingTag nil)))))
				)
				( objectStatus "DDR_B_CMD_DLL1-13" )
			)
			( electricalCSet "@crescent_city_bb_fab1_lib.crescent_city_bb_fab1(sch_1):\DDR_C_CMD_DLL1-13\"
				( groupRef "DDR_C_CMD_DLL1-13:MG_DDR_NEAR_DIMM-CLK1" )
				( groupRef "DDR_C_CMD_DLL1-13:MG_DDR_FAR_DIMM_CMD" )
				( groupRef "DDR_C_CMD_DLL1-13:MG_DDR_FAR_DIMM-CLK0" )
				( groupRef "DDR_C_CMD_DLL1-13:MG_DDR_CMD_NEAR_DIMM" )
				( pinPairRef "DDR_C_CMD_DLL1-13:U5D1.F51:J6U2.228" )
				( pinPairRef "DDR_C_CMD_DLL1-13:U5D1.F51:J4G3.228" )
				( attribute "TOPOLOGY_TEMPLATE_REVISION" "1.0"
					( Origin gBackEnd )
				)
				( topologyData 23949
(SKIDL (Circuits ("MAIN" (Parts ("CRESCENT_CITY_083_20140724_A.@@J1.228" IbisIOPkg (xy (5548 4240)) (refDes "J4G3") (model "Unknown") (Props (_SXDesignName "CRESCENT_CITY_083_20140724_A") (brdx "10643.7 MIL") (brdy "788.33 MIL") (bufferModel "CDSDefaultIO_2p5v") (cycle "1") (hold "1.0e-09") (mappingTag "") (offsets ("4" "0") ("5" "0")) (setup "2.0e-09") (state "tristate") (stimuli ("4" "local0") ("5" "local1")) (temperature "27") (termMap ("4" "Data") ("5" "Enable"))) (Terms ("CRESCENT_CITY_083_20140724_A.X1064370Y78833L2LRATS" "228"))) ("CRESCENT_CITY_083_20140724_A.@@J2.228" IbisIOPkg (xy (5528 4240)) (refDes "J6U2") (model "Unknown") (Props (_SXDesignName "CRESCENT_CITY_083_20140724_A") (brdx "10643.7 MIL") (brdy "796.23 MIL") (bufferModel "CDSDefaultIO_2p5v") (cycle "1") (hold "1.0e-09") (mappingTag "") (offsets ("4" "0") ("5" "0")) (setup "2.0e-09") (state "tristate") (stimuli ("4" "local2") ("5" "local15")) (temperature "27") (termMap ("4" "Data") ("5" "Enable"))) (Terms ("CRESCENT_CITY_083_20140724_A.X1064370Y79623L28LRATS" "228"))) ("CRESCENT_CITY_083_20140724_A.@@U36.F51" IbisIOPkg (xy (5502 4240)) (refDes "U5D1") (model "Unknown") (Props (_SXDesignName "CRESCENT_CITY_083_20140724_A") (brdx "10346.35 MIL") (brdy "2052.1 MIL") (bufferModel "CDSDefaultIO_2p5v") (cycle "1") (hold "1.0e-09") (mappingTag "") (offsets ("4" "0") ("5" "0")) (setup "2.0e-09") (state "tristate") (stimuli ("4" "local16") ("5" "local17")) (temperature "27") (termMap ("4" "Data") ("5" "Enable"))) (Terms ("CRESCENT_CITY_083_20140724_A.X1034635Y205210L2LRATS" "F51"))) ("CRESCENT_CITY_083_20140724_A.T@@RATS@@J2.228@@U36.F51" TLine (xy (5513 4235)) (mirror x) (refDes "TL1") (Props (_SXDesignName "CRESCENT_CITY_083_20140724_A") (impedance "53.474 ohm") length("1553.22 MIL") (propDelay "0.27897 ns") (traceCount "1") (traceGeometry "Microstrip") (velocity "5567.68 mil/ns")) (Terms ("CRESCENT_CITY_083_20140724_A.X1064370Y79623L28LRATS" "1") ("CRESCENT_CITY_083_20140724_A.X1034635Y205210L2LRATS" "2"))) ("CRESCENT_CITY_083_20140724_A.T@@RATS@@J2.228@@J1.228" TLine (xy (5539 4235)) (refDes "TL2") (Props (_SXDesignName "CRESCENT_CITY_083_20140724_A") (impedance "39.682 ohm") length("7.90 MIL") (propDelay "0.00142 ns") (traceCount "1") (traceGeometry "Microstrip") (velocity "5563.39 mil/ns")) (Terms ("CRESCENT_CITY_083_20140724_A.X1064370Y79623L28LRATS" "1") ("CRESCENT_CITY_083_20140724_A.X1064370Y78833L2LRATS" "2")))) (Nodes ("CRESCENT_CITY_083_20140724_A.X1034635Y205210L2LRATS" (terms "CRESCENT_CITY_083_20140724_A.T@@RATS@@J2.228@@U36.F51.2" "CRESCENT_CITY_083_20140724_A.@@U36.F51.1")) ("CRESCENT_CITY_083_20140724_A.X1064370Y78833L2LRATS" (terms "CRESCENT_CITY_083_20140724_A.T@@RATS@@J2.228@@J1.228.2" "CRESCENT_CITY_083_20140724_A.@@J1.228.1")) ("CRESCENT_CITY_083_20140724_A.X1064370Y79623L28LRATS" (terms "CRESCENT_CITY_083_20140724_A.T@@RATS@@J2.228@@J1.228.1" "CRESCENT_CITY_083_20140724_A.T@@RATS@@J2.228@@U36.F51.1" "CRESCENT_CITY_083_20140724_A.@@J2.228.1"))) (Ports) (Stimuli ("local2" (scope local) (stimType periodic) (Props (periodicFreq "5e+007") (periodicJitter "0") (periodicPattern "1"))) ("local15" (scope local) (stimType periodic) (Props (periodicFreq "5e+007") (periodicJitter "0") (periodicPattern "1"))) ("local0" (scope local) (stimType periodic) (Props (periodicFreq "5e+007") (periodicJitter "0") (periodicPattern "1"))) ("local16" (scope local) (stimType periodic) (Props (periodicFreq "5e+007") (periodicJitter "0") (periodicPattern "1"))) ("local1" (scope local) (stimType periodic) (Props (periodicFreq "5e+007") (periodicJitter "0") (periodicPattern "1"))) ("local17" (scope local) (stimType periodic) (Props (periodicFreq "5e+007") (periodicJitter "0") (periodicPattern "1")))) (Notes) (Constraints ("RELATIVE_PROPAGATION_DELAY" ("MG_DDR_NEAR_DIMM-CLK1" "CRESCENT_CITY_083_20140724_A U36.F51" "CRESCENT_CITY_083_20140724_A J6.228" "CLASS" "LENGTH" "0.01778" "LENGTH" "0") ("MG_DDR_FAR_DIMM_CMD" "CRESCENT_CITY_083_20140724_A U36.F51" "CRESCENT_CITY_083_20140724_A J5.228" "NET GROUP" "LENGTH" "0.000635" "LENGTH" "0") ("MG_DDR_FAR_DIMM-CLK0" "CRESCENT_CITY_083_20140724_A U36.F51" "CRESCENT_CITY_083_20140724_A J5.228" "CLASS" "LENGTH" "0.01778" "LENGTH" "0") ("MG_DDR_CMD_NEAR_DIMM" "CRESCENT_CITY_083_20140724_A U36.F51" "CRESCENT_CITY_083_20140724_A J6.228" "NET GROUP" "LENGTH" "0.000635" "LENGTH" "0"))) (MeasurementSets ("EMI" ("EMIStatus" status("on")) ("PeakEmission" status("on")) ("PeakFrequency" status("on")) ("PulseFreq" status("on")) ("RiseTime" status("on")) ("VoltageSwing" status("on"))) ("Reflection" ("BufferDelayFall" status("off")) ("BufferDelayRise" status("off")) ("EyeHeight" status("off")) ("EyeJitter" status("off")) ("EyeWidth" status("off")) ("FirstIncidentFall" status("off")) ("FirstIncidentRise" status("off")) ("Glitch" status("on")) ("GlitchFall" status("off")) ("GlitchRise" status("off")) ("Monotonic" status("on")) ("MonotonicFall" status("off")) ("MonotonicRise" status("off")) ("NoiseMargin" status("on")) ("NoiseMarginHigh" status("off")) ("NoiseMarginLow" status("off")) ("OvershootHigh" status("on")) ("OvershootLow" status("on")) ("PropDelay" status("on")) ("SettleDelay" status("on")) ("SettleDelayFall" status("off")) ("SettleDelayRise" status("off")) ("SwitchDelay" status("on")) ("SwitchDelayFall" status("off")) ("SwitchDelayRise" status("off"))) ("Crosstalk" ("Crosstalk" status("on"))) ("Custom")) (VectorSets) (Props (XnetName "M_A_MA<14>") (allDrivers "active") (autoSolve "Off") (customSimType "Reflection") (ftsMode ("Typ")) (rcvrSelect "all") (tlineDelayMode "time") (userRevision "1.0")))) (Subckts) (CrossSections ("CRESCENT_CITY_083_20140724_A" (Props (SXDesignName "CRESCENT_CITY_083_20140724_A")) (Layers ("" (layerType "SURFACE") (material "AIR") (thickness "0 mil") (dielectricConstant "1.000000") (lossTangent "0") (etchFactor "0.000000") (elecCondVal "0 mho/cm") (thermCondVal "0 w/cm-degC")) ("" (layerType "DIELECTRIC") (material "CONFORMAL_COAT") (thickness "0.5 mil") (dielectricConstant "3.800000") (lossTangent "0.035") (etchFactor "0.000000") (elecCondVal "0 mho/cm") (thermCondVal "0.012 w/cm-degC")) ("TOP" (layerType "CONDUCTOR") (material "COPPER") (thickness "  1.800000 mil") (width "4.00 MIL") (dielectricConstant "4.500000") (lossTangent "0") (etchFactor "70.000000") (elecCondVal "595900.000000 mho/cm") (thermCondVal "0 w/cm-degC") (signalDieConstant "3.800000") (signalLossTangent "0.035")) ("" (layerType "DIELECTRIC") (material "FR-4") (thickness "  2.700000 mil") (dielectricConstant "4.000000") (lossTangent "0.035") (etchFactor "0.000000") (elecCondVal "0 mho/cm") (thermCondVal "0.012 w/cm-degC")) ("L2_GND1" (layerType "PLANE") (material "COPPER") (isShield t) (thickness "  1.200000 mil") (dielectricConstant "4.500000") (lossTangent "0.035") (etchFactor "90.000000") (elecCondVal "595900.000000 mho/cm") (thermCondVal "0.012 w/cm-degC")) ("" (layerType "DIELECTRIC") (material "FR-4") (thickness "  9.900000 mil") (dielectricConstant "4.100000") (lossTangent "0.035") (etchFactor "0.000000") (elecCondVal "0 mho/cm") (thermCondVal "0.012 w/cm-degC")) ("L3_SIG1" (layerType "CONDUCTOR") (material "COPPER") (thickness "  1.200000 mil") (width "4.00 MIL") (dielectricConstant "4.500000") (lossTangent "0.035") (etchFactor "90.000000") (elecCondVal "595900.000000 mho/cm") (thermCondVal "0.012 w/cm-degC") (signalDieConstant "4.100000") (signalLossTangent "0.035")) ("" (layerType "DIELECTRIC") (material "FR-4") (thickness "  3.300000 mil") (dielectricConstant "4.500000") (lossTangent "0.035") (etchFactor "0.000000") (elecCondVal "0 mho/cm") (thermCondVal "0 w/cm-degC")) ("L4_GND2" (layerType "PLANE") (material "COPPER") (isShield t) (thickness "  1.200000 mil") (dielectricConstant "4.500000") (lossTangent "0.035") (etchFactor "90.000000") (elecCondVal "595900.000000 mho/cm") (thermCondVal "0 w/cm-degC")) ("" (layerType "DIELECTRIC") (material "FR-4") (thickness "  3.300000 mil") (dielectricConstant "4.000000") (lossTangent "0.035") (etchFactor "0.000000") (elecCondVal "0 mho/cm") (thermCondVal "0.012 w/cm-degC")) ("L5_SIG2" (layerType "CONDUCTOR") (material "COPPER") (thickness "  1.200000 mil") (width "4.00 MIL") (dielectricConstant "4.500000") (lossTangent "0.035") (etchFactor "90.000000") (elecCondVal "595900.000000 mho/cm") (thermCondVal "0.012 w/cm-degC") (signalDieConstant "4.000000") (signalLossTangent "0.035")) ("" (layerType "DIELECTRIC") (material "FR-4") (thickness "  9.900000 mil") (dielectricConstant "4.500000") (lossTangent "0.035") (etchFactor "0.000000") (elecCondVal "0 mho/cm") (thermCondVal "0 w/cm-degC")) ("L6_GND3" (layerType "PLANE") (material "COPPER") (isShield t) (thickness "  1.200000 mil") (dielectricConstant "4.500000") (lossTangent "0.035") (etchFactor "90.000000") (elecCondVal "595900.000000 mho/cm") (thermCondVal "0 w/cm-degC")) ("" (layerType "DIELECTRIC") (material "FR-4") (thickness "  3.300000 mil") (dielectricConstant "4.100000") (lossTangent "0.035") (etchFactor "0.000000") (elecCondVal "0 mho/cm") (thermCondVal "0.012 w/cm-degC")) ("L7_PWR1-SIG" (layerType "PLANE") (material "COPPER") (isShield t) (thickness "  1.200000 mil") (dielectricConstant "4.500000") (lossTangent "0.035") (etchFactor "90.000000") (elecCondVal "595900.000000 mho/cm") (thermCondVal "0.012 w/cm-degC")) ("" (layerType "DIELECTRIC") (material "FR-4") (thickness "  9.900000 mil") (dielectricConstant "4.000000") (lossTangent "0.035") (etchFactor "0.000000") (elecCondVal "0 mho/cm") (thermCondVal "0.012 w/cm-degC")) ("L8_PWR2-SIG" (layerType "PLANE") (material "COPPER") (isShield t) (thickness "  1.200000 mil") (dielectricConstant "4.500000") (lossTangent "0.035") (etchFactor "90.000000") (elecCondVal "595900.000000 mho/cm") (thermCondVal "0.012 w/cm-degC")) ("" (layerType "DIELECTRIC") (material "FR-4") (thickness "  3.300000 mil") (dielectricConstant "4.500000") (lossTangent "0.035") (etchFactor "0.000000") (elecCondVal "0 mho/cm") (thermCondVal "0 w/cm-degC")) ("L9_GND4" (layerType "PLANE") (material "COPPER") (isShield t) (thickness "  1.200000 mil") (dielectricConstant "4.500000") (lossTangent "0.035") (etchFactor "90.000000") (elecCondVal "595900.000000 mho/cm") (thermCondVal "0 w/cm-degC")) ("" (layerType "DIELECTRIC") (material "FR-4") (thickness "  9.900000 mil") (dielectricConstant "4.100000") (lossTangent "0.035") (etchFactor "0.000000") (elecCondVal "0 mho/cm") (thermCondVal "0.012 w/cm-degC")) ("L10_SIG3" (layerType "CONDUCTOR") (material "COPPER") (thickness "  1.200000 mil") (width "4.00 MIL") (dielectricConstant "4.500000") (lossTangent "0.035") (etchFactor "90.000000") (elecCondVal "595900.000000 mho/cm") (thermCondVal "0.012 w/cm-degC") (signalDieConstant "4.100000") (signalLossTangent "0.035")) ("" (layerType "DIELECTRIC") (material "FR-4") (thickness "  3.300000 mil") (dielectricConstant "4.500000") (lossTangent "0.035") (etchFactor "0.000000") (elecCondVal "0 mho/cm") (thermCondVal "0 w/cm-degC")) ("L11_GND5" (layerType "PLANE") (material "COPPER") (isShield t) (thickness "  1.200000 mil") (dielectricConstant "4.500000") (lossTangent "0.035") (etchFactor "90.000000") (elecCondVal "595900.000000 mho/cm") (thermCondVal "0 w/cm-degC")) ("" (layerType "DIELECTRIC") (material "FR-4") (thickness "  9.900000 mil") (dielectricConstant "4.500000") (lossTangent "0.035") (etchFactor "0.000000") (elecCondVal "0 mho/cm") (thermCondVal "0.012 w/cm-degC")) ("L12_SIG4" (layerType "CONDUCTOR") (material "COPPER") (thickness "  1.200000 mil") (width "4.00 MIL") (dielectricConstant "4.500000") (lossTangent "0.035") (etchFactor "90.000000") (elecCondVal "595900.000000 mho/cm") (thermCondVal "0.012 w/cm-degC") (signalDieConstant "4.500000") (signalLossTangent "0.035")) ("" (layerType "DIELECTRIC") (material "FR-4") (thickness "  3.300000 mil") (dielectricConstant "4.500000") (lossTangent "0.035") (etchFactor "0.000000") (elecCondVal "0 mho/cm") (thermCondVal "0 w/cm-degC")) ("L13_GND6" (layerType "PLANE") (material "COPPER") (isShield t) (thickness "  1.200000 mil") (dielectricConstant "4.500000") (lossTangent "0.035") (etchFactor "90.000000") (elecCondVal "595900.000000 mho/cm") (thermCondVal "0.012 w/cm-degC")) ("" (layerType "DIELECTRIC") (material "FR-4") (thickness "  2.700000 mil") (dielectricConstant "4.500000") (lossTangent "0.035") (etchFactor "0.000000") (elecCondVal "0 mho/cm") (thermCondVal "0.012 w/cm-degC")) ("BOTTOM" (layerType "CONDUCTOR") (material "COPPER") (thickness "  1.800000 mil") (width "4.00 MIL") (dielectricConstant "4.500000") (lossTangent "0") (etchFactor "70.000000") (elecCondVal "595900.000000 mho/cm") (thermCondVal "0 w/cm-degC") (signalDieConstant "3.800000") (signalLossTangent "0.035")) ("" (layerType "DIELECTRIC") (material "CONFORMAL_COAT") (thickness "0.5 mil") (dielectricConstant "3.800000") (lossTangent "0.035") (etchFactor "0.000000") (elecCondVal "0 mho/cm") (thermCondVal "0.012 w/cm-degC")) ("" (layerType "SURFACE") (material "AIR") (thickness "0 mil") (dielectricConstant "1.000000") (lossTangent "0") (etchFactor "0.000000") (elecCondVal "0 mho/cm") (thermCondVal "0 w/cm-degC"))))) (Props (DesUnits "mils 2") (LayerStack ("DIELECTRIC" "DIELECTRIC" "BOTTOM" "DIELECTRIC" "L13_GND6" "DIELECTRIC" "L12_SIG4" "DIELECTRIC" "L11_GND5" "DIELECTRIC" "L10_SIG3" "DIELECTRIC" "L9_GND4" "DIELECTRIC" "L8_PWR2-SIG" "DIELECTRIC" "L7_PWR1-SIG" "DIELECTRIC" "L6_GND3" "DIELECTRIC" "L5_SIG2" "DIELECTRIC" "L4_GND2" "DIELECTRIC" "L3_SIG1" "DIELECTRIC" "L2_GND1" "DIELECTRIC" "TOP" "DIELECTRIC" "DIELECTRIC")) (Revision "16.600")) (Params (IbisInput ((temperature "27") (bufferModel "CDSDefaultInput_2p5v") (cycle "1") (LEFDEFPinName nil) (LEFDEFPinType nil) (mappingTag nil))) (Trace ((d1Thickness "10 mil") (d1Constant "4.5") (d1LossTangent "0.035") (d2Thickness "10 mil") (d2Constant "4.5") (d2LossTangent "0.035") (d3Thickness "0.0") (d3Constant "1.0") (d3LossTangent "0") length("1000 mil") (spacing "5 mil") (spacing2 "5 mil") (spacing3 "5 mil") (spacing4 "5 mil") (spacing5 "5 mil") (traceConductivity "595900 mho/cm") (traceGeometry "microstrip") (traceLayerName "") (traceThickness "0.72 mil") (traceType "single") (traceWidth "5.0 mil") (traceWidth2 "5.0 mil") (traceWidth3 "5.0 mil") (traceWidth4 "5.0 mil") (traceWidth5 "5.0 mil") (traceWidth6 "5.0 mil") (offset "0 mil") (traceCount "1") (impedance nil))) (Cable (length("1 m"))) (IbisIO ((temperature "27") (bufferModel "CDSDefaultIO_2p5v") (stimuli nil) (offsets nil) (state "tristate") (cycle "1") (termMap nil) (setup "2.0e-09") (hold "1.0e-09") (rise nil) (fall nil) (macroType nil) (voltage nil) (spice nil) (LEFDEFPinName nil) (LEFDEFPinType nil) (mappingTag nil))) (IbisOutput ((temperature "27") (bufferModel "CDSDefaultOutput_2p5v") (stimuli nil) (offsets nil) (state "tristate") (cycle "1") (termMap nil) (setup "2.0e-09") (hold "1.0e-09") (rise nil) (fall nil) (macroType nil) (voltage nil) (spice nil) (LEFDEFPinName nil) (LEFDEFPinType nil) (mappingTag nil))) (Via ((model "Unknown") (viaOutputFormat "Unknown") (viaPadstack nil) (viaTopLayer nil) (viaBottomLayer nil) (viaIsPower nil) (viaIsGround nil))) (ESpiceDevice nil) (clocked ((clockRise "1e-09") (clockFall "1e-09") (clockFreq "100e6") (clockInitState "0") (clockDutyCycle "0.5") (clockJitter "0"))) (IbisIO_OpenPullUp ((temperature "27") (bufferModel "CDSDefaultIO_2p5v") (stimuli nil) (offsets nil) (state "tristate") (cycle "1") (termMap nil) (setup "2.0e-09") (hold "1.0e-09") (rise nil) (fall nil) (macroType nil) (voltage nil) (spice nil) (LEFDEFPinName nil) (LEFDEFPinType nil) (mappingTag nil))) (IbisOutput_OpenPullUp ((temperature "27") (bufferModel "CDSDefaultOutput_2p5v") (stimuli nil) (offsets nil) (state "tristate") (cycle "1") (termMap nil) (setup "2.0e-09") (hold "1.0e-09") (rise nil) (fall nil) (macroType nil) (voltage nil) (spice nil) (LEFDEFPinName nil) (LEFDEFPinType nil) (mappingTag nil))) (periodic ((periodicFreq "100e6") (periodicPattern "10") (periodicJitter "0"))) (TheveninTerm ((resistanceUp "180 ohm") (resistanceDown "270 ohm") (voltageUp "5 V") (voltageDown "0 V") (maxDelay "0.1 ns"))) (IbisInputPkg ((temperature "27") (bufferModel "CDSDefaultInput_2p5v") (cycle "1") (LEFDEFPinName nil) (LEFDEFPinType nil) (mappingTag nil))) (ShuntTerm ((resistance "50 ohm") (voltage "5 V") (maxDelay "0.1 ns"))) (IbisIOMacro ((temperature "27") (bufferModel "CDSDefaultIO_2p5v") (stimuli nil) (offsets nil) (state "tristate") (cycle "1") (termMap nil) (setup "2.0e-09") (hold "1.0e-09") (rise nil) (fall nil) (macroType nil) (voltage nil) (spice nil) (LEFDEFPinName nil) (LEFDEFPinType nil) (mappingTag nil))) (CurrentProbe nil) (IbisOutputPkg ((temperature "27") (bufferModel "CDSDefaultOutput_2p5v") (stimuli nil) (offsets nil) (state "tristate") (cycle "1") (termMap nil) (setup "2.0e-09") (hold "1.0e-09") (rise nil) (fall nil) (macroType nil) (voltage nil) (spice nil) (LEFDEFPinName nil) (LEFDEFPinType nil) (mappingTag nil))) (IbisIOPkg ((temperature "27") (bufferModel "CDSDefaultIO_2p5v") (stimuli nil) (offsets nil) (state "tristate") (cycle "1") (termMap nil) (setup "2.0e-09") (hold "1.0e-09") (rise nil) (fall nil) (macroType nil) (voltage nil) (spice nil) (LEFDEFPinName nil) (LEFDEFPinType nil) (mappingTag nil))) (SeriesTerm ((resistance "22 ohm") (maxDelay "0.1 ns"))) (DiffInputPkg ((temperature "27") (bufferModelNonInverting "CDSDefaultInput_2p5v") (bufferModelInverting "CDSDefaultInput_2p5v") (threshInputHighMin "1.7 V") (threshInputHighTyp "1.7  V") (threshInputHighMax "1.7  V") (threshInputLowMin "0.7  V") (threshInputLowTyp "0.7  V") (threshInputLowMax "0.7  V") (mappingTagNonInverting nil) (mappingTagInverting nil) (cycle "1"))) (DualClampTerm ((cutoffVoltageUp "0.7 V") (cutoffVoltageDown "0.7 V") (voltageUp "5 V") (voltageDown "0 V") (maxDelay "0.1 ns"))) (HiClampTerm ((cutoffVoltage "0.7 V") (voltage "5 V") (maxDelay "0.1 ns"))) (LowClampTerm ((cutoffVoltage "0.7 V") (voltage "0 V") (maxDelay "0.1 ns"))) (RCTerm ((resistance "50 ohm") (capacitance "20 pF") (voltage "5 V") (maxDelay "0.1 ns"))) (idlCircuit ((allDrivers "active") (ftsMode '("Typ")) (rcvrSelect "all") (simMode "Reflection") (tlineDelayMode "time") (userRevision "1.0") (autoSolve "On"))) (sync ((syncFreq "100e6") (syncInitState "1") (syncPattern "10") (syncEdgeSwitch "rise"))) (Diode ((cutoffVoltage "0.7 V"))) (TLine ((diffImpedance "100ohm") (diffVelocity "1.4142e+08M/s") (impedance "60ohm") length("2800 mil") (propDelay "0.5 ns") (velocity "5600 mil/ns") (traceCount "1") (traceGeometry "Microstrip") (impedanceMin nil) (impedanceMax nil) (lengthMin nil) (lengthMax nil) (propDelayMin nil) (propDelayMax nil) (impedanceSweepCount nil) (propDelaySweepCount nil) (velocitySweepCount nil) (lengthSweepCount nil) (matchSetName nil))) (Connector nil) (IbisIO_OpenPullDown ((temperature "27") (bufferModel "CDSDefaultIO_2p5v") (stimuli nil) (offsets nil) (state "tristate") (cycle "1") (termMap nil) (setup "2.0e-09") (hold "1.0e-09") (rise nil) (fall nil) (macroType nil) (voltage nil) (spice nil) (LEFDEFPinName nil) (LEFDEFPinType nil) (mappingTag nil))) (CPW ((d1Thickness "10 mil") (d1Constant "4.5") (d1LossTangent "0.035") (d2Thickness "0.72 mil") (d2Constant "1") (d2LossTangent "0") (d3Thickness "0.0") (d3Constant "1") (d3LossTangent "0") length("1000 mil") (spacing "5 mil") (spacing2 "5 mil") (spacing3 "5 mil") (spacing4 "5 mil") (spacing5 "5 mil") (traceConductivity "595900 mho/cm") (traceGeometry "cpwms") (traceLayerName "") (traceThickness "0.72 mil") (traceType "single") (traceWidth "5.0 mil") (traceWidth2 "5.0 mil") (traceWidth3 "5.0 mil") (traceWidth4 "5.0 mil") (traceWidth5 "5.0 mil") (traceWidth6 "5.0 mil") (offset "0 mil") (traceCount "1") (impedance nil))) (async ((asyncTimePoints "") (asyncInitState "1"))) (CPWSL ((d1Thickness "10 mil") (d1Constant "4.5") (d1LossTangent "0.035") (d2Thickness "0.72 mil") (d2Constant "4.5") (d2LossTangent "0.035") (d3Thickness "10 mil") (d3Constant "4.5") (d3LossTangent "0.035") length("1000 mil") (spacing "5 mil") (spacing2 "5 mil") (spacing3 "5 mil") (spacing4 "5 mil") (spacing5 "5 mil") (traceConductivity "595900 mho/cm") (traceGeometry "cpwms") (traceLayerName "") (traceThickness "0.72 mil") (traceType "single") (traceWidth "5.0 mil") (traceWidth2 "5.0 mil") (traceWidth3 "5.0 mil") (traceWidth4 "5.0 mil") (traceWidth5 "5.0 mil") (traceWidth6 "5.0 mil") (offset "0 mil") (traceCount "1") (impedance nil))) (CPWMS ((d1Thickness "10 mil") (d1Constant "4.5") (d1LossTangent "0.035") (d2Thickness "0.72 mil") (d2Constant "4.5") (d2LossTangent "0.035") (d3Thickness "0.0") (d3Constant "1") (d3LossTangent "0") length("1000 mil") (spacing "5 mil") (spacing2 "5 mil") (spacing3 "5 mil") (spacing4 "5 mil") (spacing5 "5 mil") (traceConductivity "595900 mho/cm") (traceGeometry "cpwms") (traceLayerName "") (traceThickness "0.72 mil") (traceType "single") (traceWidth "5.0 mil") (traceWidth2 "5.0 mil") (traceWidth3 "5.0 mil") (traceWidth4 "5.0 mil") (traceWidth5 "5.0 mil") (traceWidth6 "5.0 mil") (offset "0 mil") (traceCount "1") (impedance nil))) (DiffInput ((temperature "27") (bufferModelNonInverting "CDSDefaultInput_2p5v") (bufferModelInverting "CDSDefaultInput_2p5v") (threshInputHighMin "1.7 V") (threshInputHighTyp "1.7  V") (threshInputHighMax "1.7  V") (threshInputLowMin "0.7  V") (threshInputLowTyp "0.7  V") (threshInputLowMax "0.7  V") (mappingTagNonInverting nil) (mappingTagInverting nil) (cycle "1"))) (Resistor ((resistance "50 ohm") (orientation "0"))) (DiffOutputPkg ((temperature "27") (bufferModelNonInverting "CDSDefaultOutput_2p5v") (bufferModelInverting "CDSDefaultOutput_2p5v") (stimuli nil) (offsets nil) (state "tristate") (cycle "1") (termMap nil) (setup "0.9e-09") (hold "0.4e-09") (rise nil) (fall nil) (threshOutputHighMin "2.375  V") (threshOutputHighTyp "2.5  V") (threshOutputHighMax "2.625  V") (threshOutputLowMin "1.275  V") (threshOutputLowTyp "1.7  V") (threshOutputLowMax "1.985  V") (mappingTagNonInverting nil) (mappingTagInverting nil) (spice nil))) (DiffOutput ((temperature "27") (bufferModelNonInverting "CDSDefaultOutput_2p5v") (bufferModelInverting "CDSDefaultOutput_2p5v") (stimuli nil) (offsets nil) (state "tristate") (cycle "1") (termMap nil) (setup "0.9e-09") (hold "0.4e-09") (rise nil) (fall nil) (threshOutputHighMin "2.375  V") (threshOutputHighTyp "2.5  V") (threshOutputHighMax "2.625  V") (threshOutputLowMin "1.275  V") (threshOutputLowTyp "1.7  V") (threshOutputLowMax "1.985  V") (mappingTagNonInverting nil) (mappingTagInverting nil) (spice nil))) (Inductor ((inductance "5 nH") (orientation "0"))) (Capacitor ((capacitance "10 pF") (orientation "0"))) (DiffIOPkg ((temperature "27") (bufferModelNonInverting "CDSDefaultIO_2p5v") (bufferModelInverting "CDSDefaultIO_2p5v") (stimuli nil) (offsets nil) (state "tristate") (cycle "1") (termMap nil) (setup "0.9e-09") (hold "0.4e-09") (rise nil) (fall nil) (threshInputHighMin "1.7 V") (threshInputHighTyp "1.7  V") (threshInputHighMax "1.7  V") (threshInputLowMin "0.7  V") (threshInputLowTyp "0.7  V") (threshInputLowMax "0.7 ") (threshOutputHighMin "2.365  V") (threshOutputHighTyp "2.5  V") (threshOutputHighMax "2.625  V") (threshOutputLowMin "1.275  V") (threshOutputLowTyp "1.7  V") (threshOutputLowMax "1.985  V") (mappingTagNonInverting nil) (mappingTagInverting nil) (spice nil))) (Source ((voltage "5 V"))) (DiffIO ((temperature "27") (bufferModelNonInverting "CDSDefaultIO_2p5v") (bufferModelInverting "CDSDefaultIO_2p5v") (stimuli nil) (offsets nil) (state "tristate") (cycle "1") (termMap nil) (setup "0.9e-09") (hold "0.4e-09") (rise nil) (fall nil) (threshInputHighMin "1.7 V") (threshInputHighTyp "1.7  V") (threshInputHighMax "1.7  V") (threshInputLowMin "0.7  V") (threshInputLowTyp "0.7  V") (threshInputLowMax "0.7 ") (threshOutputHighMin "2.365  V") (threshOutputHighTyp "2.5  V") (threshOutputHighMax "2.625  V") (threshOutputLowMin "1.275  V") (threshOutputLowTyp "1.7  V") (threshOutputLowMax "1.985  V") (mappingTagNonInverting nil) (mappingTagInverting nil) (spice nil))) (RLGC (length("1000 mil")))))
				)
				( objectStatus "DDR_C_CMD_DLL1-13" )
			)
			( electricalCSet "@crescent_city_bb_fab1_lib.crescent_city_bb_fab1(sch_1):\PCIE_SLOT\"
				( groupRef "PCIE_SLOT_C:MG_PCIE_L0" )
				( groupRef "PCIE_SLOT_C:MG_PCIE_L1" )
				( groupRef "PCIE_SLOT_C:MG" )
				( pinPairRef "PCIE_SLOT_C:J8G1.195:C7G5.2" )
				( pinPairRef "PCIE_SLOT_C:U5D1.BK5:C7G5.1" )
				( pinPairRef "PCIE_SLOT_C:U5D1.BK5:J8G1.195" )
				( attribute "DIFFP_GATHER_CONTROL" "IGNORE"
					( Origin gBackEnd )
				)
				( attribute "DIFFP_UNCOUPLED_LENGTH" "1000.00"
					( Origin gBackEnd )
				)
				( attribute "DIFFP_COUPLED_PLUS" "0.10"
					( Origin gBackEnd )
				)
				( attribute "DIFFP_COUPLED_MINUS" "0.10"
					( Origin gBackEnd )
				)
				( attribute "DIFFP_PHASE_TOL" "5 mil"
					( Units "uPhaseTol" "ns" 1.000000)
					( Origin gBackEnd )
				)
				( attribute "TOPOLOGY_TEMPLATE_REVISION" "1.0"
					( Origin gBackEnd )
				)
				( topologyData 23407
(SKIDL (Circuits ("MAIN" (Parts ("CRESCENT_CITY_177_20141217_Q.@@U36.BK5" IbisOutputPkg (xy (5498 4235)) (refDes "U5D1") (model "Unknown") (Props (_SXDesignName "CRESCENT_CITY_177_20141217_Q") (brdx "11961.29 MIL") (brdy "2980.96 MIL") (bufferModel "CDSDefaultOutput_2p5v") (cycle "1") (hold "1.0e-09") (mappingTag "") (offsets ("4" "0")) (setup "2.0e-09") (state "tristate") (stimuli ("4" "local0")) (temperature "27") (termMap ("4" "Data"))) (Terms ("CRESCENT_CITY_177_20141217_Q.X1196129Y298096L2LRATS" "BK5"))) ("CRESCENT_CITY_177_20141217_Q.@@J73.195" IbisIOPkg (xy (5545 4240)) (refDes "J8G1") (model "Unknown") (Props (_SXDesignName "CRESCENT_CITY_177_20141217_Q") (brdx "14315.37 MIL") (brdy "306.76 MIL") (bufferModel "CDSDefaultIO_2p5v") (cycle "1") (hold "1.0e-09") (mappingTag "") (offsets ("4" "0") ("5" "0")) (setup "2.0e-09") (state "tristate") (stimuli ("5" "local2") ("4" "local1")) (temperature "27") (termMap ("4" "Data") ("5" "Enable"))) (Terms ("CRESCENT_CITY_177_20141217_Q.X1431537Y30676L2LRATS" "195"))) ("CRESCENT_CITY_177_20141217_Q.T@@RATS@@C1900.1@@U36.BK5" TLine (xy (5506 4235)) (mirror x) (refDes "TL1") (Props (_SXDesignName "CRESCENT_CITY_177_20141217_Q") (impedance "52.449 ohm") length("4853.31 MIL") (propDelay "0.87168 ns") (traceCount "1") (traceGeometry "Microstrip") (velocity "5567.76 mil/ns")) (Terms ("CRESCENT_CITY_177_20141217_Q.X1431362Y48000L2LRATS" "1") ("CRESCENT_CITY_177_20141217_Q.X1196129Y298096L2LRATS" "2"))) ("CRESCENT_CITY_177_20141217_Q.@@C1900.1.2" Capacitor (xy (5521 4235)) (refDes "C7G5") (value "220000 pF") (Props (_SXDesignName "CRESCENT_CITY_177_20141217_Q")) (Terms ("CRESCENT_CITY_177_20141217_Q.X1431362Y48000L2LRATS" "1") ("CRESCENT_CITY_177_20141217_Q.X1431362Y44500L2LRATS" "2"))) ("CRESCENT_CITY_177_20141217_Q.T@@RATS@@J73.195@@C1900.2" TLine (xy (5530 4235)) (mirror x) (refDes "TL2") (Props (_SXDesignName "CRESCENT_CITY_177_20141217_Q") (impedance "47.169 ohm") length("139.99 MIL") (propDelay "0.02514 ns") (traceCount "1") (traceGeometry "Microstrip") (velocity "5568.43 mil/ns")) (Terms ("CRESCENT_CITY_177_20141217_Q.X1431537Y30676L2LRATS" "1") ("CRESCENT_CITY_177_20141217_Q.X1431362Y44500L2LRATS" "2")))) (Nodes ("CRESCENT_CITY_177_20141217_Q.X1196129Y298096L2LRATS" (terms "CRESCENT_CITY_177_20141217_Q.T@@RATS@@C1900.1@@U36.BK5.2" "CRESCENT_CITY_177_20141217_Q.@@U36.BK5.1")) ("CRESCENT_CITY_177_20141217_Q.X1431537Y30676L2LRATS" (terms "CRESCENT_CITY_177_20141217_Q.T@@RATS@@J73.195@@C1900.2.1" "CRESCENT_CITY_177_20141217_Q.@@J73.195.1")) ("CRESCENT_CITY_177_20141217_Q.X1431362Y48000L2LRATS" (terms "CRESCENT_CITY_177_20141217_Q.@@C1900.1.2.1" "CRESCENT_CITY_177_20141217_Q.T@@RATS@@C1900.1@@U36.BK5.1")) ("CRESCENT_CITY_177_20141217_Q.X1431362Y44500L2LRATS" (terms "CRESCENT_CITY_177_20141217_Q.T@@RATS@@J73.195@@C1900.2.2" "CRESCENT_CITY_177_20141217_Q.@@C1900.1.2.2"))) (Ports) (Stimuli ("local2" (scope local) (stimType periodic) (Props (periodicFreq "5e+007") (periodicJitter "0") (periodicPattern "1"))) ("local0" (scope local) (stimType periodic) (Props (periodicFreq "5e+007") (periodicJitter "0") (periodicPattern "1"))) ("local1" (scope local) (stimType periodic) (Props (periodicFreq "5e+007") (periodicJitter "0") (periodicPattern "1")))) (Notes) (Constraints ("DELAY_RULE" ("CRESCENT_CITY_177_20141217_Q U36.BK5" "CRESCENT_CITY_177_20141217_Q J73.195" "LENGTH" "0.0762" "LENGTH" "0.4064")) ("RELATIVE_PROPAGATION_DELAY" ("TMP" "CRESCENT_CITY_177_20141217_Q U36.BK5" "CRESCENT_CITY_177_20141217_Q J73.195" "LOCAL" "LENGTH" "0.000127" "DELAY" "") ("MG_PCIE_LOCAL" "CRESCENT_CITY_177_20141217_Q U36.BK5" "CRESCENT_CITY_177_20141217_Q C1900.1" "LOCAL" "LENGTH" "0.000127" "DELAY" "") ("MG_PCIE_LOCAL" "CRESCENT_CITY_177_20141217_Q J73.195" "CRESCENT_CITY_177_20141217_Q C1900.2" "LOCAL" "LENGTH" "0.000127" "DELAY" ""))) (MeasurementSets ("EMI" ("EMIStatus" status("on")) ("PeakEmission" status("on")) ("PeakFrequency" status("on")) ("PulseFreq" status("on")) ("RiseTime" status("on")) ("VoltageSwing" status("on"))) ("Reflection" ("BufferDelayFall" status("off")) ("BufferDelayRise" status("off")) ("EyeHeight" status("off")) ("EyeJitter" status("off")) ("EyeWidth" status("off")) ("FirstIncidentFall" status("off")) ("FirstIncidentRise" status("off")) ("Glitch" status("on")) ("GlitchFall" status("off")) ("GlitchRise" status("off")) ("Monotonic" status("on")) ("MonotonicFall" status("off")) ("MonotonicRise" status("off")) ("NoiseMargin" status("on")) ("NoiseMarginHigh" status("off")) ("NoiseMarginLow" status("off")) ("OvershootHigh" status("on")) ("OvershootLow" status("on")) ("PropDelay" status("on")) ("SettleDelay" status("on")) ("SettleDelayFall" status("off")) ("SettleDelayRise" status("off")) ("SwitchDelay" status("on")) ("SwitchDelayFall" status("off")) ("SwitchDelayRise" status("off"))) ("Crosstalk" ("Crosstalk" status("on"))) ("Custom")) (VectorSets) (Props (XnetName "P3E_CPU0_PE2_SS_C_TXP<15>") (allDrivers "active") (customSimType "Reflection") (ftsMode ("Typ")) (rcvrSelect "all") (tlineDelayMode "time") (userRevision "1.0")))) (Subckts) (CrossSections ("CRESCENT_CITY_177_20141217_Q" (Props (SXDesignName "CRESCENT_CITY_177_20141217_Q")) (Layers ("" (layerType "SURFACE") (material "AIR") (thickness "0 mil") (dielectricConstant "1.000000") (lossTangent "0") (etchFactor "0.000000") (elecCondVal "0 mho/cm") (thermCondVal "0 w/cm-degC")) ("" (layerType "DIELECTRIC") (material "CONFORMAL_COAT") (thickness "0.5 mil") (dielectricConstant "3.800000") (lossTangent "0.035") (etchFactor "0.000000") (elecCondVal "0 mho/cm") (thermCondVal "0.012 w/cm-degC")) ("TOP" (layerType "CONDUCTOR") (material "COPPER") (thickness "  2.100000 mil") (width "4.00 MIL") (dielectricConstant "4.500000") (lossTangent "0") (etchFactor "70.000000") (elecCondVal "595900.000000 mho/cm") (thermCondVal "0 w/cm-degC") (signalDieConstant "3.800000") (signalLossTangent "0.035")) ("" (layerType "DIELECTRIC") (material "FR-4") (thickness "  2.670000 mil") (dielectricConstant "4.000000") (lossTangent "0.035") (etchFactor "0.000000") (elecCondVal "0 mho/cm") (thermCondVal "0.012 w/cm-degC")) ("L2_GND1" (layerType "PLANE") (material "COPPER") (isShield t) (thickness "  1.250000 mil") (dielectricConstant "4.500000") (lossTangent "0.035") (etchFactor "90.000000") (elecCondVal "595900.000000 mho/cm") (thermCondVal "0.012 w/cm-degC")) ("" (layerType "DIELECTRIC") (material "FR-4") (thickness "  9.000000 mil") (dielectricConstant "4.100000") (lossTangent "0.035") (etchFactor "0.000000") (elecCondVal "0 mho/cm") (thermCondVal "0.012 w/cm-degC")) ("L3_SIG1" (layerType "CONDUCTOR") (material "COPPER") (thickness "  1.250000 mil") (width "4.00 MIL") (dielectricConstant "4.500000") (lossTangent "0.035") (etchFactor "90.000000") (elecCondVal "595900.000000 mho/cm") (thermCondVal "0.012 w/cm-degC") (signalDieConstant "4.100000") (signalLossTangent "0.035")) ("" (layerType "DIELECTRIC") (material "FR-4") (thickness "  3.000000 mil") (dielectricConstant "4.500000") (lossTangent "0.035") (etchFactor "0.000000") (elecCondVal "0 mho/cm") (thermCondVal "0 w/cm-degC")) ("L4_GND2" (layerType "PLANE") (material "COPPER") (isShield t) (thickness "  1.250000 mil") (dielectricConstant "4.500000") (lossTangent "0.035") (etchFactor "90.000000") (elecCondVal "595900.000000 mho/cm") (thermCondVal "0 w/cm-degC")) ("" (layerType "DIELECTRIC") (material "FR-4") (thickness "  9.000000 mil") (dielectricConstant "4.000000") (lossTangent "0.035") (etchFactor "0.000000") (elecCondVal "0 mho/cm") (thermCondVal "0.012 w/cm-degC")) ("L5_SIG2" (layerType "CONDUCTOR") (material "COPPER") (thickness "  1.250000 mil") (width "4.00 MIL") (dielectricConstant "4.500000") (lossTangent "0.035") (etchFactor "90.000000") (elecCondVal "595900.000000 mho/cm") (thermCondVal "0.012 w/cm-degC") (signalDieConstant "4.000000") (signalLossTangent "0.035")) ("" (layerType "DIELECTRIC") (material "FR-4") (thickness "  3.000000 mil") (dielectricConstant "4.500000") (lossTangent "0.035") (etchFactor "0.000000") (elecCondVal "0 mho/cm") (thermCondVal "0 w/cm-degC")) ("L6_GND3" (layerType "PLANE") (material "COPPER") (isShield t) (thickness "  1.250000 mil") (dielectricConstant "4.500000") (lossTangent "0.035") (etchFactor "90.000000") (elecCondVal "595900.000000 mho/cm") (thermCondVal "0 w/cm-degC")) ("" (layerType "DIELECTRIC") (material "FR-4") (thickness "  4.500000 mil") (dielectricConstant "4.100000") (lossTangent "0.035") (etchFactor "0.000000") (elecCondVal "0 mho/cm") (thermCondVal "0.012 w/cm-degC")) ("L7_PWR1-SIG" (layerType "PLANE") (material "COPPER") (isShield t) (thickness "  2.400000 mil") (dielectricConstant "4.500000") (lossTangent "0.035") (etchFactor "90.000000") (elecCondVal "595900.000000 mho/cm") (thermCondVal "0.012 w/cm-degC")) ("" (layerType "DIELECTRIC") (material "FR-4") (thickness "  4.600000 mil") (dielectricConstant "4.000000") (lossTangent "0.035") (etchFactor "0.000000") (elecCondVal "0 mho/cm") (thermCondVal "0.012 w/cm-degC")) ("L8_PWR2-SIG" (layerType "PLANE") (material "COPPER") (isShield t) (thickness "  2.400000 mil") (dielectricConstant "4.500000") (lossTangent "0.035") (etchFactor "90.000000") (elecCondVal "595900.000000 mho/cm") (thermCondVal "0.012 w/cm-degC")) ("" (layerType "DIELECTRIC") (material "FR-4") (thickness "  4.500000 mil") (dielectricConstant "4.500000") (lossTangent "0.035") (etchFactor "0.000000") (elecCondVal "0 mho/cm") (thermCondVal "0 w/cm-degC")) ("L9_GND4" (layerType "PLANE") (material "COPPER") (isShield t) (thickness "  1.250000 mil") (dielectricConstant "4.500000") (lossTangent "0.035") (etchFactor "90.000000") (elecCondVal "595900.000000 mho/cm") (thermCondVal "0 w/cm-degC")) ("" (layerType "DIELECTRIC") (material "FR-4") (thickness "  3.000000 mil") (dielectricConstant "4.100000") (lossTangent "0.035") (etchFactor "0.000000") (elecCondVal "0 mho/cm") (thermCondVal "0.012 w/cm-degC")) ("L10_SIG3" (layerType "CONDUCTOR") (material "COPPER") (thickness "  1.250000 mil") (width "4.00 MIL") (dielectricConstant "4.500000") (lossTangent "0.035") (etchFactor "90.000000") (elecCondVal "595900.000000 mho/cm") (thermCondVal "0.012 w/cm-degC") (signalDieConstant "4.100000") (signalLossTangent "0.035")) ("" (layerType "DIELECTRIC") (material "FR-4") (thickness "  9.000000 mil") (dielectricConstant "4.500000") (lossTangent "0.035") (etchFactor "0.000000") (elecCondVal "0 mho/cm") (thermCondVal "0 w/cm-degC")) ("L11_GND5" (layerType "PLANE") (material "COPPER") (isShield t) (thickness "  1.250000 mil") (dielectricConstant "4.500000") (lossTangent "0.035") (etchFactor "90.000000") (elecCondVal "595900.000000 mho/cm") (thermCondVal "0 w/cm-degC")) ("" (layerType "DIELECTRIC") (material "FR-4") (thickness "  3.000000 mil") (dielectricConstant "4.500000") (lossTangent "0.035") (etchFactor "0.000000") (elecCondVal "0 mho/cm") (thermCondVal "0.012 w/cm-degC")) ("L12_SIG4" (layerType "CONDUCTOR") (material "COPPER") (thickness "  1.250000 mil") (width "4.00 MIL") (dielectricConstant "4.500000") (lossTangent "0.035") (etchFactor "90.000000") (elecCondVal "595900.000000 mho/cm") (thermCondVal "0.012 w/cm-degC") (signalDieConstant "4.500000") (signalLossTangent "0.035")) ("" (layerType "DIELECTRIC") (material "FR-4") (thickness "  9.000000 mil") (dielectricConstant "4.500000") (lossTangent "0.035") (etchFactor "0.000000") (elecCondVal "0 mho/cm") (thermCondVal "0 w/cm-degC")) ("L13_GND6" (layerType "PLANE") (material "COPPER") (isShield t) (thickness "  1.250000 mil") (dielectricConstant "4.500000") (lossTangent "0.035") (etchFactor "90.000000") (elecCondVal "595900.000000 mho/cm") (thermCondVal "0.012 w/cm-degC")) ("" (layerType "DIELECTRIC") (material "FR-4") (thickness "  2.670000 mil") (dielectricConstant "4.500000") (lossTangent "0.035") (etchFactor "0.000000") (elecCondVal "0 mho/cm") (thermCondVal "0.012 w/cm-degC")) ("BOTTOM" (layerType "CONDUCTOR") (material "COPPER") (thickness "  2.100000 mil") (width "4.00 MIL") (dielectricConstant "4.500000") (lossTangent "0") (etchFactor "70.000000") (elecCondVal "595900.000000 mho/cm") (thermCondVal "0 w/cm-degC") (signalDieConstant "3.800000") (signalLossTangent "0.035")) ("" (layerType "DIELECTRIC") (material "CONFORMAL_COAT") (thickness "0.5 mil") (dielectricConstant "3.800000") (lossTangent "0.035") (etchFactor "0.000000") (elecCondVal "0 mho/cm") (thermCondVal "0.012 w/cm-degC")) ("" (layerType "SURFACE") (material "AIR") (thickness "0 mil") (dielectricConstant "1.000000") (lossTangent "0") (etchFactor "0.000000") (elecCondVal "0 mho/cm") (thermCondVal "0 w/cm-degC"))))) (Props (DesUnits "mils 2") (LayerStack ("DIELECTRIC" "DIELECTRIC" "BOTTOM" "DIELECTRIC" "L13_GND6" "DIELECTRIC" "L12_SIG4" "DIELECTRIC" "L11_GND5" "DIELECTRIC" "L10_SIG3" "DIELECTRIC" "L9_GND4" "DIELECTRIC" "L8_PWR2-SIG" "DIELECTRIC" "L7_PWR1-SIG" "DIELECTRIC" "L6_GND3" "DIELECTRIC" "L5_SIG2" "DIELECTRIC" "L4_GND2" "DIELECTRIC" "L3_SIG1" "DIELECTRIC" "L2_GND1" "DIELECTRIC" "TOP" "DIELECTRIC" "DIELECTRIC")) (Revision "16.600")) (Params (Source ((voltage "5 V"))) (Inductor ((inductance "5 nH") (orientation "0"))) (IbisIO_OpenPullDown ((temperature "27") (bufferModel "CDSDefaultIO_2p5v") (stimuli nil) (offsets nil) (state "tristate") (cycle "1") (termMap nil) (setup "2.0e-09") (hold "1.0e-09") (rise nil) (fall nil) (macroType nil) (voltage nil) (spice nil) (LEFDEFPinName nil) (LEFDEFPinType nil) (mappingTag nil))) (DiffInputPkg ((temperature "27") (bufferModelNonInverting "CDSDefaultInput_2p5v") (bufferModelInverting "CDSDefaultInput_2p5v") (threshInputHighMin "1.7 V") (threshInputHighTyp "1.7  V") (threshInputHighMax "1.7  V") (threshInputLowMin "0.7  V") (threshInputLowTyp "0.7  V") (threshInputLowMax "0.7  V") (mappingTagNonInverting nil) (mappingTagInverting nil) (cycle "1"))) (IbisIO ((temperature "27") (bufferModel "CDSDefaultIO_2p5v") (stimuli nil) (offsets nil) (state "tristate") (cycle "1") (termMap nil) (setup "2.0e-09") (hold "1.0e-09") (rise nil) (fall nil) (macroType nil) (voltage nil) (spice nil) (LEFDEFPinName nil) (LEFDEFPinType nil) (mappingTag nil))) (Trace ((d1Thickness "10 mil") (d1Constant "4.5") (d1LossTangent "0.035") (d2Thickness "10 mil") (d2Constant "4.5") (d2LossTangent "0.035") (d3Thickness "0.0") (d3Constant "1.0") (d3LossTangent "0") length("1000 mil") (spacing "5 mil") (spacing2 "5 mil") (spacing3 "5 mil") (spacing4 "5 mil") (spacing5 "5 mil") (traceConductivity "595900 mho/cm") (traceGeometry "microstrip") (traceLayerName "") (traceThickness "0.72 mil") (traceType "single") (traceWidth "5.0 mil") (traceWidth2 "5.0 mil") (traceWidth3 "5.0 mil") (traceWidth4 "5.0 mil") (traceWidth5 "5.0 mil") (traceWidth6 "5.0 mil") (offset "0 mil") (traceCount "1") (impedance nil))) (IbisIOMacro ((temperature "27") (bufferModel "CDSDefaultIO_2p5v") (stimuli nil) (offsets nil) (state "tristate") (cycle "1") (termMap nil) (setup "2.0e-09") (hold "1.0e-09") (rise nil) (fall nil) (macroType nil) (voltage nil) (spice nil) (LEFDEFPinName nil) (LEFDEFPinType nil) (mappingTag nil))) (Cable (length("1 m"))) (Capacitor ((capacitance "10 pF") (orientation "0"))) (Via ((model "Unknown") (viaOutputFormat "Unknown") (viaPadstack nil) (viaTopLayer nil) (viaBottomLayer nil) (viaIsPower nil) (viaIsGround nil))) (Resistor ((resistance "50 ohm") (orientation "0"))) (IbisOutputPkg ((temperature "27") (bufferModel "CDSDefaultOutput_2p5v") (stimuli nil) (offsets nil) (state "tristate") (cycle "1") (termMap nil) (setup "2.0e-09") (hold "1.0e-09") (rise nil) (fall nil) (macroType nil) (voltage nil) (spice nil) (LEFDEFPinName nil) (LEFDEFPinType nil) (mappingTag nil))) (IbisOutput_OpenPullUp ((temperature "27") (bufferModel "CDSDefaultOutput_2p5v") (stimuli nil) (offsets nil) (state "tristate") (cycle "1") (termMap nil) (setup "2.0e-09") (hold "1.0e-09") (rise nil) (fall nil) (macroType nil) (voltage nil) (spice nil) (LEFDEFPinName nil) (LEFDEFPinType nil) (mappingTag nil))) (IbisIOPkg ((temperature "27") (bufferModel "CDSDefaultIO_2p5v") (stimuli nil) (offsets nil) (state "tristate") (cycle "1") (termMap nil) (setup "2.0e-09") (hold "1.0e-09") (rise nil) (fall nil) (macroType nil) (voltage nil) (spice nil) (LEFDEFPinName nil) (LEFDEFPinType nil) (mappingTag nil))) (IbisIO_OpenPullUp ((temperature "27") (bufferModel "CDSDefaultIO_2p5v") (stimuli nil) (offsets nil) (state "tristate") (cycle "1") (termMap nil) (setup "2.0e-09") (hold "1.0e-09") (rise nil) (fall nil) (macroType nil) (voltage nil) (spice nil) (LEFDEFPinName nil) (LEFDEFPinType nil) (mappingTag nil))) (ESpiceDevice nil) (IbisInputPkg ((temperature "27") (bufferModel "CDSDefaultInput_2p5v") (cycle "1") (LEFDEFPinName nil) (LEFDEFPinType nil) (mappingTag nil))) (IbisInput ((temperature "27") (bufferModel "CDSDefaultInput_2p5v") (cycle "1") (LEFDEFPinName nil) (LEFDEFPinType nil) (mappingTag nil))) (TLine ((diffImpedance "100ohm") (diffVelocity "1.4142e+08M/s") (impedance "60ohm") length("2800 mil") (propDelay "0.5 ns") (velocity "5600 mil/ns") (traceCount "1") (traceGeometry "Microstrip") (impedanceMin nil) (impedanceMax nil) (lengthMin nil) (lengthMax nil) (propDelayMin nil) (propDelayMax nil) (impedanceSweepCount nil) (propDelaySweepCount nil) (velocitySweepCount nil) (lengthSweepCount nil) (matchSetName nil))) (periodic ((periodicFreq "100e6") (periodicPattern "10") (periodicJitter "0"))) (clocked ((clockRise "1e-09") (clockFall "1e-09") (clockFreq "100e6") (clockInitState "0") (clockDutyCycle "0.5") (clockJitter "0"))) (RLGC (length("1000 mil"))) (DiffInput ((temperature "27") (bufferModelNonInverting "CDSDefaultInput_2p5v") (bufferModelInverting "CDSDefaultInput_2p5v") (threshInputHighMin "1.7 V") (threshInputHighTyp "1.7  V") (threshInputHighMax "1.7  V") (threshInputLowMin "0.7  V") (threshInputLowTyp "0.7  V") (threshInputLowMax "0.7  V") (mappingTagNonInverting nil) (mappingTagInverting nil) (cycle "1"))) (async ((asyncTimePoints "") (asyncInitState "1"))) (idlCircuit ((allDrivers "active") (ftsMode '("Typ")) (rcvrSelect "all") (simMode "Reflection") (tlineDelayMode "time") (userRevision "1.0") (autoSolve "On"))) (DiffIO ((temperature "27") (bufferModelNonInverting "CDSDefaultIO_2p5v") (bufferModelInverting "CDSDefaultIO_2p5v") (stimuli nil) (offsets nil) (state "tristate") (cycle "1") (termMap nil) (setup "0.9e-09") (hold "0.4e-09") (rise nil) (fall nil) (threshInputHighMin "1.7 V") (threshInputHighTyp "1.7  V") (threshInputHighMax "1.7  V") (threshInputLowMin "0.7  V") (threshInputLowTyp "0.7  V") (threshInputLowMax "0.7 ") (threshOutputHighMin "2.365  V") (threshOutputHighTyp "2.5  V") (threshOutputHighMax "2.625  V") (threshOutputLowMin "1.275  V") (threshOutputLowTyp "1.7  V") (threshOutputLowMax "1.985  V") (mappingTagNonInverting nil) (mappingTagInverting nil) (spice nil))) (DiffOutput ((temperature "27") (bufferModelNonInverting "CDSDefaultOutput_2p5v") (bufferModelInverting "CDSDefaultOutput_2p5v") (stimuli nil) (offsets nil) (state "tristate") (cycle "1") (termMap nil) (setup "0.9e-09") (hold "0.4e-09") (rise nil) (fall nil) (threshOutputHighMin "2.375  V") (threshOutputHighTyp "2.5  V") (threshOutputHighMax "2.625  V") (threshOutputLowMin "1.275  V") (threshOutputLowTyp "1.7  V") (threshOutputLowMax "1.985  V") (mappingTagNonInverting nil) (mappingTagInverting nil) (spice nil))) (DiffIOPkg ((temperature "27") (bufferModelNonInverting "CDSDefaultIO_2p5v") (bufferModelInverting "CDSDefaultIO_2p5v") (stimuli nil) (offsets nil) (state "tristate") (cycle "1") (termMap nil) (setup "0.9e-09") (hold "0.4e-09") (rise nil) (fall nil) (threshInputHighMin "1.7 V") (threshInputHighTyp "1.7  V") (threshInputHighMax "1.7  V") (threshInputLowMin "0.7  V") (threshInputLowTyp "0.7  V") (threshInputLowMax "0.7 ") (threshOutputHighMin "2.365  V") (threshOutputHighTyp "2.5  V") (threshOutputHighMax "2.625  V") (threshOutputLowMin "1.275  V") (threshOutputLowTyp "1.7  V") (threshOutputLowMax "1.985  V") (mappingTagNonInverting nil) (mappingTagInverting nil) (spice nil))) (sync ((syncFreq "100e6") (syncInitState "1") (syncPattern "10") (syncEdgeSwitch "rise"))) (SeriesTerm ((resistance "22 ohm") (maxDelay "0.1 ns"))) (DiffOutputPkg ((temperature "27") (bufferModelNonInverting "CDSDefaultOutput_2p5v") (bufferModelInverting "CDSDefaultOutput_2p5v") (stimuli nil) (offsets nil) (state "tristate") (cycle "1") (termMap nil) (setup "0.9e-09") (hold "0.4e-09") (rise nil) (fall nil) (threshOutputHighMin "2.375  V") (threshOutputHighTyp "2.5  V") (threshOutputHighMax "2.625  V") (threshOutputLowMin "1.275  V") (threshOutputLowTyp "1.7  V") (threshOutputLowMax "1.985  V") (mappingTagNonInverting nil) (mappingTagInverting nil) (spice nil))) (IbisOutput ((temperature "27") (bufferModel "CDSDefaultOutput_2p5v") (stimuli nil) (offsets nil) (state "tristate") (cycle "1") (termMap nil) (setup "2.0e-09") (hold "1.0e-09") (rise nil) (fall nil) (macroType nil) (voltage nil) (spice nil) (LEFDEFPinName nil) (LEFDEFPinType nil) (mappingTag nil))) (CPW ((d1Thickness "10 mil") (d1Constant "4.5") (d1LossTangent "0.035") (d2Thickness "0.72 mil") (d2Constant "1") (d2LossTangent "0") (d3Thickness "0.0") (d3Constant "1") (d3LossTangent "0") length("1000 mil") (spacing "5 mil") (spacing2 "5 mil") (spacing3 "5 mil") (spacing4 "5 mil") (spacing5 "5 mil") (traceConductivity "595900 mho/cm") (traceGeometry "cpwms") (traceLayerName "") (traceThickness "0.72 mil") (traceType "single") (traceWidth "5.0 mil") (traceWidth2 "5.0 mil") (traceWidth3 "5.0 mil") (traceWidth4 "5.0 mil") (traceWidth5 "5.0 mil") (traceWidth6 "5.0 mil") (offset "0 mil") (traceCount "1") (impedance nil))) (CPWMS ((d1Thickness "10 mil") (d1Constant "4.5") (d1LossTangent "0.035") (d2Thickness "0.72 mil") (d2Constant "4.5") (d2LossTangent "0.035") (d3Thickness "0.0") (d3Constant "1") (d3LossTangent "0") length("1000 mil") (spacing "5 mil") (spacing2 "5 mil") (spacing3 "5 mil") (spacing4 "5 mil") (spacing5 "5 mil") (traceConductivity "595900 mho/cm") (traceGeometry "cpwms") (traceLayerName "") (traceThickness "0.72 mil") (traceType "single") (traceWidth "5.0 mil") (traceWidth2 "5.0 mil") (traceWidth3 "5.0 mil") (traceWidth4 "5.0 mil") (traceWidth5 "5.0 mil") (traceWidth6 "5.0 mil") (offset "0 mil") (traceCount "1") (impedance nil))) (CurrentProbe nil) (CPWSL ((d1Thickness "10 mil") (d1Constant "4.5") (d1LossTangent "0.035") (d2Thickness "0.72 mil") (d2Constant "4.5") (d2LossTangent "0.035") (d3Thickness "10 mil") (d3Constant "4.5") (d3LossTangent "0.035") length("1000 mil") (spacing "5 mil") (spacing2 "5 mil") (spacing3 "5 mil") (spacing4 "5 mil") (spacing5 "5 mil") (traceConductivity "595900 mho/cm") (traceGeometry "cpwms") (traceLayerName "") (traceThickness "0.72 mil") (traceType "single") (traceWidth "5.0 mil") (traceWidth2 "5.0 mil") (traceWidth3 "5.0 mil") (traceWidth4 "5.0 mil") (traceWidth5 "5.0 mil") (traceWidth6 "5.0 mil") (offset "0 mil") (traceCount "1") (impedance nil))) (ShuntTerm ((resistance "50 ohm") (voltage "5 V") (maxDelay "0.1 ns"))) (TheveninTerm ((resistanceUp "180 ohm") (resistanceDown "270 ohm") (voltageUp "5 V") (voltageDown "0 V") (maxDelay "0.1 ns"))) (Connector nil) (RCTerm ((resistance "50 ohm") (capacitance "20 pF") (voltage "5 V") (maxDelay "0.1 ns"))) (LowClampTerm ((cutoffVoltage "0.7 V") (voltage "0 V") (maxDelay "0.1 ns"))) (HiClampTerm ((cutoffVoltage "0.7 V") (voltage "5 V") (maxDelay "0.1 ns"))) (DualClampTerm ((cutoffVoltageUp "0.7 V") (cutoffVoltageDown "0.7 V") (voltageUp "5 V") (voltageDown "0 V") (maxDelay "0.1 ns"))) (Diode ((cutoffVoltage "0.7 V")))))
				)
				( objectStatus "PCIE_SLOT_C" )
			)
			( electricalCSet "@crescent_city_bb_fab1_lib.crescent_city_bb_fab1(sch_1):\PCIE_SLOT_C_A\"
				( groupRef "PCIE_SLOT_C_A:MG_PCIE_L0" )
				( groupRef "PCIE_SLOT_C_A:MG_PCIE_L1" )
				( pinPairRef "PCIE_SLOT_C_A:J8G1.195:C7G5.2" )
				( pinPairRef "PCIE_SLOT_C_A:U5D1.BK5:C7G5.1" )
				( pinPairRef "PCIE_SLOT_C_A:U5D1.BK5:J8G1.195" )
				( attribute "DIFFP_GATHER_CONTROL" "IGNORE"
					( Origin gBackEnd )
				)
				( attribute "DIFFP_UNCOUPLED_LENGTH" "1000.00"
					( Origin gBackEnd )
				)
				( attribute "DIFFP_COUPLED_PLUS" "0.10"
					( Origin gBackEnd )
				)
				( attribute "DIFFP_COUPLED_MINUS" "0.10"
					( Origin gBackEnd )
				)
				( attribute "DIFFP_PHASE_TOL" "5 mil"
					( Units "uPhaseTol" "ns" 1.000000)
					( Origin gBackEnd )
				)
				( attribute "TOPOLOGY_TEMPLATE_REVISION" "1.0"
					( Origin gBackEnd )
				)
				( topologyData 23405
(SKIDL (Circuits ("MAIN" (Parts ("CRESCENT_CITY_177_20141217_Q.@@U36.BK5" IbisOutputPkg (xy (5498 4235)) (refDes "U5D1") (model "Unknown") (Props (_SXDesignName "CRESCENT_CITY_177_20141217_Q") (brdx "11961.29 MIL") (brdy "2980.96 MIL") (bufferModel "CDSDefaultOutput_2p5v") (cycle "1") (hold "1.0e-09") (mappingTag "") (offsets ("4" "0")) (setup "2.0e-09") (state "tristate") (stimuli ("4" "local0")) (temperature "27") (termMap ("4" "Data"))) (Terms ("CRESCENT_CITY_177_20141217_Q.X1196129Y298096L2LRATS" "BK5"))) ("CRESCENT_CITY_177_20141217_Q.@@J73.195" IbisIOPkg (xy (5545 4240)) (refDes "J8G1") (model "Unknown") (Props (_SXDesignName "CRESCENT_CITY_177_20141217_Q") (brdx "14315.37 MIL") (brdy "306.76 MIL") (bufferModel "CDSDefaultIO_2p5v") (cycle "1") (hold "1.0e-09") (mappingTag "") (offsets ("4" "0") ("5" "0")) (setup "2.0e-09") (state "tristate") (stimuli ("5" "local2") ("4" "local1")) (temperature "27") (termMap ("4" "Data") ("5" "Enable"))) (Terms ("CRESCENT_CITY_177_20141217_Q.X1431537Y30676L2LRATS" "195"))) ("CRESCENT_CITY_177_20141217_Q.T@@RATS@@C1900.1@@U36.BK5" TLine (xy (5506 4235)) (mirror x) (refDes "TL1") (Props (_SXDesignName "CRESCENT_CITY_177_20141217_Q") (impedance "52.449 ohm") length("4853.31 MIL") (propDelay "0.87168 ns") (traceCount "1") (traceGeometry "Microstrip") (velocity "5567.76 mil/ns")) (Terms ("CRESCENT_CITY_177_20141217_Q.X1431362Y48000L2LRATS" "1") ("CRESCENT_CITY_177_20141217_Q.X1196129Y298096L2LRATS" "2"))) ("CRESCENT_CITY_177_20141217_Q.@@C1900.1.2" Capacitor (xy (5521 4235)) (refDes "C7G5") (value "220000 pF") (Props (_SXDesignName "CRESCENT_CITY_177_20141217_Q")) (Terms ("CRESCENT_CITY_177_20141217_Q.X1431362Y48000L2LRATS" "1") ("CRESCENT_CITY_177_20141217_Q.X1431362Y44500L2LRATS" "2"))) ("CRESCENT_CITY_177_20141217_Q.T@@RATS@@J73.195@@C1900.2" TLine (xy (5530 4235)) (mirror x) (refDes "TL2") (Props (_SXDesignName "CRESCENT_CITY_177_20141217_Q") (impedance "47.169 ohm") length("139.99 MIL") (propDelay "0.02514 ns") (traceCount "1") (traceGeometry "Microstrip") (velocity "5568.43 mil/ns")) (Terms ("CRESCENT_CITY_177_20141217_Q.X1431537Y30676L2LRATS" "1") ("CRESCENT_CITY_177_20141217_Q.X1431362Y44500L2LRATS" "2")))) (Nodes ("CRESCENT_CITY_177_20141217_Q.X1196129Y298096L2LRATS" (terms "CRESCENT_CITY_177_20141217_Q.T@@RATS@@C1900.1@@U36.BK5.2" "CRESCENT_CITY_177_20141217_Q.@@U36.BK5.1")) ("CRESCENT_CITY_177_20141217_Q.X1431537Y30676L2LRATS" (terms "CRESCENT_CITY_177_20141217_Q.T@@RATS@@J73.195@@C1900.2.1" "CRESCENT_CITY_177_20141217_Q.@@J73.195.1")) ("CRESCENT_CITY_177_20141217_Q.X1431362Y48000L2LRATS" (terms "CRESCENT_CITY_177_20141217_Q.@@C1900.1.2.1" "CRESCENT_CITY_177_20141217_Q.T@@RATS@@C1900.1@@U36.BK5.1")) ("CRESCENT_CITY_177_20141217_Q.X1431362Y44500L2LRATS" (terms "CRESCENT_CITY_177_20141217_Q.T@@RATS@@J73.195@@C1900.2.2" "CRESCENT_CITY_177_20141217_Q.@@C1900.1.2.2"))) (Ports) (Stimuli ("local2" (scope local) (stimType periodic) (Props (periodicFreq "5e+007") (periodicJitter "0") (periodicPattern "1"))) ("local0" (scope local) (stimType periodic) (Props (periodicFreq "5e+007") (periodicJitter "0") (periodicPattern "1"))) ("local1" (scope local) (stimType periodic) (Props (periodicFreq "5e+007") (periodicJitter "0") (periodicPattern "1")))) (Notes) (Constraints ("DELAY_RULE" ("CRESCENT_CITY_177_20141217_Q U36.BK5" "CRESCENT_CITY_177_20141217_Q J73.195" "LENGTH" "0.0762" "LENGTH" "0.4064")) ("RELATIVE_PROPAGATION_DELAY" ("MG_PCIE_L0" "CRESCENT_CITY_177_20141217_Q J73.195" "CRESCENT_CITY_177_20141217_Q C1900.2" "LOCAL" "LENGTH" "0.000127" "LENGTH" "") ("MG_PCIE_L1" "CRESCENT_CITY_177_20141217_Q U36.BK5" "CRESCENT_CITY_177_20141217_Q C1900.1" "LOCAL" "LENGTH" "0.000127" "LENGTH" "") ("MG" "CRESCENT_CITY_177_20141217_Q U36.BK5" "CRESCENT_CITY_177_20141217_Q J73.195" "NET GROUP" "LENGTH" "0.0127" "LENGTH" ""))) (MeasurementSets ("EMI" ("EMIStatus" status("on")) ("PeakEmission" status("on")) ("PeakFrequency" status("on")) ("PulseFreq" status("on")) ("RiseTime" status("on")) ("VoltageSwing" status("on"))) ("Reflection" ("BufferDelayFall" status("off")) ("BufferDelayRise" status("off")) ("EyeHeight" status("off")) ("EyeJitter" status("off")) ("EyeWidth" status("off")) ("FirstIncidentFall" status("off")) ("FirstIncidentRise" status("off")) ("Glitch" status("on")) ("GlitchFall" status("off")) ("GlitchRise" status("off")) ("Monotonic" status("on")) ("MonotonicFall" status("off")) ("MonotonicRise" status("off")) ("NoiseMargin" status("on")) ("NoiseMarginHigh" status("off")) ("NoiseMarginLow" status("off")) ("OvershootHigh" status("on")) ("OvershootLow" status("on")) ("PropDelay" status("on")) ("SettleDelay" status("on")) ("SettleDelayFall" status("off")) ("SettleDelayRise" status("off")) ("SwitchDelay" status("on")) ("SwitchDelayFall" status("off")) ("SwitchDelayRise" status("off"))) ("Crosstalk" ("Crosstalk" status("on"))) ("Custom")) (VectorSets) (Props (XnetName "P3E_CPU0_PE2_SS_C_TXP<15>") (allDrivers "active") (customSimType "Reflection") (ftsMode ("Typ")) (rcvrSelect "all") (tlineDelayMode "time") (userRevision "1.0")))) (Subckts) (CrossSections ("CRESCENT_CITY_177_20141217_Q" (Props (SXDesignName "CRESCENT_CITY_177_20141217_Q")) (Layers ("" (layerType "SURFACE") (material "AIR") (thickness "0 mil") (dielectricConstant "1.000000") (lossTangent "0") (etchFactor "0.000000") (elecCondVal "0 mho/cm") (thermCondVal "0 w/cm-degC")) ("" (layerType "DIELECTRIC") (material "CONFORMAL_COAT") (thickness "0.5 mil") (dielectricConstant "3.800000") (lossTangent "0.035") (etchFactor "0.000000") (elecCondVal "0 mho/cm") (thermCondVal "0.012 w/cm-degC")) ("TOP" (layerType "CONDUCTOR") (material "COPPER") (thickness "  2.100000 mil") (width "4.00 MIL") (dielectricConstant "4.500000") (lossTangent "0") (etchFactor "70.000000") (elecCondVal "595900.000000 mho/cm") (thermCondVal "0 w/cm-degC") (signalDieConstant "3.800000") (signalLossTangent "0.035")) ("" (layerType "DIELECTRIC") (material "FR-4") (thickness "  2.670000 mil") (dielectricConstant "4.000000") (lossTangent "0.035") (etchFactor "0.000000") (elecCondVal "0 mho/cm") (thermCondVal "0.012 w/cm-degC")) ("L2_GND1" (layerType "PLANE") (material "COPPER") (isShield t) (thickness "  1.250000 mil") (dielectricConstant "4.500000") (lossTangent "0.035") (etchFactor "90.000000") (elecCondVal "595900.000000 mho/cm") (thermCondVal "0.012 w/cm-degC")) ("" (layerType "DIELECTRIC") (material "FR-4") (thickness "  9.000000 mil") (dielectricConstant "4.100000") (lossTangent "0.035") (etchFactor "0.000000") (elecCondVal "0 mho/cm") (thermCondVal "0.012 w/cm-degC")) ("L3_SIG1" (layerType "CONDUCTOR") (material "COPPER") (thickness "  1.250000 mil") (width "4.00 MIL") (dielectricConstant "4.500000") (lossTangent "0.035") (etchFactor "90.000000") (elecCondVal "595900.000000 mho/cm") (thermCondVal "0.012 w/cm-degC") (signalDieConstant "4.100000") (signalLossTangent "0.035")) ("" (layerType "DIELECTRIC") (material "FR-4") (thickness "  3.000000 mil") (dielectricConstant "4.500000") (lossTangent "0.035") (etchFactor "0.000000") (elecCondVal "0 mho/cm") (thermCondVal "0 w/cm-degC")) ("L4_GND2" (layerType "PLANE") (material "COPPER") (isShield t) (thickness "  1.250000 mil") (dielectricConstant "4.500000") (lossTangent "0.035") (etchFactor "90.000000") (elecCondVal "595900.000000 mho/cm") (thermCondVal "0 w/cm-degC")) ("" (layerType "DIELECTRIC") (material "FR-4") (thickness "  9.000000 mil") (dielectricConstant "4.000000") (lossTangent "0.035") (etchFactor "0.000000") (elecCondVal "0 mho/cm") (thermCondVal "0.012 w/cm-degC")) ("L5_SIG2" (layerType "CONDUCTOR") (material "COPPER") (thickness "  1.250000 mil") (width "4.00 MIL") (dielectricConstant "4.500000") (lossTangent "0.035") (etchFactor "90.000000") (elecCondVal "595900.000000 mho/cm") (thermCondVal "0.012 w/cm-degC") (signalDieConstant "4.000000") (signalLossTangent "0.035")) ("" (layerType "DIELECTRIC") (material "FR-4") (thickness "  3.000000 mil") (dielectricConstant "4.500000") (lossTangent "0.035") (etchFactor "0.000000") (elecCondVal "0 mho/cm") (thermCondVal "0 w/cm-degC")) ("L6_GND3" (layerType "PLANE") (material "COPPER") (isShield t) (thickness "  1.250000 mil") (dielectricConstant "4.500000") (lossTangent "0.035") (etchFactor "90.000000") (elecCondVal "595900.000000 mho/cm") (thermCondVal "0 w/cm-degC")) ("" (layerType "DIELECTRIC") (material "FR-4") (thickness "  4.500000 mil") (dielectricConstant "4.100000") (lossTangent "0.035") (etchFactor "0.000000") (elecCondVal "0 mho/cm") (thermCondVal "0.012 w/cm-degC")) ("L7_PWR1-SIG" (layerType "PLANE") (material "COPPER") (isShield t) (thickness "  2.400000 mil") (dielectricConstant "4.500000") (lossTangent "0.035") (etchFactor "90.000000") (elecCondVal "595900.000000 mho/cm") (thermCondVal "0.012 w/cm-degC")) ("" (layerType "DIELECTRIC") (material "FR-4") (thickness "  4.600000 mil") (dielectricConstant "4.000000") (lossTangent "0.035") (etchFactor "0.000000") (elecCondVal "0 mho/cm") (thermCondVal "0.012 w/cm-degC")) ("L8_PWR2-SIG" (layerType "PLANE") (material "COPPER") (isShield t) (thickness "  2.400000 mil") (dielectricConstant "4.500000") (lossTangent "0.035") (etchFactor "90.000000") (elecCondVal "595900.000000 mho/cm") (thermCondVal "0.012 w/cm-degC")) ("" (layerType "DIELECTRIC") (material "FR-4") (thickness "  4.500000 mil") (dielectricConstant "4.500000") (lossTangent "0.035") (etchFactor "0.000000") (elecCondVal "0 mho/cm") (thermCondVal "0 w/cm-degC")) ("L9_GND4" (layerType "PLANE") (material "COPPER") (isShield t) (thickness "  1.250000 mil") (dielectricConstant "4.500000") (lossTangent "0.035") (etchFactor "90.000000") (elecCondVal "595900.000000 mho/cm") (thermCondVal "0 w/cm-degC")) ("" (layerType "DIELECTRIC") (material "FR-4") (thickness "  3.000000 mil") (dielectricConstant "4.100000") (lossTangent "0.035") (etchFactor "0.000000") (elecCondVal "0 mho/cm") (thermCondVal "0.012 w/cm-degC")) ("L10_SIG3" (layerType "CONDUCTOR") (material "COPPER") (thickness "  1.250000 mil") (width "4.00 MIL") (dielectricConstant "4.500000") (lossTangent "0.035") (etchFactor "90.000000") (elecCondVal "595900.000000 mho/cm") (thermCondVal "0.012 w/cm-degC") (signalDieConstant "4.100000") (signalLossTangent "0.035")) ("" (layerType "DIELECTRIC") (material "FR-4") (thickness "  9.000000 mil") (dielectricConstant "4.500000") (lossTangent "0.035") (etchFactor "0.000000") (elecCondVal "0 mho/cm") (thermCondVal "0 w/cm-degC")) ("L11_GND5" (layerType "PLANE") (material "COPPER") (isShield t) (thickness "  1.250000 mil") (dielectricConstant "4.500000") (lossTangent "0.035") (etchFactor "90.000000") (elecCondVal "595900.000000 mho/cm") (thermCondVal "0 w/cm-degC")) ("" (layerType "DIELECTRIC") (material "FR-4") (thickness "  3.000000 mil") (dielectricConstant "4.500000") (lossTangent "0.035") (etchFactor "0.000000") (elecCondVal "0 mho/cm") (thermCondVal "0.012 w/cm-degC")) ("L12_SIG4" (layerType "CONDUCTOR") (material "COPPER") (thickness "  1.250000 mil") (width "4.00 MIL") (dielectricConstant "4.500000") (lossTangent "0.035") (etchFactor "90.000000") (elecCondVal "595900.000000 mho/cm") (thermCondVal "0.012 w/cm-degC") (signalDieConstant "4.500000") (signalLossTangent "0.035")) ("" (layerType "DIELECTRIC") (material "FR-4") (thickness "  9.000000 mil") (dielectricConstant "4.500000") (lossTangent "0.035") (etchFactor "0.000000") (elecCondVal "0 mho/cm") (thermCondVal "0 w/cm-degC")) ("L13_GND6" (layerType "PLANE") (material "COPPER") (isShield t) (thickness "  1.250000 mil") (dielectricConstant "4.500000") (lossTangent "0.035") (etchFactor "90.000000") (elecCondVal "595900.000000 mho/cm") (thermCondVal "0.012 w/cm-degC")) ("" (layerType "DIELECTRIC") (material "FR-4") (thickness "  2.670000 mil") (dielectricConstant "4.500000") (lossTangent "0.035") (etchFactor "0.000000") (elecCondVal "0 mho/cm") (thermCondVal "0.012 w/cm-degC")) ("BOTTOM" (layerType "CONDUCTOR") (material "COPPER") (thickness "  2.100000 mil") (width "4.00 MIL") (dielectricConstant "4.500000") (lossTangent "0") (etchFactor "70.000000") (elecCondVal "595900.000000 mho/cm") (thermCondVal "0 w/cm-degC") (signalDieConstant "3.800000") (signalLossTangent "0.035")) ("" (layerType "DIELECTRIC") (material "CONFORMAL_COAT") (thickness "0.5 mil") (dielectricConstant "3.800000") (lossTangent "0.035") (etchFactor "0.000000") (elecCondVal "0 mho/cm") (thermCondVal "0.012 w/cm-degC")) ("" (layerType "SURFACE") (material "AIR") (thickness "0 mil") (dielectricConstant "1.000000") (lossTangent "0") (etchFactor "0.000000") (elecCondVal "0 mho/cm") (thermCondVal "0 w/cm-degC"))))) (Props (DesUnits "mils 2") (LayerStack ("DIELECTRIC" "DIELECTRIC" "BOTTOM" "DIELECTRIC" "L13_GND6" "DIELECTRIC" "L12_SIG4" "DIELECTRIC" "L11_GND5" "DIELECTRIC" "L10_SIG3" "DIELECTRIC" "L9_GND4" "DIELECTRIC" "L8_PWR2-SIG" "DIELECTRIC" "L7_PWR1-SIG" "DIELECTRIC" "L6_GND3" "DIELECTRIC" "L5_SIG2" "DIELECTRIC" "L4_GND2" "DIELECTRIC" "L3_SIG1" "DIELECTRIC" "L2_GND1" "DIELECTRIC" "TOP" "DIELECTRIC" "DIELECTRIC")) (Revision "16.600")) (Params (Inductor ((inductance "5 nH") (orientation "0"))) (IbisIO_OpenPullDown ((temperature "27") (bufferModel "CDSDefaultIO_2p5v") (stimuli nil) (offsets nil) (state "tristate") (cycle "1") (termMap nil) (setup "2.0e-09") (hold "1.0e-09") (rise nil) (fall nil) (macroType nil) (voltage nil) (spice nil) (LEFDEFPinName nil) (LEFDEFPinType nil) (mappingTag nil))) (DiffInputPkg ((temperature "27") (bufferModelNonInverting "CDSDefaultInput_2p5v") (bufferModelInverting "CDSDefaultInput_2p5v") (threshInputHighMin "1.7 V") (threshInputHighTyp "1.7  V") (threshInputHighMax "1.7  V") (threshInputLowMin "0.7  V") (threshInputLowTyp "0.7  V") (threshInputLowMax "0.7  V") (mappingTagNonInverting nil) (mappingTagInverting nil) (cycle "1"))) (IbisIO ((temperature "27") (bufferModel "CDSDefaultIO_2p5v") (stimuli nil) (offsets nil) (state "tristate") (cycle "1") (termMap nil) (setup "2.0e-09") (hold "1.0e-09") (rise nil) (fall nil) (macroType nil) (voltage nil) (spice nil) (LEFDEFPinName nil) (LEFDEFPinType nil) (mappingTag nil))) (Trace ((d1Thickness "10 mil") (d1Constant "4.5") (d1LossTangent "0.035") (d2Thickness "10 mil") (d2Constant "4.5") (d2LossTangent "0.035") (d3Thickness "0.0") (d3Constant "1.0") (d3LossTangent "0") length("1000 mil") (spacing "5 mil") (spacing2 "5 mil") (spacing3 "5 mil") (spacing4 "5 mil") (spacing5 "5 mil") (traceConductivity "595900 mho/cm") (traceGeometry "microstrip") (traceLayerName "") (traceThickness "0.72 mil") (traceType "single") (traceWidth "5.0 mil") (traceWidth2 "5.0 mil") (traceWidth3 "5.0 mil") (traceWidth4 "5.0 mil") (traceWidth5 "5.0 mil") (traceWidth6 "5.0 mil") (offset "0 mil") (traceCount "1") (impedance nil))) (IbisIOMacro ((temperature "27") (bufferModel "CDSDefaultIO_2p5v") (stimuli nil) (offsets nil) (state "tristate") (cycle "1") (termMap nil) (setup "2.0e-09") (hold "1.0e-09") (rise nil) (fall nil) (macroType nil) (voltage nil) (spice nil) (LEFDEFPinName nil) (LEFDEFPinType nil) (mappingTag nil))) (Capacitor ((capacitance "10 pF") (orientation "0"))) (Via ((model "Unknown") (viaOutputFormat "Unknown") (viaPadstack nil) (viaTopLayer nil) (viaBottomLayer nil) (viaIsPower nil) (viaIsGround nil))) (TLine ((diffImpedance "100ohm") (diffVelocity "1.4142e+08M/s") (impedance "60ohm") length("2800 mil") (propDelay "0.5 ns") (velocity "5600 mil/ns") (traceCount "1") (traceGeometry "Microstrip") (impedanceMin nil) (impedanceMax nil) (lengthMin nil) (lengthMax nil) (propDelayMin nil) (propDelayMax nil) (impedanceSweepCount nil) (propDelaySweepCount nil) (velocitySweepCount nil) (lengthSweepCount nil) (matchSetName nil))) (Resistor ((resistance "50 ohm") (orientation "0"))) (IbisOutputPkg ((temperature "27") (bufferModel "CDSDefaultOutput_2p5v") (stimuli nil) (offsets nil) (state "tristate") (cycle "1") (termMap nil) (setup "2.0e-09") (hold "1.0e-09") (rise nil) (fall nil) (macroType nil) (voltage nil) (spice nil) (LEFDEFPinName nil) (LEFDEFPinType nil) (mappingTag nil))) (IbisOutput_OpenPullUp ((temperature "27") (bufferModel "CDSDefaultOutput_2p5v") (stimuli nil) (offsets nil) (state "tristate") (cycle "1") (termMap nil) (setup "2.0e-09") (hold "1.0e-09") (rise nil) (fall nil) (macroType nil) (voltage nil) (spice nil) (LEFDEFPinName nil) (LEFDEFPinType nil) (mappingTag nil))) (IbisIOPkg ((temperature "27") (bufferModel "CDSDefaultIO_2p5v") (stimuli nil) (offsets nil) (state "tristate") (cycle "1") (termMap nil) (setup "2.0e-09") (hold "1.0e-09") (rise nil) (fall nil) (macroType nil) (voltage nil) (spice nil) (LEFDEFPinName nil) (LEFDEFPinType nil) (mappingTag nil))) (IbisIO_OpenPullUp ((temperature "27") (bufferModel "CDSDefaultIO_2p5v") (stimuli nil) (offsets nil) (state "tristate") (cycle "1") (termMap nil) (setup "2.0e-09") (hold "1.0e-09") (rise nil) (fall nil) (macroType nil) (voltage nil) (spice nil) (LEFDEFPinName nil) (LEFDEFPinType nil) (mappingTag nil))) (ESpiceDevice nil) (IbisInputPkg ((temperature "27") (bufferModel "CDSDefaultInput_2p5v") (cycle "1") (LEFDEFPinName nil) (LEFDEFPinType nil) (mappingTag nil))) (Source ((voltage "5 V"))) (IbisInput ((temperature "27") (bufferModel "CDSDefaultInput_2p5v") (cycle "1") (LEFDEFPinName nil) (LEFDEFPinType nil) (mappingTag nil))) (Cable (length("1 m"))) (periodic ((periodicFreq "100e6") (periodicPattern "10") (periodicJitter "0"))) (clocked ((clockRise "1e-09") (clockFall "1e-09") (clockFreq "100e6") (clockInitState "0") (clockDutyCycle "0.5") (clockJitter "0"))) (RLGC (length("1000 mil"))) (DiffInput ((temperature "27") (bufferModelNonInverting "CDSDefaultInput_2p5v") (bufferModelInverting "CDSDefaultInput_2p5v") (threshInputHighMin "1.7 V") (threshInputHighTyp "1.7  V") (threshInputHighMax "1.7  V") (threshInputLowMin "0.7  V") (threshInputLowTyp "0.7  V") (threshInputLowMax "0.7  V") (mappingTagNonInverting nil) (mappingTagInverting nil) (cycle "1"))) (async ((asyncTimePoints "") (asyncInitState "1"))) (DiffIO ((temperature "27") (bufferModelNonInverting "CDSDefaultIO_2p5v") (bufferModelInverting "CDSDefaultIO_2p5v") (stimuli nil) (offsets nil) (state "tristate") (cycle "1") (termMap nil) (setup "0.9e-09") (hold "0.4e-09") (rise nil) (fall nil) (threshInputHighMin "1.7 V") (threshInputHighTyp "1.7  V") (threshInputHighMax "1.7  V") (threshInputLowMin "0.7  V") (threshInputLowTyp "0.7  V") (threshInputLowMax "0.7 ") (threshOutputHighMin "2.365  V") (threshOutputHighTyp "2.5  V") (threshOutputHighMax "2.625  V") (threshOutputLowMin "1.275  V") (threshOutputLowTyp "1.7  V") (threshOutputLowMax "1.985  V") (mappingTagNonInverting nil) (mappingTagInverting nil) (spice nil))) (DiffOutput ((temperature "27") (bufferModelNonInverting "CDSDefaultOutput_2p5v") (bufferModelInverting "CDSDefaultOutput_2p5v") (stimuli nil) (offsets nil) (state "tristate") (cycle "1") (termMap nil) (setup "0.9e-09") (hold "0.4e-09") (rise nil) (fall nil) (threshOutputHighMin "2.375  V") (threshOutputHighTyp "2.5  V") (threshOutputHighMax "2.625  V") (threshOutputLowMin "1.275  V") (threshOutputLowTyp "1.7  V") (threshOutputLowMax "1.985  V") (mappingTagNonInverting nil) (mappingTagInverting nil) (spice nil))) (DiffIOPkg ((temperature "27") (bufferModelNonInverting "CDSDefaultIO_2p5v") (bufferModelInverting "CDSDefaultIO_2p5v") (stimuli nil) (offsets nil) (state "tristate") (cycle "1") (termMap nil) (setup "0.9e-09") (hold "0.4e-09") (rise nil) (fall nil) (threshInputHighMin "1.7 V") (threshInputHighTyp "1.7  V") (threshInputHighMax "1.7  V") (threshInputLowMin "0.7  V") (threshInputLowTyp "0.7  V") (threshInputLowMax "0.7 ") (threshOutputHighMin "2.365  V") (threshOutputHighTyp "2.5  V") (threshOutputHighMax "2.625  V") (threshOutputLowMin "1.275  V") (threshOutputLowTyp "1.7  V") (threshOutputLowMax "1.985  V") (mappingTagNonInverting nil) (mappingTagInverting nil) (spice nil))) (idlCircuit ((allDrivers "active") (ftsMode '("Typ")) (rcvrSelect "all") (simMode "Reflection") (tlineDelayMode "time") (userRevision "1.0") (autoSolve "On"))) (sync ((syncFreq "100e6") (syncInitState "1") (syncPattern "10") (syncEdgeSwitch "rise"))) (SeriesTerm ((resistance "22 ohm") (maxDelay "0.1 ns"))) (DiffOutputPkg ((temperature "27") (bufferModelNonInverting "CDSDefaultOutput_2p5v") (bufferModelInverting "CDSDefaultOutput_2p5v") (stimuli nil) (offsets nil) (state "tristate") (cycle "1") (termMap nil) (setup "0.9e-09") (hold "0.4e-09") (rise nil) (fall nil) (threshOutputHighMin "2.375  V") (threshOutputHighTyp "2.5  V") (threshOutputHighMax "2.625  V") (threshOutputLowMin "1.275  V") (threshOutputLowTyp "1.7  V") (threshOutputLowMax "1.985  V") (mappingTagNonInverting nil) (mappingTagInverting nil) (spice nil))) (IbisOutput ((temperature "27") (bufferModel "CDSDefaultOutput_2p5v") (stimuli nil) (offsets nil) (state "tristate") (cycle "1") (termMap nil) (setup "2.0e-09") (hold "1.0e-09") (rise nil) (fall nil) (macroType nil) (voltage nil) (spice nil) (LEFDEFPinName nil) (LEFDEFPinType nil) (mappingTag nil))) (CPW ((d1Thickness "10 mil") (d1Constant "4.5") (d1LossTangent "0.035") (d2Thickness "0.72 mil") (d2Constant "1") (d2LossTangent "0") (d3Thickness "0.0") (d3Constant "1") (d3LossTangent "0") length("1000 mil") (spacing "5 mil") (spacing2 "5 mil") (spacing3 "5 mil") (spacing4 "5 mil") (spacing5 "5 mil") (traceConductivity "595900 mho/cm") (traceGeometry "cpwms") (traceLayerName "") (traceThickness "0.72 mil") (traceType "single") (traceWidth "5.0 mil") (traceWidth2 "5.0 mil") (traceWidth3 "5.0 mil") (traceWidth4 "5.0 mil") (traceWidth5 "5.0 mil") (traceWidth6 "5.0 mil") (offset "0 mil") (traceCount "1") (impedance nil))) (CPWMS ((d1Thickness "10 mil") (d1Constant "4.5") (d1LossTangent "0.035") (d2Thickness "0.72 mil") (d2Constant "4.5") (d2LossTangent "0.035") (d3Thickness "0.0") (d3Constant "1") (d3LossTangent "0") length("1000 mil") (spacing "5 mil") (spacing2 "5 mil") (spacing3 "5 mil") (spacing4 "5 mil") (spacing5 "5 mil") (traceConductivity "595900 mho/cm") (traceGeometry "cpwms") (traceLayerName "") (traceThickness "0.72 mil") (traceType "single") (traceWidth "5.0 mil") (traceWidth2 "5.0 mil") (traceWidth3 "5.0 mil") (traceWidth4 "5.0 mil") (traceWidth5 "5.0 mil") (traceWidth6 "5.0 mil") (offset "0 mil") (traceCount "1") (impedance nil))) (CurrentProbe nil) (CPWSL ((d1Thickness "10 mil") (d1Constant "4.5") (d1LossTangent "0.035") (d2Thickness "0.72 mil") (d2Constant "4.5") (d2LossTangent "0.035") (d3Thickness "10 mil") (d3Constant "4.5") (d3LossTangent "0.035") length("1000 mil") (spacing "5 mil") (spacing2 "5 mil") (spacing3 "5 mil") (spacing4 "5 mil") (spacing5 "5 mil") (traceConductivity "595900 mho/cm") (traceGeometry "cpwms") (traceLayerName "") (traceThickness "0.72 mil") (traceType "single") (traceWidth "5.0 mil") (traceWidth2 "5.0 mil") (traceWidth3 "5.0 mil") (traceWidth4 "5.0 mil") (traceWidth5 "5.0 mil") (traceWidth6 "5.0 mil") (offset "0 mil") (traceCount "1") (impedance nil))) (ShuntTerm ((resistance "50 ohm") (voltage "5 V") (maxDelay "0.1 ns"))) (TheveninTerm ((resistanceUp "180 ohm") (resistanceDown "270 ohm") (voltageUp "5 V") (voltageDown "0 V") (maxDelay "0.1 ns"))) (Connector nil) (RCTerm ((resistance "50 ohm") (capacitance "20 pF") (voltage "5 V") (maxDelay "0.1 ns"))) (LowClampTerm ((cutoffVoltage "0.7 V") (voltage "0 V") (maxDelay "0.1 ns"))) (HiClampTerm ((cutoffVoltage "0.7 V") (voltage "5 V") (maxDelay "0.1 ns"))) (DualClampTerm ((cutoffVoltageUp "0.7 V") (cutoffVoltageDown "0.7 V") (voltageUp "5 V") (voltageDown "0 V") (maxDelay "0.1 ns"))) (Diode ((cutoffVoltage "0.7 V")))))
				)
				( objectStatus "PCIE_SLOT_C_A" )
			)
			( electricalCSet "@crescent_city_bb_fab1_lib.crescent_city_bb_fab1(sch_1):\PCIE_SLOT_1\"
				( groupRef "PCIE_SLOT:MG" )
				( pinPairRef "PCIE_SLOT:U5D1.CT9:J8G1.106" )
				( attribute "DIFFP_GATHER_CONTROL" "IGNORE"
					( Origin gBackEnd )
				)
				( attribute "DIFFP_UNCOUPLED_LENGTH" "1000.00"
					( Origin gBackEnd )
				)
				( attribute "DIFFP_COUPLED_PLUS" "0.10"
					( Origin gBackEnd )
				)
				( attribute "DIFFP_COUPLED_MINUS" "0.10"
					( Origin gBackEnd )
				)
				( attribute "DIFFP_PHASE_TOL" "5 mil"
					( Units "uPhaseTol" "ns" 1.000000)
					( Origin gBackEnd )
				)
				( attribute "TOPOLOGY_TEMPLATE_REVISION" "1.0"
					( Origin gBackEnd )
				)
				( topologyData 22398
(SKIDL (Circuits ("MAIN" (Parts ("CRESCENT_CITY_177_20141217_Q.@@U36.CT9" IbisInputPkg (xy (5527 4235)) (refDes "U5D1") (model "Unknown") (Props (_SXDesignName "CRESCENT_CITY_177_20141217_Q") (brdx "11826.09 MIL") (brdy "3487.96 MIL") (bufferModel "CDSDefaultInput_2p5v") (mappingTag "") (temperature "27")) (Terms ("CRESCENT_CITY_177_20141217_Q.X1182609Y348796L2LRATS" "CT9"))) ("CRESCENT_CITY_177_20141217_Q.@@J73.106" IbisIOPkg (xy (5502 4240)) (refDes "J8G1") (model "Unknown") (Props (_SXDesignName "CRESCENT_CITY_177_20141217_Q") (brdx "15732.87 MIL") (brdy "172.76 MIL") (bufferModel "CDSDefaultIO_2p5v") (cycle "1") (hold "1.0e-09") (mappingTag "") (offsets ("4" "0") ("5" "0")) (setup "2.0e-09") (state "tristate") (stimuli ("4" "local131") ("5" "local132")) (temperature "27") (termMap ("4" "Data") ("5" "Enable"))) (Terms ("CRESCENT_CITY_177_20141217_Q.X1573287Y17276L2LRATS" "106"))) ("CRESCENT_CITY_177_20141217_Q.T@@RATS@@U36.CT9@@J73.106" TLine (xy (5513 4235)) (mirror x) (refDes "TL9") (Props (_SXDesignName "CRESCENT_CITY_177_20141217_Q") (impedance "47.169 ohm") length("7221.97 MIL") (propDelay "1.29712 ns") (traceCount "1") (traceGeometry "Microstrip") (velocity "5567.72 mil/ns")) (Terms ("CRESCENT_CITY_177_20141217_Q.X1182609Y348796L2LRATS" "1") ("CRESCENT_CITY_177_20141217_Q.X1573287Y17276L2LRATS" "2")))) (Nodes ("CRESCENT_CITY_177_20141217_Q.X1182609Y348796L2LRATS" (terms "CRESCENT_CITY_177_20141217_Q.T@@RATS@@U36.CT9@@J73.106.1" "CRESCENT_CITY_177_20141217_Q.@@U36.CT9.1")) ("CRESCENT_CITY_177_20141217_Q.X1573287Y17276L2LRATS" (terms "CRESCENT_CITY_177_20141217_Q.T@@RATS@@U36.CT9@@J73.106.2" "CRESCENT_CITY_177_20141217_Q.@@J73.106.1"))) (Ports) (Stimuli ("local2" (scope local) (stimType periodic) (Props (periodicFreq "5e+007") (periodicJitter "0") (periodicPattern "1"))) ("local132" (scope local) (stimType periodic) (Props (periodicFreq "5e+007") (periodicJitter "0") (periodicPattern "1"))) ("local131" (scope local) (stimType periodic) (Props (periodicFreq "5e+007") (periodicJitter "0") (periodicPattern "1"))) ("local0" (scope local) (stimType periodic) (Props (periodicFreq "5e+007") (periodicJitter "0") (periodicPattern "1"))) ("local1" (scope local) (stimType periodic) (Props (periodicFreq "5e+007") (periodicJitter "0") (periodicPattern "1")))) (Notes) (Constraints ("DELAY_RULE" ("CRESCENT_CITY_177_20141217_Q U36.CT9" "CRESCENT_CITY_177_20141217_Q J73.106" "LENGTH" "0.0762" "LENGTH" "0.4064")) ("DP_GATHER_CONTROL" "IGNORE") ("DP_MAX_UNCOUPLED_LENGTH" "0.000254") ("DP_NEGATIVE_COUPLED_TOLERANCE" "2.54e-006") ("DP_PHASE_TOLERANCE" ("LENGTH" "0.000127")) ("DP_POSITIVE_COUPLED_TOLERANCE" "2.54e-006") ("RELATIVE_PROPAGATION_DELAY" ("MG" "CRESCENT_CITY_177_20141217_Q U36.CT9" "CRESCENT_CITY_177_20141217_Q J73.106" "NET GROUP" "LENGTH" "0.0127" "LENGTH" ""))) (MeasurementSets ("EMI" ("EMIStatus" status("on")) ("PeakEmission" status("on")) ("PeakFrequency" status("on")) ("PulseFreq" status("on")) ("RiseTime" status("on")) ("VoltageSwing" status("on"))) ("Reflection" ("BufferDelayFall" status("off")) ("BufferDelayRise" status("off")) ("EyeHeight" status("off")) ("EyeJitter" status("off")) ("EyeWidth" status("off")) ("FirstIncidentFall" status("off")) ("FirstIncidentRise" status("off")) ("Glitch" status("on")) ("GlitchFall" status("off")) ("GlitchRise" status("off")) ("Monotonic" status("on")) ("MonotonicFall" status("off")) ("MonotonicRise" status("off")) ("NoiseMargin" status("on")) ("NoiseMarginHigh" status("off")) ("NoiseMarginLow" status("off")) ("OvershootHigh" status("on")) ("OvershootLow" status("on")) ("PropDelay" status("on")) ("SettleDelay" status("on")) ("SettleDelayFall" status("off")) ("SettleDelayRise" status("off")) ("SwitchDelay" status("on")) ("SwitchDelayFall" status("off")) ("SwitchDelayRise" status("off"))) ("Crosstalk" ("Crosstalk" status("on"))) ("Custom")) (VectorSets) (Props (XnetName "P3E_CPU0_PE2_SS_RXN<0>") (allDrivers "active") (customSimType "Reflection") (ftsMode ("Typ")) (rcvrSelect "all") (tlineDelayMode "time") (userRevision "1.0")))) (Subckts) (CrossSections ("CRESCENT_CITY_177_20141217_Q" (Props (SXDesignName "CRESCENT_CITY_177_20141217_Q")) (Layers ("" (layerType "SURFACE") (material "AIR") (thickness "0 mil") (dielectricConstant "1.000000") (lossTangent "0") (etchFactor "0.000000") (elecCondVal "0 mho/cm") (thermCondVal "0 w/cm-degC")) ("" (layerType "DIELECTRIC") (material "CONFORMAL_COAT") (thickness "0.5 mil") (dielectricConstant "3.800000") (lossTangent "0.035") (etchFactor "0.000000") (elecCondVal "0 mho/cm") (thermCondVal "0.012 w/cm-degC")) ("TOP" (layerType "CONDUCTOR") (material "COPPER") (thickness "  2.100000 mil") (width "4.00 MIL") (dielectricConstant "4.500000") (lossTangent "0") (etchFactor "70.000000") (elecCondVal "595900.000000 mho/cm") (thermCondVal "0 w/cm-degC") (signalDieConstant "3.800000") (signalLossTangent "0.035")) ("" (layerType "DIELECTRIC") (material "FR-4") (thickness "  2.670000 mil") (dielectricConstant "4.000000") (lossTangent "0.035") (etchFactor "0.000000") (elecCondVal "0 mho/cm") (thermCondVal "0.012 w/cm-degC")) ("L2_GND1" (layerType "PLANE") (material "COPPER") (isShield t) (thickness "  1.250000 mil") (dielectricConstant "4.500000") (lossTangent "0.035") (etchFactor "90.000000") (elecCondVal "595900.000000 mho/cm") (thermCondVal "0.012 w/cm-degC")) ("" (layerType "DIELECTRIC") (material "FR-4") (thickness "  9.000000 mil") (dielectricConstant "4.100000") (lossTangent "0.035") (etchFactor "0.000000") (elecCondVal "0 mho/cm") (thermCondVal "0.012 w/cm-degC")) ("L3_SIG1" (layerType "CONDUCTOR") (material "COPPER") (thickness "  1.250000 mil") (width "4.00 MIL") (dielectricConstant "4.500000") (lossTangent "0.035") (etchFactor "90.000000") (elecCondVal "595900.000000 mho/cm") (thermCondVal "0.012 w/cm-degC") (signalDieConstant "4.100000") (signalLossTangent "0.035")) ("" (layerType "DIELECTRIC") (material "FR-4") (thickness "  3.000000 mil") (dielectricConstant "4.500000") (lossTangent "0.035") (etchFactor "0.000000") (elecCondVal "0 mho/cm") (thermCondVal "0 w/cm-degC")) ("L4_GND2" (layerType "PLANE") (material "COPPER") (isShield t) (thickness "  1.250000 mil") (dielectricConstant "4.500000") (lossTangent "0.035") (etchFactor "90.000000") (elecCondVal "595900.000000 mho/cm") (thermCondVal "0 w/cm-degC")) ("" (layerType "DIELECTRIC") (material "FR-4") (thickness "  9.000000 mil") (dielectricConstant "4.000000") (lossTangent "0.035") (etchFactor "0.000000") (elecCondVal "0 mho/cm") (thermCondVal "0.012 w/cm-degC")) ("L5_SIG2" (layerType "CONDUCTOR") (material "COPPER") (thickness "  1.250000 mil") (width "4.00 MIL") (dielectricConstant "4.500000") (lossTangent "0.035") (etchFactor "90.000000") (elecCondVal "595900.000000 mho/cm") (thermCondVal "0.012 w/cm-degC") (signalDieConstant "4.000000") (signalLossTangent "0.035")) ("" (layerType "DIELECTRIC") (material "FR-4") (thickness "  3.000000 mil") (dielectricConstant "4.500000") (lossTangent "0.035") (etchFactor "0.000000") (elecCondVal "0 mho/cm") (thermCondVal "0 w/cm-degC")) ("L6_GND3" (layerType "PLANE") (material "COPPER") (isShield t) (thickness "  1.250000 mil") (dielectricConstant "4.500000") (lossTangent "0.035") (etchFactor "90.000000") (elecCondVal "595900.000000 mho/cm") (thermCondVal "0 w/cm-degC")) ("" (layerType "DIELECTRIC") (material "FR-4") (thickness "  4.500000 mil") (dielectricConstant "4.100000") (lossTangent "0.035") (etchFactor "0.000000") (elecCondVal "0 mho/cm") (thermCondVal "0.012 w/cm-degC")) ("L7_PWR1-SIG" (layerType "PLANE") (material "COPPER") (isShield t) (thickness "  2.400000 mil") (dielectricConstant "4.500000") (lossTangent "0.035") (etchFactor "90.000000") (elecCondVal "595900.000000 mho/cm") (thermCondVal "0.012 w/cm-degC")) ("" (layerType "DIELECTRIC") (material "FR-4") (thickness "  4.600000 mil") (dielectricConstant "4.000000") (lossTangent "0.035") (etchFactor "0.000000") (elecCondVal "0 mho/cm") (thermCondVal "0.012 w/cm-degC")) ("L8_PWR2-SIG" (layerType "PLANE") (material "COPPER") (isShield t) (thickness "  2.400000 mil") (dielectricConstant "4.500000") (lossTangent "0.035") (etchFactor "90.000000") (elecCondVal "595900.000000 mho/cm") (thermCondVal "0.012 w/cm-degC")) ("" (layerType "DIELECTRIC") (material "FR-4") (thickness "  4.500000 mil") (dielectricConstant "4.500000") (lossTangent "0.035") (etchFactor "0.000000") (elecCondVal "0 mho/cm") (thermCondVal "0 w/cm-degC")) ("L9_GND4" (layerType "PLANE") (material "COPPER") (isShield t) (thickness "  1.250000 mil") (dielectricConstant "4.500000") (lossTangent "0.035") (etchFactor "90.000000") (elecCondVal "595900.000000 mho/cm") (thermCondVal "0 w/cm-degC")) ("" (layerType "DIELECTRIC") (material "FR-4") (thickness "  3.000000 mil") (dielectricConstant "4.100000") (lossTangent "0.035") (etchFactor "0.000000") (elecCondVal "0 mho/cm") (thermCondVal "0.012 w/cm-degC")) ("L10_SIG3" (layerType "CONDUCTOR") (material "COPPER") (thickness "  1.250000 mil") (width "4.00 MIL") (dielectricConstant "4.500000") (lossTangent "0.035") (etchFactor "90.000000") (elecCondVal "595900.000000 mho/cm") (thermCondVal "0.012 w/cm-degC") (signalDieConstant "4.100000") (signalLossTangent "0.035")) ("" (layerType "DIELECTRIC") (material "FR-4") (thickness "  9.000000 mil") (dielectricConstant "4.500000") (lossTangent "0.035") (etchFactor "0.000000") (elecCondVal "0 mho/cm") (thermCondVal "0 w/cm-degC")) ("L11_GND5" (layerType "PLANE") (material "COPPER") (isShield t) (thickness "  1.250000 mil") (dielectricConstant "4.500000") (lossTangent "0.035") (etchFactor "90.000000") (elecCondVal "595900.000000 mho/cm") (thermCondVal "0 w/cm-degC")) ("" (layerType "DIELECTRIC") (material "FR-4") (thickness "  3.000000 mil") (dielectricConstant "4.500000") (lossTangent "0.035") (etchFactor "0.000000") (elecCondVal "0 mho/cm") (thermCondVal "0.012 w/cm-degC")) ("L12_SIG4" (layerType "CONDUCTOR") (material "COPPER") (thickness "  1.250000 mil") (width "4.00 MIL") (dielectricConstant "4.500000") (lossTangent "0.035") (etchFactor "90.000000") (elecCondVal "595900.000000 mho/cm") (thermCondVal "0.012 w/cm-degC") (signalDieConstant "4.500000") (signalLossTangent "0.035")) ("" (layerType "DIELECTRIC") (material "FR-4") (thickness "  9.000000 mil") (dielectricConstant "4.500000") (lossTangent "0.035") (etchFactor "0.000000") (elecCondVal "0 mho/cm") (thermCondVal "0 w/cm-degC")) ("L13_GND6" (layerType "PLANE") (material "COPPER") (isShield t) (thickness "  1.250000 mil") (dielectricConstant "4.500000") (lossTangent "0.035") (etchFactor "90.000000") (elecCondVal "595900.000000 mho/cm") (thermCondVal "0.012 w/cm-degC")) ("" (layerType "DIELECTRIC") (material "FR-4") (thickness "  2.670000 mil") (dielectricConstant "4.500000") (lossTangent "0.035") (etchFactor "0.000000") (elecCondVal "0 mho/cm") (thermCondVal "0.012 w/cm-degC")) ("BOTTOM" (layerType "CONDUCTOR") (material "COPPER") (thickness "  2.100000 mil") (width "4.00 MIL") (dielectricConstant "4.500000") (lossTangent "0") (etchFactor "70.000000") (elecCondVal "595900.000000 mho/cm") (thermCondVal "0 w/cm-degC") (signalDieConstant "3.800000") (signalLossTangent "0.035")) ("" (layerType "DIELECTRIC") (material "CONFORMAL_COAT") (thickness "0.5 mil") (dielectricConstant "3.800000") (lossTangent "0.035") (etchFactor "0.000000") (elecCondVal "0 mho/cm") (thermCondVal "0.012 w/cm-degC")) ("" (layerType "SURFACE") (material "AIR") (thickness "0 mil") (dielectricConstant "1.000000") (lossTangent "0") (etchFactor "0.000000") (elecCondVal "0 mho/cm") (thermCondVal "0 w/cm-degC"))))) (Props (DesUnits "mils 2") (LayerStack ("DIELECTRIC" "DIELECTRIC" "BOTTOM" "DIELECTRIC" "L13_GND6" "DIELECTRIC" "L12_SIG4" "DIELECTRIC" "L11_GND5" "DIELECTRIC" "L10_SIG3" "DIELECTRIC" "L9_GND4" "DIELECTRIC" "L8_PWR2-SIG" "DIELECTRIC" "L7_PWR1-SIG" "DIELECTRIC" "L6_GND3" "DIELECTRIC" "L5_SIG2" "DIELECTRIC" "L4_GND2" "DIELECTRIC" "L3_SIG1" "DIELECTRIC" "L2_GND1" "DIELECTRIC" "TOP" "DIELECTRIC" "DIELECTRIC")) (Revision "16.600")) (Params (Resistor ((resistance "50 ohm") (orientation "0"))) (DiffInput ((temperature "27") (bufferModelNonInverting "CDSDefaultInput_2p5v") (bufferModelInverting "CDSDefaultInput_2p5v") (threshInputHighMin "1.7 V") (threshInputHighTyp "1.7  V") (threshInputHighMax "1.7  V") (threshInputLowMin "0.7  V") (threshInputLowTyp "0.7  V") (threshInputLowMax "0.7  V") (mappingTagNonInverting nil) (mappingTagInverting nil) (cycle "1"))) (Capacitor ((capacitance "10 pF") (orientation "0"))) (DiffOutputPkg ((temperature "27") (bufferModelNonInverting "CDSDefaultOutput_2p5v") (bufferModelInverting "CDSDefaultOutput_2p5v") (stimuli nil) (offsets nil) (state "tristate") (cycle "1") (termMap nil) (setup "0.9e-09") (hold "0.4e-09") (rise nil) (fall nil) (threshOutputHighMin "2.375  V") (threshOutputHighTyp "2.5  V") (threshOutputHighMax "2.625  V") (threshOutputLowMin "1.275  V") (threshOutputLowTyp "1.7  V") (threshOutputLowMax "1.985  V") (mappingTagNonInverting nil) (mappingTagInverting nil) (spice nil))) (DiffOutput ((temperature "27") (bufferModelNonInverting "CDSDefaultOutput_2p5v") (bufferModelInverting "CDSDefaultOutput_2p5v") (stimuli nil) (offsets nil) (state "tristate") (cycle "1") (termMap nil) (setup "0.9e-09") (hold "0.4e-09") (rise nil) (fall nil) (threshOutputHighMin "2.375  V") (threshOutputHighTyp "2.5  V") (threshOutputHighMax "2.625  V") (threshOutputLowMin "1.275  V") (threshOutputLowTyp "1.7  V") (threshOutputLowMax "1.985  V") (mappingTagNonInverting nil) (mappingTagInverting nil) (spice nil))) (CPWSL ((d1Thickness "10 mil") (d1Constant "4.5") (d1LossTangent "0.035") (d2Thickness "0.72 mil") (d2Constant "4.5") (d2LossTangent "0.035") (d3Thickness "10 mil") (d3Constant "4.5") (d3LossTangent "0.035") length("1000 mil") (spacing "5 mil") (spacing2 "5 mil") (spacing3 "5 mil") (spacing4 "5 mil") (spacing5 "5 mil") (traceConductivity "595900 mho/cm") (traceGeometry "cpwms") (traceLayerName "") (traceThickness "0.72 mil") (traceType "single") (traceWidth "5.0 mil") (traceWidth2 "5.0 mil") (traceWidth3 "5.0 mil") (traceWidth4 "5.0 mil") (traceWidth5 "5.0 mil") (traceWidth6 "5.0 mil") (offset "0 mil") (traceCount "1") (impedance nil))) (Connector nil) (CPWMS ((d1Thickness "10 mil") (d1Constant "4.5") (d1LossTangent "0.035") (d2Thickness "0.72 mil") (d2Constant "4.5") (d2LossTangent "0.035") (d3Thickness "0.0") (d3Constant "1") (d3LossTangent "0") length("1000 mil") (spacing "5 mil") (spacing2 "5 mil") (spacing3 "5 mil") (spacing4 "5 mil") (spacing5 "5 mil") (traceConductivity "595900 mho/cm") (traceGeometry "cpwms") (traceLayerName "") (traceThickness "0.72 mil") (traceType "single") (traceWidth "5.0 mil") (traceWidth2 "5.0 mil") (traceWidth3 "5.0 mil") (traceWidth4 "5.0 mil") (traceWidth5 "5.0 mil") (traceWidth6 "5.0 mil") (offset "0 mil") (traceCount "1") (impedance nil))) (TLine ((diffImpedance "100ohm") (diffVelocity "1.4142e+08M/s") (impedance "60ohm") length("2800 mil") (propDelay "0.5 ns") (velocity "5600 mil/ns") (traceCount "1") (traceGeometry "Microstrip") (impedanceMin nil) (impedanceMax nil) (lengthMin nil) (lengthMax nil) (propDelayMin nil) (propDelayMax nil) (impedanceSweepCount nil) (propDelaySweepCount nil) (velocitySweepCount nil) (lengthSweepCount nil) (matchSetName nil))) (CPW ((d1Thickness "10 mil") (d1Constant "4.5") (d1LossTangent "0.035") (d2Thickness "0.72 mil") (d2Constant "1") (d2LossTangent "0") (d3Thickness "0.0") (d3Constant "1") (d3LossTangent "0") length("1000 mil") (spacing "5 mil") (spacing2 "5 mil") (spacing3 "5 mil") (spacing4 "5 mil") (spacing5 "5 mil") (traceConductivity "595900 mho/cm") (traceGeometry "cpwms") (traceLayerName "") (traceThickness "0.72 mil") (traceType "single") (traceWidth "5.0 mil") (traceWidth2 "5.0 mil") (traceWidth3 "5.0 mil") (traceWidth4 "5.0 mil") (traceWidth5 "5.0 mil") (traceWidth6 "5.0 mil") (offset "0 mil") (traceCount "1") (impedance nil))) (Via ((model "Unknown") (viaOutputFormat "Unknown") (viaPadstack nil) (viaTopLayer nil) (viaBottomLayer nil) (viaIsPower nil) (viaIsGround nil))) (Trace ((d1Thickness "10 mil") (d1Constant "4.5") (d1LossTangent "0.035") (d2Thickness "10 mil") (d2Constant "4.5") (d2LossTangent "0.035") (d3Thickness "0.0") (d3Constant "1.0") (d3LossTangent "0") length("1000 mil") (spacing "5 mil") (spacing2 "5 mil") (spacing3 "5 mil") (spacing4 "5 mil") (spacing5 "5 mil") (traceConductivity "595900 mho/cm") (traceGeometry "microstrip") (traceLayerName "") (traceThickness "0.72 mil") (traceType "single") (traceWidth "5.0 mil") (traceWidth2 "5.0 mil") (traceWidth3 "5.0 mil") (traceWidth4 "5.0 mil") (traceWidth5 "5.0 mil") (traceWidth6 "5.0 mil") (offset "0 mil") (traceCount "1") (impedance nil))) (sync ((syncFreq "100e6") (syncInitState "1") (syncPattern "10") (syncEdgeSwitch "rise"))) (idlCircuit ((allDrivers "active") (ftsMode '("Typ")) (rcvrSelect "all") (simMode "Reflection") (tlineDelayMode "time") (userRevision "1.0") (autoSolve "On"))) (CurrentProbe nil) (DiffInputPkg ((temperature "27") (bufferModelNonInverting "CDSDefaultInput_2p5v") (bufferModelInverting "CDSDefaultInput_2p5v") (threshInputHighMin "1.7 V") (threshInputHighTyp "1.7  V") (threshInputHighMax "1.7  V") (threshInputLowMin "0.7  V") (threshInputLowTyp "0.7  V") (threshInputLowMax "0.7  V") (mappingTagNonInverting nil) (mappingTagInverting nil) (cycle "1"))) (IbisIOMacro ((temperature "27") (bufferModel "CDSDefaultIO_2p5v") (stimuli nil) (offsets nil) (state "tristate") (cycle "1") (termMap nil) (setup "2.0e-09") (hold "1.0e-09") (rise nil) (fall nil) (macroType nil) (voltage nil) (spice nil) (LEFDEFPinName nil) (LEFDEFPinType nil) (mappingTag nil))) (IbisOutputPkg ((temperature "27") (bufferModel "CDSDefaultOutput_2p5v") (stimuli nil) (offsets nil) (state "tristate") (cycle "1") (termMap nil) (setup "2.0e-09") (hold "1.0e-09") (rise nil) (fall nil) (macroType nil) (voltage nil) (spice nil) (LEFDEFPinName nil) (LEFDEFPinType nil) (mappingTag nil))) (IbisIOPkg ((temperature "27") (bufferModel "CDSDefaultIO_2p5v") (stimuli nil) (offsets nil) (state "tristate") (cycle "1") (termMap nil) (setup "2.0e-09") (hold "1.0e-09") (rise nil) (fall nil) (macroType nil) (voltage nil) (spice nil) (LEFDEFPinName nil) (LEFDEFPinType nil) (mappingTag nil))) (IbisInputPkg ((temperature "27") (bufferModel "CDSDefaultInput_2p5v") (cycle "1") (LEFDEFPinName nil) (LEFDEFPinType nil) (mappingTag nil))) (TheveninTerm ((resistanceUp "180 ohm") (resistanceDown "270 ohm") (voltageUp "5 V") (voltageDown "0 V") (maxDelay "0.1 ns"))) (SeriesTerm ((resistance "22 ohm") (maxDelay "0.1 ns"))) (IbisIO_OpenPullDown ((temperature "27") (bufferModel "CDSDefaultIO_2p5v") (stimuli nil) (offsets nil) (state "tristate") (cycle "1") (termMap nil) (setup "2.0e-09") (hold "1.0e-09") (rise nil) (fall nil) (macroType nil) (voltage nil) (spice nil) (LEFDEFPinName nil) (LEFDEFPinType nil) (mappingTag nil))) (async ((asyncTimePoints "") (asyncInitState "1"))) (RCTerm ((resistance "50 ohm") (capacitance "20 pF") (voltage "5 V") (maxDelay "0.1 ns"))) (LowClampTerm ((cutoffVoltage "0.7 V") (voltage "0 V") (maxDelay "0.1 ns"))) (IbisIO_OpenPullUp ((temperature "27") (bufferModel "CDSDefaultIO_2p5v") (stimuli nil) (offsets nil) (state "tristate") (cycle "1") (termMap nil) (setup "2.0e-09") (hold "1.0e-09") (rise nil) (fall nil) (macroType nil) (voltage nil) (spice nil) (LEFDEFPinName nil) (LEFDEFPinType nil) (mappingTag nil))) (clocked ((clockRise "1e-09") (clockFall "1e-09") (clockFreq "100e6") (clockInitState "0") (clockDutyCycle "0.5") (clockJitter "0"))) (HiClampTerm ((cutoffVoltage "0.7 V") (voltage "5 V") (maxDelay "0.1 ns"))) (periodic ((periodicFreq "100e6") (periodicPattern "10") (periodicJitter "0"))) (DualClampTerm ((cutoffVoltageUp "0.7 V") (cutoffVoltageDown "0.7 V") (voltageUp "5 V") (voltageDown "0 V") (maxDelay "0.1 ns"))) (Cable (length("1 m"))) (ShuntTerm ((resistance "50 ohm") (voltage "5 V") (maxDelay "0.1 ns"))) (IbisOutput_OpenPullUp ((temperature "27") (bufferModel "CDSDefaultOutput_2p5v") (stimuli nil) (offsets nil) (state "tristate") (cycle "1") (termMap nil) (setup "2.0e-09") (hold "1.0e-09") (rise nil) (fall nil) (macroType nil) (voltage nil) (spice nil) (LEFDEFPinName nil) (LEFDEFPinType nil) (mappingTag nil))) (IbisInput ((temperature "27") (bufferModel "CDSDefaultInput_2p5v") (cycle "1") (LEFDEFPinName nil) (LEFDEFPinType nil) (mappingTag nil))) (IbisOutput ((temperature "27") (bufferModel "CDSDefaultOutput_2p5v") (stimuli nil) (offsets nil) (state "tristate") (cycle "1") (termMap nil) (setup "2.0e-09") (hold "1.0e-09") (rise nil) (fall nil) (macroType nil) (voltage nil) (spice nil) (LEFDEFPinName nil) (LEFDEFPinType nil) (mappingTag nil))) (IbisIO ((temperature "27") (bufferModel "CDSDefaultIO_2p5v") (stimuli nil) (offsets nil) (state "tristate") (cycle "1") (termMap nil) (setup "2.0e-09") (hold "1.0e-09") (rise nil) (fall nil) (macroType nil) (voltage nil) (spice nil) (LEFDEFPinName nil) (LEFDEFPinType nil) (mappingTag nil))) (Source ((voltage "5 V"))) (Inductor ((inductance "5 nH") (orientation "0"))) (DiffIOPkg ((temperature "27") (bufferModelNonInverting "CDSDefaultIO_2p5v") (bufferModelInverting "CDSDefaultIO_2p5v") (stimuli nil) (offsets nil) (state "tristate") (cycle "1") (termMap nil) (setup "0.9e-09") (hold "0.4e-09") (rise nil) (fall nil) (threshInputHighMin "1.7 V") (threshInputHighTyp "1.7  V") (threshInputHighMax "1.7  V") (threshInputLowMin "0.7  V") (threshInputLowTyp "0.7  V") (threshInputLowMax "0.7 ") (threshOutputHighMin "2.365  V") (threshOutputHighTyp "2.5  V") (threshOutputHighMax "2.625  V") (threshOutputLowMin "1.275  V") (threshOutputLowTyp "1.7  V") (threshOutputLowMax "1.985  V") (mappingTagNonInverting nil) (mappingTagInverting nil) (spice nil))) (Diode ((cutoffVoltage "0.7 V"))) (RLGC (length("1000 mil"))) (DiffIO ((temperature "27") (bufferModelNonInverting "CDSDefaultIO_2p5v") (bufferModelInverting "CDSDefaultIO_2p5v") (stimuli nil) (offsets nil) (state "tristate") (cycle "1") (termMap nil) (setup "0.9e-09") (hold "0.4e-09") (rise nil) (fall nil) (threshInputHighMin "1.7 V") (threshInputHighTyp "1.7  V") (threshInputHighMax "1.7  V") (threshInputLowMin "0.7  V") (threshInputLowTyp "0.7  V") (threshInputLowMax "0.7 ") (threshOutputHighMin "2.365  V") (threshOutputHighTyp "2.5  V") (threshOutputHighMax "2.625  V") (threshOutputLowMin "1.275  V") (threshOutputLowTyp "1.7  V") (threshOutputLowMax "1.985  V") (mappingTagNonInverting nil) (mappingTagInverting nil) (spice nil))) (ESpiceDevice nil)))
				)
				( objectStatus "PCIE_SLOT" )
			)
			( electricalCSet "@crescent_city_bb_fab1_lib.crescent_city_bb_fab1(sch_1):\PCIE_SLOT_A\"
				( pinPairRef "PCIE_SLOT_A:U5D1.CT9:J8G1.106" )
				( attribute "DIFFP_GATHER_CONTROL" "IGNORE"
					( Origin gBackEnd )
				)
				( attribute "DIFFP_UNCOUPLED_LENGTH" "1000.00"
					( Origin gBackEnd )
				)
				( attribute "DIFFP_COUPLED_PLUS" "0.10"
					( Origin gBackEnd )
				)
				( attribute "DIFFP_COUPLED_MINUS" "0.10"
					( Origin gBackEnd )
				)
				( attribute "DIFFP_PHASE_TOL" "5 mil"
					( Units "uPhaseTol" "ns" 1.000000)
					( Origin gBackEnd )
				)
				( attribute "TOPOLOGY_TEMPLATE_REVISION" "1.0"
					( Origin gBackEnd )
				)
				( topologyData 22191
(SKIDL (Circuits ("MAIN" (Parts ("CRESCENT_CITY_177_20141217_Q.@@U36.CT9" IbisInputPkg (xy (5527 4235)) (refDes "U5D1") (model "Unknown") (Props (_SXDesignName "CRESCENT_CITY_177_20141217_Q") (brdx "11826.09 MIL") (brdy "3487.96 MIL") (bufferModel "CDSDefaultInput_2p5v") (mappingTag "") (temperature "27")) (Terms ("CRESCENT_CITY_177_20141217_Q.X1182609Y348796L2LRATS" "CT9"))) ("CRESCENT_CITY_177_20141217_Q.@@J73.106" IbisIOPkg (xy (5502 4240)) (refDes "J8G1") (model "Unknown") (Props (_SXDesignName "CRESCENT_CITY_177_20141217_Q") (brdx "15732.87 MIL") (brdy "172.76 MIL") (bufferModel "CDSDefaultIO_2p5v") (cycle "1") (hold "1.0e-09") (mappingTag "") (offsets ("4" "0") ("5" "0")) (setup "2.0e-09") (state "tristate") (stimuli ("4" "local131") ("5" "local132")) (temperature "27") (termMap ("4" "Data") ("5" "Enable"))) (Terms ("CRESCENT_CITY_177_20141217_Q.X1573287Y17276L2LRATS" "106"))) ("CRESCENT_CITY_177_20141217_Q.T@@RATS@@U36.CT9@@J73.106" TLine (xy (5513 4235)) (mirror x) (refDes "TL9") (Props (_SXDesignName "CRESCENT_CITY_177_20141217_Q") (impedance "47.169 ohm") length("7221.97 MIL") (propDelay "1.29712 ns") (traceCount "1") (traceGeometry "Microstrip") (velocity "5567.72 mil/ns")) (Terms ("CRESCENT_CITY_177_20141217_Q.X1182609Y348796L2LRATS" "1") ("CRESCENT_CITY_177_20141217_Q.X1573287Y17276L2LRATS" "2")))) (Nodes ("CRESCENT_CITY_177_20141217_Q.X1182609Y348796L2LRATS" (terms "CRESCENT_CITY_177_20141217_Q.T@@RATS@@U36.CT9@@J73.106.1" "CRESCENT_CITY_177_20141217_Q.@@U36.CT9.1")) ("CRESCENT_CITY_177_20141217_Q.X1573287Y17276L2LRATS" (terms "CRESCENT_CITY_177_20141217_Q.T@@RATS@@U36.CT9@@J73.106.2" "CRESCENT_CITY_177_20141217_Q.@@J73.106.1"))) (Ports) (Stimuli ("local2" (scope local) (stimType periodic) (Props (periodicFreq "5e+007") (periodicJitter "0") (periodicPattern "1"))) ("local132" (scope local) (stimType periodic) (Props (periodicFreq "5e+007") (periodicJitter "0") (periodicPattern "1"))) ("local131" (scope local) (stimType periodic) (Props (periodicFreq "5e+007") (periodicJitter "0") (periodicPattern "1"))) ("local0" (scope local) (stimType periodic) (Props (periodicFreq "5e+007") (periodicJitter "0") (periodicPattern "1"))) ("local1" (scope local) (stimType periodic) (Props (periodicFreq "5e+007") (periodicJitter "0") (periodicPattern "1")))) (Notes) (Constraints ("DELAY_RULE" ("CRESCENT_CITY_177_20141217_Q U36.CT9" "CRESCENT_CITY_177_20141217_Q J73.106" "LENGTH" "0.0762" "LENGTH" "0.4064")) ("RELATIVE_PROPAGATION_DELAY" ("MG" "CRESCENT_CITY_177_20141217_Q U36.CT9" "CRESCENT_CITY_177_20141217_Q J73.106" "NET GROUP" "LENGTH" "0.0127" "LENGTH" ""))) (MeasurementSets ("EMI" ("EMIStatus" status("on")) ("PeakEmission" status("on")) ("PeakFrequency" status("on")) ("PulseFreq" status("on")) ("RiseTime" status("on")) ("VoltageSwing" status("on"))) ("Reflection" ("BufferDelayFall" status("off")) ("BufferDelayRise" status("off")) ("EyeHeight" status("off")) ("EyeJitter" status("off")) ("EyeWidth" status("off")) ("FirstIncidentFall" status("off")) ("FirstIncidentRise" status("off")) ("Glitch" status("on")) ("GlitchFall" status("off")) ("GlitchRise" status("off")) ("Monotonic" status("on")) ("MonotonicFall" status("off")) ("MonotonicRise" status("off")) ("NoiseMargin" status("on")) ("NoiseMarginHigh" status("off")) ("NoiseMarginLow" status("off")) ("OvershootHigh" status("on")) ("OvershootLow" status("on")) ("PropDelay" status("on")) ("SettleDelay" status("on")) ("SettleDelayFall" status("off")) ("SettleDelayRise" status("off")) ("SwitchDelay" status("on")) ("SwitchDelayFall" status("off")) ("SwitchDelayRise" status("off"))) ("Crosstalk" ("Crosstalk" status("on"))) ("Custom")) (VectorSets) (Props (XnetName "P3E_CPU0_PE2_SS_RXN<0>") (allDrivers "active") (customSimType "Reflection") (ftsMode ("Typ")) (rcvrSelect "all") (tlineDelayMode "time") (userRevision "1.0")))) (Subckts) (CrossSections ("CRESCENT_CITY_177_20141217_Q" (Props (SXDesignName "CRESCENT_CITY_177_20141217_Q")) (Layers ("" (layerType "SURFACE") (material "AIR") (thickness "0 mil") (dielectricConstant "1.000000") (lossTangent "0") (etchFactor "0.000000") (elecCondVal "0 mho/cm") (thermCondVal "0 w/cm-degC")) ("" (layerType "DIELECTRIC") (material "CONFORMAL_COAT") (thickness "0.5 mil") (dielectricConstant "3.800000") (lossTangent "0.035") (etchFactor "0.000000") (elecCondVal "0 mho/cm") (thermCondVal "0.012 w/cm-degC")) ("TOP" (layerType "CONDUCTOR") (material "COPPER") (thickness "  2.100000 mil") (width "4.00 MIL") (dielectricConstant "4.500000") (lossTangent "0") (etchFactor "70.000000") (elecCondVal "595900.000000 mho/cm") (thermCondVal "0 w/cm-degC") (signalDieConstant "3.800000") (signalLossTangent "0.035")) ("" (layerType "DIELECTRIC") (material "FR-4") (thickness "  2.670000 mil") (dielectricConstant "4.000000") (lossTangent "0.035") (etchFactor "0.000000") (elecCondVal "0 mho/cm") (thermCondVal "0.012 w/cm-degC")) ("L2_GND1" (layerType "PLANE") (material "COPPER") (isShield t) (thickness "  1.250000 mil") (dielectricConstant "4.500000") (lossTangent "0.035") (etchFactor "90.000000") (elecCondVal "595900.000000 mho/cm") (thermCondVal "0.012 w/cm-degC")) ("" (layerType "DIELECTRIC") (material "FR-4") (thickness "  9.000000 mil") (dielectricConstant "4.100000") (lossTangent "0.035") (etchFactor "0.000000") (elecCondVal "0 mho/cm") (thermCondVal "0.012 w/cm-degC")) ("L3_SIG1" (layerType "CONDUCTOR") (material "COPPER") (thickness "  1.250000 mil") (width "4.00 MIL") (dielectricConstant "4.500000") (lossTangent "0.035") (etchFactor "90.000000") (elecCondVal "595900.000000 mho/cm") (thermCondVal "0.012 w/cm-degC") (signalDieConstant "4.100000") (signalLossTangent "0.035")) ("" (layerType "DIELECTRIC") (material "FR-4") (thickness "  3.000000 mil") (dielectricConstant "4.500000") (lossTangent "0.035") (etchFactor "0.000000") (elecCondVal "0 mho/cm") (thermCondVal "0 w/cm-degC")) ("L4_GND2" (layerType "PLANE") (material "COPPER") (isShield t) (thickness "  1.250000 mil") (dielectricConstant "4.500000") (lossTangent "0.035") (etchFactor "90.000000") (elecCondVal "595900.000000 mho/cm") (thermCondVal "0 w/cm-degC")) ("" (layerType "DIELECTRIC") (material "FR-4") (thickness "  9.000000 mil") (dielectricConstant "4.000000") (lossTangent "0.035") (etchFactor "0.000000") (elecCondVal "0 mho/cm") (thermCondVal "0.012 w/cm-degC")) ("L5_SIG2" (layerType "CONDUCTOR") (material "COPPER") (thickness "  1.250000 mil") (width "4.00 MIL") (dielectricConstant "4.500000") (lossTangent "0.035") (etchFactor "90.000000") (elecCondVal "595900.000000 mho/cm") (thermCondVal "0.012 w/cm-degC") (signalDieConstant "4.000000") (signalLossTangent "0.035")) ("" (layerType "DIELECTRIC") (material "FR-4") (thickness "  3.000000 mil") (dielectricConstant "4.500000") (lossTangent "0.035") (etchFactor "0.000000") (elecCondVal "0 mho/cm") (thermCondVal "0 w/cm-degC")) ("L6_GND3" (layerType "PLANE") (material "COPPER") (isShield t) (thickness "  1.250000 mil") (dielectricConstant "4.500000") (lossTangent "0.035") (etchFactor "90.000000") (elecCondVal "595900.000000 mho/cm") (thermCondVal "0 w/cm-degC")) ("" (layerType "DIELECTRIC") (material "FR-4") (thickness "  4.500000 mil") (dielectricConstant "4.100000") (lossTangent "0.035") (etchFactor "0.000000") (elecCondVal "0 mho/cm") (thermCondVal "0.012 w/cm-degC")) ("L7_PWR1-SIG" (layerType "PLANE") (material "COPPER") (isShield t) (thickness "  2.400000 mil") (dielectricConstant "4.500000") (lossTangent "0.035") (etchFactor "90.000000") (elecCondVal "595900.000000 mho/cm") (thermCondVal "0.012 w/cm-degC")) ("" (layerType "DIELECTRIC") (material "FR-4") (thickness "  4.600000 mil") (dielectricConstant "4.000000") (lossTangent "0.035") (etchFactor "0.000000") (elecCondVal "0 mho/cm") (thermCondVal "0.012 w/cm-degC")) ("L8_PWR2-SIG" (layerType "PLANE") (material "COPPER") (isShield t) (thickness "  2.400000 mil") (dielectricConstant "4.500000") (lossTangent "0.035") (etchFactor "90.000000") (elecCondVal "595900.000000 mho/cm") (thermCondVal "0.012 w/cm-degC")) ("" (layerType "DIELECTRIC") (material "FR-4") (thickness "  4.500000 mil") (dielectricConstant "4.500000") (lossTangent "0.035") (etchFactor "0.000000") (elecCondVal "0 mho/cm") (thermCondVal "0 w/cm-degC")) ("L9_GND4" (layerType "PLANE") (material "COPPER") (isShield t) (thickness "  1.250000 mil") (dielectricConstant "4.500000") (lossTangent "0.035") (etchFactor "90.000000") (elecCondVal "595900.000000 mho/cm") (thermCondVal "0 w/cm-degC")) ("" (layerType "DIELECTRIC") (material "FR-4") (thickness "  3.000000 mil") (dielectricConstant "4.100000") (lossTangent "0.035") (etchFactor "0.000000") (elecCondVal "0 mho/cm") (thermCondVal "0.012 w/cm-degC")) ("L10_SIG3" (layerType "CONDUCTOR") (material "COPPER") (thickness "  1.250000 mil") (width "4.00 MIL") (dielectricConstant "4.500000") (lossTangent "0.035") (etchFactor "90.000000") (elecCondVal "595900.000000 mho/cm") (thermCondVal "0.012 w/cm-degC") (signalDieConstant "4.100000") (signalLossTangent "0.035")) ("" (layerType "DIELECTRIC") (material "FR-4") (thickness "  9.000000 mil") (dielectricConstant "4.500000") (lossTangent "0.035") (etchFactor "0.000000") (elecCondVal "0 mho/cm") (thermCondVal "0 w/cm-degC")) ("L11_GND5" (layerType "PLANE") (material "COPPER") (isShield t) (thickness "  1.250000 mil") (dielectricConstant "4.500000") (lossTangent "0.035") (etchFactor "90.000000") (elecCondVal "595900.000000 mho/cm") (thermCondVal "0 w/cm-degC")) ("" (layerType "DIELECTRIC") (material "FR-4") (thickness "  3.000000 mil") (dielectricConstant "4.500000") (lossTangent "0.035") (etchFactor "0.000000") (elecCondVal "0 mho/cm") (thermCondVal "0.012 w/cm-degC")) ("L12_SIG4" (layerType "CONDUCTOR") (material "COPPER") (thickness "  1.250000 mil") (width "4.00 MIL") (dielectricConstant "4.500000") (lossTangent "0.035") (etchFactor "90.000000") (elecCondVal "595900.000000 mho/cm") (thermCondVal "0.012 w/cm-degC") (signalDieConstant "4.500000") (signalLossTangent "0.035")) ("" (layerType "DIELECTRIC") (material "FR-4") (thickness "  9.000000 mil") (dielectricConstant "4.500000") (lossTangent "0.035") (etchFactor "0.000000") (elecCondVal "0 mho/cm") (thermCondVal "0 w/cm-degC")) ("L13_GND6" (layerType "PLANE") (material "COPPER") (isShield t) (thickness "  1.250000 mil") (dielectricConstant "4.500000") (lossTangent "0.035") (etchFactor "90.000000") (elecCondVal "595900.000000 mho/cm") (thermCondVal "0.012 w/cm-degC")) ("" (layerType "DIELECTRIC") (material "FR-4") (thickness "  2.670000 mil") (dielectricConstant "4.500000") (lossTangent "0.035") (etchFactor "0.000000") (elecCondVal "0 mho/cm") (thermCondVal "0.012 w/cm-degC")) ("BOTTOM" (layerType "CONDUCTOR") (material "COPPER") (thickness "  2.100000 mil") (width "4.00 MIL") (dielectricConstant "4.500000") (lossTangent "0") (etchFactor "70.000000") (elecCondVal "595900.000000 mho/cm") (thermCondVal "0 w/cm-degC") (signalDieConstant "3.800000") (signalLossTangent "0.035")) ("" (layerType "DIELECTRIC") (material "CONFORMAL_COAT") (thickness "0.5 mil") (dielectricConstant "3.800000") (lossTangent "0.035") (etchFactor "0.000000") (elecCondVal "0 mho/cm") (thermCondVal "0.012 w/cm-degC")) ("" (layerType "SURFACE") (material "AIR") (thickness "0 mil") (dielectricConstant "1.000000") (lossTangent "0") (etchFactor "0.000000") (elecCondVal "0 mho/cm") (thermCondVal "0 w/cm-degC"))))) (Props (DesUnits "mils 2") (LayerStack ("DIELECTRIC" "DIELECTRIC" "BOTTOM" "DIELECTRIC" "L13_GND6" "DIELECTRIC" "L12_SIG4" "DIELECTRIC" "L11_GND5" "DIELECTRIC" "L10_SIG3" "DIELECTRIC" "L9_GND4" "DIELECTRIC" "L8_PWR2-SIG" "DIELECTRIC" "L7_PWR1-SIG" "DIELECTRIC" "L6_GND3" "DIELECTRIC" "L5_SIG2" "DIELECTRIC" "L4_GND2" "DIELECTRIC" "L3_SIG1" "DIELECTRIC" "L2_GND1" "DIELECTRIC" "TOP" "DIELECTRIC" "DIELECTRIC")) (Revision "16.600")) (Params (Inductor ((inductance "5 nH") (orientation "0"))) (IbisIO_OpenPullDown ((temperature "27") (bufferModel "CDSDefaultIO_2p5v") (stimuli nil) (offsets nil) (state "tristate") (cycle "1") (termMap nil) (setup "2.0e-09") (hold "1.0e-09") (rise nil) (fall nil) (macroType nil) (voltage nil) (spice nil) (LEFDEFPinName nil) (LEFDEFPinType nil) (mappingTag nil))) (DiffInputPkg ((temperature "27") (bufferModelNonInverting "CDSDefaultInput_2p5v") (bufferModelInverting "CDSDefaultInput_2p5v") (threshInputHighMin "1.7 V") (threshInputHighTyp "1.7  V") (threshInputHighMax "1.7  V") (threshInputLowMin "0.7  V") (threshInputLowTyp "0.7  V") (threshInputLowMax "0.7  V") (mappingTagNonInverting nil) (mappingTagInverting nil) (cycle "1"))) (IbisIO ((temperature "27") (bufferModel "CDSDefaultIO_2p5v") (stimuli nil) (offsets nil) (state "tristate") (cycle "1") (termMap nil) (setup "2.0e-09") (hold "1.0e-09") (rise nil) (fall nil) (macroType nil) (voltage nil) (spice nil) (LEFDEFPinName nil) (LEFDEFPinType nil) (mappingTag nil))) (Trace ((d1Thickness "10 mil") (d1Constant "4.5") (d1LossTangent "0.035") (d2Thickness "10 mil") (d2Constant "4.5") (d2LossTangent "0.035") (d3Thickness "0.0") (d3Constant "1.0") (d3LossTangent "0") length("1000 mil") (spacing "5 mil") (spacing2 "5 mil") (spacing3 "5 mil") (spacing4 "5 mil") (spacing5 "5 mil") (traceConductivity "595900 mho/cm") (traceGeometry "microstrip") (traceLayerName "") (traceThickness "0.72 mil") (traceType "single") (traceWidth "5.0 mil") (traceWidth2 "5.0 mil") (traceWidth3 "5.0 mil") (traceWidth4 "5.0 mil") (traceWidth5 "5.0 mil") (traceWidth6 "5.0 mil") (offset "0 mil") (traceCount "1") (impedance nil))) (IbisIOMacro ((temperature "27") (bufferModel "CDSDefaultIO_2p5v") (stimuli nil) (offsets nil) (state "tristate") (cycle "1") (termMap nil) (setup "2.0e-09") (hold "1.0e-09") (rise nil) (fall nil) (macroType nil) (voltage nil) (spice nil) (LEFDEFPinName nil) (LEFDEFPinType nil) (mappingTag nil))) (Capacitor ((capacitance "10 pF") (orientation "0"))) (Via ((model "Unknown") (viaOutputFormat "Unknown") (viaPadstack nil) (viaTopLayer nil) (viaBottomLayer nil) (viaIsPower nil) (viaIsGround nil))) (TLine ((diffImpedance "100ohm") (diffVelocity "1.4142e+08M/s") (impedance "60ohm") length("2800 mil") (propDelay "0.5 ns") (velocity "5600 mil/ns") (traceCount "1") (traceGeometry "Microstrip") (impedanceMin nil) (impedanceMax nil) (lengthMin nil) (lengthMax nil) (propDelayMin nil) (propDelayMax nil) (impedanceSweepCount nil) (propDelaySweepCount nil) (velocitySweepCount nil) (lengthSweepCount nil) (matchSetName nil))) (Resistor ((resistance "50 ohm") (orientation "0"))) (IbisOutputPkg ((temperature "27") (bufferModel "CDSDefaultOutput_2p5v") (stimuli nil) (offsets nil) (state "tristate") (cycle "1") (termMap nil) (setup "2.0e-09") (hold "1.0e-09") (rise nil) (fall nil) (macroType nil) (voltage nil) (spice nil) (LEFDEFPinName nil) (LEFDEFPinType nil) (mappingTag nil))) (IbisOutput_OpenPullUp ((temperature "27") (bufferModel "CDSDefaultOutput_2p5v") (stimuli nil) (offsets nil) (state "tristate") (cycle "1") (termMap nil) (setup "2.0e-09") (hold "1.0e-09") (rise nil) (fall nil) (macroType nil) (voltage nil) (spice nil) (LEFDEFPinName nil) (LEFDEFPinType nil) (mappingTag nil))) (IbisIOPkg ((temperature "27") (bufferModel "CDSDefaultIO_2p5v") (stimuli nil) (offsets nil) (state "tristate") (cycle "1") (termMap nil) (setup "2.0e-09") (hold "1.0e-09") (rise nil) (fall nil) (macroType nil) (voltage nil) (spice nil) (LEFDEFPinName nil) (LEFDEFPinType nil) (mappingTag nil))) (IbisIO_OpenPullUp ((temperature "27") (bufferModel "CDSDefaultIO_2p5v") (stimuli nil) (offsets nil) (state "tristate") (cycle "1") (termMap nil) (setup "2.0e-09") (hold "1.0e-09") (rise nil) (fall nil) (macroType nil) (voltage nil) (spice nil) (LEFDEFPinName nil) (LEFDEFPinType nil) (mappingTag nil))) (ESpiceDevice nil) (IbisInputPkg ((temperature "27") (bufferModel "CDSDefaultInput_2p5v") (cycle "1") (LEFDEFPinName nil) (LEFDEFPinType nil) (mappingTag nil))) (Source ((voltage "5 V"))) (IbisInput ((temperature "27") (bufferModel "CDSDefaultInput_2p5v") (cycle "1") (LEFDEFPinName nil) (LEFDEFPinType nil) (mappingTag nil))) (Cable (length("1 m"))) (periodic ((periodicFreq "100e6") (periodicPattern "10") (periodicJitter "0"))) (clocked ((clockRise "1e-09") (clockFall "1e-09") (clockFreq "100e6") (clockInitState "0") (clockDutyCycle "0.5") (clockJitter "0"))) (RLGC (length("1000 mil"))) (DiffInput ((temperature "27") (bufferModelNonInverting "CDSDefaultInput_2p5v") (bufferModelInverting "CDSDefaultInput_2p5v") (threshInputHighMin "1.7 V") (threshInputHighTyp "1.7  V") (threshInputHighMax "1.7  V") (threshInputLowMin "0.7  V") (threshInputLowTyp "0.7  V") (threshInputLowMax "0.7  V") (mappingTagNonInverting nil) (mappingTagInverting nil) (cycle "1"))) (async ((asyncTimePoints "") (asyncInitState "1"))) (DiffIO ((temperature "27") (bufferModelNonInverting "CDSDefaultIO_2p5v") (bufferModelInverting "CDSDefaultIO_2p5v") (stimuli nil) (offsets nil) (state "tristate") (cycle "1") (termMap nil) (setup "0.9e-09") (hold "0.4e-09") (rise nil) (fall nil) (threshInputHighMin "1.7 V") (threshInputHighTyp "1.7  V") (threshInputHighMax "1.7  V") (threshInputLowMin "0.7  V") (threshInputLowTyp "0.7  V") (threshInputLowMax "0.7 ") (threshOutputHighMin "2.365  V") (threshOutputHighTyp "2.5  V") (threshOutputHighMax "2.625  V") (threshOutputLowMin "1.275  V") (threshOutputLowTyp "1.7  V") (threshOutputLowMax "1.985  V") (mappingTagNonInverting nil) (mappingTagInverting nil) (spice nil))) (DiffOutput ((temperature "27") (bufferModelNonInverting "CDSDefaultOutput_2p5v") (bufferModelInverting "CDSDefaultOutput_2p5v") (stimuli nil) (offsets nil) (state "tristate") (cycle "1") (termMap nil) (setup "0.9e-09") (hold "0.4e-09") (rise nil) (fall nil) (threshOutputHighMin "2.375  V") (threshOutputHighTyp "2.5  V") (threshOutputHighMax "2.625  V") (threshOutputLowMin "1.275  V") (threshOutputLowTyp "1.7  V") (threshOutputLowMax "1.985  V") (mappingTagNonInverting nil) (mappingTagInverting nil) (spice nil))) (DiffIOPkg ((temperature "27") (bufferModelNonInverting "CDSDefaultIO_2p5v") (bufferModelInverting "CDSDefaultIO_2p5v") (stimuli nil) (offsets nil) (state "tristate") (cycle "1") (termMap nil) (setup "0.9e-09") (hold "0.4e-09") (rise nil) (fall nil) (threshInputHighMin "1.7 V") (threshInputHighTyp "1.7  V") (threshInputHighMax "1.7  V") (threshInputLowMin "0.7  V") (threshInputLowTyp "0.7  V") (threshInputLowMax "0.7 ") (threshOutputHighMin "2.365  V") (threshOutputHighTyp "2.5  V") (threshOutputHighMax "2.625  V") (threshOutputLowMin "1.275  V") (threshOutputLowTyp "1.7  V") (threshOutputLowMax "1.985  V") (mappingTagNonInverting nil) (mappingTagInverting nil) (spice nil))) (idlCircuit ((allDrivers "active") (ftsMode '("Typ")) (rcvrSelect "all") (simMode "Reflection") (tlineDelayMode "time") (userRevision "1.0") (autoSolve "On"))) (sync ((syncFreq "100e6") (syncInitState "1") (syncPattern "10") (syncEdgeSwitch "rise"))) (SeriesTerm ((resistance "22 ohm") (maxDelay "0.1 ns"))) (DiffOutputPkg ((temperature "27") (bufferModelNonInverting "CDSDefaultOutput_2p5v") (bufferModelInverting "CDSDefaultOutput_2p5v") (stimuli nil) (offsets nil) (state "tristate") (cycle "1") (termMap nil) (setup "0.9e-09") (hold "0.4e-09") (rise nil) (fall nil) (threshOutputHighMin "2.375  V") (threshOutputHighTyp "2.5  V") (threshOutputHighMax "2.625  V") (threshOutputLowMin "1.275  V") (threshOutputLowTyp "1.7  V") (threshOutputLowMax "1.985  V") (mappingTagNonInverting nil) (mappingTagInverting nil) (spice nil))) (IbisOutput ((temperature "27") (bufferModel "CDSDefaultOutput_2p5v") (stimuli nil) (offsets nil) (state "tristate") (cycle "1") (termMap nil) (setup "2.0e-09") (hold "1.0e-09") (rise nil) (fall nil) (macroType nil) (voltage nil) (spice nil) (LEFDEFPinName nil) (LEFDEFPinType nil) (mappingTag nil))) (CPW ((d1Thickness "10 mil") (d1Constant "4.5") (d1LossTangent "0.035") (d2Thickness "0.72 mil") (d2Constant "1") (d2LossTangent "0") (d3Thickness "0.0") (d3Constant "1") (d3LossTangent "0") length("1000 mil") (spacing "5 mil") (spacing2 "5 mil") (spacing3 "5 mil") (spacing4 "5 mil") (spacing5 "5 mil") (traceConductivity "595900 mho/cm") (traceGeometry "cpwms") (traceLayerName "") (traceThickness "0.72 mil") (traceType "single") (traceWidth "5.0 mil") (traceWidth2 "5.0 mil") (traceWidth3 "5.0 mil") (traceWidth4 "5.0 mil") (traceWidth5 "5.0 mil") (traceWidth6 "5.0 mil") (offset "0 mil") (traceCount "1") (impedance nil))) (CPWMS ((d1Thickness "10 mil") (d1Constant "4.5") (d1LossTangent "0.035") (d2Thickness "0.72 mil") (d2Constant "4.5") (d2LossTangent "0.035") (d3Thickness "0.0") (d3Constant "1") (d3LossTangent "0") length("1000 mil") (spacing "5 mil") (spacing2 "5 mil") (spacing3 "5 mil") (spacing4 "5 mil") (spacing5 "5 mil") (traceConductivity "595900 mho/cm") (traceGeometry "cpwms") (traceLayerName "") (traceThickness "0.72 mil") (traceType "single") (traceWidth "5.0 mil") (traceWidth2 "5.0 mil") (traceWidth3 "5.0 mil") (traceWidth4 "5.0 mil") (traceWidth5 "5.0 mil") (traceWidth6 "5.0 mil") (offset "0 mil") (traceCount "1") (impedance nil))) (CurrentProbe nil) (CPWSL ((d1Thickness "10 mil") (d1Constant "4.5") (d1LossTangent "0.035") (d2Thickness "0.72 mil") (d2Constant "4.5") (d2LossTangent "0.035") (d3Thickness "10 mil") (d3Constant "4.5") (d3LossTangent "0.035") length("1000 mil") (spacing "5 mil") (spacing2 "5 mil") (spacing3 "5 mil") (spacing4 "5 mil") (spacing5 "5 mil") (traceConductivity "595900 mho/cm") (traceGeometry "cpwms") (traceLayerName "") (traceThickness "0.72 mil") (traceType "single") (traceWidth "5.0 mil") (traceWidth2 "5.0 mil") (traceWidth3 "5.0 mil") (traceWidth4 "5.0 mil") (traceWidth5 "5.0 mil") (traceWidth6 "5.0 mil") (offset "0 mil") (traceCount "1") (impedance nil))) (ShuntTerm ((resistance "50 ohm") (voltage "5 V") (maxDelay "0.1 ns"))) (TheveninTerm ((resistanceUp "180 ohm") (resistanceDown "270 ohm") (voltageUp "5 V") (voltageDown "0 V") (maxDelay "0.1 ns"))) (Connector nil) (RCTerm ((resistance "50 ohm") (capacitance "20 pF") (voltage "5 V") (maxDelay "0.1 ns"))) (LowClampTerm ((cutoffVoltage "0.7 V") (voltage "0 V") (maxDelay "0.1 ns"))) (HiClampTerm ((cutoffVoltage "0.7 V") (voltage "5 V") (maxDelay "0.1 ns"))) (DualClampTerm ((cutoffVoltageUp "0.7 V") (cutoffVoltageDown "0.7 V") (voltageUp "5 V") (voltageDown "0 V") (maxDelay "0.1 ns"))) (Diode ((cutoffVoltage "0.7 V")))))
				)
				( objectStatus "PCIE_SLOT_A" )
			)
			( electricalCSet "@baseboard_fab2_lib.baseboard_fab2(sch_1):\SVID_ALERT1_CPU0_N\"
				( groupRef "SVID_ALERT1_CPU0_N:#SVID_CPU1_0_U36-EU75" )
				( groupRef "SVID_ALERT1_CPU0_N:#SVID_CPU1_0_U36-EU21" )
				( pinPairRef "SVID_ALERT1_CPU0_N:EU7A5.17:U5D1.DL44" )
				( pinPairRef "SVID_ALERT1_CPU0_N:EU7G1.17:U5D1.DL44" )
				( pinPairRef "SVID_ALERT1_CPU0_N:U5D1.DL44:R6B3.1" )
				( pinPairRef "SVID_ALERT1_CPU0_N:R6B1.2:R6B3.2" )
				( pinPairRef "SVID_ALERT1_CPU0_N:EU7A5.17:R7A11.1" )
				( pinPairRef "SVID_ALERT1_CPU0_N:EU7G1.17:R7G4.1" )
				( pinPairRef "SVID_ALERT1_CPU0_N:R7G4.2:R6B3.2" )
				( attribute "TOPOLOGY_TEMPLATE_REVISION" "1.0"
					( Origin gBackEnd )
				)
				( topologyData 28518
(SKIDL (Circuits ("MAIN" (Parts ("CRESCENT_CITY_195_20150128_Q.@@U36.DL44" IbisInputPkg (xy (5617 4235)) (refDes "U5D1") (model "Unknown") (Props (_SXDesignName "CRESCENT_CITY_195_20150128_Q") (brdx "10582.94 MIL") (brdy "3709.59 MIL") (bufferModel "CDSDefaultInput_2p5v") (mappingTag "") (temperature "27")) (Terms ("CRESCENT_CITY_195_20150128_Q.X1058294Y370959L2LRATS" "DL44"))) ("CRESCENT_CITY_195_20150128_Q.@@EU75.17" IbisOutputPkg (xy (5498 4235)) (refDes "EU7A5") (model "Unknown") (Props (_SXDesignName "CRESCENT_CITY_195_20150128_Q") (brdx "14242.1 MIL") (brdy "5463.17 MIL") (bufferModel "CDSDefaultOutput_2p5v") (cycle "1") (hold "1.0e-09") (mappingTag "") (offsets ("4" "0")) (setup "2.0e-09") (state "tristate") (stimuli ("4" "local97")) (temperature "27") (termMap ("4" "Data"))) (Terms ("CRESCENT_CITY_195_20150128_Q.X1424210Y546317L2LRATS" "17"))) ("CRESCENT_CITY_195_20150128_Q.@@EU21.17" IbisOutputPkg (xy (5556 4227)) (refDes "EU7G1") (model "Unknown") (Props (_SXDesignName "CRESCENT_CITY_195_20150128_Q") (brdx "13473.5 MIL") (brdy "581.38 MIL") (bufferModel "CDSDefaultOutput_2p5v") (cycle "1") (hold "1.0e-09") (mappingTag "") (offsets ("4" "0")) (setup "2.0e-09") (state "tristate") (stimuli ("4" "local98")) (temperature "27") (termMap ("4" "Data"))) (Terms ("CRESCENT_CITY_195_20150128_Q.X1347350Y58138L2LRATS" "17"))) ("CRESCENT_CITY_195_20150128_Q.T@@RATS@@U36.DL44@@R1194.1" TLine (xy (5603 4235)) (mirror x) (refDes "TL146") (Props (_SXDesignName "CRESCENT_CITY_195_20150128_Q") (impedance "49.728 ohm") length("3474.64 MIL") (propDelay "0.62407 ns") (traceCount "1") (traceGeometry "Microstrip") (velocity "5567.72 mil/ns")) (Terms ("CRESCENT_CITY_195_20150128_Q.X1058294Y370959L2LRATS" "1") ("CRESCENT_CITY_195_20150128_Q.X1271543Y505174L2LRATS" "2"))) ("CRESCENT_CITY_195_20150128_Q.@@R1178.1.2" Resistor (xy (5536 4229)) (refDes "R6B1") (value "49.9 Ohm") (Props (_SXDesignName "CRESCENT_CITY_195_20150128_Q")) (Terms ("CRESCENT_CITY_195_20150128_Q.X1275700Y514000L2RATS" "1") ("CRESCENT_CITY_195_20150128_Q.X1272200Y514000L2LRATS" "2"))) ("CRESCENT_CITY_195_20150128_Q.T@@RATS@@R877.2@@R1194.2" TLine (xy (5588 4227)) (refDes "TL147") (Props (_SXDesignName "CRESCENT_CITY_195_20150128_Q") (impedance "48.412 ohm") length("5031.30 MIL") (propDelay "0.90366 ns") (traceCount "1") (traceGeometry "Microstrip") (velocity "5567.72 mil/ns")) (Terms ("CRESCENT_CITY_195_20150128_Q.X1330500Y64500L2LRATS" "1") ("CRESCENT_CITY_195_20150128_Q.X1271543Y508674L2LRATS" "2"))) ("CRESCENT_CITY_195_20150128_Q.T@@RATS@@R2035.1@@EU75.17" TLine (xy (5506 4235)) (mirror x) (refDes "TL148") (Props (_SXDesignName "CRESCENT_CITY_195_20150128_Q") (impedance "48.412 ohm") length("97.12 MIL") (propDelay "0.01744 ns") (traceCount "1") (traceGeometry "Microstrip") (velocity "5568.82 mil/ns")) (Terms ("CRESCENT_CITY_195_20150128_Q.X1432560Y544955L2LRATS" "1") ("CRESCENT_CITY_195_20150128_Q.X1424210Y546317L2LRATS" "2"))) ("CRESCENT_CITY_195_20150128_Q.@@R1178.1_SOURCE" Source (xy (5529 4229)) (refDes "PVCCIO_CPU0") (value "1.05 V") (Props (_SXDesignName "CRESCENT_CITY_195_20150128_Q")) (Terms ("CRESCENT_CITY_195_20150128_Q.X1275700Y514000L2RATS" "1"))) ("CRESCENT_CITY_195_20150128_Q.T@@RATS@@R1194.2@@R1178.2" TLine (xy (5551 4235)) (mirror x) (refDes "TL149") (Props (_SXDesignName "CRESCENT_CITY_195_20150128_Q") (impedance "48.412 ohm") length("59.83 MIL") (propDelay "0.01075 ns") (traceCount "1") (traceGeometry "Microstrip") (velocity "5565.59 mil/ns")) (Terms ("CRESCENT_CITY_195_20150128_Q.X1271543Y508674L2LRATS" "1") ("CRESCENT_CITY_195_20150128_Q.X1272200Y514000L2LRATS" "2"))) ("CRESCENT_CITY_195_20150128_Q.@@R2035.2.1" Resistor (xy (5521 4235)) (mirror x) (refDes "R7A11") (value "2.2e-007 Ohm") (Props (_SXDesignName "CRESCENT_CITY_195_20150128_Q")) (Terms ("CRESCENT_CITY_195_20150128_Q.X1436060Y544955L2LRATS" "2") ("CRESCENT_CITY_195_20150128_Q.X1432560Y544955L2LRATS" "1"))) ("CRESCENT_CITY_195_20150128_Q.T@@RATS@@R1178.2@@R2035.2" TLine (xy (5536 4235)) (mirror x) (refDes "TL150") (Props (_SXDesignName "CRESCENT_CITY_195_20150128_Q") (impedance "48.412 ohm") length("1948.15 MIL") (propDelay "0.3499 ns") (traceCount "1") (traceGeometry "Microstrip") (velocity "5567.72 mil/ns")) (Terms ("CRESCENT_CITY_195_20150128_Q.X1272200Y514000L2LRATS" "1") ("CRESCENT_CITY_195_20150128_Q.X1436060Y544955L2LRATS" "2"))) ("CRESCENT_CITY_195_20150128_Q.@@R877.1.2" Resistor (xy (5579 4227)) (refDes "R7G4") (value "2.2e-007 Ohm") (Props (_SXDesignName "CRESCENT_CITY_195_20150128_Q")) (Terms ("CRESCENT_CITY_195_20150128_Q.X1334000Y64500L2LRATS" "1") ("CRESCENT_CITY_195_20150128_Q.X1330500Y64500L2LRATS" "2"))) ("CRESCENT_CITY_195_20150128_Q.T@@RATS@@R877.1@@EU21.17" TLine (xy (5570 4227)) (mirror x) (refDes "TL151") (Props (_SXDesignName "CRESCENT_CITY_195_20150128_Q") (impedance "48.412 ohm") length("197.12 MIL") (propDelay "0.0354 ns") (traceCount "1") (traceGeometry "Microstrip") (velocity "5568.35 mil/ns")) (Terms ("CRESCENT_CITY_195_20150128_Q.X1334000Y64500L2LRATS" "1") ("CRESCENT_CITY_195_20150128_Q.X1347350Y58138L2LRATS" "2"))) ("CRESCENT_CITY_195_20150128_Q.@@R1194.1.2" Resistor (xy (5588 4235)) (mirror x) (refDes "R6B3") (value "220 Ohm") (Props (_SXDesignName "CRESCENT_CITY_195_20150128_Q")) (Terms ("CRESCENT_CITY_195_20150128_Q.X1271543Y505174L2LRATS" "1") ("CRESCENT_CITY_195_20150128_Q.X1271543Y508674L2LRATS" "2")))) (Nodes ("CRESCENT_CITY_195_20150128_Q.X1424210Y546317L2LRATS" (terms "CRESCENT_CITY_195_20150128_Q.T@@RATS@@R2035.1@@EU75.17.2" "CRESCENT_CITY_195_20150128_Q.@@EU75.17.1")) ("CRESCENT_CITY_195_20150128_Q.X1271543Y508674L2LRATS" (terms "CRESCENT_CITY_195_20150128_Q.@@R1194.1.2.2" "CRESCENT_CITY_195_20150128_Q.T@@RATS@@R1194.2@@R1178.2.1" "CRESCENT_CITY_195_20150128_Q.T@@RATS@@R877.2@@R1194.2.2")) ("CRESCENT_CITY_195_20150128_Q.X1058294Y370959L2LRATS" (terms "CRESCENT_CITY_195_20150128_Q.T@@RATS@@U36.DL44@@R1194.1.1" "CRESCENT_CITY_195_20150128_Q.@@U36.DL44.1")) ("CRESCENT_CITY_195_20150128_Q.X1436060Y544955L2LRATS" (terms "CRESCENT_CITY_195_20150128_Q.T@@RATS@@R1178.2@@R2035.2.2" "CRESCENT_CITY_195_20150128_Q.@@R2035.2.1.1")) ("CRESCENT_CITY_195_20150128_Q.X1347350Y58138L2LRATS" (terms "CRESCENT_CITY_195_20150128_Q.T@@RATS@@R877.1@@EU21.17.2" "CRESCENT_CITY_195_20150128_Q.@@EU21.17.1")) ("CRESCENT_CITY_195_20150128_Q.X1275700Y514000L2RATS" (terms "CRESCENT_CITY_195_20150128_Q.@@R1178.1_SOURCE.1" "CRESCENT_CITY_195_20150128_Q.@@R1178.1.2.1")) ("CRESCENT_CITY_195_20150128_Q.X1271543Y505174L2LRATS" (terms "CRESCENT_CITY_195_20150128_Q.@@R1194.1.2.1" "CRESCENT_CITY_195_20150128_Q.T@@RATS@@U36.DL44@@R1194.1.2")) ("CRESCENT_CITY_195_20150128_Q.X1330500Y64500L2LRATS" (terms "CRESCENT_CITY_195_20150128_Q.@@R877.1.2.2" "CRESCENT_CITY_195_20150128_Q.T@@RATS@@R877.2@@R1194.2.1")) ("CRESCENT_CITY_195_20150128_Q.X1272200Y514000L2LRATS" (terms "CRESCENT_CITY_195_20150128_Q.T@@RATS@@R1178.2@@R2035.2.1" "CRESCENT_CITY_195_20150128_Q.T@@RATS@@R1194.2@@R1178.2.2" "CRESCENT_CITY_195_20150128_Q.@@R1178.1.2.2")) ("CRESCENT_CITY_195_20150128_Q.X1432560Y544955L2LRATS" (terms "CRESCENT_CITY_195_20150128_Q.@@R2035.2.1.2" "CRESCENT_CITY_195_20150128_Q.T@@RATS@@R2035.1@@EU75.17.1")) ("CRESCENT_CITY_195_20150128_Q.X1334000Y64500L2LRATS" (terms "CRESCENT_CITY_195_20150128_Q.T@@RATS@@R877.1@@EU21.17.1" "CRESCENT_CITY_195_20150128_Q.@@R877.1.2.1"))) (Ports) (Stimuli ("local97" (scope local) (stimType periodic) (Props (periodicFreq "5e+007") (periodicJitter "0") (periodicPattern "1"))) ("local98" (scope local) (stimType periodic) (Props (periodicFreq "5e+007") (periodicJitter "0") (periodicPattern "1")))) (Notes) (Constraints ("DELAY_RULE" ("CRESCENT_CITY_195_20150128_Q U36.DL44" "CRESCENT_CITY_195_20150128_Q R1194.1" "LENGTH" "" "LENGTH" "0.1143") ("CRESCENT_CITY_195_20150128_Q R1178.2" "CRESCENT_CITY_195_20150128_Q R1194.2" "LENGTH" "" "LENGTH" "0.01016") ("CRESCENT_CITY_195_20150128_Q R877.2" "CRESCENT_CITY_195_20150128_Q R1194.2" "LENGTH" "" "LENGTH" "0.6858") ("CRESCENT_CITY_195_20150128_Q R877.1" "CRESCENT_CITY_195_20150128_Q EU21.17" "LENGTH" "" "LENGTH" "0.0254") ("CRESCENT_CITY_195_20150128_Q EU75.17" "CRESCENT_CITY_195_20150128_Q R2035.1" "LENGTH" "" "LENGTH" "0.0254")) ("RELATIVE_PROPAGATION_DELAY" ("#SVID_CPU1_0_U36-EU75" "CRESCENT_CITY_195_20150128_Q EU75.17" "CRESCENT_CITY_195_20150128_Q U36.DL44" "GLOBAL" "LENGTH" "0.00635" "NONE" "") ("#SVID_CPU1_0_U36-EU21" "CRESCENT_CITY_195_20150128_Q EU21.17" "CRESCENT_CITY_195_20150128_Q U36.DL44" "GLOBAL" "LENGTH" "0.00635" "NONE" ""))) (MeasurementSets ("EMI" ("EMIStatus" status("on")) ("PeakEmission" status("on")) ("PeakFrequency" status("on")) ("PulseFreq" status("on")) ("RiseTime" status("on")) ("VoltageSwing" status("on"))) ("Reflection" ("BufferDelayFall" status("off")) ("BufferDelayRise" status("off")) ("EyeHeight" status("off")) ("EyeJitter" status("off")) ("EyeWidth" status("off")) ("FirstIncidentFall" status("off")) ("FirstIncidentRise" status("off")) ("Glitch" status("on")) ("GlitchFall" status("off")) ("GlitchRise" status("off")) ("Monotonic" status("on")) ("MonotonicFall" status("off")) ("MonotonicRise" status("off")) ("NoiseMargin" status("on")) ("NoiseMarginHigh" status("off")) ("NoiseMarginLow" status("off")) ("OvershootHigh" status("on")) ("OvershootLow" status("on")) ("PropDelay" status("on")) ("SettleDelay" status("on")) ("SettleDelayFall" status("off")) ("SettleDelayRise" status("off")) ("SwitchDelay" status("on")) ("SwitchDelayFall" status("off")) ("SwitchDelayRise" status("off"))) ("Crosstalk" ("Crosstalk" status("on"))) ("Custom")) (VectorSets) (Props (XnetName "SVID_ALERT1_CPU0_N") (allDrivers "active") (customSimType "Reflection") (ftsMode ("Typ")) (rcvrSelect "all") (tlineDelayMode "time") (userRevision "1.0")))) (Subckts) (CrossSections ("CRESCENT_CITY_195_20150128_Q" (Props (SXDesignName "CRESCENT_CITY_195_20150128_Q")) (Layers ("" (layerType "SURFACE") (material "AIR") (thickness "0 mil") (dielectricConstant "1.000000") (lossTangent "0") (etchFactor "0.000000") (elecCondVal "0 mho/cm") (thermCondVal "0 w/cm-degC")) ("" (layerType "DIELECTRIC") (material "CONFORMAL_COAT") (thickness "0.5 mil") (dielectricConstant "3.800000") (lossTangent "0.035") (etchFactor "0.000000") (elecCondVal "0 mho/cm") (thermCondVal "0.012 w/cm-degC")) ("TOP" (layerType "CONDUCTOR") (material "COPPER") (thickness "  2.100000 mil") (width "4.00 MIL") (dielectricConstant "4.500000") (lossTangent "0") (etchFactor "70.000000") (elecCondVal "595900.000000 mho/cm") (thermCondVal "0 w/cm-degC") (signalDieConstant "3.800000") (signalLossTangent "0.035")) ("" (layerType "DIELECTRIC") (material "FR-4") (thickness "  2.670000 mil") (dielectricConstant "4.000000") (lossTangent "0.035") (etchFactor "0.000000") (elecCondVal "0 mho/cm") (thermCondVal "0.012 w/cm-degC")) ("L2_GND1" (layerType "PLANE") (material "COPPER") (isShield t) (thickness "  1.250000 mil") (dielectricConstant "4.500000") (lossTangent "0.035") (etchFactor "90.000000") (elecCondVal "595900.000000 mho/cm") (thermCondVal "0.012 w/cm-degC")) ("" (layerType "DIELECTRIC") (material "FR-4") (thickness "  9.000000 mil") (dielectricConstant "4.100000") (lossTangent "0.035") (etchFactor "0.000000") (elecCondVal "0 mho/cm") (thermCondVal "0.012 w/cm-degC")) ("L3_SIG1" (layerType "CONDUCTOR") (material "COPPER") (thickness "  1.250000 mil") (width "4.00 MIL") (dielectricConstant "4.500000") (lossTangent "0.035") (etchFactor "90.000000") (elecCondVal "595900.000000 mho/cm") (thermCondVal "0.012 w/cm-degC") (signalDieConstant "4.100000") (signalLossTangent "0.035")) ("" (layerType "DIELECTRIC") (material "FR-4") (thickness "  3.000000 mil") (dielectricConstant "4.500000") (lossTangent "0.035") (etchFactor "0.000000") (elecCondVal "0 mho/cm") (thermCondVal "0 w/cm-degC")) ("L4_GND2" (layerType "PLANE") (material "COPPER") (isShield t) (thickness "  1.250000 mil") (dielectricConstant "4.500000") (lossTangent "0.035") (etchFactor "90.000000") (elecCondVal "595900.000000 mho/cm") (thermCondVal "0 w/cm-degC")) ("" (layerType "DIELECTRIC") (material "FR-4") (thickness "  9.000000 mil") (dielectricConstant "4.000000") (lossTangent "0.035") (etchFactor "0.000000") (elecCondVal "0 mho/cm") (thermCondVal "0.012 w/cm-degC")) ("L5_SIG2" (layerType "CONDUCTOR") (material "COPPER") (thickness "  1.250000 mil") (width "4.00 MIL") (dielectricConstant "4.500000") (lossTangent "0.035") (etchFactor "90.000000") (elecCondVal "595900.000000 mho/cm") (thermCondVal "0.012 w/cm-degC") (signalDieConstant "4.000000") (signalLossTangent "0.035")) ("" (layerType "DIELECTRIC") (material "FR-4") (thickness "  3.000000 mil") (dielectricConstant "4.500000") (lossTangent "0.035") (etchFactor "0.000000") (elecCondVal "0 mho/cm") (thermCondVal "0 w/cm-degC")) ("L6_GND3" (layerType "PLANE") (material "COPPER") (isShield t) (thickness "  1.250000 mil") (dielectricConstant "4.500000") (lossTangent "0.035") (etchFactor "90.000000") (elecCondVal "595900.000000 mho/cm") (thermCondVal "0 w/cm-degC")) ("" (layerType "DIELECTRIC") (material "FR-4") (thickness "  4.500000 mil") (dielectricConstant "4.100000") (lossTangent "0.035") (etchFactor "0.000000") (elecCondVal "0 mho/cm") (thermCondVal "0.012 w/cm-degC")) ("L7_PWR1-SIG" (layerType "PLANE") (material "COPPER") (isShield t) (thickness "  2.400000 mil") (dielectricConstant "4.500000") (lossTangent "0.035") (etchFactor "90.000000") (elecCondVal "595900.000000 mho/cm") (thermCondVal "0.012 w/cm-degC")) ("" (layerType "DIELECTRIC") (material "FR-4") (thickness "  4.600000 mil") (dielectricConstant "4.000000") (lossTangent "0.035") (etchFactor "0.000000") (elecCondVal "0 mho/cm") (thermCondVal "0.012 w/cm-degC")) ("L8_PWR2-SIG" (layerType "PLANE") (material "COPPER") (isShield t) (thickness "  2.400000 mil") (dielectricConstant "4.500000") (lossTangent "0.035") (etchFactor "90.000000") (elecCondVal "595900.000000 mho/cm") (thermCondVal "0.012 w/cm-degC")) ("" (layerType "DIELECTRIC") (material "FR-4") (thickness "  8.000000 mil") (dielectricConstant "4.500000") (lossTangent "0.035") (etchFactor "0.000000") (elecCondVal "0 mho/cm") (thermCondVal "0 w/cm-degC")) ("" (layerType "DIELECTRIC") (material "FR-4") (thickness "  8.000000 mil") (dielectricConstant "4.500000") (lossTangent "0.035") (etchFactor "0.000000") (elecCondVal "0 mho/cm") (thermCondVal "0 w/cm-degC")) ("" (layerType "DIELECTRIC") (material "FR-4") (thickness "  4.500000 mil") (dielectricConstant "4.500000") (lossTangent "0.035") (etchFactor "0.000000") (elecCondVal "0 mho/cm") (thermCondVal "0 w/cm-degC")) ("L9_GND4" (layerType "PLANE") (material "COPPER") (isShield t) (thickness "  1.250000 mil") (dielectricConstant "4.500000") (lossTangent "0.035") (etchFactor "90.000000") (elecCondVal "595900.000000 mho/cm") (thermCondVal "0 w/cm-degC")) ("" (layerType "DIELECTRIC") (material "FR-4") (thickness "  3.000000 mil") (dielectricConstant "4.100000") (lossTangent "0.035") (etchFactor "0.000000") (elecCondVal "0 mho/cm") (thermCondVal "0.012 w/cm-degC")) ("L10_SIG3" (layerType "CONDUCTOR") (material "COPPER") (thickness "  1.250000 mil") (width "4.00 MIL") (dielectricConstant "4.500000") (lossTangent "0.035") (etchFactor "90.000000") (elecCondVal "595900.000000 mho/cm") (thermCondVal "0.012 w/cm-degC") (signalDieConstant "4.100000") (signalLossTangent "0.035")) ("" (layerType "DIELECTRIC") (material "FR-4") (thickness "  9.000000 mil") (dielectricConstant "4.500000") (lossTangent "0.035") (etchFactor "0.000000") (elecCondVal "0 mho/cm") (thermCondVal "0 w/cm-degC")) ("L11_GND5" (layerType "PLANE") (material "COPPER") (isShield t) (thickness "  1.250000 mil") (dielectricConstant "4.500000") (lossTangent "0.035") (etchFactor "90.000000") (elecCondVal "595900.000000 mho/cm") (thermCondVal "0 w/cm-degC")) ("" (layerType "DIELECTRIC") (material "FR-4") (thickness "  3.000000 mil") (dielectricConstant "4.500000") (lossTangent "0.035") (etchFactor "0.000000") (elecCondVal "0 mho/cm") (thermCondVal "0.012 w/cm-degC")) ("L12_SIG4" (layerType "CONDUCTOR") (material "COPPER") (thickness "  1.250000 mil") (width "4.00 MIL") (dielectricConstant "4.500000") (lossTangent "0.035") (etchFactor "90.000000") (elecCondVal "595900.000000 mho/cm") (thermCondVal "0.012 w/cm-degC") (signalDieConstant "4.500000") (signalLossTangent "0.035")) ("" (layerType "DIELECTRIC") (material "FR-4") (thickness "  9.000000 mil") (dielectricConstant "4.500000") (lossTangent "0.035") (etchFactor "0.000000") (elecCondVal "0 mho/cm") (thermCondVal "0 w/cm-degC")) ("L13_GND6" (layerType "PLANE") (material "COPPER") (isShield t) (thickness "  1.250000 mil") (dielectricConstant "4.500000") (lossTangent "0.035") (etchFactor "90.000000") (elecCondVal "595900.000000 mho/cm") (thermCondVal "0.012 w/cm-degC")) ("" (layerType "DIELECTRIC") (material "FR-4") (thickness "  2.670000 mil") (dielectricConstant "4.500000") (lossTangent "0.035") (etchFactor "0.000000") (elecCondVal "0 mho/cm") (thermCondVal "0.012 w/cm-degC")) ("BOTTOM" (layerType "CONDUCTOR") (material "COPPER") (thickness "  2.100000 mil") (width "4.00 MIL") (dielectricConstant "4.500000") (lossTangent "0") (etchFactor "70.000000") (elecCondVal "595900.000000 mho/cm") (thermCondVal "0 w/cm-degC") (signalDieConstant "3.800000") (signalLossTangent "0.035")) ("" (layerType "DIELECTRIC") (material "CONFORMAL_COAT") (thickness "0.5 mil") (dielectricConstant "3.800000") (lossTangent "0.035") (etchFactor "0.000000") (elecCondVal "0 mho/cm") (thermCondVal "0.012 w/cm-degC")) ("" (layerType "SURFACE") (material "AIR") (thickness "0 mil") (dielectricConstant "1.000000") (lossTangent "0") (etchFactor "0.000000") (elecCondVal "0 mho/cm") (thermCondVal "0 w/cm-degC"))))) (Props (DesUnits "mils 2") (LayerStack ("DIELECTRIC" "DIELECTRIC" "BOTTOM" "DIELECTRIC" "L13_GND6" "DIELECTRIC" "L12_SIG4" "DIELECTRIC" "L11_GND5" "DIELECTRIC" "L10_SIG3" "DIELECTRIC" "L9_GND4" "DIELECTRIC" "DIELECTRIC" "DIELECTRIC" "L8_PWR2-SIG" "DIELECTRIC" "L7_PWR1-SIG" "DIELECTRIC" "L6_GND3" "DIELECTRIC" "L5_SIG2" "DIELECTRIC" "L4_GND2" "DIELECTRIC" "L3_SIG1" "DIELECTRIC" "L2_GND1" "DIELECTRIC" "TOP" "DIELECTRIC" "DIELECTRIC")) (Revision "16.600")) (Params (DiffOutputPkg ((temperature "27") (bufferModelNonInverting "CDSDefaultOutput_2p5v") (bufferModelInverting "CDSDefaultOutput_2p5v") (stimuli nil) (offsets nil) (state "tristate") (cycle "1") (termMap nil) (setup "0.9e-09") (hold "0.4e-09") (rise nil) (fall nil) (threshOutputHighMin "2.375  V") (threshOutputHighTyp "2.5  V") (threshOutputHighMax "2.625  V") (threshOutputLowMin "1.275  V") (threshOutputLowTyp "1.7  V") (threshOutputLowMax "1.985  V") (mappingTagNonInverting nil) (mappingTagInverting nil) (spice nil))) (HiClampTerm ((cutoffVoltage "0.7 V") (voltage "5 V") (maxDelay "0.1 ns"))) (LowClampTerm ((cutoffVoltage "0.7 V") (voltage "0 V") (maxDelay "0.1 ns"))) (DiffOutput ((temperature "27") (bufferModelNonInverting "CDSDefaultOutput_2p5v") (bufferModelInverting "CDSDefaultOutput_2p5v") (stimuli nil) (offsets nil) (state "tristate") (cycle "1") (termMap nil) (setup "0.9e-09") (hold "0.4e-09") (rise nil) (fall nil) (threshOutputHighMin "2.375  V") (threshOutputHighTyp "2.5  V") (threshOutputHighMax "2.625  V") (threshOutputLowMin "1.275  V") (threshOutputLowTyp "1.7  V") (threshOutputLowMax "1.985  V") (mappingTagNonInverting nil) (mappingTagInverting nil) (spice nil))) (Via ((model "Unknown") (viaOutputFormat "Unknown") (viaPadstack nil) (viaTopLayer nil) (viaBottomLayer nil) (viaIsPower nil) (viaIsGround nil))) (Resistor ((resistance "50 ohm") (orientation "0"))) (RCTerm ((resistance "50 ohm") (capacitance "20 pF") (voltage "5 V") (maxDelay "0.1 ns"))) (DiffIOPkg ((temperature "27") (bufferModelNonInverting "CDSDefaultIO_2p5v") (bufferModelInverting "CDSDefaultIO_2p5v") (stimuli nil) (offsets nil) (state "tristate") (cycle "1") (termMap nil) (setup "0.9e-09") (hold "0.4e-09") (rise nil) (fall nil) (threshInputHighMin "1.7 V") (threshInputHighTyp "1.7  V") (threshInputHighMax "1.7  V") (threshInputLowMin "0.7  V") (threshInputLowTyp "0.7  V") (threshInputLowMax "0.7 ") (threshOutputHighMin "2.365  V") (threshOutputHighTyp "2.5  V") (threshOutputHighMax "2.625  V") (threshOutputLowMin "1.275  V") (threshOutputLowTyp "1.7  V") (threshOutputLowMax "1.985  V") (mappingTagNonInverting nil) (mappingTagInverting nil) (spice nil))) (Trace ((d1Thickness "10 mil") (d1Constant "4.5") (d1LossTangent "0.035") (d2Thickness "10 mil") (d2Constant "4.5") (d2LossTangent "0.035") (d3Thickness "0.0") (d3Constant "1.0") (d3LossTangent "0") length("1000 mil") (spacing "5 mil") (spacing2 "5 mil") (spacing3 "5 mil") (spacing4 "5 mil") (spacing5 "5 mil") (traceConductivity "595900 mho/cm") (traceGeometry "microstrip") (traceLayerName "") (traceThickness "0.72 mil") (traceType "single") (traceWidth "5.0 mil") (traceWidth2 "5.0 mil") (traceWidth3 "5.0 mil") (traceWidth4 "5.0 mil") (traceWidth5 "5.0 mil") (traceWidth6 "5.0 mil") (offset "0 mil") (traceCount "1") (impedance nil))) (TheveninTerm ((resistanceUp "180 ohm") (resistanceDown "270 ohm") (voltageUp "5 V") (voltageDown "0 V") (maxDelay "0.1 ns"))) (DiffIO ((temperature "27") (bufferModelNonInverting "CDSDefaultIO_2p5v") (bufferModelInverting "CDSDefaultIO_2p5v") (stimuli nil) (offsets nil) (state "tristate") (cycle "1") (termMap nil) (setup "0.9e-09") (hold "0.4e-09") (rise nil) (fall nil) (threshInputHighMin "1.7 V") (threshInputHighTyp "1.7  V") (threshInputHighMax "1.7  V") (threshInputLowMin "0.7  V") (threshInputLowTyp "0.7  V") (threshInputLowMax "0.7 ") (threshOutputHighMin "2.365  V") (threshOutputHighTyp "2.5  V") (threshOutputHighMax "2.625  V") (threshOutputLowMin "1.275  V") (threshOutputLowTyp "1.7  V") (threshOutputLowMax "1.985  V") (mappingTagNonInverting nil) (mappingTagInverting nil) (spice nil))) (ShuntTerm ((resistance "50 ohm") (voltage "5 V") (maxDelay "0.1 ns"))) (Inductor ((inductance "5 nH") (orientation "0"))) (Capacitor ((capacitance "10 pF") (orientation "0"))) (RLGC (length("1000 mil"))) (Source ((voltage "5 V"))) (DiffInput ((temperature "27") (bufferModelNonInverting "CDSDefaultInput_2p5v") (bufferModelInverting "CDSDefaultInput_2p5v") (threshInputHighMin "1.7 V") (threshInputHighTyp "1.7  V") (threshInputHighMax "1.7  V") (threshInputLowMin "0.7  V") (threshInputLowTyp "0.7  V") (threshInputLowMax "0.7  V") (mappingTagNonInverting nil) (mappingTagInverting nil) (cycle "1"))) (Cable (length("1 m"))) (CPWSL ((d1Thickness "10 mil") (d1Constant "4.5") (d1LossTangent "0.035") (d2Thickness "0.72 mil") (d2Constant "4.5") (d2LossTangent "0.035") (d3Thickness "10 mil") (d3Constant "4.5") (d3LossTangent "0.035") length("1000 mil") (spacing "5 mil") (spacing2 "5 mil") (spacing3 "5 mil") (spacing4 "5 mil") (spacing5 "5 mil") (traceConductivity "595900 mho/cm") (traceGeometry "cpwms") (traceLayerName "") (traceThickness "0.72 mil") (traceType "single") (traceWidth "5.0 mil") (traceWidth2 "5.0 mil") (traceWidth3 "5.0 mil") (traceWidth4 "5.0 mil") (traceWidth5 "5.0 mil") (traceWidth6 "5.0 mil") (offset "0 mil") (traceCount "1") (impedance nil))) (ESpiceDevice nil) (CPWMS ((d1Thickness "10 mil") (d1Constant "4.5") (d1LossTangent "0.035") (d2Thickness "0.72 mil") (d2Constant "4.5") (d2LossTangent "0.035") (d3Thickness "0.0") (d3Constant "1") (d3LossTangent "0") length("1000 mil") (spacing "5 mil") (spacing2 "5 mil") (spacing3 "5 mil") (spacing4 "5 mil") (spacing5 "5 mil") (traceConductivity "595900 mho/cm") (traceGeometry "cpwms") (traceLayerName "") (traceThickness "0.72 mil") (traceType "single") (traceWidth "5.0 mil") (traceWidth2 "5.0 mil") (traceWidth3 "5.0 mil") (traceWidth4 "5.0 mil") (traceWidth5 "5.0 mil") (traceWidth6 "5.0 mil") (offset "0 mil") (traceCount "1") (impedance nil))) (Diode ((cutoffVoltage "0.7 V"))) (CPW ((d1Thickness "10 mil") (d1Constant "4.5") (d1LossTangent "0.035") (d2Thickness "0.72 mil") (d2Constant "1") (d2LossTangent "0") (d3Thickness "0.0") (d3Constant "1") (d3LossTangent "0") length("1000 mil") (spacing "5 mil") (spacing2 "5 mil") (spacing3 "5 mil") (spacing4 "5 mil") (spacing5 "5 mil") (traceConductivity "595900 mho/cm") (traceGeometry "cpwms") (traceLayerName "") (traceThickness "0.72 mil") (traceType "single") (traceWidth "5.0 mil") (traceWidth2 "5.0 mil") (traceWidth3 "5.0 mil") (traceWidth4 "5.0 mil") (traceWidth5 "5.0 mil") (traceWidth6 "5.0 mil") (offset "0 mil") (traceCount "1") (impedance nil))) (DualClampTerm ((cutoffVoltageUp "0.7 V") (cutoffVoltageDown "0.7 V") (voltageUp "5 V") (voltageDown "0 V") (maxDelay "0.1 ns"))) (IbisOutputPkg ((temperature "27") (bufferModel "CDSDefaultOutput_2p5v") (stimuli nil) (offsets nil) (state "tristate") (cycle "1") (termMap nil) (setup "2.0e-09") (hold "1.0e-09") (rise nil) (fall nil) (macroType nil) (voltage nil) (spice nil) (LEFDEFPinName nil) (LEFDEFPinType nil) (mappingTag nil))) (IbisIO_OpenPullDown ((temperature "27") (bufferModel "CDSDefaultIO_2p5v") (stimuli nil) (offsets nil) (state "tristate") (cycle "1") (termMap nil) (setup "2.0e-09") (hold "1.0e-09") (rise nil) (fall nil) (macroType nil) (voltage nil) (spice nil) (LEFDEFPinName nil) (LEFDEFPinType nil) (mappingTag nil))) (IbisInputPkg ((temperature "27") (bufferModel "CDSDefaultInput_2p5v") (cycle "1") (LEFDEFPinName nil) (LEFDEFPinType nil) (mappingTag nil))) (IbisIOMacro ((temperature "27") (bufferModel "CDSDefaultIO_2p5v") (stimuli nil) (offsets nil) (state "tristate") (cycle "1") (termMap nil) (setup "2.0e-09") (hold "1.0e-09") (rise nil) (fall nil) (macroType nil) (voltage nil) (spice nil) (LEFDEFPinName nil) (LEFDEFPinType nil) (mappingTag nil))) (IbisIO_OpenPullUp ((temperature "27") (bufferModel "CDSDefaultIO_2p5v") (stimuli nil) (offsets nil) (state "tristate") (cycle "1") (termMap nil) (setup "2.0e-09") (hold "1.0e-09") (rise nil) (fall nil) (macroType nil) (voltage nil) (spice nil) (LEFDEFPinName nil) (LEFDEFPinType nil) (mappingTag nil))) (IbisIOPkg ((temperature "27") (bufferModel "CDSDefaultIO_2p5v") (stimuli nil) (offsets nil) (state "tristate") (cycle "1") (termMap nil) (setup "2.0e-09") (hold "1.0e-09") (rise nil) (fall nil) (macroType nil) (voltage nil) (spice nil) (LEFDEFPinName nil) (LEFDEFPinType nil) (mappingTag nil))) (clocked ((clockRise "1e-09") (clockFall "1e-09") (clockFreq "100e6") (clockInitState "0") (clockDutyCycle "0.5") (clockJitter "0"))) (periodic ((periodicFreq "100e6") (periodicPattern "10") (periodicJitter "0"))) (IbisIO ((temperature "27") (bufferModel "CDSDefaultIO_2p5v") (stimuli nil) (offsets nil) (state "tristate") (cycle "1") (termMap nil) (setup "2.0e-09") (hold "1.0e-09") (rise nil) (fall nil) (macroType nil) (voltage nil) (spice nil) (LEFDEFPinName nil) (LEFDEFPinType nil) (mappingTag nil))) (async ((asyncTimePoints "") (asyncInitState "1"))) (IbisOutput ((temperature "27") (bufferModel "CDSDefaultOutput_2p5v") (stimuli nil) (offsets nil) (state "tristate") (cycle "1") (termMap nil) (setup "2.0e-09") (hold "1.0e-09") (rise nil) (fall nil) (macroType nil) (voltage nil) (spice nil) (LEFDEFPinName nil) (LEFDEFPinType nil) (mappingTag nil))) (TLine ((diffImpedance "100ohm") (diffVelocity "1.4142e+08M/s") (impedance "60ohm") length("2800 mil") (propDelay "0.5 ns") (velocity "5600 mil/ns") (traceCount "1") (traceGeometry "Microstrip") (impedanceMin nil) (impedanceMax nil) (lengthMin nil) (lengthMax nil) (propDelayMin nil) (propDelayMax nil) (impedanceSweepCount nil) (propDelaySweepCount nil) (velocitySweepCount nil) (lengthSweepCount nil) (matchSetName nil))) (CurrentProbe nil) (IbisInput ((temperature "27") (bufferModel "CDSDefaultInput_2p5v") (cycle "1") (LEFDEFPinName nil) (LEFDEFPinType nil) (mappingTag nil))) (SeriesTerm ((resistance "22 ohm") (maxDelay "0.1 ns"))) (Connector nil) (sync ((syncFreq "100e6") (syncInitState "1") (syncPattern "10") (syncEdgeSwitch "rise"))) (IbisOutput_OpenPullUp ((temperature "27") (bufferModel "CDSDefaultOutput_2p5v") (stimuli nil) (offsets nil) (state "tristate") (cycle "1") (termMap nil) (setup "2.0e-09") (hold "1.0e-09") (rise nil) (fall nil) (macroType nil) (voltage nil) (spice nil) (LEFDEFPinName nil) (LEFDEFPinType nil) (mappingTag nil))) (DiffInputPkg ((temperature "27") (bufferModelNonInverting "CDSDefaultInput_2p5v") (bufferModelInverting "CDSDefaultInput_2p5v") (threshInputHighMin "1.7 V") (threshInputHighTyp "1.7  V") (threshInputHighMax "1.7  V") (threshInputLowMin "0.7  V") (threshInputLowTyp "0.7  V") (threshInputLowMax "0.7  V") (mappingTagNonInverting nil) (mappingTagInverting nil) (cycle "1"))) (idlCircuit ((allDrivers "active") (ftsMode '("Typ")) (rcvrSelect "all") (simMode "Reflection") (tlineDelayMode "time") (userRevision "1.0") (autoSolve "On")))))
				)
				( objectStatus "SVID_ALERT1_CPU0_N" )
			)
			( electricalCSet "@baseboard_fab2_lib.baseboard_fab2(sch_1):\SVID_CLK1_CPU0\"
				( groupRef "SVID_CLK1_CPU0:#SVID_CPU1_0_U36-EU75" )
				( groupRef "SVID_CLK1_CPU0:#SVID_CPU1_0_U36-EU21" )
				( pinPairRef "SVID_CLK1_CPU0:U5D1.DG44:R7G24.1" )
				( pinPairRef "SVID_CLK1_CPU0:U5D1.DG44:R6B5.1" )
				( pinPairRef "SVID_CLK1_CPU0:R7A17.2:R3L13.2" )
				( pinPairRef "SVID_CLK1_CPU0:EU7A5.15:R7A17.1" )
				( pinPairRef "SVID_CLK1_CPU0:EU7G1.15:R7G24.2" )
				( pinPairRef "SVID_CLK1_CPU0:U5D1.DG44:EU7A5.15" )
				( pinPairRef "SVID_CLK1_CPU0:U5D1.DG44:EU7G1.15" )
				( attribute "TOPOLOGY_TEMPLATE_REVISION" "1.0"
					( Origin gBackEnd )
				)
				( topologyData 29486
(SKIDL (Circuits ("MAIN" (Parts ("CRESCENT_CITY_195_20150128_Q.@@U36.DG44" IbisOutputPkg (xy (5498 4235)) (refDes "U5D1") (model "Unknown") (Props (_SXDesignName "CRESCENT_CITY_195_20150128_Q") (brdx "10582.94 MIL") (brdy "3631.6 MIL") (bufferModel "CDSDefaultOutput_2p5v") (cycle "1") (hold "1.0e-09") (mappingTag "") (offsets ("4" "0")) (setup "2.0e-09") (state "tristate") (stimuli ("4" "local39")) (temperature "27") (termMap ("4" "Data"))) (Terms ("CRESCENT_CITY_195_20150128_Q.X1058294Y363160L2LRATS" "DG44"))) ("CRESCENT_CITY_195_20150128_Q.@@EU21.15" IbisInputPkg (xy (5565 4221)) (refDes "EU7G1") (model "Unknown") (Props (_SXDesignName "CRESCENT_CITY_195_20150128_Q") (brdx "13473.5 MIL") (brdy "612.87 MIL") (bufferModel "CDSDefaultInput_2p5v") (mappingTag "") (temperature "27")) (Terms ("CRESCENT_CITY_195_20150128_Q.X1347350Y61287L2LRATS" "15"))) ("CRESCENT_CITY_195_20150128_Q.@@EU75.15" IbisInputPkg (xy (5557 4235)) (refDes "EU7A5") (model "Unknown") (Props (_SXDesignName "CRESCENT_CITY_195_20150128_Q") (brdx "14242.1 MIL") (brdy "5431.68 MIL") (bufferModel "CDSDefaultInput_2p5v") (mappingTag "") (temperature "27")) (Terms ("CRESCENT_CITY_195_20150128_Q.X1424210Y543168L2LRATS" "15"))) ("CRESCENT_CITY_195_20150128_Q.@@R1193.1.2" Resistor (xy (5515 4235)) (refDes "R6B5") (value "2.2e-007 Ohm") (Props (_SXDesignName "CRESCENT_CITY_195_20150128_Q")) (Terms ("CRESCENT_CITY_195_20150128_Q.X1278043Y505174L2LRATS" "1") ("CRESCENT_CITY_195_20150128_Q.X1278043Y508674L2LRATS" "2"))) ("CRESCENT_CITY_195_20150128_Q.@@R2831.2.1" Resistor (xy (5542 4221)) (mirror x) (refDes "R7G24") (value "150 Ohm") (Props (_SXDesignName "CRESCENT_CITY_195_20150128_Q")) (Terms ("CRESCENT_CITY_195_20150128_Q.X1334000Y71500L2LRATS" "2") ("CRESCENT_CITY_195_20150128_Q.X1330500Y71500L2LRATS" "1"))) ("CRESCENT_CITY_195_20150128_Q.T@@RATS@@U36.DG44@@R1193.1" TLine (xy (5506 4235)) (refDes "TL50") (Props (_SXDesignName "CRESCENT_CITY_195_20150128_Q") (impedance "49.728 ohm") length("3617.63 MIL") (propDelay "0.64975 ns") (traceCount "1") (traceGeometry "Microstrip") (velocity "5567.72 mil/ns")) (Terms ("CRESCENT_CITY_195_20150128_Q.X1058294Y363160L2LRATS" "1") ("CRESCENT_CITY_195_20150128_Q.X1278043Y505174L2LRATS" "2"))) ("CRESCENT_CITY_195_20150128_Q.T@@RATS@@R2027.1@@R2026.2" TLine (xy (5540 4228)) (mirror x) (refDes "TL51") (Props (_SXDesignName "CRESCENT_CITY_195_20150128_Q") (impedance "48.412 ohm") (propDelay "1.79607e-006 ns") (traceCount "1") (traceGeometry "Microstrip")) (Terms ("CRESCENT_CITY_195_20150128_Q.X1436060Y537955L2LRATS" "1") ("CRESCENT_CITY_195_20150128_Q.X1436060Y537955L30LRATS" "2"))) ("CRESCENT_CITY_195_20150128_Q.@@R2027.1.2" Resistor (xy (5540 4235)) (refDes "R7A17") (value "150 Ohm") (Props (_SXDesignName "CRESCENT_CITY_195_20150128_Q")) (Terms ("CRESCENT_CITY_195_20150128_Q.X1436060Y537955L2LRATS" "1") ("CRESCENT_CITY_195_20150128_Q.X1432560Y537955L2LRATS" "2"))) ("CRESCENT_CITY_195_20150128_Q.@@R868.1.2" Resistor (xy (5524 4215)) (refDes "R3T11") (value "1 Ohm") (Props (_SXDesignName "CRESCENT_CITY_195_20150128_Q")) (Terms ("CRESCENT_CITY_195_20150128_Q.X1334000Y71510L30RATS" "1") ("CRESCENT_CITY_195_20150128_Q.X1330500Y71510L30LRATS" "2"))) ("CRESCENT_CITY_195_20150128_Q.@@R2026.1.2" Resistor (xy (5525 4228)) (refDes "R3L13") (value "49.9 Ohm") (Props (_SXDesignName "CRESCENT_CITY_195_20150128_Q")) (Terms ("CRESCENT_CITY_195_20150128_Q.X1432560Y537955L30RATS" "1") ("CRESCENT_CITY_195_20150128_Q.X1436060Y537955L30LRATS" "2"))) ("CRESCENT_CITY_195_20150128_Q.@@R868.1_SOURCE" Source (xy (5517 4215)) (refDes "PVCCIO_CPU0_1") (value "1.05 V") (Props (_SXDesignName "CRESCENT_CITY_195_20150128_Q")) (Terms ("CRESCENT_CITY_195_20150128_Q.X1334000Y71510L30RATS" "1"))) ("CRESCENT_CITY_195_20150128_Q.T@@RATS@@R1193.2@@R868.2" TLine (xy (5524 4221)) (refDes "TL52") (Props (_SXDesignName "CRESCENT_CITY_195_20150128_Q") (impedance "48.412 ohm") length("4896.22 MIL") (propDelay "0.87939 ns") (traceCount "1") (traceGeometry "Microstrip") (velocity "5567.72 mil/ns")) (Terms ("CRESCENT_CITY_195_20150128_Q.X1278043Y508674L2LRATS" "1") ("CRESCENT_CITY_195_20150128_Q.X1330500Y71510L30LRATS" "2"))) ("CRESCENT_CITY_195_20150128_Q.@@R2026.1_SOURCE" Source (xy (5518 4228)) (refDes "PVCCIO_CPU0") (value "1.05 V") (Props (_SXDesignName "CRESCENT_CITY_195_20150128_Q")) (Terms ("CRESCENT_CITY_195_20150128_Q.X1432560Y537955L30RATS" "1"))) ("CRESCENT_CITY_195_20150128_Q.T@@RATS@@R2831.2@@EU21.15" TLine (xy (5557 4221)) (refDes "TL53") (Props (_SXDesignName "CRESCENT_CITY_195_20150128_Q") (impedance "48.412 ohm") length("235.63 MIL") (propDelay "0.04232 ns") (traceCount "1") (traceGeometry "Microstrip") (velocity "5567.83 mil/ns")) (Terms ("CRESCENT_CITY_195_20150128_Q.X1334000Y71500L2LRATS" "1") ("CRESCENT_CITY_195_20150128_Q.X1347350Y61287L2LRATS" "2"))) ("CRESCENT_CITY_195_20150128_Q.T@@RATS@@R1193.2@@R2027.1" TLine (xy (5524 4235)) (refDes "TL54") (Props (_SXDesignName "CRESCENT_CITY_195_20150128_Q") (impedance "48.412 ohm") length("1872.98 MIL") (propDelay "0.3364 ns") (traceCount "1") (traceGeometry "Microstrip") (velocity "5567.72 mil/ns")) (Terms ("CRESCENT_CITY_195_20150128_Q.X1278043Y508674L2LRATS" "1") ("CRESCENT_CITY_195_20150128_Q.X1436060Y537955L2LRATS" "2"))) ("CRESCENT_CITY_195_20150128_Q.T@@RATS@@R2027.2@@EU75.15" TLine (xy (5549 4235)) (refDes "TL55") (Props (_SXDesignName "CRESCENT_CITY_195_20150128_Q") (impedance "48.412 ohm") length("135.63 MIL") (propDelay "0.02436 ns") (traceCount "1") (traceGeometry "Microstrip") (velocity "5567.72 mil/ns")) (Terms ("CRESCENT_CITY_195_20150128_Q.X1432560Y537955L2LRATS" "1") ("CRESCENT_CITY_195_20150128_Q.X1424210Y543168L2LRATS" "2"))) ("CRESCENT_CITY_195_20150128_Q.T@@RATS@@R868.2@@R2831.1" TLine (xy (5533 4221)) (refDes "TL56") (Props (_SXDesignName "CRESCENT_CITY_195_20150128_Q") (impedance "48.412 ohm") length("0.10 MIL") (propDelay "2e-005 ns") (traceCount "1") (traceGeometry "Microstrip") (velocity "5000 mil/ns")) (Terms ("CRESCENT_CITY_195_20150128_Q.X1330500Y71510L30LRATS" "1") ("CRESCENT_CITY_195_20150128_Q.X1330500Y71500L2LRATS" "2")))) (Nodes ("CRESCENT_CITY_195_20150128_Q.X1058294Y363160L2LRATS" (terms "CRESCENT_CITY_195_20150128_Q.T@@RATS@@U36.DG44@@R1193.1.1" "CRESCENT_CITY_195_20150128_Q.@@U36.DG44.1")) ("CRESCENT_CITY_195_20150128_Q.X1432560Y537955L2LRATS" (terms "CRESCENT_CITY_195_20150128_Q.T@@RATS@@R2027.2@@EU75.15.1" "CRESCENT_CITY_195_20150128_Q.@@R2027.1.2.2")) ("CRESCENT_CITY_195_20150128_Q.X1424210Y543168L2LRATS" (terms "CRESCENT_CITY_195_20150128_Q.T@@RATS@@R2027.2@@EU75.15.2" "CRESCENT_CITY_195_20150128_Q.@@EU75.15.1")) ("CRESCENT_CITY_195_20150128_Q.X1278043Y505174L2LRATS" (terms "CRESCENT_CITY_195_20150128_Q.T@@RATS@@U36.DG44@@R1193.1.2" "CRESCENT_CITY_195_20150128_Q.@@R1193.1.2.1")) ("CRESCENT_CITY_195_20150128_Q.X1436060Y537955L2LRATS" (terms "CRESCENT_CITY_195_20150128_Q.T@@RATS@@R1193.2@@R2027.1.2" "CRESCENT_CITY_195_20150128_Q.@@R2027.1.2.1" "CRESCENT_CITY_195_20150128_Q.T@@RATS@@R2027.1@@R2026.2.1")) ("CRESCENT_CITY_195_20150128_Q.X1347350Y61287L2LRATS" (terms "CRESCENT_CITY_195_20150128_Q.T@@RATS@@R2831.2@@EU21.15.2" "CRESCENT_CITY_195_20150128_Q.@@EU21.15.1")) ("CRESCENT_CITY_195_20150128_Q.X1330500Y71500L2LRATS" (terms "CRESCENT_CITY_195_20150128_Q.T@@RATS@@R868.2@@R2831.1.2" "CRESCENT_CITY_195_20150128_Q.@@R2831.2.1.2")) ("CRESCENT_CITY_195_20150128_Q.X1334000Y71500L2LRATS" (terms "CRESCENT_CITY_195_20150128_Q.T@@RATS@@R2831.2@@EU21.15.1" "CRESCENT_CITY_195_20150128_Q.@@R2831.2.1.1")) ("CRESCENT_CITY_195_20150128_Q.X1278043Y508674L2LRATS" (terms "CRESCENT_CITY_195_20150128_Q.T@@RATS@@R1193.2@@R2027.1.1" "CRESCENT_CITY_195_20150128_Q.T@@RATS@@R1193.2@@R868.2.1" "CRESCENT_CITY_195_20150128_Q.@@R1193.1.2.2")) ("CRESCENT_CITY_195_20150128_Q.X1436060Y537955L30LRATS" (terms "CRESCENT_CITY_195_20150128_Q.@@R2026.1.2.2" "CRESCENT_CITY_195_20150128_Q.T@@RATS@@R2027.1@@R2026.2.2")) ("CRESCENT_CITY_195_20150128_Q.X1334000Y71510L30RATS" (terms "CRESCENT_CITY_195_20150128_Q.@@R868.1_SOURCE.1" "CRESCENT_CITY_195_20150128_Q.@@R868.1.2.1")) ("CRESCENT_CITY_195_20150128_Q.X1330500Y71510L30LRATS" (terms "CRESCENT_CITY_195_20150128_Q.T@@RATS@@R868.2@@R2831.1.1" "CRESCENT_CITY_195_20150128_Q.T@@RATS@@R1193.2@@R868.2.2" "CRESCENT_CITY_195_20150128_Q.@@R868.1.2.2")) ("CRESCENT_CITY_195_20150128_Q.X1432560Y537955L30RATS" (terms "CRESCENT_CITY_195_20150128_Q.@@R2026.1_SOURCE.1" "CRESCENT_CITY_195_20150128_Q.@@R2026.1.2.1"))) (Ports) (Stimuli ("local39" (scope local) (stimType periodic) (Props (periodicFreq "5e+007") (periodicJitter "0") (periodicPattern "1")))) (Notes) (Constraints ("DELAY_RULE" ("CRESCENT_CITY_195_20150128_Q U36.DG44" "CRESCENT_CITY_195_20150128_Q R2831.1" "LENGTH" "" "LENGTH" "0.6858") ("CRESCENT_CITY_195_20150128_Q U36.DG44" "CRESCENT_CITY_195_20150128_Q R1193.1" "LENGTH" "" "LENGTH" "0.1143") ("CRESCENT_CITY_195_20150128_Q R2027.2" "CRESCENT_CITY_195_20150128_Q R2026.2" "LENGTH" "" "LENGTH" "0.00508") ("CRESCENT_CITY_195_20150128_Q EU75.15" "CRESCENT_CITY_195_20150128_Q R2027.1" "LENGTH" "" "LENGTH" "0.0254") ("CRESCENT_CITY_195_20150128_Q EU21.15" "CRESCENT_CITY_195_20150128_Q R2831.2" "LENGTH" "" "LENGTH" "0.0254")) ("RELATIVE_PROPAGATION_DELAY" ("#SVID_CPU1_0_U36-EU75" "CRESCENT_CITY_195_20150128_Q U36.DG44" "CRESCENT_CITY_195_20150128_Q EU75.15" "GLOBAL" "LENGTH" "0.00635" "NONE" "") ("#SVID_CPU1_0_U36-EU21" "CRESCENT_CITY_195_20150128_Q U36.DG44" "CRESCENT_CITY_195_20150128_Q EU21.15" "GLOBAL" "LENGTH" "0.00635" "NONE" ""))) (MeasurementSets ("EMI" ("EMIStatus" status("on")) ("PeakEmission" status("on")) ("PeakFrequency" status("on")) ("PulseFreq" status("on")) ("RiseTime" status("on")) ("VoltageSwing" status("on"))) ("Reflection" ("BufferDelayFall" status("off")) ("BufferDelayRise" status("off")) ("EyeHeight" status("off")) ("EyeJitter" status("off")) ("EyeWidth" status("off")) ("FirstIncidentFall" status("off")) ("FirstIncidentRise" status("off")) ("Glitch" status("on")) ("GlitchFall" status("off")) ("GlitchRise" status("off")) ("Monotonic" status("on")) ("MonotonicFall" status("off")) ("MonotonicRise" status("off")) ("NoiseMargin" status("on")) ("NoiseMarginHigh" status("off")) ("NoiseMarginLow" status("off")) ("OvershootHigh" status("on")) ("OvershootLow" status("on")) ("PropDelay" status("on")) ("SettleDelay" status("on")) ("SettleDelayFall" status("off")) ("SettleDelayRise" status("off")) ("SwitchDelay" status("on")) ("SwitchDelayFall" status("off")) ("SwitchDelayRise" status("off"))) ("Crosstalk" ("Crosstalk" status("on"))) ("Custom")) (VectorSets) (Props (XnetName "SVID_CLK1_CPU0") (allDrivers "active") (customSimType "Reflection") (ftsMode ("Typ")) (rcvrSelect "all") (tlineDelayMode "time") (userRevision "1.0")))) (Subckts) (CrossSections ("CRESCENT_CITY_195_20150128_Q" (Props (SXDesignName "CRESCENT_CITY_195_20150128_Q")) (Layers ("" (layerType "SURFACE") (material "AIR") (thickness "0 mil") (dielectricConstant "1.000000") (lossTangent "0") (etchFactor "0.000000") (elecCondVal "0 mho/cm") (thermCondVal "0 w/cm-degC")) ("" (layerType "DIELECTRIC") (material "CONFORMAL_COAT") (thickness "0.5 mil") (dielectricConstant "3.800000") (lossTangent "0.035") (etchFactor "0.000000") (elecCondVal "0 mho/cm") (thermCondVal "0.012 w/cm-degC")) ("TOP" (layerType "CONDUCTOR") (material "COPPER") (thickness "  2.100000 mil") (width "4.00 MIL") (dielectricConstant "4.500000") (lossTangent "0") (etchFactor "70.000000") (elecCondVal "595900.000000 mho/cm") (thermCondVal "0 w/cm-degC") (signalDieConstant "3.800000") (signalLossTangent "0.035")) ("" (layerType "DIELECTRIC") (material "FR-4") (thickness "  2.670000 mil") (dielectricConstant "4.000000") (lossTangent "0.035") (etchFactor "0.000000") (elecCondVal "0 mho/cm") (thermCondVal "0.012 w/cm-degC")) ("L2_GND1" (layerType "PLANE") (material "COPPER") (isShield t) (thickness "  1.250000 mil") (dielectricConstant "4.500000") (lossTangent "0.035") (etchFactor "90.000000") (elecCondVal "595900.000000 mho/cm") (thermCondVal "0.012 w/cm-degC")) ("" (layerType "DIELECTRIC") (material "FR-4") (thickness "  9.000000 mil") (dielectricConstant "4.100000") (lossTangent "0.035") (etchFactor "0.000000") (elecCondVal "0 mho/cm") (thermCondVal "0.012 w/cm-degC")) ("L3_SIG1" (layerType "CONDUCTOR") (material "COPPER") (thickness "  1.250000 mil") (width "4.00 MIL") (dielectricConstant "4.500000") (lossTangent "0.035") (etchFactor "90.000000") (elecCondVal "595900.000000 mho/cm") (thermCondVal "0.012 w/cm-degC") (signalDieConstant "4.100000") (signalLossTangent "0.035")) ("" (layerType "DIELECTRIC") (material "FR-4") (thickness "  3.000000 mil") (dielectricConstant "4.500000") (lossTangent "0.035") (etchFactor "0.000000") (elecCondVal "0 mho/cm") (thermCondVal "0 w/cm-degC")) ("L4_GND2" (layerType "PLANE") (material "COPPER") (isShield t) (thickness "  1.250000 mil") (dielectricConstant "4.500000") (lossTangent "0.035") (etchFactor "90.000000") (elecCondVal "595900.000000 mho/cm") (thermCondVal "0 w/cm-degC")) ("" (layerType "DIELECTRIC") (material "FR-4") (thickness "  9.000000 mil") (dielectricConstant "4.000000") (lossTangent "0.035") (etchFactor "0.000000") (elecCondVal "0 mho/cm") (thermCondVal "0.012 w/cm-degC")) ("L5_SIG2" (layerType "CONDUCTOR") (material "COPPER") (thickness "  1.250000 mil") (width "4.00 MIL") (dielectricConstant "4.500000") (lossTangent "0.035") (etchFactor "90.000000") (elecCondVal "595900.000000 mho/cm") (thermCondVal "0.012 w/cm-degC") (signalDieConstant "4.000000") (signalLossTangent "0.035")) ("" (layerType "DIELECTRIC") (material "FR-4") (thickness "  3.000000 mil") (dielectricConstant "4.500000") (lossTangent "0.035") (etchFactor "0.000000") (elecCondVal "0 mho/cm") (thermCondVal "0 w/cm-degC")) ("L6_GND3" (layerType "PLANE") (material "COPPER") (isShield t) (thickness "  1.250000 mil") (dielectricConstant "4.500000") (lossTangent "0.035") (etchFactor "90.000000") (elecCondVal "595900.000000 mho/cm") (thermCondVal "0 w/cm-degC")) ("" (layerType "DIELECTRIC") (material "FR-4") (thickness "  4.500000 mil") (dielectricConstant "4.100000") (lossTangent "0.035") (etchFactor "0.000000") (elecCondVal "0 mho/cm") (thermCondVal "0.012 w/cm-degC")) ("L7_PWR1-SIG" (layerType "PLANE") (material "COPPER") (isShield t) (thickness "  2.400000 mil") (dielectricConstant "4.500000") (lossTangent "0.035") (etchFactor "90.000000") (elecCondVal "595900.000000 mho/cm") (thermCondVal "0.012 w/cm-degC")) ("" (layerType "DIELECTRIC") (material "FR-4") (thickness "  4.600000 mil") (dielectricConstant "4.000000") (lossTangent "0.035") (etchFactor "0.000000") (elecCondVal "0 mho/cm") (thermCondVal "0.012 w/cm-degC")) ("L8_PWR2-SIG" (layerType "PLANE") (material "COPPER") (isShield t) (thickness "  2.400000 mil") (dielectricConstant "4.500000") (lossTangent "0.035") (etchFactor "90.000000") (elecCondVal "595900.000000 mho/cm") (thermCondVal "0.012 w/cm-degC")) ("" (layerType "DIELECTRIC") (material "FR-4") (thickness "  8.000000 mil") (dielectricConstant "4.500000") (lossTangent "0.035") (etchFactor "0.000000") (elecCondVal "0 mho/cm") (thermCondVal "0 w/cm-degC")) ("" (layerType "DIELECTRIC") (material "FR-4") (thickness "  8.000000 mil") (dielectricConstant "4.500000") (lossTangent "0.035") (etchFactor "0.000000") (elecCondVal "0 mho/cm") (thermCondVal "0 w/cm-degC")) ("" (layerType "DIELECTRIC") (material "FR-4") (thickness "  4.500000 mil") (dielectricConstant "4.500000") (lossTangent "0.035") (etchFactor "0.000000") (elecCondVal "0 mho/cm") (thermCondVal "0 w/cm-degC")) ("L9_GND4" (layerType "PLANE") (material "COPPER") (isShield t) (thickness "  1.250000 mil") (dielectricConstant "4.500000") (lossTangent "0.035") (etchFactor "90.000000") (elecCondVal "595900.000000 mho/cm") (thermCondVal "0 w/cm-degC")) ("" (layerType "DIELECTRIC") (material "FR-4") (thickness "  3.000000 mil") (dielectricConstant "4.100000") (lossTangent "0.035") (etchFactor "0.000000") (elecCondVal "0 mho/cm") (thermCondVal "0.012 w/cm-degC")) ("L10_SIG3" (layerType "CONDUCTOR") (material "COPPER") (thickness "  1.250000 mil") (width "4.00 MIL") (dielectricConstant "4.500000") (lossTangent "0.035") (etchFactor "90.000000") (elecCondVal "595900.000000 mho/cm") (thermCondVal "0.012 w/cm-degC") (signalDieConstant "4.100000") (signalLossTangent "0.035")) ("" (layerType "DIELECTRIC") (material "FR-4") (thickness "  9.000000 mil") (dielectricConstant "4.500000") (lossTangent "0.035") (etchFactor "0.000000") (elecCondVal "0 mho/cm") (thermCondVal "0 w/cm-degC")) ("L11_GND5" (layerType "PLANE") (material "COPPER") (isShield t) (thickness "  1.250000 mil") (dielectricConstant "4.500000") (lossTangent "0.035") (etchFactor "90.000000") (elecCondVal "595900.000000 mho/cm") (thermCondVal "0 w/cm-degC")) ("" (layerType "DIELECTRIC") (material "FR-4") (thickness "  3.000000 mil") (dielectricConstant "4.500000") (lossTangent "0.035") (etchFactor "0.000000") (elecCondVal "0 mho/cm") (thermCondVal "0.012 w/cm-degC")) ("L12_SIG4" (layerType "CONDUCTOR") (material "COPPER") (thickness "  1.250000 mil") (width "4.00 MIL") (dielectricConstant "4.500000") (lossTangent "0.035") (etchFactor "90.000000") (elecCondVal "595900.000000 mho/cm") (thermCondVal "0.012 w/cm-degC") (signalDieConstant "4.500000") (signalLossTangent "0.035")) ("" (layerType "DIELECTRIC") (material "FR-4") (thickness "  9.000000 mil") (dielectricConstant "4.500000") (lossTangent "0.035") (etchFactor "0.000000") (elecCondVal "0 mho/cm") (thermCondVal "0 w/cm-degC")) ("L13_GND6" (layerType "PLANE") (material "COPPER") (isShield t) (thickness "  1.250000 mil") (dielectricConstant "4.500000") (lossTangent "0.035") (etchFactor "90.000000") (elecCondVal "595900.000000 mho/cm") (thermCondVal "0.012 w/cm-degC")) ("" (layerType "DIELECTRIC") (material "FR-4") (thickness "  2.670000 mil") (dielectricConstant "4.500000") (lossTangent "0.035") (etchFactor "0.000000") (elecCondVal "0 mho/cm") (thermCondVal "0.012 w/cm-degC")) ("BOTTOM" (layerType "CONDUCTOR") (material "COPPER") (thickness "  2.100000 mil") (width "4.00 MIL") (dielectricConstant "4.500000") (lossTangent "0") (etchFactor "70.000000") (elecCondVal "595900.000000 mho/cm") (thermCondVal "0 w/cm-degC") (signalDieConstant "3.800000") (signalLossTangent "0.035")) ("" (layerType "DIELECTRIC") (material "CONFORMAL_COAT") (thickness "0.5 mil") (dielectricConstant "3.800000") (lossTangent "0.035") (etchFactor "0.000000") (elecCondVal "0 mho/cm") (thermCondVal "0.012 w/cm-degC")) ("" (layerType "SURFACE") (material "AIR") (thickness "0 mil") (dielectricConstant "1.000000") (lossTangent "0") (etchFactor "0.000000") (elecCondVal "0 mho/cm") (thermCondVal "0 w/cm-degC"))))) (Props (DesUnits "mils 2") (LayerStack ("DIELECTRIC" "DIELECTRIC" "BOTTOM" "DIELECTRIC" "L13_GND6" "DIELECTRIC" "L12_SIG4" "DIELECTRIC" "L11_GND5" "DIELECTRIC" "L10_SIG3" "DIELECTRIC" "L9_GND4" "DIELECTRIC" "DIELECTRIC" "DIELECTRIC" "L8_PWR2-SIG" "DIELECTRIC" "L7_PWR1-SIG" "DIELECTRIC" "L6_GND3" "DIELECTRIC" "L5_SIG2" "DIELECTRIC" "L4_GND2" "DIELECTRIC" "L3_SIG1" "DIELECTRIC" "L2_GND1" "DIELECTRIC" "TOP" "DIELECTRIC" "DIELECTRIC")) (Revision "16.600")) (Params (DiffOutputPkg ((temperature "27") (bufferModelNonInverting "CDSDefaultOutput_2p5v") (bufferModelInverting "CDSDefaultOutput_2p5v") (stimuli nil) (offsets nil) (state "tristate") (cycle "1") (termMap nil) (setup "0.9e-09") (hold "0.4e-09") (rise nil) (fall nil) (threshOutputHighMin "2.375  V") (threshOutputHighTyp "2.5  V") (threshOutputHighMax "2.625  V") (threshOutputLowMin "1.275  V") (threshOutputLowTyp "1.7  V") (threshOutputLowMax "1.985  V") (mappingTagNonInverting nil) (mappingTagInverting nil) (spice nil))) (HiClampTerm ((cutoffVoltage "0.7 V") (voltage "5 V") (maxDelay "0.1 ns"))) (LowClampTerm ((cutoffVoltage "0.7 V") (voltage "0 V") (maxDelay "0.1 ns"))) (DiffOutput ((temperature "27") (bufferModelNonInverting "CDSDefaultOutput_2p5v") (bufferModelInverting "CDSDefaultOutput_2p5v") (stimuli nil) (offsets nil) (state "tristate") (cycle "1") (termMap nil) (setup "0.9e-09") (hold "0.4e-09") (rise nil) (fall nil) (threshOutputHighMin "2.375  V") (threshOutputHighTyp "2.5  V") (threshOutputHighMax "2.625  V") (threshOutputLowMin "1.275  V") (threshOutputLowTyp "1.7  V") (threshOutputLowMax "1.985  V") (mappingTagNonInverting nil) (mappingTagInverting nil) (spice nil))) (Via ((model "Unknown") (viaOutputFormat "Unknown") (viaPadstack nil) (viaTopLayer nil) (viaBottomLayer nil) (viaIsPower nil) (viaIsGround nil))) (Resistor ((resistance "50 ohm") (orientation "0"))) (RCTerm ((resistance "50 ohm") (capacitance "20 pF") (voltage "5 V") (maxDelay "0.1 ns"))) (DiffIOPkg ((temperature "27") (bufferModelNonInverting "CDSDefaultIO_2p5v") (bufferModelInverting "CDSDefaultIO_2p5v") (stimuli nil) (offsets nil) (state "tristate") (cycle "1") (termMap nil) (setup "0.9e-09") (hold "0.4e-09") (rise nil) (fall nil) (threshInputHighMin "1.7 V") (threshInputHighTyp "1.7  V") (threshInputHighMax "1.7  V") (threshInputLowMin "0.7  V") (threshInputLowTyp "0.7  V") (threshInputLowMax "0.7 ") (threshOutputHighMin "2.365  V") (threshOutputHighTyp "2.5  V") (threshOutputHighMax "2.625  V") (threshOutputLowMin "1.275  V") (threshOutputLowTyp "1.7  V") (threshOutputLowMax "1.985  V") (mappingTagNonInverting nil) (mappingTagInverting nil) (spice nil))) (Trace ((d1Thickness "10 mil") (d1Constant "4.5") (d1LossTangent "0.035") (d2Thickness "10 mil") (d2Constant "4.5") (d2LossTangent "0.035") (d3Thickness "0.0") (d3Constant "1.0") (d3LossTangent "0") length("1000 mil") (spacing "5 mil") (spacing2 "5 mil") (spacing3 "5 mil") (spacing4 "5 mil") (spacing5 "5 mil") (traceConductivity "595900 mho/cm") (traceGeometry "microstrip") (traceLayerName "") (traceThickness "0.72 mil") (traceType "single") (traceWidth "5.0 mil") (traceWidth2 "5.0 mil") (traceWidth3 "5.0 mil") (traceWidth4 "5.0 mil") (traceWidth5 "5.0 mil") (traceWidth6 "5.0 mil") (offset "0 mil") (traceCount "1") (impedance nil))) (TheveninTerm ((resistanceUp "180 ohm") (resistanceDown "270 ohm") (voltageUp "5 V") (voltageDown "0 V") (maxDelay "0.1 ns"))) (DiffIO ((temperature "27") (bufferModelNonInverting "CDSDefaultIO_2p5v") (bufferModelInverting "CDSDefaultIO_2p5v") (stimuli nil) (offsets nil) (state "tristate") (cycle "1") (termMap nil) (setup "0.9e-09") (hold "0.4e-09") (rise nil) (fall nil) (threshInputHighMin "1.7 V") (threshInputHighTyp "1.7  V") (threshInputHighMax "1.7  V") (threshInputLowMin "0.7  V") (threshInputLowTyp "0.7  V") (threshInputLowMax "0.7 ") (threshOutputHighMin "2.365  V") (threshOutputHighTyp "2.5  V") (threshOutputHighMax "2.625  V") (threshOutputLowMin "1.275  V") (threshOutputLowTyp "1.7  V") (threshOutputLowMax "1.985  V") (mappingTagNonInverting nil) (mappingTagInverting nil) (spice nil))) (ShuntTerm ((resistance "50 ohm") (voltage "5 V") (maxDelay "0.1 ns"))) (Inductor ((inductance "5 nH") (orientation "0"))) (Capacitor ((capacitance "10 pF") (orientation "0"))) (RLGC (length("1000 mil"))) (Source ((voltage "5 V"))) (DiffInput ((temperature "27") (bufferModelNonInverting "CDSDefaultInput_2p5v") (bufferModelInverting "CDSDefaultInput_2p5v") (threshInputHighMin "1.7 V") (threshInputHighTyp "1.7  V") (threshInputHighMax "1.7  V") (threshInputLowMin "0.7  V") (threshInputLowTyp "0.7  V") (threshInputLowMax "0.7  V") (mappingTagNonInverting nil) (mappingTagInverting nil) (cycle "1"))) (Cable (length("1 m"))) (CPWSL ((d1Thickness "10 mil") (d1Constant "4.5") (d1LossTangent "0.035") (d2Thickness "0.72 mil") (d2Constant "4.5") (d2LossTangent "0.035") (d3Thickness "10 mil") (d3Constant "4.5") (d3LossTangent "0.035") length("1000 mil") (spacing "5 mil") (spacing2 "5 mil") (spacing3 "5 mil") (spacing4 "5 mil") (spacing5 "5 mil") (traceConductivity "595900 mho/cm") (traceGeometry "cpwms") (traceLayerName "") (traceThickness "0.72 mil") (traceType "single") (traceWidth "5.0 mil") (traceWidth2 "5.0 mil") (traceWidth3 "5.0 mil") (traceWidth4 "5.0 mil") (traceWidth5 "5.0 mil") (traceWidth6 "5.0 mil") (offset "0 mil") (traceCount "1") (impedance nil))) (ESpiceDevice nil) (CPWMS ((d1Thickness "10 mil") (d1Constant "4.5") (d1LossTangent "0.035") (d2Thickness "0.72 mil") (d2Constant "4.5") (d2LossTangent "0.035") (d3Thickness "0.0") (d3Constant "1") (d3LossTangent "0") length("1000 mil") (spacing "5 mil") (spacing2 "5 mil") (spacing3 "5 mil") (spacing4 "5 mil") (spacing5 "5 mil") (traceConductivity "595900 mho/cm") (traceGeometry "cpwms") (traceLayerName "") (traceThickness "0.72 mil") (traceType "single") (traceWidth "5.0 mil") (traceWidth2 "5.0 mil") (traceWidth3 "5.0 mil") (traceWidth4 "5.0 mil") (traceWidth5 "5.0 mil") (traceWidth6 "5.0 mil") (offset "0 mil") (traceCount "1") (impedance nil))) (Diode ((cutoffVoltage "0.7 V"))) (CPW ((d1Thickness "10 mil") (d1Constant "4.5") (d1LossTangent "0.035") (d2Thickness "0.72 mil") (d2Constant "1") (d2LossTangent "0") (d3Thickness "0.0") (d3Constant "1") (d3LossTangent "0") length("1000 mil") (spacing "5 mil") (spacing2 "5 mil") (spacing3 "5 mil") (spacing4 "5 mil") (spacing5 "5 mil") (traceConductivity "595900 mho/cm") (traceGeometry "cpwms") (traceLayerName "") (traceThickness "0.72 mil") (traceType "single") (traceWidth "5.0 mil") (traceWidth2 "5.0 mil") (traceWidth3 "5.0 mil") (traceWidth4 "5.0 mil") (traceWidth5 "5.0 mil") (traceWidth6 "5.0 mil") (offset "0 mil") (traceCount "1") (impedance nil))) (DualClampTerm ((cutoffVoltageUp "0.7 V") (cutoffVoltageDown "0.7 V") (voltageUp "5 V") (voltageDown "0 V") (maxDelay "0.1 ns"))) (IbisOutputPkg ((temperature "27") (bufferModel "CDSDefaultOutput_2p5v") (stimuli nil) (offsets nil) (state "tristate") (cycle "1") (termMap nil) (setup "2.0e-09") (hold "1.0e-09") (rise nil) (fall nil) (macroType nil) (voltage nil) (spice nil) (LEFDEFPinName nil) (LEFDEFPinType nil) (mappingTag nil))) (IbisIO_OpenPullDown ((temperature "27") (bufferModel "CDSDefaultIO_2p5v") (stimuli nil) (offsets nil) (state "tristate") (cycle "1") (termMap nil) (setup "2.0e-09") (hold "1.0e-09") (rise nil) (fall nil) (macroType nil) (voltage nil) (spice nil) (LEFDEFPinName nil) (LEFDEFPinType nil) (mappingTag nil))) (IbisInputPkg ((temperature "27") (bufferModel "CDSDefaultInput_2p5v") (cycle "1") (LEFDEFPinName nil) (LEFDEFPinType nil) (mappingTag nil))) (IbisIOMacro ((temperature "27") (bufferModel "CDSDefaultIO_2p5v") (stimuli nil) (offsets nil) (state "tristate") (cycle "1") (termMap nil) (setup "2.0e-09") (hold "1.0e-09") (rise nil) (fall nil) (macroType nil) (voltage nil) (spice nil) (LEFDEFPinName nil) (LEFDEFPinType nil) (mappingTag nil))) (IbisIO_OpenPullUp ((temperature "27") (bufferModel "CDSDefaultIO_2p5v") (stimuli nil) (offsets nil) (state "tristate") (cycle "1") (termMap nil) (setup "2.0e-09") (hold "1.0e-09") (rise nil) (fall nil) (macroType nil) (voltage nil) (spice nil) (LEFDEFPinName nil) (LEFDEFPinType nil) (mappingTag nil))) (IbisIOPkg ((temperature "27") (bufferModel "CDSDefaultIO_2p5v") (stimuli nil) (offsets nil) (state "tristate") (cycle "1") (termMap nil) (setup "2.0e-09") (hold "1.0e-09") (rise nil) (fall nil) (macroType nil) (voltage nil) (spice nil) (LEFDEFPinName nil) (LEFDEFPinType nil) (mappingTag nil))) (clocked ((clockRise "1e-09") (clockFall "1e-09") (clockFreq "100e6") (clockInitState "0") (clockDutyCycle "0.5") (clockJitter "0"))) (periodic ((periodicFreq "100e6") (periodicPattern "10") (periodicJitter "0"))) (IbisIO ((temperature "27") (bufferModel "CDSDefaultIO_2p5v") (stimuli nil) (offsets nil) (state "tristate") (cycle "1") (termMap nil) (setup "2.0e-09") (hold "1.0e-09") (rise nil) (fall nil) (macroType nil) (voltage nil) (spice nil) (LEFDEFPinName nil) (LEFDEFPinType nil) (mappingTag nil))) (async ((asyncTimePoints "") (asyncInitState "1"))) (IbisOutput ((temperature "27") (bufferModel "CDSDefaultOutput_2p5v") (stimuli nil) (offsets nil) (state "tristate") (cycle "1") (termMap nil) (setup "2.0e-09") (hold "1.0e-09") (rise nil) (fall nil) (macroType nil) (voltage nil) (spice nil) (LEFDEFPinName nil) (LEFDEFPinType nil) (mappingTag nil))) (TLine ((diffImpedance "100ohm") (diffVelocity "1.4142e+08M/s") (impedance "60ohm") length("2800 mil") (propDelay "0.5 ns") (velocity "5600 mil/ns") (traceCount "1") (traceGeometry "Microstrip") (impedanceMin nil) (impedanceMax nil) (lengthMin nil) (lengthMax nil) (propDelayMin nil) (propDelayMax nil) (impedanceSweepCount nil) (propDelaySweepCount nil) (velocitySweepCount nil) (lengthSweepCount nil) (matchSetName nil))) (CurrentProbe nil) (IbisInput ((temperature "27") (bufferModel "CDSDefaultInput_2p5v") (cycle "1") (LEFDEFPinName nil) (LEFDEFPinType nil) (mappingTag nil))) (SeriesTerm ((resistance "22 ohm") (maxDelay "0.1 ns"))) (Connector nil) (sync ((syncFreq "100e6") (syncInitState "1") (syncPattern "10") (syncEdgeSwitch "rise"))) (IbisOutput_OpenPullUp ((temperature "27") (bufferModel "CDSDefaultOutput_2p5v") (stimuli nil) (offsets nil) (state "tristate") (cycle "1") (termMap nil) (setup "2.0e-09") (hold "1.0e-09") (rise nil) (fall nil) (macroType nil) (voltage nil) (spice nil) (LEFDEFPinName nil) (LEFDEFPinType nil) (mappingTag nil))) (DiffInputPkg ((temperature "27") (bufferModelNonInverting "CDSDefaultInput_2p5v") (bufferModelInverting "CDSDefaultInput_2p5v") (threshInputHighMin "1.7 V") (threshInputHighTyp "1.7  V") (threshInputHighMax "1.7  V") (threshInputLowMin "0.7  V") (threshInputLowTyp "0.7  V") (threshInputLowMax "0.7  V") (mappingTagNonInverting nil) (mappingTagInverting nil) (cycle "1"))) (idlCircuit ((allDrivers "active") (ftsMode '("Typ")) (rcvrSelect "all") (simMode "Reflection") (tlineDelayMode "time") (userRevision "1.0") (autoSolve "On")))))
				)
				( objectStatus "SVID_CLK1_CPU0" )
			)
			( electricalCSet "@crescent_city_bb_fab1_lib.crescent_city_bb_fab1(sch_1):\CLK_100M_CPU0_MCP_DN\"
				( groupRef "CLK_100M_CPU_MCP_&_REFCLK:MG_CLK_G1-BCLK" )
				( pinPairRef "CLK_100M_CPU_MCP_&_REFCLK:EU4D2.39:U5D1.BB25" )
				( attribute "DIFFP_GATHER_CONTROL" "IGNORE"
					( Origin gBackEnd )
				)
				( attribute "DIFFP_UNCOUPLED_LENGTH" "475.00"
					( Origin gBackEnd )
				)
				( attribute "DIFFP_COUPLED_PLUS" "0.50"
					( Origin gBackEnd )
				)
				( attribute "DIFFP_COUPLED_MINUS" "0.50"
					( Origin gBackEnd )
				)
				( attribute "DIFFP_PHASE_TOL" "10 mil"
					( Units "uPhaseTol" "ns" 1.000000)
					( Origin gBackEnd )
				)
				( attribute "TOPOLOGY_TEMPLATE_REVISION" "1.0"
					( Origin gBackEnd )
				)
				( topologyData 26490
(SKIDL (Circuits ("MAIN" (Parts ("CRESCENT_CITY_623_20150314_B.@@EU119.39" IbisOutputPkg (xy (5498 4235)) (refDes "EU4D2") (model "Unknown") (Props (_SXDesignName "CRESCENT_CITY_623_20150314_B") (brdx "6699.73 MIL") (brdy "3359.48 MIL") (bufferModel "CDSDefaultOutput_2p5v") (cycle "1") (hold "1.0e-09") (mappingTag "") (offsets ("4" "0")) (setup "2.0e-09") (state "tristate") (stimuli ("4" "local8")) (temperature "27") (termMap ("4" "Data"))) (Terms ("CRESCENT_CITY_623_20150314_B.X669973Y335948L2LRATS" "39"))) ("CRESCENT_CITY_623_20150314_B.@@U36.BB25" IbisIOPkg (xy (5560 4240)) (refDes "U5D1") (model "Unknown") (Props (_SXDesignName "CRESCENT_CITY_623_20150314_B") (brdx "11285.3 MIL") (brdy "2824.96 MIL") (bufferModel "CDSDefaultIO_2p5v") (cycle "1") (hold "1.0e-09") (mappingTag "") (offsets ("4" "0") ("5" "0")) (setup "2.0e-09") (state "tristate") (stimuli ("4" "local9") ("5" "local10")) (temperature "27") (termMap ("4" "Data") ("5" "Enable"))) (Terms ("CRESCENT_CITY_623_20150314_B.X1128530Y282496L2LRATS" "BB25"))) ("CRESCENT_CITY_623_20150314_B.T@@RATS@@R3425.1@@R3413.2" TLine (xy (5536 4235)) (mirror x) (refDes "TL5") (Props (_SXDesignName "CRESCENT_CITY_623_20150314_B") (impedance "47.169 ohm") (propDelay "1.79607e-006 ns") (traceCount "1") (traceGeometry "Microstrip")) (Terms ("CRESCENT_CITY_623_20150314_B.X669000Y345500L36LRATS" "1") ("CRESCENT_CITY_623_20150314_B.X669000Y345500L2LRATS" "2"))) ("CRESCENT_CITY_623_20150314_B.T@@RATS@@R3425.1@@U36.BB25" TLine (xy (5551 4235)) (refDes "TL6") (Props (_SXDesignName "CRESCENT_CITY_623_20150314_B") (impedance "47.169 ohm") length("5225.35 MIL") (propDelay "0.93851 ns") (traceCount "1") (traceGeometry "Microstrip") (velocity "5567.72 mil/ns")) (Terms ("CRESCENT_CITY_623_20150314_B.X669000Y345500L36LRATS" "1") ("CRESCENT_CITY_623_20150314_B.X1128530Y282496L2LRATS" "2"))) ("CRESCENT_CITY_623_20150314_B.T@@RATS@@R3413.1@@EU119.39" TLine (xy (5506 4235)) (mirror x) (refDes "TL7") (Props (_SXDesignName "CRESCENT_CITY_623_20150314_B") (impedance "47.169 ohm") length("70.25 MIL") (propDelay "0.01262 ns") (traceCount "1") (traceGeometry "Microstrip") (velocity "5566.57 mil/ns")) (Terms ("CRESCENT_CITY_623_20150314_B.X669000Y342000L2LRATS" "1") ("CRESCENT_CITY_623_20150314_B.X669973Y335948L2LRATS" "2"))) ("CRESCENT_CITY_623_20150314_B.@@R3425.2_SOURCE" Source (xy (5529 4229)) (refDes "GND") (value "0 V") (Props (_SXDesignName "CRESCENT_CITY_623_20150314_B")) (Terms ("CRESCENT_CITY_623_20150314_B.X669000Y342000L36RATS" "1"))) ("CRESCENT_CITY_623_20150314_B.@@R3413.2.1" Resistor (xy (5521 4235)) (mirror x) (refDes "R4D5") (value "27.4 Ohm") (Props (_SXDesignName "CRESCENT_CITY_623_20150314_B")) (Terms ("CRESCENT_CITY_623_20150314_B.X669000Y345500L2LRATS" "2") ("CRESCENT_CITY_623_20150314_B.X669000Y342000L2LRATS" "1"))) ("CRESCENT_CITY_623_20150314_B.@@R3425.2.1" Resistor (xy (5536 4229)) (refDes "R6P4") (value "42.2 Ohm") (Props (_SXDesignName "CRESCENT_CITY_623_20150314_B")) (Terms ("CRESCENT_CITY_623_20150314_B.X669000Y342000L36RATS" "2") ("CRESCENT_CITY_623_20150314_B.X669000Y345500L36LRATS" "1")))) (Nodes ("CRESCENT_CITY_623_20150314_B.X1128530Y282496L2LRATS" (terms "CRESCENT_CITY_623_20150314_B.T@@RATS@@R3425.1@@U36.BB25.2" "CRESCENT_CITY_623_20150314_B.@@U36.BB25.1")) ("CRESCENT_CITY_623_20150314_B.X669000Y342000L2LRATS" (terms "CRESCENT_CITY_623_20150314_B.@@R3413.2.1.2" "CRESCENT_CITY_623_20150314_B.T@@RATS@@R3413.1@@EU119.39.1")) ("CRESCENT_CITY_623_20150314_B.X669000Y345500L2LRATS" (terms "CRESCENT_CITY_623_20150314_B.@@R3413.2.1.1" "CRESCENT_CITY_623_20150314_B.T@@RATS@@R3425.1@@R3413.2.2")) ("CRESCENT_CITY_623_20150314_B.X669973Y335948L2LRATS" (terms "CRESCENT_CITY_623_20150314_B.T@@RATS@@R3413.1@@EU119.39.2" "CRESCENT_CITY_623_20150314_B.@@EU119.39.1")) ("CRESCENT_CITY_623_20150314_B.X669000Y345500L36LRATS" (terms "CRESCENT_CITY_623_20150314_B.@@R3425.2.1.2" "CRESCENT_CITY_623_20150314_B.T@@RATS@@R3425.1@@U36.BB25.1" "CRESCENT_CITY_623_20150314_B.T@@RATS@@R3425.1@@R3413.2.1")) ("CRESCENT_CITY_623_20150314_B.X669000Y342000L36RATS" (terms "CRESCENT_CITY_623_20150314_B.@@R3425.2.1.1" "CRESCENT_CITY_623_20150314_B.@@R3425.2_SOURCE.1"))) (Ports) (Stimuli ("local8" (scope local) (stimType periodic) (Props (periodicFreq "5e+007") (periodicJitter "0") (periodicPattern "1"))) ("local10" (scope local) (stimType periodic) (Props (periodicFreq "5e+007") (periodicJitter "0") (periodicPattern "1"))) ("local9" (scope local) (stimType periodic) (Props (periodicFreq "5e+007") (periodicJitter "0") (periodicPattern "1")))) (Notes) (Constraints ("DP_GATHER_CONTROL" "IGNORE") ("DP_MAX_UNCOUPLED_LENGTH" "0.000254") ("DP_PHASE_TOLERANCE" ("LENGTH" "0.000254")) ("RELATIVE_PROPAGATION_DELAY" ("MG_CLK_G1-BCLK" "CRESCENT_CITY_623_20150314_B EU119.39" "CRESCENT_CITY_623_20150314_B U36.BB25" "GLOBAL" "LENGTH" "0.127" "LENGTH" "0"))) (MeasurementSets ("EMI" ("EMIStatus" status("on")) ("PeakEmission" status("on")) ("PeakFrequency" status("on")) ("PulseFreq" status("on")) ("RiseTime" status("on")) ("VoltageSwing" status("on"))) ("Reflection" ("BufferDelayFall" status("off")) ("BufferDelayRise" status("off")) ("EyeHeight" status("off")) ("EyeJitter" status("off")) ("EyeWidth" status("off")) ("FirstIncidentFall" status("off")) ("FirstIncidentRise" status("off")) ("Glitch" status("on")) ("GlitchFall" status("off")) ("GlitchRise" status("off")) ("Monotonic" status("on")) ("MonotonicFall" status("off")) ("MonotonicRise" status("off")) ("NoiseMargin" status("on")) ("NoiseMarginHigh" status("off")) ("NoiseMarginLow" status("off")) ("OvershootHigh" status("on")) ("OvershootLow" status("on")) ("PropDelay" status("on")) ("SettleDelay" status("on")) ("SettleDelayFall" status("off")) ("SettleDelayRise" status("off")) ("SwitchDelay" status("on")) ("SwitchDelayFall" status("off")) ("SwitchDelayRise" status("off"))) ("Crosstalk" ("Crosstalk" status("on"))) ("Custom")) (VectorSets) (Props (XnetName "CLK_100M_CPU0_MCP_DN") (allDrivers "active") (customSimType "Reflection") (ftsMode ("Typ")) (rcvrSelect "all") (tlineDelayMode "time") (userRevision "1.0")))) (Subckts) (CrossSections ("CRESCENT_CITY_623_20150314_B" (Props (SXDesignName "CRESCENT_CITY_623_20150314_B")) (Layers ("" (layerType "SURFACE") (material "AIR") (thickness "0 mil") (dielectricConstant "1.000000") (lossTangent "0") (etchFactor "0.000000") (elecCondVal "0 mho/cm") (thermCondVal "0 w/cm-degC")) ("" (layerType "DIELECTRIC") (material "CONFORMAL_COAT") (thickness "0.5 mil") (dielectricConstant "3.800000") (lossTangent "0.035") (etchFactor "0.000000") (elecCondVal "0 mho/cm") (thermCondVal "0.012 w/cm-degC")) ("TOP" (layerType "CONDUCTOR") (material "COPPER") (thickness "  2.100000 mil") (width "4.00 MIL") (dielectricConstant "4.500000") (lossTangent "0") (etchFactor "70.000000") (elecCondVal "595900.000000 mho/cm") (thermCondVal "0 w/cm-degC") (signalDieConstant "3.800000") (signalLossTangent "0.035")) ("" (layerType "DIELECTRIC") (material "FR-4") (thickness "  2.670000 mil") (dielectricConstant "4.000000") (lossTangent "0.035") (etchFactor "0.000000") (elecCondVal "0 mho/cm") (thermCondVal "0.012 w/cm-degC")) ("L2_GND1" (layerType "PLANE") (material "COPPER") (isShield t) (thickness "  1.250000 mil") (dielectricConstant "4.500000") (lossTangent "0.035") (etchFactor "90.000000") (elecCondVal "595900.000000 mho/cm") (thermCondVal "0.012 w/cm-degC")) ("" (layerType "DIELECTRIC") (material "FR-4") (thickness "  9.000000 mil") (dielectricConstant "4.100000") (lossTangent "0.035") (etchFactor "0.000000") (elecCondVal "0 mho/cm") (thermCondVal "0.012 w/cm-degC")) ("L3_SIG1" (layerType "CONDUCTOR") (material "COPPER") (thickness "  1.250000 mil") (width "4.00 MIL") (dielectricConstant "4.500000") (lossTangent "0.035") (etchFactor "90.000000") (elecCondVal "595900.000000 mho/cm") (thermCondVal "0.012 w/cm-degC") (signalDieConstant "4.100000") (signalLossTangent "0.035")) ("" (layerType "DIELECTRIC") (material "FR-4") (thickness "  3.000000 mil") (dielectricConstant "4.500000") (lossTangent "0.035") (etchFactor "0.000000") (elecCondVal "0 mho/cm") (thermCondVal "0 w/cm-degC")) ("L4_GND2" (layerType "PLANE") (material "COPPER") (isShield t) (thickness "  1.250000 mil") (dielectricConstant "4.500000") (lossTangent "0.035") (etchFactor "90.000000") (elecCondVal "595900.000000 mho/cm") (thermCondVal "0 w/cm-degC")) ("" (layerType "DIELECTRIC") (material "FR-4") (thickness "  9.000000 mil") (dielectricConstant "4.000000") (lossTangent "0.035") (etchFactor "0.000000") (elecCondVal "0 mho/cm") (thermCondVal "0.012 w/cm-degC")) ("L5_SIG2" (layerType "CONDUCTOR") (material "COPPER") (thickness "  1.250000 mil") (width "4.00 MIL") (dielectricConstant "4.500000") (lossTangent "0.035") (etchFactor "90.000000") (elecCondVal "595900.000000 mho/cm") (thermCondVal "0.012 w/cm-degC") (signalDieConstant "4.000000") (signalLossTangent "0.035")) ("" (layerType "DIELECTRIC") (material "FR-4") (thickness "  3.000000 mil") (dielectricConstant "4.500000") (lossTangent "0.035") (etchFactor "0.000000") (elecCondVal "0 mho/cm") (thermCondVal "0 w/cm-degC")) ("L6_GND3" (layerType "PLANE") (material "COPPER") (isShield t) (thickness "  1.250000 mil") (dielectricConstant "4.500000") (lossTangent "0.035") (etchFactor "90.000000") (elecCondVal "595900.000000 mho/cm") (thermCondVal "0 w/cm-degC")) ("" (layerType "DIELECTRIC") (material "FR-4") (thickness "  4.500000 mil") (dielectricConstant "4.100000") (lossTangent "0.035") (etchFactor "0.000000") (elecCondVal "0 mho/cm") (thermCondVal "0.012 w/cm-degC")) ("L7_PWR1-SIG" (layerType "PLANE") (material "COPPER") (isShield t) (thickness "  2.610000 mil") (dielectricConstant "4.500000") (lossTangent "0.035") (etchFactor "90.000000") (elecCondVal "595900.000000 mho/cm") (thermCondVal "0.012 w/cm-degC")) ("" (layerType "DIELECTRIC") (material "FR-4") (thickness "  3.100000 mil") (dielectricConstant "4.500000") (lossTangent "0.035") (etchFactor "0.000000") (elecCondVal "0 mho/cm") (thermCondVal "0 w/cm-degC")) ("L8_GND_TEMP" (layerType "PLANE") (material "COPPER") (isShield t) (thickness "  1.250000 mil") (dielectricConstant "4.500000") (lossTangent "0.035") (etchFactor "90.000000") (elecCondVal "595900.000000 mho/cm") (thermCondVal "0 w/cm-degC")) ("" (layerType "DIELECTRIC") (material "FR-4") (thickness "  3.030000 mil") (dielectricConstant "4.500000") (lossTangent "0.035") (etchFactor "0.000000") (elecCondVal "0 mho/cm") (thermCondVal "0 w/cm-degC")) ("L9_SIG_TEMP" (layerType "CONDUCTOR") (material "COPPER") (thickness "  1.250000 mil") (width "3.52 MIL") (dielectricConstant "4.500000") (lossTangent "0.035") (etchFactor "90.000000") (elecCondVal "595900.000000 mho/cm") (thermCondVal "0 w/cm-degC") (signalDieConstant "4.500000") (signalLossTangent "0.035")) ("" (layerType "DIELECTRIC") (material "FR-4") (thickness "  5.000000 mil") (dielectricConstant "4.500000") (lossTangent "0.035") (etchFactor "0.000000") (elecCondVal "0 mho/cm") (thermCondVal "0 w/cm-degC")) ("L10_SIG_TEMP" (layerType "CONDUCTOR") (material "COPPER") (thickness "  1.250000 mil") (width "3.52 MIL") (dielectricConstant "4.500000") (lossTangent "0.035") (etchFactor "90.000000") (elecCondVal "595900.000000 mho/cm") (thermCondVal "0 w/cm-degC") (signalDieConstant "4.500000") (signalLossTangent "0.035")) ("" (layerType "DIELECTRIC") (material "FR-4") (thickness "  3.030000 mil") (dielectricConstant "4.500000") (lossTangent "0.035") (etchFactor "0.000000") (elecCondVal "0 mho/cm") (thermCondVal "0 w/cm-degC")) ("L11_GND_TEMP" (layerType "PLANE") (material "COPPER") (isShield t) (thickness "  1.250000 mil") (dielectricConstant "4.500000") (lossTangent "0.035") (etchFactor "90.000000") (elecCondVal "595900.000000 mho/cm") (thermCondVal "0 w/cm-degC")) ("" (layerType "DIELECTRIC") (material "FR-4") (thickness "  3.100000 mil") (dielectricConstant "4.000000") (lossTangent "0.035") (etchFactor "0.000000") (elecCondVal "0 mho/cm") (thermCondVal "0.012 w/cm-degC")) ("L12_PWR2-SIG" (layerType "PLANE") (material "COPPER") (isShield t) (thickness "  2.610000 mil") (dielectricConstant "4.500000") (lossTangent "0.035") (etchFactor "90.000000") (elecCondVal "595900.000000 mho/cm") (thermCondVal "0.012 w/cm-degC")) ("" (layerType "DIELECTRIC") (material "FR-4") (thickness "  4.500000 mil") (dielectricConstant "4.500000") (lossTangent "0.035") (etchFactor "0.000000") (elecCondVal "0 mho/cm") (thermCondVal "0 w/cm-degC")) ("L13_GND4" (layerType "PLANE") (material "COPPER") (isShield t) (thickness "  1.250000 mil") (dielectricConstant "4.500000") (lossTangent "0.035") (etchFactor "90.000000") (elecCondVal "595900.000000 mho/cm") (thermCondVal "0 w/cm-degC")) ("" (layerType "DIELECTRIC") (material "FR-4") (thickness "  3.000000 mil") (dielectricConstant "4.100000") (lossTangent "0.035") (etchFactor "0.000000") (elecCondVal "0 mho/cm") (thermCondVal "0.012 w/cm-degC")) ("L14_SIG3" (layerType "CONDUCTOR") (material "COPPER") (thickness "  1.250000 mil") (width "4.00 MIL") (dielectricConstant "4.500000") (lossTangent "0.035") (etchFactor "90.000000") (elecCondVal "595900.000000 mho/cm") (thermCondVal "0.012 w/cm-degC") (signalDieConstant "4.100000") (signalLossTangent "0.035")) ("" (layerType "DIELECTRIC") (material "FR-4") (thickness "  9.000000 mil") (dielectricConstant "4.500000") (lossTangent "0.035") (etchFactor "0.000000") (elecCondVal "0 mho/cm") (thermCondVal "0 w/cm-degC")) ("L15_GND5" (layerType "PLANE") (material "COPPER") (isShield t) (thickness "  1.250000 mil") (dielectricConstant "4.500000") (lossTangent "0.035") (etchFactor "90.000000") (elecCondVal "595900.000000 mho/cm") (thermCondVal "0 w/cm-degC")) ("" (layerType "DIELECTRIC") (material "FR-4") (thickness "  3.000000 mil") (dielectricConstant "4.500000") (lossTangent "0.035") (etchFactor "0.000000") (elecCondVal "0 mho/cm") (thermCondVal "0.012 w/cm-degC")) ("L16_SIG4" (layerType "CONDUCTOR") (material "COPPER") (thickness "  1.250000 mil") (width "4.00 MIL") (dielectricConstant "4.500000") (lossTangent "0.035") (etchFactor "90.000000") (elecCondVal "595900.000000 mho/cm") (thermCondVal "0.012 w/cm-degC") (signalDieConstant "4.500000") (signalLossTangent "0.035")) ("" (layerType "DIELECTRIC") (material "FR-4") (thickness "  9.000000 mil") (dielectricConstant "4.500000") (lossTangent "0.035") (etchFactor "0.000000") (elecCondVal "0 mho/cm") (thermCondVal "0 w/cm-degC")) ("L17_GND6" (layerType "PLANE") (material "COPPER") (isShield t) (thickness "  1.250000 mil") (dielectricConstant "4.500000") (lossTangent "0.035") (etchFactor "90.000000") (elecCondVal "595900.000000 mho/cm") (thermCondVal "0.012 w/cm-degC")) ("" (layerType "DIELECTRIC") (material "FR-4") (thickness "  2.670000 mil") (dielectricConstant "4.500000") (lossTangent "0.035") (etchFactor "0.000000") (elecCondVal "0 mho/cm") (thermCondVal "0.012 w/cm-degC")) ("BOTTOM" (layerType "CONDUCTOR") (material "COPPER") (thickness "  2.100000 mil") (width "4.00 MIL") (dielectricConstant "4.500000") (lossTangent "0") (etchFactor "70.000000") (elecCondVal "595900.000000 mho/cm") (thermCondVal "0 w/cm-degC") (signalDieConstant "3.800000") (signalLossTangent "0.035")) ("" (layerType "DIELECTRIC") (material "CONFORMAL_COAT") (thickness "0.5 mil") (dielectricConstant "3.800000") (lossTangent "0.035") (etchFactor "0.000000") (elecCondVal "0 mho/cm") (thermCondVal "0.012 w/cm-degC")) ("" (layerType "SURFACE") (material "AIR") (thickness "0 mil") (dielectricConstant "1.000000") (lossTangent "0") (etchFactor "0.000000") (elecCondVal "0 mho/cm") (thermCondVal "0 w/cm-degC"))))) (Props (DesUnits "mils 2") (LayerStack ("DIELECTRIC" "DIELECTRIC" "BOTTOM" "DIELECTRIC" "L17_GND6" "DIELECTRIC" "L16_SIG4" "DIELECTRIC" "L15_GND5" "DIELECTRIC" "L14_SIG3" "DIELECTRIC" "L13_GND4" "DIELECTRIC" "L12_PWR2-SIG" "DIELECTRIC" "L11_GND_TEMP" "DIELECTRIC" "L10_SIG_TEMP" "DIELECTRIC" "L9_SIG_TEMP" "DIELECTRIC" "L8_GND_TEMP" "DIELECTRIC" "L7_PWR1-SIG" "DIELECTRIC" "L6_GND3" "DIELECTRIC" "L5_SIG2" "DIELECTRIC" "L4_GND2" "DIELECTRIC" "L3_SIG1" "DIELECTRIC" "L2_GND1" "DIELECTRIC" "TOP" "DIELECTRIC" "DIELECTRIC")) (Revision "16.600")) (Params (RLGC (length("1000 mil"))) (DiffIO ((temperature "27") (bufferModelNonInverting "CDSDefaultIO_2p5v") (bufferModelInverting "CDSDefaultIO_2p5v") (stimuli nil) (offsets nil) (state "tristate") (cycle "1") (termMap nil) (setup "0.9e-09") (hold "0.4e-09") (rise nil) (fall nil) (threshInputHighMin "1.7 V") (threshInputHighTyp "1.7  V") (threshInputHighMax "1.7  V") (threshInputLowMin "0.7  V") (threshInputLowTyp "0.7  V") (threshInputLowMax "0.7 ") (threshOutputHighMin "2.365  V") (threshOutputHighTyp "2.5  V") (threshOutputHighMax "2.625  V") (threshOutputLowMin "1.275  V") (threshOutputLowTyp "1.7  V") (threshOutputLowMax "1.985  V") (mappingTagNonInverting nil) (mappingTagInverting nil) (spice nil))) (Source ((voltage "5 V"))) (DiffIOPkg ((temperature "27") (bufferModelNonInverting "CDSDefaultIO_2p5v") (bufferModelInverting "CDSDefaultIO_2p5v") (stimuli nil) (offsets nil) (state "tristate") (cycle "1") (termMap nil) (setup "0.9e-09") (hold "0.4e-09") (rise nil) (fall nil) (threshInputHighMin "1.7 V") (threshInputHighTyp "1.7  V") (threshInputHighMax "1.7  V") (threshInputLowMin "0.7  V") (threshInputLowTyp "0.7  V") (threshInputLowMax "0.7 ") (threshOutputHighMin "2.365  V") (threshOutputHighTyp "2.5  V") (threshOutputHighMax "2.625  V") (threshOutputLowMin "1.275  V") (threshOutputLowTyp "1.7  V") (threshOutputLowMax "1.985  V") (mappingTagNonInverting nil) (mappingTagInverting nil) (spice nil))) (Inductor ((inductance "5 nH") (orientation "0"))) (DiffOutput ((temperature "27") (bufferModelNonInverting "CDSDefaultOutput_2p5v") (bufferModelInverting "CDSDefaultOutput_2p5v") (stimuli nil) (offsets nil) (state "tristate") (cycle "1") (termMap nil) (setup "0.9e-09") (hold "0.4e-09") (rise nil) (fall nil) (threshOutputHighMin "2.375  V") (threshOutputHighTyp "2.5  V") (threshOutputHighMax "2.625  V") (threshOutputLowMin "1.275  V") (threshOutputLowTyp "1.7  V") (threshOutputLowMax "1.985  V") (mappingTagNonInverting nil) (mappingTagInverting nil) (spice nil))) (Capacitor ((capacitance "10 pF") (orientation "0"))) (DiffOutputPkg ((temperature "27") (bufferModelNonInverting "CDSDefaultOutput_2p5v") (bufferModelInverting "CDSDefaultOutput_2p5v") (stimuli nil) (offsets nil) (state "tristate") (cycle "1") (termMap nil) (setup "0.9e-09") (hold "0.4e-09") (rise nil) (fall nil) (threshOutputHighMin "2.375  V") (threshOutputHighTyp "2.5  V") (threshOutputHighMax "2.625  V") (threshOutputLowMin "1.275  V") (threshOutputLowTyp "1.7  V") (threshOutputLowMax "1.985  V") (mappingTagNonInverting nil) (mappingTagInverting nil) (spice nil))) (IbisOutput ((temperature "27") (bufferModel "CDSDefaultOutput_2p5v") (stimuli nil) (offsets nil) (state "tristate") (cycle "1") (termMap nil) (setup "2.0e-09") (hold "1.0e-09") (rise nil) (fall nil) (macroType nil) (voltage nil) (spice nil) (LEFDEFPinName nil) (LEFDEFPinType nil) (mappingTag nil))) (IbisIO ((temperature "27") (bufferModel "CDSDefaultIO_2p5v") (stimuli nil) (offsets nil) (state "tristate") (cycle "1") (termMap nil) (setup "2.0e-09") (hold "1.0e-09") (rise nil) (fall nil) (macroType nil) (voltage nil) (spice nil) (LEFDEFPinName nil) (LEFDEFPinType nil) (mappingTag nil))) (CPWMS ((d1Thickness "10 mil") (d1Constant "4.5") (d1LossTangent "0.035") (d2Thickness "0.72 mil") (d2Constant "4.5") (d2LossTangent "0.035") (d3Thickness "0.0") (d3Constant "1") (d3LossTangent "0") length("1000 mil") (spacing "5 mil") (spacing2 "5 mil") (spacing3 "5 mil") (spacing4 "5 mil") (spacing5 "5 mil") (traceConductivity "595900 mho/cm") (traceGeometry "cpwms") (traceLayerName "") (traceThickness "0.72 mil") (traceType "single") (traceWidth "5.0 mil") (traceWidth2 "5.0 mil") (traceWidth3 "5.0 mil") (traceWidth4 "5.0 mil") (traceWidth5 "5.0 mil") (traceWidth6 "5.0 mil") (offset "0 mil") (traceCount "1") (impedance nil))) (CPW ((d1Thickness "10 mil") (d1Constant "4.5") (d1LossTangent "0.035") (d2Thickness "0.72 mil") (d2Constant "1") (d2LossTangent "0") (d3Thickness "0.0") (d3Constant "1") (d3LossTangent "0") length("1000 mil") (spacing "5 mil") (spacing2 "5 mil") (spacing3 "5 mil") (spacing4 "5 mil") (spacing5 "5 mil") (traceConductivity "595900 mho/cm") (traceGeometry "cpwms") (traceLayerName "") (traceThickness "0.72 mil") (traceType "single") (traceWidth "5.0 mil") (traceWidth2 "5.0 mil") (traceWidth3 "5.0 mil") (traceWidth4 "5.0 mil") (traceWidth5 "5.0 mil") (traceWidth6 "5.0 mil") (offset "0 mil") (traceCount "1") (impedance nil))) (Resistor ((resistance "50 ohm") (orientation "0"))) (async ((asyncTimePoints "") (asyncInitState "1"))) (DiffInput ((temperature "27") (bufferModelNonInverting "CDSDefaultInput_2p5v") (bufferModelInverting "CDSDefaultInput_2p5v") (threshInputHighMin "1.7 V") (threshInputHighTyp "1.7  V") (threshInputHighMax "1.7  V") (threshInputLowMin "0.7  V") (threshInputLowTyp "0.7  V") (threshInputLowMax "0.7  V") (mappingTagNonInverting nil) (mappingTagInverting nil) (cycle "1"))) (Cable (length("1 m"))) (CPWSL ((d1Thickness "10 mil") (d1Constant "4.5") (d1LossTangent "0.035") (d2Thickness "0.72 mil") (d2Constant "4.5") (d2LossTangent "0.035") (d3Thickness "10 mil") (d3Constant "4.5") (d3LossTangent "0.035") length("1000 mil") (spacing "5 mil") (spacing2 "5 mil") (spacing3 "5 mil") (spacing4 "5 mil") (spacing5 "5 mil") (traceConductivity "595900 mho/cm") (traceGeometry "cpwms") (traceLayerName "") (traceThickness "0.72 mil") (traceType "single") (traceWidth "5.0 mil") (traceWidth2 "5.0 mil") (traceWidth3 "5.0 mil") (traceWidth4 "5.0 mil") (traceWidth5 "5.0 mil") (traceWidth6 "5.0 mil") (offset "0 mil") (traceCount "1") (impedance nil))) (Trace ((d1Thickness "10 mil") (d1Constant "4.5") (d1LossTangent "0.035") (d2Thickness "10 mil") (d2Constant "4.5") (d2LossTangent "0.035") (d3Thickness "0.0") (d3Constant "1.0") (d3LossTangent "0") length("1000 mil") (spacing "5 mil") (spacing2 "5 mil") (spacing3 "5 mil") (spacing4 "5 mil") (spacing5 "5 mil") (traceConductivity "595900 mho/cm") (traceGeometry "microstrip") (traceLayerName "") (traceThickness "0.72 mil") (traceType "single") (traceWidth "5.0 mil") (traceWidth2 "5.0 mil") (traceWidth3 "5.0 mil") (traceWidth4 "5.0 mil") (traceWidth5 "5.0 mil") (traceWidth6 "5.0 mil") (offset "0 mil") (traceCount "1") (impedance nil))) (Via ((model "Unknown") (viaOutputFormat "Unknown") (viaPadstack nil) (viaTopLayer nil) (viaBottomLayer nil) (viaIsPower nil) (viaIsGround nil))) (Connector nil) (IbisOutput_OpenPullUp ((temperature "27") (bufferModel "CDSDefaultOutput_2p5v") (stimuli nil) (offsets nil) (state "tristate") (cycle "1") (termMap nil) (setup "2.0e-09") (hold "1.0e-09") (rise nil) (fall nil) (macroType nil) (voltage nil) (spice nil) (LEFDEFPinName nil) (LEFDEFPinType nil) (mappingTag nil))) (TLine ((diffImpedance "100ohm") (diffVelocity "1.4142e+08M/s") (impedance "60ohm") length("2800 mil") (propDelay "0.5 ns") (velocity "5600 mil/ns") (traceCount "1") (traceGeometry "Microstrip") (impedanceMin nil) (impedanceMax nil) (lengthMin nil) (lengthMax nil) (propDelayMin nil) (propDelayMax nil) (impedanceSweepCount nil) (propDelaySweepCount nil) (velocitySweepCount nil) (lengthSweepCount nil) (matchSetName nil))) (sync ((syncFreq "100e6") (syncInitState "1") (syncPattern "10") (syncEdgeSwitch "rise"))) (idlCircuit ((allDrivers "active") (ftsMode '("Typ")) (rcvrSelect "all") (simMode "Reflection") (tlineDelayMode "time") (userRevision "1.0") (autoSolve "On"))) (IbisInputPkg ((temperature "27") (bufferModel "CDSDefaultInput_2p5v") (cycle "1") (LEFDEFPinName nil) (LEFDEFPinType nil) (mappingTag nil))) (IbisOutputPkg ((temperature "27") (bufferModel "CDSDefaultOutput_2p5v") (stimuli nil) (offsets nil) (state "tristate") (cycle "1") (termMap nil) (setup "2.0e-09") (hold "1.0e-09") (rise nil) (fall nil) (macroType nil) (voltage nil) (spice nil) (LEFDEFPinName nil) (LEFDEFPinType nil) (mappingTag nil))) (IbisIOPkg ((temperature "27") (bufferModel "CDSDefaultIO_2p5v") (stimuli nil) (offsets nil) (state "tristate") (cycle "1") (termMap nil) (setup "2.0e-09") (hold "1.0e-09") (rise nil) (fall nil) (macroType nil) (voltage nil) (spice nil) (LEFDEFPinName nil) (LEFDEFPinType nil) (mappingTag nil))) (IbisIOMacro ((temperature "27") (bufferModel "CDSDefaultIO_2p5v") (stimuli nil) (offsets nil) (state "tristate") (cycle "1") (termMap nil) (setup "2.0e-09") (hold "1.0e-09") (rise nil) (fall nil) (macroType nil) (voltage nil) (spice nil) (LEFDEFPinName nil) (LEFDEFPinType nil) (mappingTag nil))) (CurrentProbe nil) (DiffInputPkg ((temperature "27") (bufferModelNonInverting "CDSDefaultInput_2p5v") (bufferModelInverting "CDSDefaultInput_2p5v") (threshInputHighMin "1.7 V") (threshInputHighTyp "1.7  V") (threshInputHighMax "1.7  V") (threshInputLowMin "0.7  V") (threshInputLowTyp "0.7  V") (threshInputLowMax "0.7  V") (mappingTagNonInverting nil) (mappingTagInverting nil) (cycle "1"))) (Diode ((cutoffVoltage "0.7 V"))) (HiClampTerm ((cutoffVoltage "0.7 V") (voltage "5 V") (maxDelay "0.1 ns"))) (DualClampTerm ((cutoffVoltageUp "0.7 V") (cutoffVoltageDown "0.7 V") (voltageUp "5 V") (voltageDown "0 V") (maxDelay "0.1 ns"))) (RCTerm ((resistance "50 ohm") (capacitance "20 pF") (voltage "5 V") (maxDelay "0.1 ns"))) (LowClampTerm ((cutoffVoltage "0.7 V") (voltage "0 V") (maxDelay "0.1 ns"))) (ShuntTerm ((resistance "50 ohm") (voltage "5 V") (maxDelay "0.1 ns"))) (SeriesTerm ((resistance "22 ohm") (maxDelay "0.1 ns"))) (periodic ((periodicFreq "100e6") (periodicPattern "10") (periodicJitter "0"))) (IbisIO_OpenPullDown ((temperature "27") (bufferModel "CDSDefaultIO_2p5v") (stimuli nil) (offsets nil) (state "tristate") (cycle "1") (termMap nil) (setup "2.0e-09") (hold "1.0e-09") (rise nil) (fall nil) (macroType nil) (voltage nil) (spice nil) (LEFDEFPinName nil) (LEFDEFPinType nil) (mappingTag nil))) (IbisIO_OpenPullUp ((temperature "27") (bufferModel "CDSDefaultIO_2p5v") (stimuli nil) (offsets nil) (state "tristate") (cycle "1") (termMap nil) (setup "2.0e-09") (hold "1.0e-09") (rise nil) (fall nil) (macroType nil) (voltage nil) (spice nil) (LEFDEFPinName nil) (LEFDEFPinType nil) (mappingTag nil))) (TheveninTerm ((resistanceUp "180 ohm") (resistanceDown "270 ohm") (voltageUp "5 V") (voltageDown "0 V") (maxDelay "0.1 ns"))) (clocked ((clockRise "1e-09") (clockFall "1e-09") (clockFreq "100e6") (clockInitState "0") (clockDutyCycle "0.5") (clockJitter "0"))) (ESpiceDevice nil) (IbisInput ((temperature "27") (bufferModel "CDSDefaultInput_2p5v") (cycle "1") (LEFDEFPinName nil) (LEFDEFPinType nil) (mappingTag nil)))))
				)
				( objectStatus "CLK_100M_CPU_MCP_&_REFCLK" )
			)
			( electricalCSet "@baseboard_fab2_lib.baseboard_fab2(sch_1):\SVID_DIO1_CPU0\"
				( groupRef "SVID_DIO1_CPU0:#SVID_CPU1_0_U36-EU75" )
				( groupRef "SVID_DIO1_CPU0:#SVID_CPU1_0_U36-EU21" )
				( pinPairRef "SVID_DIO1_CPU0:EU7A5.16:U5D1.DJ44" )
				( pinPairRef "SVID_DIO1_CPU0:EU7G1.16:U5D1.DJ44" )
				( pinPairRef "SVID_DIO1_CPU0:U5D1.DJ44:R6B4.1" )
				( pinPairRef "SVID_DIO1_CPU0:R7A12.2:R3L11.2" )
				( pinPairRef "SVID_DIO1_CPU0:R6B2.2:R6B4.2" )
				( pinPairRef "SVID_DIO1_CPU0:R3U2.2:R7G2.2" )
				( pinPairRef "SVID_DIO1_CPU0:EU7A5.16:R7A12.1" )
				( pinPairRef "SVID_DIO1_CPU0:EU7G1.16:R7G2.1" )
				( pinPairRef "SVID_DIO1_CPU0:R7A12.1:R7G2.2" )
				( attribute "TOPOLOGY_TEMPLATE_REVISION" "1.0"
					( Origin gBackEnd )
				)
				( topologyData 32040
(SKIDL (Circuits ("MAIN" (Parts ("CRESCENT_CITY_195_20150128_Q.@@EU75.16" IbisIOPkg (xy (5506 4213)) (refDes "EU7A5") (model "Unknown") (Props (_SXDesignName "CRESCENT_CITY_195_20150128_Q") (brdx "14242.1 MIL") (brdy "5447.42 MIL") (bufferModel "CDSDefaultIO_2p5v") (cycle "1") (hold "1.0e-09") (mappingTag "") (offsets ("5" "0") ("4" "0")) (setup "2.0e-09") (state "tristate") (stimuli ("5" "local84") ("4" "local83")) (temperature "27") (termMap ("4" "Data") ("5" "Enable"))) (Terms ("CRESCENT_CITY_195_20150128_Q.X1424210Y544742L2LRATS" "16"))) ("CRESCENT_CITY_195_20150128_Q.@@U36.DJ44" IbisIOPkg (xy (5512 4227)) (refDes "U5D1") (model "Unknown") (Props (_SXDesignName "CRESCENT_CITY_195_20150128_Q") (brdx "10582.94 MIL") (brdy "3670.6 MIL") (bufferModel "CDSDefaultIO_2p5v") (cycle "1") (hold "1.0e-09") (mappingTag "") (offsets ("5" "0") ("4" "0")) (setup "2.0e-09") (state "tristate") (stimuli ("5" "local86") ("4" "local85")) (temperature "27") (termMap ("4" "Data") ("5" "Enable"))) (Terms ("CRESCENT_CITY_195_20150128_Q.X1058294Y367060L2LRATS" "DJ44"))) ("CRESCENT_CITY_195_20150128_Q.@@EU21.16" IbisIOPkg (xy (5502 4240)) (refDes "EU7G1") (model "Unknown") (Props (_SXDesignName "CRESCENT_CITY_195_20150128_Q") (brdx "13473.5 MIL") (brdy "597.13 MIL") (bufferModel "CDSDefaultIO_2p5v") (cycle "1") (hold "1.0e-09") (mappingTag "") (offsets ("5" "0") ("4" "0")) (setup "2.0e-09") (state "tristate") (stimuli ("5" "local88") ("4" "local87")) (temperature "27") (termMap ("4" "Data") ("5" "Enable"))) (Terms ("CRESCENT_CITY_195_20150128_Q.X1347350Y59713L2LRATS" "16"))) ("CRESCENT_CITY_195_20150128_Q.@@R1174.1.2" Resistor (xy (5464 4215)) (refDes "R6B2") (value "100 Ohm") (Props (_SXDesignName "CRESCENT_CITY_195_20150128_Q")) (Terms ("CRESCENT_CITY_195_20150128_Q.X1282000Y514000L2RATS" "1") ("CRESCENT_CITY_195_20150128_Q.X1278500Y514000L2LRATS" "2"))) ("CRESCENT_CITY_195_20150128_Q.T@@RATS@@U36.DJ44@@R1192.1" TLine (xy (5497 4222)) (mirror x) (refDes "TL124") (Props (_SXDesignName "CRESCENT_CITY_195_20150128_Q") (impedance "49.728 ohm") length("3548.63 MIL") (propDelay "0.63736 ns") (traceCount "1") (traceGeometry "Microstrip") (velocity "5567.72 mil/ns")) (Terms ("CRESCENT_CITY_195_20150128_Q.X1058294Y367060L2LRATS" "1") ("CRESCENT_CITY_195_20150128_Q.X1275043Y505174L2LRATS" "2"))) ("CRESCENT_CITY_195_20150128_Q.T@@RATS@@R1192.2@@R1174.2" TLine (xy (5479 4215)) (mirror x) (refDes "TL125") (Props (_SXDesignName "CRESCENT_CITY_195_20150128_Q") (impedance "48.412 ohm") length("87.83 MIL") (propDelay "0.01577 ns") (traceCount "1") (traceGeometry "Microstrip") (velocity "5569.45 mil/ns")) (Terms ("CRESCENT_CITY_195_20150128_Q.X1275043Y508674L2LRATS" "1") ("CRESCENT_CITY_195_20150128_Q.X1278500Y514000L2LRATS" "2"))) ("CRESCENT_CITY_195_20150128_Q.@@R1660.1.2" Resistor (xy (5488 4229)) (mirror x) (refDes "R7G2") (value "2.2e-007 Ohm") (Props (_SXDesignName "CRESCENT_CITY_195_20150128_Q")) (Terms ("CRESCENT_CITY_195_20150128_Q.X1334000Y68000L2LRATS" "1") ("CRESCENT_CITY_195_20150128_Q.X1330500Y68000L2LRATS" "2"))) ("CRESCENT_CITY_195_20150128_Q.@@R1174.1_SOURCE" Source (xy (5457 4215)) (refDes "PVCCIO_CPU0_1") (value "1.05 V") (Props (_SXDesignName "CRESCENT_CITY_195_20150128_Q")) (Terms ("CRESCENT_CITY_195_20150128_Q.X1282000Y514000L2RATS" "1"))) ("CRESCENT_CITY_195_20150128_Q.T@@RATS@@R2037.1@@EU75.16" TLine (xy (5497 4208)) (refDes "TL126") (Props (_SXDesignName "CRESCENT_CITY_195_20150128_Q") (impedance "48.412 ohm") length("116.37 MIL") (propDelay "0.0209 ns") (traceCount "1") (traceGeometry "Microstrip") (velocity "5567.95 mil/ns")) (Terms ("CRESCENT_CITY_195_20150128_Q.X1432560Y541455L2LRATS" "1") ("CRESCENT_CITY_195_20150128_Q.X1424210Y544742L2LRATS" "2"))) ("CRESCENT_CITY_195_20150128_Q.@@R2042.1.2" Resistor (xy (5470 4201)) (refDes "R3L11") (value "100 Ohm") (Props (_SXDesignName "CRESCENT_CITY_195_20150128_Q")) (Terms ("CRESCENT_CITY_195_20150128_Q.X1432560Y541455L30RATS" "1") ("CRESCENT_CITY_195_20150128_Q.X1436060Y541455L30LRATS" "2"))) ("CRESCENT_CITY_195_20150128_Q.T@@RATS@@R1174.2@@R2037.2" TLine (xy (5479 4208)) (refDes "TL127") (Props (_SXDesignName "CRESCENT_CITY_195_20150128_Q") (impedance "48.412 ohm") length("1850.15 MIL") (propDelay "0.3323 ns") (traceCount "1") (traceGeometry "Microstrip") (velocity "5567.72 mil/ns")) (Terms ("CRESCENT_CITY_195_20150128_Q.X1278500Y514000L2LRATS" "1") ("CRESCENT_CITY_195_20150128_Q.X1436060Y541455L2LRATS" "2"))) ("CRESCENT_CITY_195_20150128_Q.T@@RATS@@R2037.2@@R2042.2" TLine (xy (5485 4201)) (mirror x) (refDes "TL128") (Props (_SXDesignName "CRESCENT_CITY_195_20150128_Q") (impedance "48.412 ohm") (propDelay "1.79607e-006 ns") (traceCount "1") (traceGeometry "Microstrip")) (Terms ("CRESCENT_CITY_195_20150128_Q.X1436060Y541455L2LRATS" "1") ("CRESCENT_CITY_195_20150128_Q.X1436060Y541455L30LRATS" "2"))) ("CRESCENT_CITY_195_20150128_Q.@@R661.1.2" Resistor (xy (5464 4229)) (refDes "R3U2") (value "100 Ohm") (Props (_SXDesignName "CRESCENT_CITY_195_20150128_Q")) (Terms ("CRESCENT_CITY_195_20150128_Q.X1334000Y68000L30RATS" "1") ("CRESCENT_CITY_195_20150128_Q.X1330500Y68000L30LRATS" "2"))) ("CRESCENT_CITY_195_20150128_Q.T@@RATS@@R661.2@@R1192.2" TLine (xy (5473 4222)) (refDes "TL129") (Props (_SXDesignName "CRESCENT_CITY_195_20150128_Q") (impedance "48.412 ohm") length("4961.30 MIL") (propDelay "0.89109 ns") (traceCount "1") (traceGeometry "Microstrip") (velocity "5567.68 mil/ns")) (Terms ("CRESCENT_CITY_195_20150128_Q.X1330500Y68000L30LRATS" "1") ("CRESCENT_CITY_195_20150128_Q.X1275043Y508674L2LRATS" "2"))) ("CRESCENT_CITY_195_20150128_Q.@@R2042.1_SOURCE" Source (xy (5463 4201)) (refDes "PVCCIO_CPU0_2") (value "1.05 V") (Props (_SXDesignName "CRESCENT_CITY_195_20150128_Q")) (Terms ("CRESCENT_CITY_195_20150128_Q.X1432560Y541455L30RATS" "1"))) ("CRESCENT_CITY_195_20150128_Q.@@R661.1_SOURCE" Source (xy (5457 4229)) (refDes "PVCCIO_CPU0") (value "1.05 V") (Props (_SXDesignName "CRESCENT_CITY_195_20150128_Q")) (Terms ("CRESCENT_CITY_195_20150128_Q.X1334000Y68000L30RATS" "1"))) ("CRESCENT_CITY_195_20150128_Q.@@R1192.1.2" Resistor (xy (5482 4222)) (mirror x) (refDes "R6B4") (value "2.2e-007 Ohm") (Props (_SXDesignName "CRESCENT_CITY_195_20150128_Q")) (Terms ("CRESCENT_CITY_195_20150128_Q.X1275043Y505174L2LRATS" "1") ("CRESCENT_CITY_195_20150128_Q.X1275043Y508674L2LRATS" "2"))) ("CRESCENT_CITY_195_20150128_Q.T@@RATS@@EU21.16@@R1660.1" TLine (xy (5503 4229)) (mirror x) (refDes "TL130") (Props (_SXDesignName "CRESCENT_CITY_195_20150128_Q") (impedance "48.412 ohm") length("216.37 MIL") (propDelay "0.03886 ns") (traceCount "1") (traceGeometry "Microstrip") (velocity "5567.95 mil/ns")) (Terms ("CRESCENT_CITY_195_20150128_Q.X1347350Y59713L2LRATS" "1") ("CRESCENT_CITY_195_20150128_Q.X1334000Y68000L2LRATS" "2"))) ("CRESCENT_CITY_195_20150128_Q.T@@RATS@@R661.2@@R1660.2" TLine (xy (5473 4229)) (refDes "TL131") (Props (_SXDesignName "CRESCENT_CITY_195_20150128_Q") (impedance "48.412 ohm") (propDelay "1.79607e-006 ns") (traceCount "1") (traceGeometry "Microstrip")) (Terms ("CRESCENT_CITY_195_20150128_Q.X1330500Y68000L30LRATS" "1") ("CRESCENT_CITY_195_20150128_Q.X1330500Y68000L2LRATS" "2"))) ("CRESCENT_CITY_195_20150128_Q.@@R2037.2.1" Resistor (xy (5488 4208)) (refDes "R7A12") (value "2.2e-007 Ohm") (Props (_SXDesignName "CRESCENT_CITY_195_20150128_Q")) (Terms ("CRESCENT_CITY_195_20150128_Q.X1436060Y541455L2LRATS" "2") ("CRESCENT_CITY_195_20150128_Q.X1432560Y541455L2LRATS" "1")))) (Nodes ("CRESCENT_CITY_195_20150128_Q.X1432560Y541455L30RATS" (terms "CRESCENT_CITY_195_20150128_Q.@@R2042.1_SOURCE.1" "CRESCENT_CITY_195_20150128_Q.@@R2042.1.2.1")) ("CRESCENT_CITY_195_20150128_Q.X1334000Y68000L30RATS" (terms "CRESCENT_CITY_195_20150128_Q.@@R661.1_SOURCE.1" "CRESCENT_CITY_195_20150128_Q.@@R661.1.2.1")) ("CRESCENT_CITY_195_20150128_Q.X1436060Y541455L30LRATS" (terms "CRESCENT_CITY_195_20150128_Q.T@@RATS@@R2037.2@@R2042.2.2" "CRESCENT_CITY_195_20150128_Q.@@R2042.1.2.2")) ("CRESCENT_CITY_195_20150128_Q.X1334000Y68000L2LRATS" (terms "CRESCENT_CITY_195_20150128_Q.T@@RATS@@EU21.16@@R1660.1.2" "CRESCENT_CITY_195_20150128_Q.@@R1660.1.2.1")) ("CRESCENT_CITY_195_20150128_Q.X1058294Y367060L2LRATS" (terms "CRESCENT_CITY_195_20150128_Q.T@@RATS@@U36.DJ44@@R1192.1.1" "CRESCENT_CITY_195_20150128_Q.@@U36.DJ44.1")) ("CRESCENT_CITY_195_20150128_Q.X1424210Y544742L2LRATS" (terms "CRESCENT_CITY_195_20150128_Q.T@@RATS@@R2037.1@@EU75.16.2" "CRESCENT_CITY_195_20150128_Q.@@EU75.16.1")) ("CRESCENT_CITY_195_20150128_Q.X1330500Y68000L30LRATS" (terms "CRESCENT_CITY_195_20150128_Q.T@@RATS@@R661.2@@R1660.2.1" "CRESCENT_CITY_195_20150128_Q.T@@RATS@@R661.2@@R1192.2.1" "CRESCENT_CITY_195_20150128_Q.@@R661.1.2.2")) ("CRESCENT_CITY_195_20150128_Q.X1275043Y505174L2LRATS" (terms "CRESCENT_CITY_195_20150128_Q.@@R1192.1.2.1" "CRESCENT_CITY_195_20150128_Q.T@@RATS@@U36.DJ44@@R1192.1.2")) ("CRESCENT_CITY_195_20150128_Q.X1432560Y541455L2LRATS" (terms "CRESCENT_CITY_195_20150128_Q.@@R2037.2.1.2" "CRESCENT_CITY_195_20150128_Q.T@@RATS@@R2037.1@@EU75.16.1")) ("CRESCENT_CITY_195_20150128_Q.X1275043Y508674L2LRATS" (terms "CRESCENT_CITY_195_20150128_Q.@@R1192.1.2.2" "CRESCENT_CITY_195_20150128_Q.T@@RATS@@R661.2@@R1192.2.2" "CRESCENT_CITY_195_20150128_Q.T@@RATS@@R1192.2@@R1174.2.1")) ("CRESCENT_CITY_195_20150128_Q.X1347350Y59713L2LRATS" (terms "CRESCENT_CITY_195_20150128_Q.T@@RATS@@EU21.16@@R1660.1.1" "CRESCENT_CITY_195_20150128_Q.@@EU21.16.1")) ("CRESCENT_CITY_195_20150128_Q.X1330500Y68000L2LRATS" (terms "CRESCENT_CITY_195_20150128_Q.T@@RATS@@R661.2@@R1660.2.2" "CRESCENT_CITY_195_20150128_Q.@@R1660.1.2.2")) ("CRESCENT_CITY_195_20150128_Q.X1436060Y541455L2LRATS" (terms "CRESCENT_CITY_195_20150128_Q.@@R2037.2.1.1" "CRESCENT_CITY_195_20150128_Q.T@@RATS@@R2037.2@@R2042.2.1" "CRESCENT_CITY_195_20150128_Q.T@@RATS@@R1174.2@@R2037.2.2")) ("CRESCENT_CITY_195_20150128_Q.X1282000Y514000L2RATS" (terms "CRESCENT_CITY_195_20150128_Q.@@R1174.1_SOURCE.1" "CRESCENT_CITY_195_20150128_Q.@@R1174.1.2.1")) ("CRESCENT_CITY_195_20150128_Q.X1278500Y514000L2LRATS" (terms "CRESCENT_CITY_195_20150128_Q.T@@RATS@@R1174.2@@R2037.2.1" "CRESCENT_CITY_195_20150128_Q.T@@RATS@@R1192.2@@R1174.2.2" "CRESCENT_CITY_195_20150128_Q.@@R1174.1.2.2"))) (Ports) (Stimuli ("local88" (scope local) (stimType periodic) (Props (periodicFreq "5e+007") (periodicJitter "0") (periodicPattern "1"))) ("local86" (scope local) (stimType periodic) (Props (periodicFreq "5e+007") (periodicJitter "0") (periodicPattern "1"))) ("local83" (scope local) (stimType periodic) (Props (periodicFreq "5e+007") (periodicJitter "0") (periodicPattern "1"))) ("local84" (scope local) (stimType periodic) (Props (periodicFreq "5e+007") (periodicJitter "0") (periodicPattern "1"))) ("local85" (scope local) (stimType periodic) (Props (periodicFreq "5e+007") (periodicJitter "0") (periodicPattern "1"))) ("local87" (scope local) (stimType periodic) (Props (periodicFreq "5e+007") (periodicJitter "0") (periodicPattern "1")))) (Notes) (Constraints ("DELAY_RULE" ("CRESCENT_CITY_195_20150128_Q U36.DJ44" "CRESCENT_CITY_195_20150128_Q R1192.1" "LENGTH" "" "LENGTH" "0.1143") ("CRESCENT_CITY_195_20150128_Q R2037.2" "CRESCENT_CITY_195_20150128_Q R2042.2" "LENGTH" "" "LENGTH" "0.00508") ("CRESCENT_CITY_195_20150128_Q R2037.1" "CRESCENT_CITY_195_20150128_Q R1660.2" "LENGTH" "" "LENGTH" "0.6858") ("CRESCENT_CITY_195_20150128_Q R1174.2" "CRESCENT_CITY_195_20150128_Q R1192.2" "LENGTH" "" "LENGTH" "0.01016") ("CRESCENT_CITY_195_20150128_Q R661.2" "CRESCENT_CITY_195_20150128_Q R1660.2" "LENGTH" "" "LENGTH" "0.0508") ("CRESCENT_CITY_195_20150128_Q EU75.16" "CRESCENT_CITY_195_20150128_Q R2037.1" "LENGTH" "" "LENGTH" "0.0254") ("CRESCENT_CITY_195_20150128_Q EU21.16" "CRESCENT_CITY_195_20150128_Q R1660.1" "LENGTH" "" "LENGTH" "0.0254")) ("RELATIVE_PROPAGATION_DELAY" ("#SVID_CPU1_0_U36-EU75" "CRESCENT_CITY_195_20150128_Q EU75.16" "CRESCENT_CITY_195_20150128_Q U36.DJ44" "GLOBAL" "LENGTH" "0.00635" "NONE" "") ("#SVID_CPU1_0_U36-EU21" "CRESCENT_CITY_195_20150128_Q EU21.16" "CRESCENT_CITY_195_20150128_Q U36.DJ44" "GLOBAL" "LENGTH" "0.00635" "NONE" ""))) (MeasurementSets ("EMI" ("EMIStatus" status("on")) ("PeakEmission" status("on")) ("PeakFrequency" status("on")) ("PulseFreq" status("on")) ("RiseTime" status("on")) ("VoltageSwing" status("on"))) ("Reflection" ("BufferDelayFall" status("off")) ("BufferDelayRise" status("off")) ("EyeHeight" status("off")) ("EyeJitter" status("off")) ("EyeWidth" status("off")) ("FirstIncidentFall" status("off")) ("FirstIncidentRise" status("off")) ("Glitch" status("on")) ("GlitchFall" status("off")) ("GlitchRise" status("off")) ("Monotonic" status("on")) ("MonotonicFall" status("off")) ("MonotonicRise" status("off")) ("NoiseMargin" status("on")) ("NoiseMarginHigh" status("off")) ("NoiseMarginLow" status("off")) ("OvershootHigh" status("on")) ("OvershootLow" status("on")) ("PropDelay" status("on")) ("SettleDelay" status("on")) ("SettleDelayFall" status("off")) ("SettleDelayRise" status("off")) ("SwitchDelay" status("on")) ("SwitchDelayFall" status("off")) ("SwitchDelayRise" status("off"))) ("Crosstalk" ("Crosstalk" status("on"))) ("Custom")) (VectorSets) (Props (XnetName "SVID_DIO1_CPU0") (allDrivers "active") (customSimType "Reflection") (ftsMode ("Typ")) (rcvrSelect "all") (tlineDelayMode "time") (userRevision "1.0")))) (Subckts) (CrossSections ("CRESCENT_CITY_195_20150128_Q" (Props (SXDesignName "CRESCENT_CITY_195_20150128_Q")) (Layers ("" (layerType "SURFACE") (material "AIR") (thickness "0 mil") (dielectricConstant "1.000000") (lossTangent "0") (etchFactor "0.000000") (elecCondVal "0 mho/cm") (thermCondVal "0 w/cm-degC")) ("" (layerType "DIELECTRIC") (material "CONFORMAL_COAT") (thickness "0.5 mil") (dielectricConstant "3.800000") (lossTangent "0.035") (etchFactor "0.000000") (elecCondVal "0 mho/cm") (thermCondVal "0.012 w/cm-degC")) ("TOP" (layerType "CONDUCTOR") (material "COPPER") (thickness "  2.100000 mil") (width "4.00 MIL") (dielectricConstant "4.500000") (lossTangent "0") (etchFactor "70.000000") (elecCondVal "595900.000000 mho/cm") (thermCondVal "0 w/cm-degC") (signalDieConstant "3.800000") (signalLossTangent "0.035")) ("" (layerType "DIELECTRIC") (material "FR-4") (thickness "  2.670000 mil") (dielectricConstant "4.000000") (lossTangent "0.035") (etchFactor "0.000000") (elecCondVal "0 mho/cm") (thermCondVal "0.012 w/cm-degC")) ("L2_GND1" (layerType "PLANE") (material "COPPER") (isShield t) (thickness "  1.250000 mil") (dielectricConstant "4.500000") (lossTangent "0.035") (etchFactor "90.000000") (elecCondVal "595900.000000 mho/cm") (thermCondVal "0.012 w/cm-degC")) ("" (layerType "DIELECTRIC") (material "FR-4") (thickness "  9.000000 mil") (dielectricConstant "4.100000") (lossTangent "0.035") (etchFactor "0.000000") (elecCondVal "0 mho/cm") (thermCondVal "0.012 w/cm-degC")) ("L3_SIG1" (layerType "CONDUCTOR") (material "COPPER") (thickness "  1.250000 mil") (width "4.00 MIL") (dielectricConstant "4.500000") (lossTangent "0.035") (etchFactor "90.000000") (elecCondVal "595900.000000 mho/cm") (thermCondVal "0.012 w/cm-degC") (signalDieConstant "4.100000") (signalLossTangent "0.035")) ("" (layerType "DIELECTRIC") (material "FR-4") (thickness "  3.000000 mil") (dielectricConstant "4.500000") (lossTangent "0.035") (etchFactor "0.000000") (elecCondVal "0 mho/cm") (thermCondVal "0 w/cm-degC")) ("L4_GND2" (layerType "PLANE") (material "COPPER") (isShield t) (thickness "  1.250000 mil") (dielectricConstant "4.500000") (lossTangent "0.035") (etchFactor "90.000000") (elecCondVal "595900.000000 mho/cm") (thermCondVal "0 w/cm-degC")) ("" (layerType "DIELECTRIC") (material "FR-4") (thickness "  9.000000 mil") (dielectricConstant "4.000000") (lossTangent "0.035") (etchFactor "0.000000") (elecCondVal "0 mho/cm") (thermCondVal "0.012 w/cm-degC")) ("L5_SIG2" (layerType "CONDUCTOR") (material "COPPER") (thickness "  1.250000 mil") (width "4.00 MIL") (dielectricConstant "4.500000") (lossTangent "0.035") (etchFactor "90.000000") (elecCondVal "595900.000000 mho/cm") (thermCondVal "0.012 w/cm-degC") (signalDieConstant "4.000000") (signalLossTangent "0.035")) ("" (layerType "DIELECTRIC") (material "FR-4") (thickness "  3.000000 mil") (dielectricConstant "4.500000") (lossTangent "0.035") (etchFactor "0.000000") (elecCondVal "0 mho/cm") (thermCondVal "0 w/cm-degC")) ("L6_GND3" (layerType "PLANE") (material "COPPER") (isShield t) (thickness "  1.250000 mil") (dielectricConstant "4.500000") (lossTangent "0.035") (etchFactor "90.000000") (elecCondVal "595900.000000 mho/cm") (thermCondVal "0 w/cm-degC")) ("" (layerType "DIELECTRIC") (material "FR-4") (thickness "  4.500000 mil") (dielectricConstant "4.100000") (lossTangent "0.035") (etchFactor "0.000000") (elecCondVal "0 mho/cm") (thermCondVal "0.012 w/cm-degC")) ("L7_PWR1-SIG" (layerType "PLANE") (material "COPPER") (isShield t) (thickness "  2.400000 mil") (dielectricConstant "4.500000") (lossTangent "0.035") (etchFactor "90.000000") (elecCondVal "595900.000000 mho/cm") (thermCondVal "0.012 w/cm-degC")) ("" (layerType "DIELECTRIC") (material "FR-4") (thickness "  4.600000 mil") (dielectricConstant "4.000000") (lossTangent "0.035") (etchFactor "0.000000") (elecCondVal "0 mho/cm") (thermCondVal "0.012 w/cm-degC")) ("L8_PWR2-SIG" (layerType "PLANE") (material "COPPER") (isShield t) (thickness "  2.400000 mil") (dielectricConstant "4.500000") (lossTangent "0.035") (etchFactor "90.000000") (elecCondVal "595900.000000 mho/cm") (thermCondVal "0.012 w/cm-degC")) ("" (layerType "DIELECTRIC") (material "FR-4") (thickness "  8.000000 mil") (dielectricConstant "4.500000") (lossTangent "0.035") (etchFactor "0.000000") (elecCondVal "0 mho/cm") (thermCondVal "0 w/cm-degC")) ("" (layerType "DIELECTRIC") (material "FR-4") (thickness "  8.000000 mil") (dielectricConstant "4.500000") (lossTangent "0.035") (etchFactor "0.000000") (elecCondVal "0 mho/cm") (thermCondVal "0 w/cm-degC")) ("" (layerType "DIELECTRIC") (material "FR-4") (thickness "  4.500000 mil") (dielectricConstant "4.500000") (lossTangent "0.035") (etchFactor "0.000000") (elecCondVal "0 mho/cm") (thermCondVal "0 w/cm-degC")) ("L9_GND4" (layerType "PLANE") (material "COPPER") (isShield t) (thickness "  1.250000 mil") (dielectricConstant "4.500000") (lossTangent "0.035") (etchFactor "90.000000") (elecCondVal "595900.000000 mho/cm") (thermCondVal "0 w/cm-degC")) ("" (layerType "DIELECTRIC") (material "FR-4") (thickness "  3.000000 mil") (dielectricConstant "4.100000") (lossTangent "0.035") (etchFactor "0.000000") (elecCondVal "0 mho/cm") (thermCondVal "0.012 w/cm-degC")) ("L10_SIG3" (layerType "CONDUCTOR") (material "COPPER") (thickness "  1.250000 mil") (width "4.00 MIL") (dielectricConstant "4.500000") (lossTangent "0.035") (etchFactor "90.000000") (elecCondVal "595900.000000 mho/cm") (thermCondVal "0.012 w/cm-degC") (signalDieConstant "4.100000") (signalLossTangent "0.035")) ("" (layerType "DIELECTRIC") (material "FR-4") (thickness "  9.000000 mil") (dielectricConstant "4.500000") (lossTangent "0.035") (etchFactor "0.000000") (elecCondVal "0 mho/cm") (thermCondVal "0 w/cm-degC")) ("L11_GND5" (layerType "PLANE") (material "COPPER") (isShield t) (thickness "  1.250000 mil") (dielectricConstant "4.500000") (lossTangent "0.035") (etchFactor "90.000000") (elecCondVal "595900.000000 mho/cm") (thermCondVal "0 w/cm-degC")) ("" (layerType "DIELECTRIC") (material "FR-4") (thickness "  3.000000 mil") (dielectricConstant "4.500000") (lossTangent "0.035") (etchFactor "0.000000") (elecCondVal "0 mho/cm") (thermCondVal "0.012 w/cm-degC")) ("L12_SIG4" (layerType "CONDUCTOR") (material "COPPER") (thickness "  1.250000 mil") (width "4.00 MIL") (dielectricConstant "4.500000") (lossTangent "0.035") (etchFactor "90.000000") (elecCondVal "595900.000000 mho/cm") (thermCondVal "0.012 w/cm-degC") (signalDieConstant "4.500000") (signalLossTangent "0.035")) ("" (layerType "DIELECTRIC") (material "FR-4") (thickness "  9.000000 mil") (dielectricConstant "4.500000") (lossTangent "0.035") (etchFactor "0.000000") (elecCondVal "0 mho/cm") (thermCondVal "0 w/cm-degC")) ("L13_GND6" (layerType "PLANE") (material "COPPER") (isShield t) (thickness "  1.250000 mil") (dielectricConstant "4.500000") (lossTangent "0.035") (etchFactor "90.000000") (elecCondVal "595900.000000 mho/cm") (thermCondVal "0.012 w/cm-degC")) ("" (layerType "DIELECTRIC") (material "FR-4") (thickness "  2.670000 mil") (dielectricConstant "4.500000") (lossTangent "0.035") (etchFactor "0.000000") (elecCondVal "0 mho/cm") (thermCondVal "0.012 w/cm-degC")) ("BOTTOM" (layerType "CONDUCTOR") (material "COPPER") (thickness "  2.100000 mil") (width "4.00 MIL") (dielectricConstant "4.500000") (lossTangent "0") (etchFactor "70.000000") (elecCondVal "595900.000000 mho/cm") (thermCondVal "0 w/cm-degC") (signalDieConstant "3.800000") (signalLossTangent "0.035")) ("" (layerType "DIELECTRIC") (material "CONFORMAL_COAT") (thickness "0.5 mil") (dielectricConstant "3.800000") (lossTangent "0.035") (etchFactor "0.000000") (elecCondVal "0 mho/cm") (thermCondVal "0.012 w/cm-degC")) ("" (layerType "SURFACE") (material "AIR") (thickness "0 mil") (dielectricConstant "1.000000") (lossTangent "0") (etchFactor "0.000000") (elecCondVal "0 mho/cm") (thermCondVal "0 w/cm-degC"))))) (Props (DesUnits "mils 2") (LayerStack ("DIELECTRIC" "DIELECTRIC" "BOTTOM" "DIELECTRIC" "L13_GND6" "DIELECTRIC" "L12_SIG4" "DIELECTRIC" "L11_GND5" "DIELECTRIC" "L10_SIG3" "DIELECTRIC" "L9_GND4" "DIELECTRIC" "DIELECTRIC" "DIELECTRIC" "L8_PWR2-SIG" "DIELECTRIC" "L7_PWR1-SIG" "DIELECTRIC" "L6_GND3" "DIELECTRIC" "L5_SIG2" "DIELECTRIC" "L4_GND2" "DIELECTRIC" "L3_SIG1" "DIELECTRIC" "L2_GND1" "DIELECTRIC" "TOP" "DIELECTRIC" "DIELECTRIC")) (Revision "16.600")) (Params (DiffOutputPkg ((temperature "27") (bufferModelNonInverting "CDSDefaultOutput_2p5v") (bufferModelInverting "CDSDefaultOutput_2p5v") (stimuli nil) (offsets nil) (state "tristate") (cycle "1") (termMap nil) (setup "0.9e-09") (hold "0.4e-09") (rise nil) (fall nil) (threshOutputHighMin "2.375  V") (threshOutputHighTyp "2.5  V") (threshOutputHighMax "2.625  V") (threshOutputLowMin "1.275  V") (threshOutputLowTyp "1.7  V") (threshOutputLowMax "1.985  V") (mappingTagNonInverting nil) (mappingTagInverting nil) (spice nil))) (HiClampTerm ((cutoffVoltage "0.7 V") (voltage "5 V") (maxDelay "0.1 ns"))) (LowClampTerm ((cutoffVoltage "0.7 V") (voltage "0 V") (maxDelay "0.1 ns"))) (DiffOutput ((temperature "27") (bufferModelNonInverting "CDSDefaultOutput_2p5v") (bufferModelInverting "CDSDefaultOutput_2p5v") (stimuli nil) (offsets nil) (state "tristate") (cycle "1") (termMap nil) (setup "0.9e-09") (hold "0.4e-09") (rise nil) (fall nil) (threshOutputHighMin "2.375  V") (threshOutputHighTyp "2.5  V") (threshOutputHighMax "2.625  V") (threshOutputLowMin "1.275  V") (threshOutputLowTyp "1.7  V") (threshOutputLowMax "1.985  V") (mappingTagNonInverting nil) (mappingTagInverting nil) (spice nil))) (Via ((model "Unknown") (viaOutputFormat "Unknown") (viaPadstack nil) (viaTopLayer nil) (viaBottomLayer nil) (viaIsPower nil) (viaIsGround nil))) (Resistor ((resistance "50 ohm") (orientation "0"))) (RCTerm ((resistance "50 ohm") (capacitance "20 pF") (voltage "5 V") (maxDelay "0.1 ns"))) (DiffIOPkg ((temperature "27") (bufferModelNonInverting "CDSDefaultIO_2p5v") (bufferModelInverting "CDSDefaultIO_2p5v") (stimuli nil) (offsets nil) (state "tristate") (cycle "1") (termMap nil) (setup "0.9e-09") (hold "0.4e-09") (rise nil) (fall nil) (threshInputHighMin "1.7 V") (threshInputHighTyp "1.7  V") (threshInputHighMax "1.7  V") (threshInputLowMin "0.7  V") (threshInputLowTyp "0.7  V") (threshInputLowMax "0.7 ") (threshOutputHighMin "2.365  V") (threshOutputHighTyp "2.5  V") (threshOutputHighMax "2.625  V") (threshOutputLowMin "1.275  V") (threshOutputLowTyp "1.7  V") (threshOutputLowMax "1.985  V") (mappingTagNonInverting nil) (mappingTagInverting nil) (spice nil))) (Trace ((d1Thickness "10 mil") (d1Constant "4.5") (d1LossTangent "0.035") (d2Thickness "10 mil") (d2Constant "4.5") (d2LossTangent "0.035") (d3Thickness "0.0") (d3Constant "1.0") (d3LossTangent "0") length("1000 mil") (spacing "5 mil") (spacing2 "5 mil") (spacing3 "5 mil") (spacing4 "5 mil") (spacing5 "5 mil") (traceConductivity "595900 mho/cm") (traceGeometry "microstrip") (traceLayerName "") (traceThickness "0.72 mil") (traceType "single") (traceWidth "5.0 mil") (traceWidth2 "5.0 mil") (traceWidth3 "5.0 mil") (traceWidth4 "5.0 mil") (traceWidth5 "5.0 mil") (traceWidth6 "5.0 mil") (offset "0 mil") (traceCount "1") (impedance nil))) (TheveninTerm ((resistanceUp "180 ohm") (resistanceDown "270 ohm") (voltageUp "5 V") (voltageDown "0 V") (maxDelay "0.1 ns"))) (DiffIO ((temperature "27") (bufferModelNonInverting "CDSDefaultIO_2p5v") (bufferModelInverting "CDSDefaultIO_2p5v") (stimuli nil) (offsets nil) (state "tristate") (cycle "1") (termMap nil) (setup "0.9e-09") (hold "0.4e-09") (rise nil) (fall nil) (threshInputHighMin "1.7 V") (threshInputHighTyp "1.7  V") (threshInputHighMax "1.7  V") (threshInputLowMin "0.7  V") (threshInputLowTyp "0.7  V") (threshInputLowMax "0.7 ") (threshOutputHighMin "2.365  V") (threshOutputHighTyp "2.5  V") (threshOutputHighMax "2.625  V") (threshOutputLowMin "1.275  V") (threshOutputLowTyp "1.7  V") (threshOutputLowMax "1.985  V") (mappingTagNonInverting nil) (mappingTagInverting nil) (spice nil))) (ShuntTerm ((resistance "50 ohm") (voltage "5 V") (maxDelay "0.1 ns"))) (Inductor ((inductance "5 nH") (orientation "0"))) (Capacitor ((capacitance "10 pF") (orientation "0"))) (RLGC (length("1000 mil"))) (Source ((voltage "5 V"))) (DiffInput ((temperature "27") (bufferModelNonInverting "CDSDefaultInput_2p5v") (bufferModelInverting "CDSDefaultInput_2p5v") (threshInputHighMin "1.7 V") (threshInputHighTyp "1.7  V") (threshInputHighMax "1.7  V") (threshInputLowMin "0.7  V") (threshInputLowTyp "0.7  V") (threshInputLowMax "0.7  V") (mappingTagNonInverting nil) (mappingTagInverting nil) (cycle "1"))) (Cable (length("1 m"))) (CPWSL ((d1Thickness "10 mil") (d1Constant "4.5") (d1LossTangent "0.035") (d2Thickness "0.72 mil") (d2Constant "4.5") (d2LossTangent "0.035") (d3Thickness "10 mil") (d3Constant "4.5") (d3LossTangent "0.035") length("1000 mil") (spacing "5 mil") (spacing2 "5 mil") (spacing3 "5 mil") (spacing4 "5 mil") (spacing5 "5 mil") (traceConductivity "595900 mho/cm") (traceGeometry "cpwms") (traceLayerName "") (traceThickness "0.72 mil") (traceType "single") (traceWidth "5.0 mil") (traceWidth2 "5.0 mil") (traceWidth3 "5.0 mil") (traceWidth4 "5.0 mil") (traceWidth5 "5.0 mil") (traceWidth6 "5.0 mil") (offset "0 mil") (traceCount "1") (impedance nil))) (ESpiceDevice nil) (CPWMS ((d1Thickness "10 mil") (d1Constant "4.5") (d1LossTangent "0.035") (d2Thickness "0.72 mil") (d2Constant "4.5") (d2LossTangent "0.035") (d3Thickness "0.0") (d3Constant "1") (d3LossTangent "0") length("1000 mil") (spacing "5 mil") (spacing2 "5 mil") (spacing3 "5 mil") (spacing4 "5 mil") (spacing5 "5 mil") (traceConductivity "595900 mho/cm") (traceGeometry "cpwms") (traceLayerName "") (traceThickness "0.72 mil") (traceType "single") (traceWidth "5.0 mil") (traceWidth2 "5.0 mil") (traceWidth3 "5.0 mil") (traceWidth4 "5.0 mil") (traceWidth5 "5.0 mil") (traceWidth6 "5.0 mil") (offset "0 mil") (traceCount "1") (impedance nil))) (Diode ((cutoffVoltage "0.7 V"))) (CPW ((d1Thickness "10 mil") (d1Constant "4.5") (d1LossTangent "0.035") (d2Thickness "0.72 mil") (d2Constant "1") (d2LossTangent "0") (d3Thickness "0.0") (d3Constant "1") (d3LossTangent "0") length("1000 mil") (spacing "5 mil") (spacing2 "5 mil") (spacing3 "5 mil") (spacing4 "5 mil") (spacing5 "5 mil") (traceConductivity "595900 mho/cm") (traceGeometry "cpwms") (traceLayerName "") (traceThickness "0.72 mil") (traceType "single") (traceWidth "5.0 mil") (traceWidth2 "5.0 mil") (traceWidth3 "5.0 mil") (traceWidth4 "5.0 mil") (traceWidth5 "5.0 mil") (traceWidth6 "5.0 mil") (offset "0 mil") (traceCount "1") (impedance nil))) (DualClampTerm ((cutoffVoltageUp "0.7 V") (cutoffVoltageDown "0.7 V") (voltageUp "5 V") (voltageDown "0 V") (maxDelay "0.1 ns"))) (IbisOutputPkg ((temperature "27") (bufferModel "CDSDefaultOutput_2p5v") (stimuli nil) (offsets nil) (state "tristate") (cycle "1") (termMap nil) (setup "2.0e-09") (hold "1.0e-09") (rise nil) (fall nil) (macroType nil) (voltage nil) (spice nil) (LEFDEFPinName nil) (LEFDEFPinType nil) (mappingTag nil))) (IbisIO_OpenPullDown ((temperature "27") (bufferModel "CDSDefaultIO_2p5v") (stimuli nil) (offsets nil) (state "tristate") (cycle "1") (termMap nil) (setup "2.0e-09") (hold "1.0e-09") (rise nil) (fall nil) (macroType nil) (voltage nil) (spice nil) (LEFDEFPinName nil) (LEFDEFPinType nil) (mappingTag nil))) (IbisInputPkg ((temperature "27") (bufferModel "CDSDefaultInput_2p5v") (cycle "1") (LEFDEFPinName nil) (LEFDEFPinType nil) (mappingTag nil))) (IbisIOMacro ((temperature "27") (bufferModel "CDSDefaultIO_2p5v") (stimuli nil) (offsets nil) (state "tristate") (cycle "1") (termMap nil) (setup "2.0e-09") (hold "1.0e-09") (rise nil) (fall nil) (macroType nil) (voltage nil) (spice nil) (LEFDEFPinName nil) (LEFDEFPinType nil) (mappingTag nil))) (IbisIO_OpenPullUp ((temperature "27") (bufferModel "CDSDefaultIO_2p5v") (stimuli nil) (offsets nil) (state "tristate") (cycle "1") (termMap nil) (setup "2.0e-09") (hold "1.0e-09") (rise nil) (fall nil) (macroType nil) (voltage nil) (spice nil) (LEFDEFPinName nil) (LEFDEFPinType nil) (mappingTag nil))) (IbisIOPkg ((temperature "27") (bufferModel "CDSDefaultIO_2p5v") (stimuli nil) (offsets nil) (state "tristate") (cycle "1") (termMap nil) (setup "2.0e-09") (hold "1.0e-09") (rise nil) (fall nil) (macroType nil) (voltage nil) (spice nil) (LEFDEFPinName nil) (LEFDEFPinType nil) (mappingTag nil))) (clocked ((clockRise "1e-09") (clockFall "1e-09") (clockFreq "100e6") (clockInitState "0") (clockDutyCycle "0.5") (clockJitter "0"))) (periodic ((periodicFreq "100e6") (periodicPattern "10") (periodicJitter "0"))) (IbisIO ((temperature "27") (bufferModel "CDSDefaultIO_2p5v") (stimuli nil) (offsets nil) (state "tristate") (cycle "1") (termMap nil) (setup "2.0e-09") (hold "1.0e-09") (rise nil) (fall nil) (macroType nil) (voltage nil) (spice nil) (LEFDEFPinName nil) (LEFDEFPinType nil) (mappingTag nil))) (async ((asyncTimePoints "") (asyncInitState "1"))) (IbisOutput ((temperature "27") (bufferModel "CDSDefaultOutput_2p5v") (stimuli nil) (offsets nil) (state "tristate") (cycle "1") (termMap nil) (setup "2.0e-09") (hold "1.0e-09") (rise nil) (fall nil) (macroType nil) (voltage nil) (spice nil) (LEFDEFPinName nil) (LEFDEFPinType nil) (mappingTag nil))) (TLine ((diffImpedance "100ohm") (diffVelocity "1.4142e+08M/s") (impedance "60ohm") length("2800 mil") (propDelay "0.5 ns") (velocity "5600 mil/ns") (traceCount "1") (traceGeometry "Microstrip") (impedanceMin nil) (impedanceMax nil) (lengthMin nil) (lengthMax nil) (propDelayMin nil) (propDelayMax nil) (impedanceSweepCount nil) (propDelaySweepCount nil) (velocitySweepCount nil) (lengthSweepCount nil) (matchSetName nil))) (CurrentProbe nil) (IbisInput ((temperature "27") (bufferModel "CDSDefaultInput_2p5v") (cycle "1") (LEFDEFPinName nil) (LEFDEFPinType nil) (mappingTag nil))) (SeriesTerm ((resistance "22 ohm") (maxDelay "0.1 ns"))) (Connector nil) (sync ((syncFreq "100e6") (syncInitState "1") (syncPattern "10") (syncEdgeSwitch "rise"))) (IbisOutput_OpenPullUp ((temperature "27") (bufferModel "CDSDefaultOutput_2p5v") (stimuli nil) (offsets nil) (state "tristate") (cycle "1") (termMap nil) (setup "2.0e-09") (hold "1.0e-09") (rise nil) (fall nil) (macroType nil) (voltage nil) (spice nil) (LEFDEFPinName nil) (LEFDEFPinType nil) (mappingTag nil))) (DiffInputPkg ((temperature "27") (bufferModelNonInverting "CDSDefaultInput_2p5v") (bufferModelInverting "CDSDefaultInput_2p5v") (threshInputHighMin "1.7 V") (threshInputHighTyp "1.7  V") (threshInputHighMax "1.7  V") (threshInputLowMin "0.7  V") (threshInputLowTyp "0.7  V") (threshInputLowMax "0.7  V") (mappingTagNonInverting nil) (mappingTagInverting nil) (cycle "1"))) (idlCircuit ((allDrivers "active") (ftsMode '("Typ")) (rcvrSelect "all") (simMode "Reflection") (tlineDelayMode "time") (userRevision "1.0") (autoSolve "On")))))
				)
				( objectStatus "SVID_DIO1_CPU0" )
			)
			( electricalCSet "@crescent_city_bb_fab1_lib.crescent_city_bb_fab1(sch_1):\CATERR\"
				( pinPairRef "CATERR:R4R2.2:NET.T.1" )
				( pinPairRef "CATERR:R4R2.2:U5D1.AL14" )
				( pinPairRef "CATERR:R7P18.2:NET.T.1" )
				( pinPairRef "CATERR:U2T4.2:NET.T.1" )
				( pinPairRef "CATERR:U2D1.AL14:R7P18.2" )
				( attribute "RATSNEST_SCHEDULE" "TEMPLATE"
					( Status sLocked )
					( Origin gBackEnd )
				)
				( attribute "DIFFP_COUPLED_PLUS" "0.50"
					( Origin gBackEnd )
				)
				( attribute "DIFFP_COUPLED_MINUS" "0.50"
					( Origin gBackEnd )
				)
				( attribute "TOPOLOGY_TEMPLATE_REVISION" "1.0"
					( Origin gBackEnd )
				)
				( topologyData 28827
(SKIDL (Circuits ("MAIN" (Parts ("CRESCENT_CITY_176_20141216_Q.@@U36.AL14" IbisIOPkg (xy (5507.5 4216.5)) (refDes "U5D1") (model "Unknown") (Props (_SXDesignName "CRESCENT_CITY_176_20141216_Q") (brdx "11657.1 MIL") (brdy "2610.47 MIL") (bufferModel "CDSDefaultIO_2p5v") (cycle "1") (hold "1.0e-09") (mappingTag "") (offsets ("4" "0") ("5" "0")) (setup "2.0e-09") (state "tristate") (stimuli ("4" "local3") ("5" "local4")) (temperature "27") (termMap ("4" "Data") ("5" "Enable"))) (Terms ("CRESCENT_CITY_176_20141216_Q.X1165710Y261047L2LRATS" "AL14"))) ("CRESCENT_CITY_176_20141216_Q.@@U56.2" IbisIOPkg (xy (5446.0 4240.5)) (refDes "U2T4") (model "Unknown") (Props (_SXDesignName "CRESCENT_CITY_176_20141216_Q") (brdx "15754.46 MIL") (brdy "820.03 MIL") (bufferModel "CDSDefaultIO_2p5v") (cycle "1") (hold "1.0e-09") (mappingTag "") (offsets ("4" "0") ("5" "0")) (setup "2.0e-09") (state "tristate") (stimuli ("4" "local5") ("5" "local6")) (temperature "27") (termMap ("4" "Data") ("5" "Enable"))) (Terms ("idlNode_79" "2"))) ("CRESCENT_CITY_176_20141216_Q.@@U100.AL14" IbisIOPkg (xy (5502 4240)) (refDes "U2D1") (model "Unknown") (Props (_SXDesignName "CRESCENT_CITY_176_20141216_Q") (brdx "5161.02 MIL") (brdy "2610.47 MIL") (bufferModel "CDSDefaultIO_2p5v") (cycle "1") (hold "1.0e-09") (mappingTag "") (offsets ("4" "0") ("5" "0")) (setup "2.0e-09") (state "tristate") (stimuli ("4" "local7") ("5" "local8")) (temperature "27") (termMap ("4" "Data") ("5" "Enable"))) (Terms ("CRESCENT_CITY_176_20141216_Q.X516102Y261047L2LRATS" "AL14"))) ("CRESCENT_CITY_176_20141216_Q.T@@RATS@@R600.2@@R572.1" TLine (xy (5487.5 4229.0)) (mirror x) (refDes "TL5") (Props (_SXDesignName "CRESCENT_CITY_176_20141216_Q") (impedance "46.577 ohm") length("65.00 MIL") (propDelay "0.01167 ns") (traceCount "1") (traceGeometry "Microstrip") (velocity "5569.84 mil/ns")) (Terms ("CRESCENT_CITY_176_20141216_Q.X1555000Y75500L28LRATS" "1") ("idlNode_12" "2"))) ("CRESCENT_CITY_176_20141216_Q.@@R570.1.2" Resistor (xy (5474.5 4211.5)) (mirror x) (refDes "R3P59") (value "2.2e-007 Ohm") (Props (_SXDesignName "CRESCENT_CITY_176_20141216_Q")) (Terms ("CRESCENT_CITY_176_20141216_Q.X1561500Y72000L28LRATS" "1") ("CRESCENT_CITY_176_20141216_Q.X1565000Y72000L28LRATS" "2"))) ("CRESCENT_CITY_176_20141216_Q.@@R600.1_SOURCE" Source (xy (5480.5 4238.5)) (refDes "PVCCIO_CPU0_1") (value "1.05 V") (Props (_SXDesignName "CRESCENT_CITY_176_20141216_Q")) (Terms ("CRESCENT_CITY_176_20141216_Q.X1551500Y75500L28RATS" "1"))) ("CRESCENT_CITY_176_20141216_Q.T@@RATS@@U100.AL14@@R600.2" TLine (xy (5497.0 4229.0)) (mirror x) (refDes "TL6") (Props (_SXDesignName "CRESCENT_CITY_176_20141216_Q") (impedance "60 ohm") length("12244.45 MIL") (propDelay "2.19919 ns") (traceCount "1") (traceGeometry "Microstrip") (velocity "5567.72 mil/ns")) (Terms ("CRESCENT_CITY_176_20141216_Q.X516102Y261047L2LRATS" "1") ("CRESCENT_CITY_176_20141216_Q.X1555000Y75500L28LRATS" "2"))) ("CRESCENT_CITY_176_20141216_Q.T@@RATS@@U56.2@@R572.2" TLine (xy (5453.5 4229.5)) (refDes "TL7") (orientation "270") (Props (_SXDesignName "CRESCENT_CITY_176_20141216_Q") (impedance "46.577 ohm") length("169.49 MIL") (propDelay "0.03044 ns") (traceCount "1") (traceGeometry "Microstrip") (velocity "5567.99 mil/ns")) (Terms ("idlNode_39" "1") ("idlNode_46" "2"))) ("idlPart_31" TLine (xy (5448.0 4220.0)) (refDes "TL11") (Props (_SXDesignName "CRESCENT_CITY_176_20141216_Q") (impedance "46.577 ohm") length("169.49 MIL") (propDelay "0.03044 ns") (traceCount "1") (traceGeometry "Microstrip") (velocity "5567.99 mil/ns")) (Terms ("idlNode_79" "1") ("idlNode_46" "2"))) ("CRESCENT_CITY_176_20141216_Q.@@R597.1.2" Resistor (xy (5491.0 4205.5)) (refDes "R4R2") (value "150 Ohm") (Props (_SXDesignName "CRESCENT_CITY_176_20141216_Q")) (Terms ("CRESCENT_CITY_176_20141216_Q.X1551500Y72000L28RATS" "1") ("CRESCENT_CITY_176_20141216_Q.X1555000Y72000L28LRATS" "2"))) ("CRESCENT_CITY_176_20141216_Q.@@R572.1.2" Resistor (xy (5474.5 4230.0)) (mirror x) (refDes "R3P58") (value "2.2e-007 Ohm") (Props (_SXDesignName "CRESCENT_CITY_176_20141216_Q")) (Terms ("idlNode_12" "1") ("idlNode_39" "2"))) ("CRESCENT_CITY_176_20141216_Q.T@@RATS@@U36.AL14@@R597.2" TLine (xy (5497.0 4211.5)) (mirror x) (refDes "TL8") (Props (_SXDesignName "CRESCENT_CITY_176_20141216_Q") (impedance "60 ohm") length("5783.39 MIL") (propDelay "1.03873 ns") (traceCount "1") (traceGeometry "Microstrip") (velocity "5567.72 mil/ns")) (Terms ("CRESCENT_CITY_176_20141216_Q.X1165710Y261047L2LRATS" "1") ("CRESCENT_CITY_176_20141216_Q.X1555000Y72000L28LRATS" "2"))) ("CRESCENT_CITY_176_20141216_Q.T@@RATS@@R597.2@@R570.1" TLine (xy (5486.5 4211.5)) (mirror x) (refDes "TL9") (Props (_SXDesignName "CRESCENT_CITY_176_20141216_Q") (impedance "46.577 ohm") length("65.00 MIL") (propDelay "0.01167 ns") (traceCount "1") (traceGeometry "Microstrip") (velocity "5569.84 mil/ns")) (Terms ("CRESCENT_CITY_176_20141216_Q.X1555000Y72000L28LRATS" "1") ("CRESCENT_CITY_176_20141216_Q.X1561500Y72000L28LRATS" "2"))) ("CRESCENT_CITY_176_20141216_Q.@@R600.1.2" Resistor (xy (5487.5 4236.5)) (refDes "R7P18") (value "150 Ohm") (Props (_SXDesignName "CRESCENT_CITY_176_20141216_Q")) (Terms ("CRESCENT_CITY_176_20141216_Q.X1551500Y75500L28RATS" "1") ("CRESCENT_CITY_176_20141216_Q.X1555000Y75500L28LRATS" "2"))) ("CRESCENT_CITY_176_20141216_Q.@@R597.1_SOURCE" Source (xy (5484.0 4205.5)) (refDes "PVCCIO_CPU0") (value "1.05 V") (Props (_SXDesignName "CRESCENT_CITY_176_20141216_Q")) (Terms ("CRESCENT_CITY_176_20141216_Q.X1551500Y72000L28RATS" "1"))) ("CRESCENT_CITY_176_20141216_Q.T@@RATS@@R572.2@@R570.2" TLine (xy (5453.5 4213.0)) (refDes "TL10") (orientation "270") (Props (_SXDesignName "CRESCENT_CITY_176_20141216_Q") (impedance "46.577 ohm") length("35.00 MIL") (propDelay "0.00629 ns") (traceCount "1") (traceGeometry "Microstrip") (velocity "5564.37 mil/ns")) (Terms ("idlNode_46" "1") ("CRESCENT_CITY_176_20141216_Q.X1565000Y72000L28LRATS" "2")))) (Nodes ("CRESCENT_CITY_176_20141216_Q.X1555000Y75500L28LRATS" (terms "CRESCENT_CITY_176_20141216_Q.@@R600.1.2.2" "CRESCENT_CITY_176_20141216_Q.T@@RATS@@U100.AL14@@R600.2.2" "CRESCENT_CITY_176_20141216_Q.T@@RATS@@R600.2@@R572.1.1")) ("CRESCENT_CITY_176_20141216_Q.X1565000Y72000L28LRATS" (terms "CRESCENT_CITY_176_20141216_Q.T@@RATS@@R572.2@@R570.2.2" "CRESCENT_CITY_176_20141216_Q.@@R570.1.2.2")) ("CRESCENT_CITY_176_20141216_Q.X1555000Y72000L28LRATS" (terms "CRESCENT_CITY_176_20141216_Q.T@@RATS@@R597.2@@R570.1.1" "CRESCENT_CITY_176_20141216_Q.T@@RATS@@U36.AL14@@R597.2.2" "CRESCENT_CITY_176_20141216_Q.@@R597.1.2.2")) ("CRESCENT_CITY_176_20141216_Q.X1551500Y72000L28RATS" (terms "CRESCENT_CITY_176_20141216_Q.@@R597.1_SOURCE.1" "CRESCENT_CITY_176_20141216_Q.@@R597.1.2.1")) ("idlNode_39" (terms "CRESCENT_CITY_176_20141216_Q.@@R572.1.2.2" "CRESCENT_CITY_176_20141216_Q.T@@RATS@@U56.2@@R572.2.1")) ("CRESCENT_CITY_176_20141216_Q.X516102Y261047L2LRATS" (terms "CRESCENT_CITY_176_20141216_Q.T@@RATS@@U100.AL14@@R600.2.1" "CRESCENT_CITY_176_20141216_Q.@@U100.AL14.1")) ("idlNode_12" (terms "CRESCENT_CITY_176_20141216_Q.@@R572.1.2.1" "CRESCENT_CITY_176_20141216_Q.T@@RATS@@R600.2@@R572.1.2")) ("idlNode_46" (terms "CRESCENT_CITY_176_20141216_Q.T@@RATS@@R572.2@@R570.2.1" "idlPart_31.2" "CRESCENT_CITY_176_20141216_Q.T@@RATS@@U56.2@@R572.2.2") (tee "CRESCENT_CITY_176_20141216_Q NET.T.1")) ("idlNode_79" (terms "idlPart_31.1" "CRESCENT_CITY_176_20141216_Q.@@U56.2.1")) ("CRESCENT_CITY_176_20141216_Q.X1551500Y75500L28RATS" (terms "CRESCENT_CITY_176_20141216_Q.@@R600.1.2.1" "CRESCENT_CITY_176_20141216_Q.@@R600.1_SOURCE.1")) ("CRESCENT_CITY_176_20141216_Q.X1165710Y261047L2LRATS" (terms "CRESCENT_CITY_176_20141216_Q.T@@RATS@@U36.AL14@@R597.2.1" "CRESCENT_CITY_176_20141216_Q.@@U36.AL14.1")) ("CRESCENT_CITY_176_20141216_Q.X1561500Y72000L28LRATS" (terms "CRESCENT_CITY_176_20141216_Q.T@@RATS@@R597.2@@R570.1.2" "CRESCENT_CITY_176_20141216_Q.@@R570.1.2.1"))) (Ports) (Stimuli ("local6" (scope local) (stimType periodic) (Props (periodicFreq "5e+007") (periodicJitter "0") (periodicPattern "1"))) ("local8" (scope local) (stimType periodic) (Props (periodicFreq "5e+007") (periodicJitter "0") (periodicPattern "1"))) ("local7" (scope local) (stimType periodic) (Props (periodicFreq "5e+007") (periodicJitter "0") (periodicPattern "1"))) ("local3" (scope local) (stimType periodic) (Props (periodicFreq "5e+007") (periodicJitter "0") (periodicPattern "1"))) ("local4" (scope local) (stimType periodic) (Props (periodicFreq "5e+007") (periodicJitter "0") (periodicPattern "1"))) ("local5" (scope local) (stimType periodic) (Props (periodicFreq "5e+007") (periodicJitter "0") (periodicPattern "1")))) (Notes) (Constraints ("DELAY_RULE" ("CRESCENT_CITY_176_20141216_Q R597.2" "CRESCENT_CITY_176_20141216_Q NET.T.1" "LENGTH" "" "LENGTH" "0.254") ("CRESCENT_CITY_176_20141216_Q R597.2" "CRESCENT_CITY_176_20141216_Q U36.AL14" "LENGTH" "" "LENGTH" "0.0635") ("CRESCENT_CITY_176_20141216_Q R600.2" "CRESCENT_CITY_176_20141216_Q NET.T.1" "LENGTH" "" "LENGTH" "0.254") ("CRESCENT_CITY_176_20141216_Q U56.2" "CRESCENT_CITY_176_20141216_Q NET.T.1" "LENGTH" "" "LENGTH" "0.0127") ("CRESCENT_CITY_176_20141216_Q U100.AL14" "CRESCENT_CITY_176_20141216_Q R600.2" "LENGTH" "" "LENGTH" "0.0635")) ("RATSNEST_SCHEDULE" "TEMPLATE")) (MeasurementSets ("EMI" ("EMIStatus" status("on")) ("PeakEmission" status("on")) ("PeakFrequency" status("on")) ("PulseFreq" status("on")) ("RiseTime" status("on")) ("VoltageSwing" status("on"))) ("Reflection" ("BufferDelayFall" status("off")) ("BufferDelayRise" status("off")) ("EyeHeight" status("off")) ("EyeJitter" status("off")) ("EyeWidth" status("off")) ("FirstIncidentFall" status("off")) ("FirstIncidentRise" status("off")) ("Glitch" status("on")) ("GlitchFall" status("off")) ("GlitchRise" status("off")) ("Monotonic" status("on")) ("MonotonicFall" status("off")) ("MonotonicRise" status("off")) ("NoiseMargin" status("on")) ("NoiseMarginHigh" status("off")) ("NoiseMarginLow" status("off")) ("OvershootHigh" status("on")) ("OvershootLow" status("on")) ("PropDelay" status("on")) ("SettleDelay" status("on")) ("SettleDelayFall" status("off")) ("SettleDelayRise" status("off")) ("SwitchDelay" status("on")) ("SwitchDelayFall" status("off")) ("SwitchDelayRise" status("off"))) ("Crosstalk" ("Crosstalk" status("on"))) ("Custom")) (VectorSets) (Props (XnetName "H_CPU0_CATERR_G_N") (allDrivers "active") (autoSolve "Off") (customSimType "Reflection") (ftsMode ("Typ")) (rcvrSelect "all") (tlineDelayMode "time") (userRevision "1.0")))) (Subckts) (CrossSections ("CRESCENT_CITY_176_20141216_Q" (Props (SXDesignName "CRESCENT_CITY_176_20141216_Q")) (Layers ("" (layerType "SURFACE") (material "AIR") (thickness "0 mil") (dielectricConstant "1.000000") (lossTangent "0") (etchFactor "0.000000") (elecCondVal "0 mho/cm") (thermCondVal "0 w/cm-degC")) ("" (layerType "DIELECTRIC") (material "CONFORMAL_COAT") (thickness "0.5 mil") (dielectricConstant "3.800000") (lossTangent "0.035") (etchFactor "0.000000") (elecCondVal "0 mho/cm") (thermCondVal "0.012 w/cm-degC")) ("TOP" (layerType "CONDUCTOR") (material "COPPER") (thickness "  2.100000 mil") (width "5.0 MILS") (dielectricConstant "4.500000") (lossTangent "0") (etchFactor "70.000000") (elecCondVal "595900.000000 mho/cm") (thermCondVal "0 w/cm-degC") (signalDieConstant "3.800000") (signalLossTangent "0.035")) ("" (layerType "DIELECTRIC") (material "FR-4") (thickness "  2.670000 mil") (dielectricConstant "4.000000") (lossTangent "0.035") (etchFactor "0.000000") (elecCondVal "0 mho/cm") (thermCondVal "0.012 w/cm-degC")) ("L2_GND1" (layerType "PLANE") (material "COPPER") (isShield t) (thickness "  1.250000 mil") (dielectricConstant "4.500000") (lossTangent "0.035") (etchFactor "90.000000") (elecCondVal "595900.000000 mho/cm") (thermCondVal "0.012 w/cm-degC")) ("" (layerType "DIELECTRIC") (material "FR-4") (thickness "  9.000000 mil") (dielectricConstant "4.100000") (lossTangent "0.035") (etchFactor "0.000000") (elecCondVal "0 mho/cm") (thermCondVal "0.012 w/cm-degC")) ("L3_SIG1" (layerType "CONDUCTOR") (material "COPPER") (thickness "  1.250000 mil") (width "5.0 MILS") (dielectricConstant "4.500000") (lossTangent "0.035") (etchFactor "90.000000") (elecCondVal "595900.000000 mho/cm") (thermCondVal "0.012 w/cm-degC") (signalDieConstant "4.100000") (signalLossTangent "0.035")) ("" (layerType "DIELECTRIC") (material "FR-4") (thickness "  3.000000 mil") (dielectricConstant "4.500000") (lossTangent "0.035") (etchFactor "0.000000") (elecCondVal "0 mho/cm") (thermCondVal "0 w/cm-degC")) ("L4_GND2" (layerType "PLANE") (material "COPPER") (isShield t) (thickness "  1.250000 mil") (dielectricConstant "4.500000") (lossTangent "0.035") (etchFactor "90.000000") (elecCondVal "595900.000000 mho/cm") (thermCondVal "0 w/cm-degC")) ("" (layerType "DIELECTRIC") (material "FR-4") (thickness "  9.000000 mil") (dielectricConstant "4.000000") (lossTangent "0.035") (etchFactor "0.000000") (elecCondVal "0 mho/cm") (thermCondVal "0.012 w/cm-degC")) ("L5_SIG2" (layerType "CONDUCTOR") (material "COPPER") (thickness "  1.250000 mil") (width "5.0 MILS") (dielectricConstant "4.500000") (lossTangent "0.035") (etchFactor "90.000000") (elecCondVal "595900.000000 mho/cm") (thermCondVal "0.012 w/cm-degC") (signalDieConstant "4.000000") (signalLossTangent "0.035")) ("" (layerType "DIELECTRIC") (material "FR-4") (thickness "  3.000000 mil") (dielectricConstant "4.500000") (lossTangent "0.035") (etchFactor "0.000000") (elecCondVal "0 mho/cm") (thermCondVal "0 w/cm-degC")) ("L6_GND3" (layerType "PLANE") (material "COPPER") (isShield t) (thickness "  1.250000 mil") (dielectricConstant "4.500000") (lossTangent "0.035") (etchFactor "90.000000") (elecCondVal "595900.000000 mho/cm") (thermCondVal "0 w/cm-degC")) ("" (layerType "DIELECTRIC") (material "FR-4") (thickness "  4.500000 mil") (dielectricConstant "4.100000") (lossTangent "0.035") (etchFactor "0.000000") (elecCondVal "0 mho/cm") (thermCondVal "0.012 w/cm-degC")) ("L7_PWR1-SIG" (layerType "PLANE") (material "COPPER") (isShield t) (thickness "  2.400000 mil") (dielectricConstant "4.500000") (lossTangent "0.035") (etchFactor "90.000000") (elecCondVal "595900.000000 mho/cm") (thermCondVal "0.012 w/cm-degC")) ("" (layerType "DIELECTRIC") (material "FR-4") (thickness "  4.600000 mil") (dielectricConstant "4.000000") (lossTangent "0.035") (etchFactor "0.000000") (elecCondVal "0 mho/cm") (thermCondVal "0.012 w/cm-degC")) ("L8_PWR2-SIG" (layerType "PLANE") (material "COPPER") (isShield t) (thickness "  2.400000 mil") (dielectricConstant "4.500000") (lossTangent "0.035") (etchFactor "90.000000") (elecCondVal "595900.000000 mho/cm") (thermCondVal "0.012 w/cm-degC")) ("" (layerType "DIELECTRIC") (material "FR-4") (thickness "  4.500000 mil") (dielectricConstant "4.500000") (lossTangent "0.035") (etchFactor "0.000000") (elecCondVal "0 mho/cm") (thermCondVal "0 w/cm-degC")) ("L9_GND4" (layerType "PLANE") (material "COPPER") (isShield t) (thickness "  1.250000 mil") (dielectricConstant "4.500000") (lossTangent "0.035") (etchFactor "90.000000") (elecCondVal "595900.000000 mho/cm") (thermCondVal "0 w/cm-degC")) ("" (layerType "DIELECTRIC") (material "FR-4") (thickness "  3.000000 mil") (dielectricConstant "4.100000") (lossTangent "0.035") (etchFactor "0.000000") (elecCondVal "0 mho/cm") (thermCondVal "0.012 w/cm-degC")) ("L10_SIG3" (layerType "CONDUCTOR") (material "COPPER") (thickness "  1.250000 mil") (width "5.0 MILS") (dielectricConstant "4.500000") (lossTangent "0.035") (etchFactor "90.000000") (elecCondVal "595900.000000 mho/cm") (thermCondVal "0.012 w/cm-degC") (signalDieConstant "4.100000") (signalLossTangent "0.035")) ("" (layerType "DIELECTRIC") (material "FR-4") (thickness "  9.000000 mil") (dielectricConstant "4.500000") (lossTangent "0.035") (etchFactor "0.000000") (elecCondVal "0 mho/cm") (thermCondVal "0 w/cm-degC")) ("L11_GND5" (layerType "PLANE") (material "COPPER") (isShield t) (thickness "  1.250000 mil") (dielectricConstant "4.500000") (lossTangent "0.035") (etchFactor "90.000000") (elecCondVal "595900.000000 mho/cm") (thermCondVal "0 w/cm-degC")) ("" (layerType "DIELECTRIC") (material "FR-4") (thickness "  3.000000 mil") (dielectricConstant "4.500000") (lossTangent "0.035") (etchFactor "0.000000") (elecCondVal "0 mho/cm") (thermCondVal "0.012 w/cm-degC")) ("L12_SIG4" (layerType "CONDUCTOR") (material "COPPER") (thickness "  1.250000 mil") (width "5.0 MILS") (dielectricConstant "4.500000") (lossTangent "0.035") (etchFactor "90.000000") (elecCondVal "595900.000000 mho/cm") (thermCondVal "0.012 w/cm-degC") (signalDieConstant "4.500000") (signalLossTangent "0.035")) ("" (layerType "DIELECTRIC") (material "FR-4") (thickness "  9.000000 mil") (dielectricConstant "4.500000") (lossTangent "0.035") (etchFactor "0.000000") (elecCondVal "0 mho/cm") (thermCondVal "0 w/cm-degC")) ("L13_GND6" (layerType "PLANE") (material "COPPER") (isShield t) (thickness "  1.250000 mil") (dielectricConstant "4.500000") (lossTangent "0.035") (etchFactor "90.000000") (elecCondVal "595900.000000 mho/cm") (thermCondVal "0.012 w/cm-degC")) ("" (layerType "DIELECTRIC") (material "FR-4") (thickness "  2.670000 mil") (dielectricConstant "4.500000") (lossTangent "0.035") (etchFactor "0.000000") (elecCondVal "0 mho/cm") (thermCondVal "0.012 w/cm-degC")) ("BOTTOM" (layerType "CONDUCTOR") (material "COPPER") (thickness "  2.100000 mil") (width "5.0 MILS") (dielectricConstant "4.500000") (lossTangent "0") (etchFactor "70.000000") (elecCondVal "595900.000000 mho/cm") (thermCondVal "0 w/cm-degC") (signalDieConstant "3.800000") (signalLossTangent "0.035")) ("" (layerType "DIELECTRIC") (material "CONFORMAL_COAT") (thickness "0.5 mil") (dielectricConstant "3.800000") (lossTangent "0.035") (etchFactor "0.000000") (elecCondVal "0 mho/cm") (thermCondVal "0.012 w/cm-degC")) ("" (layerType "SURFACE") (material "AIR") (thickness "0 mil") (dielectricConstant "1.000000") (lossTangent "0") (etchFactor "0.000000") (elecCondVal "0 mho/cm") (thermCondVal "0 w/cm-degC"))))) (Props (DesUnits "mils 2") (LayerStack ("DIELECTRIC" "DIELECTRIC" "BOTTOM" "DIELECTRIC" "L13_GND6" "DIELECTRIC" "L12_SIG4" "DIELECTRIC" "L11_GND5" "DIELECTRIC" "L10_SIG3" "DIELECTRIC" "L9_GND4" "DIELECTRIC" "L8_PWR2-SIG" "DIELECTRIC" "L7_PWR1-SIG" "DIELECTRIC" "L6_GND3" "DIELECTRIC" "L5_SIG2" "DIELECTRIC" "L4_GND2" "DIELECTRIC" "L3_SIG1" "DIELECTRIC" "L2_GND1" "DIELECTRIC" "TOP" "DIELECTRIC" "DIELECTRIC")) (Revision "16.600")) (Params (Via ((model "Unknown") (viaOutputFormat "Unknown") (viaPadstack nil) (viaTopLayer nil) (viaBottomLayer nil) (viaIsPower nil) (viaIsGround nil))) (IbisIOMacro ((temperature "27") (bufferModel "CDSDefaultIO_2p5v") (stimuli nil) (offsets nil) (state "tristate") (cycle "1") (termMap nil) (setup "2.0e-09") (hold "1.0e-09") (rise nil) (fall nil) (macroType nil) (voltage nil) (spice nil) (LEFDEFPinName nil) (LEFDEFPinType nil) (mappingTag nil))) (DiffInputPkg ((temperature "27") (bufferModelNonInverting "CDSDefaultInput_2p5v") (bufferModelInverting "CDSDefaultInput_2p5v") (threshInputHighMin "1.7 V") (threshInputHighTyp "1.7  V") (threshInputHighMax "1.7  V") (threshInputLowMin "0.7  V") (threshInputLowTyp "0.7  V") (threshInputLowMax "0.7  V") (mappingTagNonInverting nil) (mappingTagInverting nil) (cycle "1"))) (DiffIO ((temperature "27") (bufferModelNonInverting "CDSDefaultIO_2p5v") (bufferModelInverting "CDSDefaultIO_2p5v") (stimuli nil) (offsets nil) (state "tristate") (cycle "1") (termMap nil) (setup "0.9e-09") (hold "0.4e-09") (rise nil) (fall nil) (threshInputHighMin "1.7 V") (threshInputHighTyp "1.7  V") (threshInputHighMax "1.7  V") (threshInputLowMin "0.7  V") (threshInputLowTyp "0.7  V") (threshInputLowMax "0.7 ") (threshOutputHighMin "2.365  V") (threshOutputHighTyp "2.5  V") (threshOutputHighMax "2.625  V") (threshOutputLowMin "1.275  V") (threshOutputLowTyp "1.7  V") (threshOutputLowMax "1.985  V") (mappingTagNonInverting nil) (mappingTagInverting nil) (spice nil))) (Trace ((d1Thickness "10 mil") (d1Constant "4.5") (d1LossTangent "0.035") (d2Thickness "10 mil") (d2Constant "4.5") (d2LossTangent "0.035") (d3Thickness "0.0") (d3Constant "1.0") (d3LossTangent "0") length("1000 mil") (spacing "5 mil") (spacing2 "5 mil") (spacing3 "5 mil") (spacing4 "5 mil") (spacing5 "5 mil") (traceConductivity "595900 mho/cm") (traceGeometry "microstrip") (traceLayerName "") (traceThickness "0.72 mil") (traceType "single") (traceWidth "5.0 mil") (traceWidth2 "5.0 mil") (traceWidth3 "5.0 mil") (traceWidth4 "5.0 mil") (traceWidth5 "5.0 mil") (traceWidth6 "5.0 mil") (offset "0 mil") (traceCount "1") (impedance nil))) (sync ((syncFreq "100e6") (syncInitState "1") (syncPattern "10") (syncEdgeSwitch "rise"))) (DiffOutputPkg ((temperature "27") (bufferModelNonInverting "CDSDefaultOutput_2p5v") (bufferModelInverting "CDSDefaultOutput_2p5v") (stimuli nil) (offsets nil) (state "tristate") (cycle "1") (termMap nil) (setup "0.9e-09") (hold "0.4e-09") (rise nil) (fall nil) (threshOutputHighMin "2.375  V") (threshOutputHighTyp "2.5  V") (threshOutputHighMax "2.625  V") (threshOutputLowMin "1.275  V") (threshOutputLowTyp "1.7  V") (threshOutputLowMax "1.985  V") (mappingTagNonInverting nil) (mappingTagInverting nil) (spice nil))) (DiffOutput ((temperature "27") (bufferModelNonInverting "CDSDefaultOutput_2p5v") (bufferModelInverting "CDSDefaultOutput_2p5v") (stimuli nil) (offsets nil) (state "tristate") (cycle "1") (termMap nil) (setup "0.9e-09") (hold "0.4e-09") (rise nil) (fall nil) (threshOutputHighMin "2.375  V") (threshOutputHighTyp "2.5  V") (threshOutputHighMax "2.625  V") (threshOutputLowMin "1.275  V") (threshOutputLowTyp "1.7  V") (threshOutputLowMax "1.985  V") (mappingTagNonInverting nil) (mappingTagInverting nil) (spice nil))) (IbisOutputPkg ((temperature "27") (bufferModel "CDSDefaultOutput_2p5v") (stimuli nil) (offsets nil) (state "tristate") (cycle "1") (termMap nil) (setup "2.0e-09") (hold "1.0e-09") (rise nil) (fall nil) (macroType nil) (voltage nil) (spice nil) (LEFDEFPinName nil) (LEFDEFPinType nil) (mappingTag nil))) (DiffIOPkg ((temperature "27") (bufferModelNonInverting "CDSDefaultIO_2p5v") (bufferModelInverting "CDSDefaultIO_2p5v") (stimuli nil) (offsets nil) (state "tristate") (cycle "1") (termMap nil) (setup "0.9e-09") (hold "0.4e-09") (rise nil) (fall nil) (threshInputHighMin "1.7 V") (threshInputHighTyp "1.7  V") (threshInputHighMax "1.7  V") (threshInputLowMin "0.7  V") (threshInputLowTyp "0.7  V") (threshInputLowMax "0.7 ") (threshOutputHighMin "2.365  V") (threshOutputHighTyp "2.5  V") (threshOutputHighMax "2.625  V") (threshOutputLowMin "1.275  V") (threshOutputLowTyp "1.7  V") (threshOutputLowMax "1.985  V") (mappingTagNonInverting nil) (mappingTagInverting nil) (spice nil))) (IbisIOPkg ((temperature "27") (bufferModel "CDSDefaultIO_2p5v") (stimuli nil) (offsets nil) (state "tristate") (cycle "1") (termMap nil) (setup "2.0e-09") (hold "1.0e-09") (rise nil) (fall nil) (macroType nil) (voltage nil) (spice nil) (LEFDEFPinName nil) (LEFDEFPinType nil) (mappingTag nil))) (CurrentProbe nil) (DiffInput ((temperature "27") (bufferModelNonInverting "CDSDefaultInput_2p5v") (bufferModelInverting "CDSDefaultInput_2p5v") (threshInputHighMin "1.7 V") (threshInputHighTyp "1.7  V") (threshInputHighMax "1.7  V") (threshInputLowMin "0.7  V") (threshInputLowTyp "0.7  V") (threshInputLowMax "0.7  V") (mappingTagNonInverting nil) (mappingTagInverting nil) (cycle "1"))) (IbisInputPkg ((temperature "27") (bufferModel "CDSDefaultInput_2p5v") (cycle "1") (LEFDEFPinName nil) (LEFDEFPinType nil) (mappingTag nil))) (idlCircuit ((allDrivers "active") (ftsMode '("Typ")) (rcvrSelect "all") (simMode "Reflection") (tlineDelayMode "time") (userRevision "1.0") (autoSolve "On"))) (SeriesTerm ((resistance "22 ohm") (maxDelay "0.1 ns"))) (RLGC (length("1000 mil"))) (periodic ((periodicFreq "100e6") (periodicPattern "10") (periodicJitter "0"))) (Resistor ((resistance "50 ohm") (orientation "0"))) (async ((asyncTimePoints "") (asyncInitState "1"))) (Capacitor ((capacitance "10 pF") (orientation "0"))) (Inductor ((inductance "5 nH") (orientation "0"))) (clocked ((clockRise "1e-09") (clockFall "1e-09") (clockFreq "100e6") (clockInitState "0") (clockDutyCycle "0.5") (clockJitter "0"))) (TLine ((diffImpedance "100ohm") (diffVelocity "1.4142e+08M/s") (impedance "60ohm") length("2800 mil") (propDelay "0.5 ns") (velocity "5600 mil/ns") (traceCount "1") (traceGeometry "Microstrip") (impedanceMin nil) (impedanceMax nil) (lengthMin nil) (lengthMax nil) (propDelayMin nil) (propDelayMax nil) (impedanceSweepCount nil) (propDelaySweepCount nil) (velocitySweepCount nil) (lengthSweepCount nil) (matchSetName nil))) (Cable (length("1 m"))) (DualClampTerm ((cutoffVoltageUp "0.7 V") (cutoffVoltageDown "0.7 V") (voltageUp "5 V") (voltageDown "0 V") (maxDelay "0.1 ns"))) (LowClampTerm ((cutoffVoltage "0.7 V") (voltage "0 V") (maxDelay "0.1 ns"))) (HiClampTerm ((cutoffVoltage "0.7 V") (voltage "5 V") (maxDelay "0.1 ns"))) (RCTerm ((resistance "50 ohm") (capacitance "20 pF") (voltage "5 V") (maxDelay "0.1 ns"))) (IbisOutput ((temperature "27") (bufferModel "CDSDefaultOutput_2p5v") (stimuli nil) (offsets nil) (state "tristate") (cycle "1") (termMap nil) (setup "2.0e-09") (hold "1.0e-09") (rise nil) (fall nil) (macroType nil) (voltage nil) (spice nil) (LEFDEFPinName nil) (LEFDEFPinType nil) (mappingTag nil))) (IbisIO ((temperature "27") (bufferModel "CDSDefaultIO_2p5v") (stimuli nil) (offsets nil) (state "tristate") (cycle "1") (termMap nil) (setup "2.0e-09") (hold "1.0e-09") (rise nil) (fall nil) (macroType nil) (voltage nil) (spice nil) (LEFDEFPinName nil) (LEFDEFPinType nil) (mappingTag nil))) (Diode ((cutoffVoltage "0.7 V"))) (IbisInput ((temperature "27") (bufferModel "CDSDefaultInput_2p5v") (cycle "1") (LEFDEFPinName nil) (LEFDEFPinType nil) (mappingTag nil))) (ESpiceDevice nil) (CPW ((d1Thickness "10 mil") (d1Constant "4.5") (d1LossTangent "0.035") (d2Thickness "0.72 mil") (d2Constant "1") (d2LossTangent "0") (d3Thickness "0.0") (d3Constant "1") (d3LossTangent "0") length("1000 mil") (spacing "5 mil") (spacing2 "5 mil") (spacing3 "5 mil") (spacing4 "5 mil") (spacing5 "5 mil") (traceConductivity "595900 mho/cm") (traceGeometry "cpwms") (traceLayerName "") (traceThickness "0.72 mil") (traceType "single") (traceWidth "5.0 mil") (traceWidth2 "5.0 mil") (traceWidth3 "5.0 mil") (traceWidth4 "5.0 mil") (traceWidth5 "5.0 mil") (traceWidth6 "5.0 mil") (offset "0 mil") (traceCount "1") (impedance nil))) (IbisOutput_OpenPullUp ((temperature "27") (bufferModel "CDSDefaultOutput_2p5v") (stimuli nil) (offsets nil) (state "tristate") (cycle "1") (termMap nil) (setup "2.0e-09") (hold "1.0e-09") (rise nil) (fall nil) (macroType nil) (voltage nil) (spice nil) (LEFDEFPinName nil) (LEFDEFPinType nil) (mappingTag nil))) (CPWMS ((d1Thickness "10 mil") (d1Constant "4.5") (d1LossTangent "0.035") (d2Thickness "0.72 mil") (d2Constant "4.5") (d2LossTangent "0.035") (d3Thickness "0.0") (d3Constant "1") (d3LossTangent "0") length("1000 mil") (spacing "5 mil") (spacing2 "5 mil") (spacing3 "5 mil") (spacing4 "5 mil") (spacing5 "5 mil") (traceConductivity "595900 mho/cm") (traceGeometry "cpwms") (traceLayerName "") (traceThickness "0.72 mil") (traceType "single") (traceWidth "5.0 mil") (traceWidth2 "5.0 mil") (traceWidth3 "5.0 mil") (traceWidth4 "5.0 mil") (traceWidth5 "5.0 mil") (traceWidth6 "5.0 mil") (offset "0 mil") (traceCount "1") (impedance nil))) (IbisIO_OpenPullDown ((temperature "27") (bufferModel "CDSDefaultIO_2p5v") (stimuli nil) (offsets nil) (state "tristate") (cycle "1") (termMap nil) (setup "2.0e-09") (hold "1.0e-09") (rise nil) (fall nil) (macroType nil) (voltage nil) (spice nil) (LEFDEFPinName nil) (LEFDEFPinType nil) (mappingTag nil))) (Connector nil) (CPWSL ((d1Thickness "10 mil") (d1Constant "4.5") (d1LossTangent "0.035") (d2Thickness "0.72 mil") (d2Constant "4.5") (d2LossTangent "0.035") (d3Thickness "10 mil") (d3Constant "4.5") (d3LossTangent "0.035") length("1000 mil") (spacing "5 mil") (spacing2 "5 mil") (spacing3 "5 mil") (spacing4 "5 mil") (spacing5 "5 mil") (traceConductivity "595900 mho/cm") (traceGeometry "cpwms") (traceLayerName "") (traceThickness "0.72 mil") (traceType "single") (traceWidth "5.0 mil") (traceWidth2 "5.0 mil") (traceWidth3 "5.0 mil") (traceWidth4 "5.0 mil") (traceWidth5 "5.0 mil") (traceWidth6 "5.0 mil") (offset "0 mil") (traceCount "1") (impedance nil))) (IbisIO_OpenPullUp ((temperature "27") (bufferModel "CDSDefaultIO_2p5v") (stimuli nil) (offsets nil) (state "tristate") (cycle "1") (termMap nil) (setup "2.0e-09") (hold "1.0e-09") (rise nil) (fall nil) (macroType nil) (voltage nil) (spice nil) (LEFDEFPinName nil) (LEFDEFPinType nil) (mappingTag nil))) (TheveninTerm ((resistanceUp "180 ohm") (resistanceDown "270 ohm") (voltageUp "5 V") (voltageDown "0 V") (maxDelay "0.1 ns"))) (ShuntTerm ((resistance "50 ohm") (voltage "5 V") (maxDelay "0.1 ns"))) (Source ((voltage "5 V")))))
				)
				( objectStatus "CATERR" )
			)
			( electricalCSet "@baseboard_fab2_lib.baseboard_fab2(sch_1):\SVID_CLK1_CPU1\"
				( groupRef "SVID_CLK1_CPU1:#SVID_CPU1_1_U100-EU76" )
				( groupRef "SVID_CLK1_CPU1:#SVID_CPU1_1_U100-EU77" )
				( pinPairRef "SVID_CLK1_CPU1:U2D1.DG44:EU1G2.15" )
				( pinPairRef "SVID_CLK1_CPU1:U2D1.DG44:EU1B1.15" )
				( pinPairRef "SVID_CLK1_CPU1:U2D1.DG44:R1C3.1" )
				( pinPairRef "SVID_CLK1_CPU1:R1B8.1:R1C3.2" )
				( pinPairRef "SVID_CLK1_CPU1:R9M6.2:R1B8.1" )
				( pinPairRef "SVID_CLK1_CPU1:EU1B1.15:R1B8.2" )
				( pinPairRef "SVID_CLK1_CPU1:EU1G2.15:R1G7.2" )
				( attribute "TOPOLOGY_TEMPLATE_REVISION" "1.0"
					( Origin gBackEnd )
				)
				( topologyData 29419
(SKIDL (Circuits ("MAIN" (Parts ("CRESCENT_CITY_195_20150128_Q.@@EU77.15" IbisInputPkg (xy (5587 4235)) (refDes "EU1B1") (model "Unknown") (Props (_SXDesignName "CRESCENT_CITY_195_20150128_Q") (brdx "-15.5 MIL") (brdy "5045.87 MIL") (bufferModel "CDSDefaultInput_2p5v") (mappingTag "") (temperature "27")) (Terms ("CRESCENT_CITY_195_20150128_Q.Xn1550Y504587L2LRATS" "15"))) ("CRESCENT_CITY_195_20150128_Q.@@U100.DG44" IbisOutputPkg (xy (5498 4235)) (refDes "U2D1") (model "Unknown") (Props (_SXDesignName "CRESCENT_CITY_195_20150128_Q") (brdx "4086.86 MIL") (brdy "3631.6 MIL") (bufferModel "CDSDefaultOutput_2p5v") (cycle "1") (hold "1.0e-09") (mappingTag "") (offsets ("4" "0")) (setup "2.0e-09") (state "tristate") (stimuli ("4" "local101")) (temperature "27") (termMap ("4" "Data"))) (Terms ("CRESCENT_CITY_195_20150128_Q.X408686Y363160L2LRATS" "DG44"))) ("CRESCENT_CITY_195_20150128_Q.@@EU76.15" IbisInputPkg (xy (5565 4222)) (refDes "EU1G2") (model "Unknown") (Props (_SXDesignName "CRESCENT_CITY_195_20150128_Q") (brdx "402.87 MIL") (brdy "146.5 MIL") (bufferModel "CDSDefaultInput_2p5v") (mappingTag "") (temperature "27")) (Terms ("CRESCENT_CITY_195_20150128_Q.X40287Y14650L2LRATS" "15"))) ("CRESCENT_CITY_195_20150128_Q.@@R2047.1.2" Resistor (xy (5530 4216)) (refDes "R9U4") (value "1 Ohm") (Props (_SXDesignName "CRESCENT_CITY_195_20150128_Q")) (Terms ("CRESCENT_CITY_195_20150128_Q.X45500Y23000L30RATS" "1") ("CRESCENT_CITY_195_20150128_Q.X45500Y26500L30LRATS" "2"))) ("CRESCENT_CITY_195_20150128_Q.T@@RATS@@R1201.2@@R2047.2" TLine (xy (5530 4222)) (refDes "TL158") (Props (_SXDesignName "CRESCENT_CITY_195_20150128_Q") (impedance "48.412 ohm") length("4918.43 MIL") (propDelay "0.88338 ns") (traceCount "1") (traceGeometry "Microstrip") (velocity "5567.72 mil/ns")) (Terms ("CRESCENT_CITY_195_20150128_Q.X151142Y412700L2LRATS" "1") ("CRESCENT_CITY_195_20150128_Q.X45500Y26500L30LRATS" "2"))) ("CRESCENT_CITY_195_20150128_Q.T@@RATS@@EU77.15@@R2069.2" TLine (xy (5573 4235)) (mirror x) (refDes "TL159") (Props (_SXDesignName "CRESCENT_CITY_195_20150128_Q") (impedance "48.412 ohm") length("135.63 MIL") (propDelay "0.02436 ns") (traceCount "1") (traceGeometry "Microstrip") (velocity "5567.72 mil/ns")) (Terms ("CRESCENT_CITY_195_20150128_Q.Xn1550Y504587L2LRATS" "1") ("CRESCENT_CITY_195_20150128_Q.Xn9900Y509800L2LRATS" "2"))) ("CRESCENT_CITY_195_20150128_Q.T@@RATS@@R2068.2@@R2069.1" TLine (xy (5549 4235)) (refDes "TL160") (Props (_SXDesignName "CRESCENT_CITY_195_20150128_Q") (impedance "48.412 ohm") (propDelay "1.79607e-006 ns") (traceCount "1") (traceGeometry "Microstrip")) (Terms ("CRESCENT_CITY_195_20150128_Q.Xn13400Y509800L30LRATS" "1") ("CRESCENT_CITY_195_20150128_Q.Xn13400Y509800L2LRATS" "2"))) ("CRESCENT_CITY_195_20150128_Q.T@@RATS@@R2047.2@@R2048.1" TLine (xy (5539 4222)) (refDes "TL161") (Props (_SXDesignName "CRESCENT_CITY_195_20150128_Q") (impedance "48.412 ohm") (propDelay "1.79607e-006 ns") (traceCount "1") (traceGeometry "Microstrip")) (Terms ("CRESCENT_CITY_195_20150128_Q.X45500Y26500L30LRATS" "1") ("CRESCENT_CITY_195_20150128_Q.X45500Y26500L2LRATS" "2"))) ("CRESCENT_CITY_195_20150128_Q.@@R2068.1_SOURCE" Source (xy (5536 4229)) (refDes "PVCCIO_CPU1_1") (value "1 V") (Props (_SXDesignName "CRESCENT_CITY_195_20150128_Q")) (Terms ("CRESCENT_CITY_195_20150128_Q.Xn9900Y509800L30RATS" "1"))) ("CRESCENT_CITY_195_20150128_Q.@@R2068.1.2" Resistor (xy (5543 4229)) (refDes "R9M6") (value "49.9 Ohm") (Props (_SXDesignName "CRESCENT_CITY_195_20150128_Q")) (Terms ("CRESCENT_CITY_195_20150128_Q.Xn9900Y509800L30RATS" "1") ("CRESCENT_CITY_195_20150128_Q.Xn13400Y509800L30LRATS" "2"))) ("CRESCENT_CITY_195_20150128_Q.@@R2069.2.1" Resistor (xy (5558 4235)) (mirror x) (refDes "R1B8") (value "150 Ohm") (Props (_SXDesignName "CRESCENT_CITY_195_20150128_Q")) (Terms ("CRESCENT_CITY_195_20150128_Q.Xn9900Y509800L2LRATS" "2") ("CRESCENT_CITY_195_20150128_Q.Xn13400Y509800L2LRATS" "1"))) ("CRESCENT_CITY_195_20150128_Q.@@R2048.1.2" Resistor (xy (5548 4222)) (refDes "R1G7") (value "150 Ohm") (Props (_SXDesignName "CRESCENT_CITY_195_20150128_Q")) (Terms ("CRESCENT_CITY_195_20150128_Q.X45500Y26500L2LRATS" "1") ("CRESCENT_CITY_195_20150128_Q.X45500Y23000L2LRATS" "2"))) ("CRESCENT_CITY_195_20150128_Q.@@R2047.1_SOURCE" Source (xy (5523 4216)) (refDes "PVCCIO_CPU1") (value "1 V") (Props (_SXDesignName "CRESCENT_CITY_195_20150128_Q")) (Terms ("CRESCENT_CITY_195_20150128_Q.X45500Y23000L30RATS" "1"))) ("CRESCENT_CITY_195_20150128_Q.@@R1201.1.2" Resistor (xy (5521 4235)) (refDes "R1C3") (value "2.2e-007 Ohm") (Props (_SXDesignName "CRESCENT_CITY_195_20150128_Q")) (Terms ("CRESCENT_CITY_195_20150128_Q.X154642Y412700L2LRATS" "1") ("CRESCENT_CITY_195_20150128_Q.X151142Y412700L2LRATS" "2"))) ("CRESCENT_CITY_195_20150128_Q.T@@RATS@@R2068.2@@R1201.2" TLine (xy (5530 4235)) (mirror x) (refDes "TL162") (Props (_SXDesignName "CRESCENT_CITY_195_20150128_Q") (impedance "48.412 ohm") length("2616.42 MIL") (propDelay "0.46993 ns") (traceCount "1") (traceGeometry "Microstrip") (velocity "5567.68 mil/ns")) (Terms ("CRESCENT_CITY_195_20150128_Q.Xn13400Y509800L30LRATS" "1") ("CRESCENT_CITY_195_20150128_Q.X151142Y412700L2LRATS" "2"))) ("CRESCENT_CITY_195_20150128_Q.T@@RATS@@R1201.1@@U100.DG44" TLine (xy (5506 4235)) (mirror x) (refDes "TL163") (Props (_SXDesignName "CRESCENT_CITY_195_20150128_Q") (impedance "49.728 ohm") length("3035.84 MIL") (propDelay "0.54526 ns") (traceCount "1") (traceGeometry "Microstrip") (velocity "5567.68 mil/ns")) (Terms ("CRESCENT_CITY_195_20150128_Q.X154642Y412700L2LRATS" "1") ("CRESCENT_CITY_195_20150128_Q.X408686Y363160L2LRATS" "2"))) ("CRESCENT_CITY_195_20150128_Q.T@@RATS@@R2048.2@@EU76.15" TLine (xy (5557 4222)) (refDes "TL164") (Props (_SXDesignName "CRESCENT_CITY_195_20150128_Q") (impedance "48.412 ohm") length("135.63 MIL") (propDelay "0.02436 ns") (traceCount "1") (traceGeometry "Microstrip") (velocity "5567.72 mil/ns")) (Terms ("CRESCENT_CITY_195_20150128_Q.X45500Y23000L2LRATS" "1") ("CRESCENT_CITY_195_20150128_Q.X40287Y14650L2LRATS" "2")))) (Nodes ("CRESCENT_CITY_195_20150128_Q.Xn1550Y504587L2LRATS" (terms "CRESCENT_CITY_195_20150128_Q.T@@RATS@@EU77.15@@R2069.2.1" "CRESCENT_CITY_195_20150128_Q.@@EU77.15.1")) ("CRESCENT_CITY_195_20150128_Q.X408686Y363160L2LRATS" (terms "CRESCENT_CITY_195_20150128_Q.T@@RATS@@R1201.1@@U100.DG44.2" "CRESCENT_CITY_195_20150128_Q.@@U100.DG44.1")) ("CRESCENT_CITY_195_20150128_Q.Xn13400Y509800L2LRATS" (terms "CRESCENT_CITY_195_20150128_Q.@@R2069.2.1.2" "CRESCENT_CITY_195_20150128_Q.T@@RATS@@R2068.2@@R2069.1.2")) ("CRESCENT_CITY_195_20150128_Q.X151142Y412700L2LRATS" (terms "CRESCENT_CITY_195_20150128_Q.T@@RATS@@R2068.2@@R1201.2.2" "CRESCENT_CITY_195_20150128_Q.@@R1201.1.2.2" "CRESCENT_CITY_195_20150128_Q.T@@RATS@@R1201.2@@R2047.2.1")) ("CRESCENT_CITY_195_20150128_Q.Xn9900Y509800L2LRATS" (terms "CRESCENT_CITY_195_20150128_Q.@@R2069.2.1.1" "CRESCENT_CITY_195_20150128_Q.T@@RATS@@EU77.15@@R2069.2.2")) ("CRESCENT_CITY_195_20150128_Q.Xn9900Y509800L30RATS" (terms "CRESCENT_CITY_195_20150128_Q.@@R2068.1.2.1" "CRESCENT_CITY_195_20150128_Q.@@R2068.1_SOURCE.1")) ("CRESCENT_CITY_195_20150128_Q.X45500Y23000L2LRATS" (terms "CRESCENT_CITY_195_20150128_Q.T@@RATS@@R2048.2@@EU76.15.1" "CRESCENT_CITY_195_20150128_Q.@@R2048.1.2.2")) ("CRESCENT_CITY_195_20150128_Q.Xn13400Y509800L30LRATS" (terms "CRESCENT_CITY_195_20150128_Q.T@@RATS@@R2068.2@@R1201.2.1" "CRESCENT_CITY_195_20150128_Q.@@R2068.1.2.2" "CRESCENT_CITY_195_20150128_Q.T@@RATS@@R2068.2@@R2069.1.1")) ("CRESCENT_CITY_195_20150128_Q.X154642Y412700L2LRATS" (terms "CRESCENT_CITY_195_20150128_Q.T@@RATS@@R1201.1@@U100.DG44.1" "CRESCENT_CITY_195_20150128_Q.@@R1201.1.2.1")) ("CRESCENT_CITY_195_20150128_Q.X45500Y23000L30RATS" (terms "CRESCENT_CITY_195_20150128_Q.@@R2047.1_SOURCE.1" "CRESCENT_CITY_195_20150128_Q.@@R2047.1.2.1")) ("CRESCENT_CITY_195_20150128_Q.X40287Y14650L2LRATS" (terms "CRESCENT_CITY_195_20150128_Q.T@@RATS@@R2048.2@@EU76.15.2" "CRESCENT_CITY_195_20150128_Q.@@EU76.15.1")) ("CRESCENT_CITY_195_20150128_Q.X45500Y26500L30LRATS" (terms "CRESCENT_CITY_195_20150128_Q.T@@RATS@@R2047.2@@R2048.1.1" "CRESCENT_CITY_195_20150128_Q.T@@RATS@@R1201.2@@R2047.2.2" "CRESCENT_CITY_195_20150128_Q.@@R2047.1.2.2")) ("CRESCENT_CITY_195_20150128_Q.X45500Y26500L2LRATS" (terms "CRESCENT_CITY_195_20150128_Q.@@R2048.1.2.1" "CRESCENT_CITY_195_20150128_Q.T@@RATS@@R2047.2@@R2048.1.2"))) (Ports) (Stimuli ("local101" (scope local) (stimType periodic) (Props (periodicFreq "5e+007") (periodicJitter "0") (periodicPattern "1")))) (Notes) (Constraints ("DELAY_RULE" ("CRESCENT_CITY_195_20150128_Q U100.DG44" "CRESCENT_CITY_195_20150128_Q R1201.1" "LENGTH" "" "LENGTH" "0.1143") ("CRESCENT_CITY_195_20150128_Q R2069.1" "CRESCENT_CITY_195_20150128_Q R2068.2" "LENGTH" "" "LENGTH" "0.00508") ("CRESCENT_CITY_195_20150128_Q R2069.1" "CRESCENT_CITY_195_20150128_Q R1201.2" "LENGTH" "" "LENGTH" "0.6858") ("CRESCENT_CITY_195_20150128_Q EU77.15" "CRESCENT_CITY_195_20150128_Q R2069.2" "LENGTH" "" "LENGTH" "0.0254") ("CRESCENT_CITY_195_20150128_Q EU76.15" "CRESCENT_CITY_195_20150128_Q R2048.2" "LENGTH" "" "LENGTH" "0.0254")) ("RELATIVE_PROPAGATION_DELAY" ("#SVID_CPU1_1_U100-EU76" "CRESCENT_CITY_195_20150128_Q U100.DG44" "CRESCENT_CITY_195_20150128_Q EU76.15" "GLOBAL" "LENGTH" "0.00635" "NONE" "") ("#SVID_CPU1_1_U100-EU77" "CRESCENT_CITY_195_20150128_Q U100.DG44" "CRESCENT_CITY_195_20150128_Q EU77.15" "GLOBAL" "LENGTH" "0.00635" "NONE" ""))) (MeasurementSets ("EMI" ("EMIStatus" status("on")) ("PeakEmission" status("on")) ("PeakFrequency" status("on")) ("PulseFreq" status("on")) ("RiseTime" status("on")) ("VoltageSwing" status("on"))) ("Reflection" ("BufferDelayFall" status("off")) ("BufferDelayRise" status("off")) ("EyeHeight" status("off")) ("EyeJitter" status("off")) ("EyeWidth" status("off")) ("FirstIncidentFall" status("off")) ("FirstIncidentRise" status("off")) ("Glitch" status("on")) ("GlitchFall" status("off")) ("GlitchRise" status("off")) ("Monotonic" status("on")) ("MonotonicFall" status("off")) ("MonotonicRise" status("off")) ("NoiseMargin" status("on")) ("NoiseMarginHigh" status("off")) ("NoiseMarginLow" status("off")) ("OvershootHigh" status("on")) ("OvershootLow" status("on")) ("PropDelay" status("on")) ("SettleDelay" status("on")) ("SettleDelayFall" status("off")) ("SettleDelayRise" status("off")) ("SwitchDelay" status("on")) ("SwitchDelayFall" status("off")) ("SwitchDelayRise" status("off"))) ("Crosstalk" ("Crosstalk" status("on"))) ("Custom")) (VectorSets) (Props (XnetName "SVID_CLK1_CPU1") (allDrivers "active") (customSimType "Reflection") (ftsMode ("Typ")) (rcvrSelect "all") (tlineDelayMode "time") (userRevision "1.0")))) (Subckts) (CrossSections ("CRESCENT_CITY_195_20150128_Q" (Props (SXDesignName "CRESCENT_CITY_195_20150128_Q")) (Layers ("" (layerType "SURFACE") (material "AIR") (thickness "0 mil") (dielectricConstant "1.000000") (lossTangent "0") (etchFactor "0.000000") (elecCondVal "0 mho/cm") (thermCondVal "0 w/cm-degC")) ("" (layerType "DIELECTRIC") (material "CONFORMAL_COAT") (thickness "0.5 mil") (dielectricConstant "3.800000") (lossTangent "0.035") (etchFactor "0.000000") (elecCondVal "0 mho/cm") (thermCondVal "0.012 w/cm-degC")) ("TOP" (layerType "CONDUCTOR") (material "COPPER") (thickness "  2.100000 mil") (width "4.00 MIL") (dielectricConstant "4.500000") (lossTangent "0") (etchFactor "70.000000") (elecCondVal "595900.000000 mho/cm") (thermCondVal "0 w/cm-degC") (signalDieConstant "3.800000") (signalLossTangent "0.035")) ("" (layerType "DIELECTRIC") (material "FR-4") (thickness "  2.670000 mil") (dielectricConstant "4.000000") (lossTangent "0.035") (etchFactor "0.000000") (elecCondVal "0 mho/cm") (thermCondVal "0.012 w/cm-degC")) ("L2_GND1" (layerType "PLANE") (material "COPPER") (isShield t) (thickness "  1.250000 mil") (dielectricConstant "4.500000") (lossTangent "0.035") (etchFactor "90.000000") (elecCondVal "595900.000000 mho/cm") (thermCondVal "0.012 w/cm-degC")) ("" (layerType "DIELECTRIC") (material "FR-4") (thickness "  9.000000 mil") (dielectricConstant "4.100000") (lossTangent "0.035") (etchFactor "0.000000") (elecCondVal "0 mho/cm") (thermCondVal "0.012 w/cm-degC")) ("L3_SIG1" (layerType "CONDUCTOR") (material "COPPER") (thickness "  1.250000 mil") (width "4.00 MIL") (dielectricConstant "4.500000") (lossTangent "0.035") (etchFactor "90.000000") (elecCondVal "595900.000000 mho/cm") (thermCondVal "0.012 w/cm-degC") (signalDieConstant "4.100000") (signalLossTangent "0.035")) ("" (layerType "DIELECTRIC") (material "FR-4") (thickness "  3.000000 mil") (dielectricConstant "4.500000") (lossTangent "0.035") (etchFactor "0.000000") (elecCondVal "0 mho/cm") (thermCondVal "0 w/cm-degC")) ("L4_GND2" (layerType "PLANE") (material "COPPER") (isShield t) (thickness "  1.250000 mil") (dielectricConstant "4.500000") (lossTangent "0.035") (etchFactor "90.000000") (elecCondVal "595900.000000 mho/cm") (thermCondVal "0 w/cm-degC")) ("" (layerType "DIELECTRIC") (material "FR-4") (thickness "  9.000000 mil") (dielectricConstant "4.000000") (lossTangent "0.035") (etchFactor "0.000000") (elecCondVal "0 mho/cm") (thermCondVal "0.012 w/cm-degC")) ("L5_SIG2" (layerType "CONDUCTOR") (material "COPPER") (thickness "  1.250000 mil") (width "4.00 MIL") (dielectricConstant "4.500000") (lossTangent "0.035") (etchFactor "90.000000") (elecCondVal "595900.000000 mho/cm") (thermCondVal "0.012 w/cm-degC") (signalDieConstant "4.000000") (signalLossTangent "0.035")) ("" (layerType "DIELECTRIC") (material "FR-4") (thickness "  3.000000 mil") (dielectricConstant "4.500000") (lossTangent "0.035") (etchFactor "0.000000") (elecCondVal "0 mho/cm") (thermCondVal "0 w/cm-degC")) ("L6_GND3" (layerType "PLANE") (material "COPPER") (isShield t) (thickness "  1.250000 mil") (dielectricConstant "4.500000") (lossTangent "0.035") (etchFactor "90.000000") (elecCondVal "595900.000000 mho/cm") (thermCondVal "0 w/cm-degC")) ("" (layerType "DIELECTRIC") (material "FR-4") (thickness "  4.500000 mil") (dielectricConstant "4.100000") (lossTangent "0.035") (etchFactor "0.000000") (elecCondVal "0 mho/cm") (thermCondVal "0.012 w/cm-degC")) ("L7_PWR1-SIG" (layerType "PLANE") (material "COPPER") (isShield t) (thickness "  2.400000 mil") (dielectricConstant "4.500000") (lossTangent "0.035") (etchFactor "90.000000") (elecCondVal "595900.000000 mho/cm") (thermCondVal "0.012 w/cm-degC")) ("" (layerType "DIELECTRIC") (material "FR-4") (thickness "  4.600000 mil") (dielectricConstant "4.000000") (lossTangent "0.035") (etchFactor "0.000000") (elecCondVal "0 mho/cm") (thermCondVal "0.012 w/cm-degC")) ("L8_PWR2-SIG" (layerType "PLANE") (material "COPPER") (isShield t) (thickness "  2.400000 mil") (dielectricConstant "4.500000") (lossTangent "0.035") (etchFactor "90.000000") (elecCondVal "595900.000000 mho/cm") (thermCondVal "0.012 w/cm-degC")) ("" (layerType "DIELECTRIC") (material "FR-4") (thickness "  8.000000 mil") (dielectricConstant "4.500000") (lossTangent "0.035") (etchFactor "0.000000") (elecCondVal "0 mho/cm") (thermCondVal "0 w/cm-degC")) ("" (layerType "DIELECTRIC") (material "FR-4") (thickness "  8.000000 mil") (dielectricConstant "4.500000") (lossTangent "0.035") (etchFactor "0.000000") (elecCondVal "0 mho/cm") (thermCondVal "0 w/cm-degC")) ("" (layerType "DIELECTRIC") (material "FR-4") (thickness "  4.500000 mil") (dielectricConstant "4.500000") (lossTangent "0.035") (etchFactor "0.000000") (elecCondVal "0 mho/cm") (thermCondVal "0 w/cm-degC")) ("L9_GND4" (layerType "PLANE") (material "COPPER") (isShield t) (thickness "  1.250000 mil") (dielectricConstant "4.500000") (lossTangent "0.035") (etchFactor "90.000000") (elecCondVal "595900.000000 mho/cm") (thermCondVal "0 w/cm-degC")) ("" (layerType "DIELECTRIC") (material "FR-4") (thickness "  3.000000 mil") (dielectricConstant "4.100000") (lossTangent "0.035") (etchFactor "0.000000") (elecCondVal "0 mho/cm") (thermCondVal "0.012 w/cm-degC")) ("L10_SIG3" (layerType "CONDUCTOR") (material "COPPER") (thickness "  1.250000 mil") (width "4.00 MIL") (dielectricConstant "4.500000") (lossTangent "0.035") (etchFactor "90.000000") (elecCondVal "595900.000000 mho/cm") (thermCondVal "0.012 w/cm-degC") (signalDieConstant "4.100000") (signalLossTangent "0.035")) ("" (layerType "DIELECTRIC") (material "FR-4") (thickness "  9.000000 mil") (dielectricConstant "4.500000") (lossTangent "0.035") (etchFactor "0.000000") (elecCondVal "0 mho/cm") (thermCondVal "0 w/cm-degC")) ("L11_GND5" (layerType "PLANE") (material "COPPER") (isShield t) (thickness "  1.250000 mil") (dielectricConstant "4.500000") (lossTangent "0.035") (etchFactor "90.000000") (elecCondVal "595900.000000 mho/cm") (thermCondVal "0 w/cm-degC")) ("" (layerType "DIELECTRIC") (material "FR-4") (thickness "  3.000000 mil") (dielectricConstant "4.500000") (lossTangent "0.035") (etchFactor "0.000000") (elecCondVal "0 mho/cm") (thermCondVal "0.012 w/cm-degC")) ("L12_SIG4" (layerType "CONDUCTOR") (material "COPPER") (thickness "  1.250000 mil") (width "4.00 MIL") (dielectricConstant "4.500000") (lossTangent "0.035") (etchFactor "90.000000") (elecCondVal "595900.000000 mho/cm") (thermCondVal "0.012 w/cm-degC") (signalDieConstant "4.500000") (signalLossTangent "0.035")) ("" (layerType "DIELECTRIC") (material "FR-4") (thickness "  9.000000 mil") (dielectricConstant "4.500000") (lossTangent "0.035") (etchFactor "0.000000") (elecCondVal "0 mho/cm") (thermCondVal "0 w/cm-degC")) ("L13_GND6" (layerType "PLANE") (material "COPPER") (isShield t) (thickness "  1.250000 mil") (dielectricConstant "4.500000") (lossTangent "0.035") (etchFactor "90.000000") (elecCondVal "595900.000000 mho/cm") (thermCondVal "0.012 w/cm-degC")) ("" (layerType "DIELECTRIC") (material "FR-4") (thickness "  2.670000 mil") (dielectricConstant "4.500000") (lossTangent "0.035") (etchFactor "0.000000") (elecCondVal "0 mho/cm") (thermCondVal "0.012 w/cm-degC")) ("BOTTOM" (layerType "CONDUCTOR") (material "COPPER") (thickness "  2.100000 mil") (width "4.00 MIL") (dielectricConstant "4.500000") (lossTangent "0") (etchFactor "70.000000") (elecCondVal "595900.000000 mho/cm") (thermCondVal "0 w/cm-degC") (signalDieConstant "3.800000") (signalLossTangent "0.035")) ("" (layerType "DIELECTRIC") (material "CONFORMAL_COAT") (thickness "0.5 mil") (dielectricConstant "3.800000") (lossTangent "0.035") (etchFactor "0.000000") (elecCondVal "0 mho/cm") (thermCondVal "0.012 w/cm-degC")) ("" (layerType "SURFACE") (material "AIR") (thickness "0 mil") (dielectricConstant "1.000000") (lossTangent "0") (etchFactor "0.000000") (elecCondVal "0 mho/cm") (thermCondVal "0 w/cm-degC"))))) (Props (DesUnits "mils 2") (LayerStack ("DIELECTRIC" "DIELECTRIC" "BOTTOM" "DIELECTRIC" "L13_GND6" "DIELECTRIC" "L12_SIG4" "DIELECTRIC" "L11_GND5" "DIELECTRIC" "L10_SIG3" "DIELECTRIC" "L9_GND4" "DIELECTRIC" "DIELECTRIC" "DIELECTRIC" "L8_PWR2-SIG" "DIELECTRIC" "L7_PWR1-SIG" "DIELECTRIC" "L6_GND3" "DIELECTRIC" "L5_SIG2" "DIELECTRIC" "L4_GND2" "DIELECTRIC" "L3_SIG1" "DIELECTRIC" "L2_GND1" "DIELECTRIC" "TOP" "DIELECTRIC" "DIELECTRIC")) (Revision "16.600")) (Params (DiffOutputPkg ((temperature "27") (bufferModelNonInverting "CDSDefaultOutput_2p5v") (bufferModelInverting "CDSDefaultOutput_2p5v") (stimuli nil) (offsets nil) (state "tristate") (cycle "1") (termMap nil) (setup "0.9e-09") (hold "0.4e-09") (rise nil) (fall nil) (threshOutputHighMin "2.375  V") (threshOutputHighTyp "2.5  V") (threshOutputHighMax "2.625  V") (threshOutputLowMin "1.275  V") (threshOutputLowTyp "1.7  V") (threshOutputLowMax "1.985  V") (mappingTagNonInverting nil) (mappingTagInverting nil) (spice nil))) (HiClampTerm ((cutoffVoltage "0.7 V") (voltage "5 V") (maxDelay "0.1 ns"))) (LowClampTerm ((cutoffVoltage "0.7 V") (voltage "0 V") (maxDelay "0.1 ns"))) (DiffOutput ((temperature "27") (bufferModelNonInverting "CDSDefaultOutput_2p5v") (bufferModelInverting "CDSDefaultOutput_2p5v") (stimuli nil) (offsets nil) (state "tristate") (cycle "1") (termMap nil) (setup "0.9e-09") (hold "0.4e-09") (rise nil) (fall nil) (threshOutputHighMin "2.375  V") (threshOutputHighTyp "2.5  V") (threshOutputHighMax "2.625  V") (threshOutputLowMin "1.275  V") (threshOutputLowTyp "1.7  V") (threshOutputLowMax "1.985  V") (mappingTagNonInverting nil) (mappingTagInverting nil) (spice nil))) (Via ((model "Unknown") (viaOutputFormat "Unknown") (viaPadstack nil) (viaTopLayer nil) (viaBottomLayer nil) (viaIsPower nil) (viaIsGround nil))) (Resistor ((resistance "50 ohm") (orientation "0"))) (RCTerm ((resistance "50 ohm") (capacitance "20 pF") (voltage "5 V") (maxDelay "0.1 ns"))) (DiffIOPkg ((temperature "27") (bufferModelNonInverting "CDSDefaultIO_2p5v") (bufferModelInverting "CDSDefaultIO_2p5v") (stimuli nil) (offsets nil) (state "tristate") (cycle "1") (termMap nil) (setup "0.9e-09") (hold "0.4e-09") (rise nil) (fall nil) (threshInputHighMin "1.7 V") (threshInputHighTyp "1.7  V") (threshInputHighMax "1.7  V") (threshInputLowMin "0.7  V") (threshInputLowTyp "0.7  V") (threshInputLowMax "0.7 ") (threshOutputHighMin "2.365  V") (threshOutputHighTyp "2.5  V") (threshOutputHighMax "2.625  V") (threshOutputLowMin "1.275  V") (threshOutputLowTyp "1.7  V") (threshOutputLowMax "1.985  V") (mappingTagNonInverting nil) (mappingTagInverting nil) (spice nil))) (Trace ((d1Thickness "10 mil") (d1Constant "4.5") (d1LossTangent "0.035") (d2Thickness "10 mil") (d2Constant "4.5") (d2LossTangent "0.035") (d3Thickness "0.0") (d3Constant "1.0") (d3LossTangent "0") length("1000 mil") (spacing "5 mil") (spacing2 "5 mil") (spacing3 "5 mil") (spacing4 "5 mil") (spacing5 "5 mil") (traceConductivity "595900 mho/cm") (traceGeometry "microstrip") (traceLayerName "") (traceThickness "0.72 mil") (traceType "single") (traceWidth "5.0 mil") (traceWidth2 "5.0 mil") (traceWidth3 "5.0 mil") (traceWidth4 "5.0 mil") (traceWidth5 "5.0 mil") (traceWidth6 "5.0 mil") (offset "0 mil") (traceCount "1") (impedance nil))) (TheveninTerm ((resistanceUp "180 ohm") (resistanceDown "270 ohm") (voltageUp "5 V") (voltageDown "0 V") (maxDelay "0.1 ns"))) (DiffIO ((temperature "27") (bufferModelNonInverting "CDSDefaultIO_2p5v") (bufferModelInverting "CDSDefaultIO_2p5v") (stimuli nil) (offsets nil) (state "tristate") (cycle "1") (termMap nil) (setup "0.9e-09") (hold "0.4e-09") (rise nil) (fall nil) (threshInputHighMin "1.7 V") (threshInputHighTyp "1.7  V") (threshInputHighMax "1.7  V") (threshInputLowMin "0.7  V") (threshInputLowTyp "0.7  V") (threshInputLowMax "0.7 ") (threshOutputHighMin "2.365  V") (threshOutputHighTyp "2.5  V") (threshOutputHighMax "2.625  V") (threshOutputLowMin "1.275  V") (threshOutputLowTyp "1.7  V") (threshOutputLowMax "1.985  V") (mappingTagNonInverting nil) (mappingTagInverting nil) (spice nil))) (ShuntTerm ((resistance "50 ohm") (voltage "5 V") (maxDelay "0.1 ns"))) (Inductor ((inductance "5 nH") (orientation "0"))) (Capacitor ((capacitance "10 pF") (orientation "0"))) (RLGC (length("1000 mil"))) (Source ((voltage "5 V"))) (DiffInput ((temperature "27") (bufferModelNonInverting "CDSDefaultInput_2p5v") (bufferModelInverting "CDSDefaultInput_2p5v") (threshInputHighMin "1.7 V") (threshInputHighTyp "1.7  V") (threshInputHighMax "1.7  V") (threshInputLowMin "0.7  V") (threshInputLowTyp "0.7  V") (threshInputLowMax "0.7  V") (mappingTagNonInverting nil) (mappingTagInverting nil) (cycle "1"))) (Cable (length("1 m"))) (CPWSL ((d1Thickness "10 mil") (d1Constant "4.5") (d1LossTangent "0.035") (d2Thickness "0.72 mil") (d2Constant "4.5") (d2LossTangent "0.035") (d3Thickness "10 mil") (d3Constant "4.5") (d3LossTangent "0.035") length("1000 mil") (spacing "5 mil") (spacing2 "5 mil") (spacing3 "5 mil") (spacing4 "5 mil") (spacing5 "5 mil") (traceConductivity "595900 mho/cm") (traceGeometry "cpwms") (traceLayerName "") (traceThickness "0.72 mil") (traceType "single") (traceWidth "5.0 mil") (traceWidth2 "5.0 mil") (traceWidth3 "5.0 mil") (traceWidth4 "5.0 mil") (traceWidth5 "5.0 mil") (traceWidth6 "5.0 mil") (offset "0 mil") (traceCount "1") (impedance nil))) (ESpiceDevice nil) (CPWMS ((d1Thickness "10 mil") (d1Constant "4.5") (d1LossTangent "0.035") (d2Thickness "0.72 mil") (d2Constant "4.5") (d2LossTangent "0.035") (d3Thickness "0.0") (d3Constant "1") (d3LossTangent "0") length("1000 mil") (spacing "5 mil") (spacing2 "5 mil") (spacing3 "5 mil") (spacing4 "5 mil") (spacing5 "5 mil") (traceConductivity "595900 mho/cm") (traceGeometry "cpwms") (traceLayerName "") (traceThickness "0.72 mil") (traceType "single") (traceWidth "5.0 mil") (traceWidth2 "5.0 mil") (traceWidth3 "5.0 mil") (traceWidth4 "5.0 mil") (traceWidth5 "5.0 mil") (traceWidth6 "5.0 mil") (offset "0 mil") (traceCount "1") (impedance nil))) (Diode ((cutoffVoltage "0.7 V"))) (CPW ((d1Thickness "10 mil") (d1Constant "4.5") (d1LossTangent "0.035") (d2Thickness "0.72 mil") (d2Constant "1") (d2LossTangent "0") (d3Thickness "0.0") (d3Constant "1") (d3LossTangent "0") length("1000 mil") (spacing "5 mil") (spacing2 "5 mil") (spacing3 "5 mil") (spacing4 "5 mil") (spacing5 "5 mil") (traceConductivity "595900 mho/cm") (traceGeometry "cpwms") (traceLayerName "") (traceThickness "0.72 mil") (traceType "single") (traceWidth "5.0 mil") (traceWidth2 "5.0 mil") (traceWidth3 "5.0 mil") (traceWidth4 "5.0 mil") (traceWidth5 "5.0 mil") (traceWidth6 "5.0 mil") (offset "0 mil") (traceCount "1") (impedance nil))) (DualClampTerm ((cutoffVoltageUp "0.7 V") (cutoffVoltageDown "0.7 V") (voltageUp "5 V") (voltageDown "0 V") (maxDelay "0.1 ns"))) (IbisOutputPkg ((temperature "27") (bufferModel "CDSDefaultOutput_2p5v") (stimuli nil) (offsets nil) (state "tristate") (cycle "1") (termMap nil) (setup "2.0e-09") (hold "1.0e-09") (rise nil) (fall nil) (macroType nil) (voltage nil) (spice nil) (LEFDEFPinName nil) (LEFDEFPinType nil) (mappingTag nil))) (IbisIO_OpenPullDown ((temperature "27") (bufferModel "CDSDefaultIO_2p5v") (stimuli nil) (offsets nil) (state "tristate") (cycle "1") (termMap nil) (setup "2.0e-09") (hold "1.0e-09") (rise nil) (fall nil) (macroType nil) (voltage nil) (spice nil) (LEFDEFPinName nil) (LEFDEFPinType nil) (mappingTag nil))) (IbisInputPkg ((temperature "27") (bufferModel "CDSDefaultInput_2p5v") (cycle "1") (LEFDEFPinName nil) (LEFDEFPinType nil) (mappingTag nil))) (IbisIOMacro ((temperature "27") (bufferModel "CDSDefaultIO_2p5v") (stimuli nil) (offsets nil) (state "tristate") (cycle "1") (termMap nil) (setup "2.0e-09") (hold "1.0e-09") (rise nil) (fall nil) (macroType nil) (voltage nil) (spice nil) (LEFDEFPinName nil) (LEFDEFPinType nil) (mappingTag nil))) (IbisIO_OpenPullUp ((temperature "27") (bufferModel "CDSDefaultIO_2p5v") (stimuli nil) (offsets nil) (state "tristate") (cycle "1") (termMap nil) (setup "2.0e-09") (hold "1.0e-09") (rise nil) (fall nil) (macroType nil) (voltage nil) (spice nil) (LEFDEFPinName nil) (LEFDEFPinType nil) (mappingTag nil))) (IbisIOPkg ((temperature "27") (bufferModel "CDSDefaultIO_2p5v") (stimuli nil) (offsets nil) (state "tristate") (cycle "1") (termMap nil) (setup "2.0e-09") (hold "1.0e-09") (rise nil) (fall nil) (macroType nil) (voltage nil) (spice nil) (LEFDEFPinName nil) (LEFDEFPinType nil) (mappingTag nil))) (clocked ((clockRise "1e-09") (clockFall "1e-09") (clockFreq "100e6") (clockInitState "0") (clockDutyCycle "0.5") (clockJitter "0"))) (periodic ((periodicFreq "100e6") (periodicPattern "10") (periodicJitter "0"))) (IbisIO ((temperature "27") (bufferModel "CDSDefaultIO_2p5v") (stimuli nil) (offsets nil) (state "tristate") (cycle "1") (termMap nil) (setup "2.0e-09") (hold "1.0e-09") (rise nil) (fall nil) (macroType nil) (voltage nil) (spice nil) (LEFDEFPinName nil) (LEFDEFPinType nil) (mappingTag nil))) (async ((asyncTimePoints "") (asyncInitState "1"))) (IbisOutput ((temperature "27") (bufferModel "CDSDefaultOutput_2p5v") (stimuli nil) (offsets nil) (state "tristate") (cycle "1") (termMap nil) (setup "2.0e-09") (hold "1.0e-09") (rise nil) (fall nil) (macroType nil) (voltage nil) (spice nil) (LEFDEFPinName nil) (LEFDEFPinType nil) (mappingTag nil))) (TLine ((diffImpedance "100ohm") (diffVelocity "1.4142e+08M/s") (impedance "60ohm") length("2800 mil") (propDelay "0.5 ns") (velocity "5600 mil/ns") (traceCount "1") (traceGeometry "Microstrip") (impedanceMin nil) (impedanceMax nil) (lengthMin nil) (lengthMax nil) (propDelayMin nil) (propDelayMax nil) (impedanceSweepCount nil) (propDelaySweepCount nil) (velocitySweepCount nil) (lengthSweepCount nil) (matchSetName nil))) (CurrentProbe nil) (IbisInput ((temperature "27") (bufferModel "CDSDefaultInput_2p5v") (cycle "1") (LEFDEFPinName nil) (LEFDEFPinType nil) (mappingTag nil))) (SeriesTerm ((resistance "22 ohm") (maxDelay "0.1 ns"))) (Connector nil) (sync ((syncFreq "100e6") (syncInitState "1") (syncPattern "10") (syncEdgeSwitch "rise"))) (IbisOutput_OpenPullUp ((temperature "27") (bufferModel "CDSDefaultOutput_2p5v") (stimuli nil) (offsets nil) (state "tristate") (cycle "1") (termMap nil) (setup "2.0e-09") (hold "1.0e-09") (rise nil) (fall nil) (macroType nil) (voltage nil) (spice nil) (LEFDEFPinName nil) (LEFDEFPinType nil) (mappingTag nil))) (DiffInputPkg ((temperature "27") (bufferModelNonInverting "CDSDefaultInput_2p5v") (bufferModelInverting "CDSDefaultInput_2p5v") (threshInputHighMin "1.7 V") (threshInputHighTyp "1.7  V") (threshInputHighMax "1.7  V") (threshInputLowMin "0.7  V") (threshInputLowTyp "0.7  V") (threshInputLowMax "0.7  V") (mappingTagNonInverting nil) (mappingTagInverting nil) (cycle "1"))) (idlCircuit ((allDrivers "active") (ftsMode '("Typ")) (rcvrSelect "all") (simMode "Reflection") (tlineDelayMode "time") (userRevision "1.0") (autoSolve "On")))))
				)
				( objectStatus "SVID_CLK1_CPU1" )
			)
			( electricalCSet "@baseboard_fab2_lib.baseboard_fab2(sch_1):\SVID_DIO1_CPU1\"
				( groupRef "SVID_DIO1_CPU1:#SVID_CPU1_1_U100-EU76" )
				( groupRef "SVID_DIO1_CPU1:#SVID_CPU1_1_U100-EU77" )
				( pinPairRef "SVID_DIO1_CPU1:EU1G2.16:U2D1.DJ44" )
				( pinPairRef "SVID_DIO1_CPU1:EU1B1.16:U2D1.DJ44" )
				( pinPairRef "SVID_DIO1_CPU1:U2D1.DJ44:R1C2.1" )
				( pinPairRef "SVID_DIO1_CPU1:R9M7.2:R1B10.2" )
				( pinPairRef "SVID_DIO1_CPU1:R1G10.2:R9U3.2" )
				( pinPairRef "SVID_DIO1_CPU1:R1C2.2:R1G10.2" )
				( pinPairRef "SVID_DIO1_CPU1:R1C2.2:R9N2.2" )
				( pinPairRef "SVID_DIO1_CPU1:EU1B1.16:R1B10.1" )
				( pinPairRef "SVID_DIO1_CPU1:EU1G2.16:R1G10.1" )
				( attribute "TOPOLOGY_TEMPLATE_REVISION" "1.0"
					( Origin gBackEnd )
				)
				( topologyData 31949
(SKIDL (Circuits ("MAIN" (Parts ("CRESCENT_CITY_195_20150128_Q.@@EU77.16" IbisIOPkg (xy (5521 4206)) (refDes "EU1B1") (model "Unknown") (Props (_SXDesignName "CRESCENT_CITY_195_20150128_Q") (brdx "-15.5 MIL") (brdy "5030.13 MIL") (bufferModel "CDSDefaultIO_2p5v") (cycle "1") (hold "1.0e-09") (mappingTag "") (offsets ("4" "0") ("5" "0")) (setup "2.0e-09") (state "tristate") (stimuli ("4" "local89") ("5" "local90")) (temperature "27") (termMap ("4" "Data") ("5" "Enable"))) (Terms ("CRESCENT_CITY_195_20150128_Q.Xn1550Y503013L2LRATS" "16"))) ("CRESCENT_CITY_195_20150128_Q.@@U100.DJ44" IbisIOPkg (xy (5527 4227)) (refDes "U2D1") (model "Unknown") (Props (_SXDesignName "CRESCENT_CITY_195_20150128_Q") (brdx "4086.86 MIL") (brdy "3670.6 MIL") (bufferModel "CDSDefaultIO_2p5v") (cycle "1") (hold "1.0e-09") (mappingTag "") (offsets ("4" "0") ("5" "0")) (setup "2.0e-09") (state "tristate") (stimuli ("4" "local91") ("5" "local92")) (temperature "27") (termMap ("4" "Data") ("5" "Enable"))) (Terms ("CRESCENT_CITY_195_20150128_Q.X408686Y367060L2LRATS" "DJ44"))) ("CRESCENT_CITY_195_20150128_Q.@@EU76.16" IbisIOPkg (xy (5502 4240)) (refDes "EU1G2") (model "Unknown") (Props (_SXDesignName "CRESCENT_CITY_195_20150128_Q") (brdx "387.13 MIL") (brdy "146.5 MIL") (bufferModel "CDSDefaultIO_2p5v") (cycle "1") (hold "1.0e-09") (mappingTag "") (offsets ("4" "0") ("5" "0")) (setup "2.0e-09") (state "tristate") (stimuli ("4" "local93") ("5" "local94")) (temperature "27") (termMap ("4" "Data") ("5" "Enable"))) (Terms ("CRESCENT_CITY_195_20150128_Q.X38713Y14650L2LRATS" "16"))) ("CRESCENT_CITY_195_20150128_Q.T@@RATS@@R2084.2@@R2079.2" TLine (xy (5482 4201)) (refDes "TL132") (Props (_SXDesignName "CRESCENT_CITY_195_20150128_Q") (impedance "48.412 ohm") (propDelay "1.79607e-006 ns") (traceCount "1") (traceGeometry "Microstrip")) (Terms ("CRESCENT_CITY_195_20150128_Q.Xn13400Y506300L30LRATS" "1") ("CRESCENT_CITY_195_20150128_Q.Xn13400Y506300L2LRATS" "2"))) ("CRESCENT_CITY_195_20150128_Q.T@@RATS@@R2084.2@@R1451.2" TLine (xy (5482 4208)) (refDes "TL133") (Props (_SXDesignName "CRESCENT_CITY_195_20150128_Q") (impedance "48.412 ohm") length("2546.42 MIL") (propDelay "0.45735 ns") (traceCount "1") (traceGeometry "Microstrip") (velocity "5567.76 mil/ns")) (Terms ("CRESCENT_CITY_195_20150128_Q.Xn13400Y506300L30LRATS" "1") ("CRESCENT_CITY_195_20150128_Q.X151142Y416200L2LRATS" "2"))) ("CRESCENT_CITY_195_20150128_Q.@@R2058.2.1" Resistor (xy (5488 4229)) (refDes "R1G10") (value "2.2e-007 Ohm") (Props (_SXDesignName "CRESCENT_CITY_195_20150128_Q")) (Terms ("CRESCENT_CITY_195_20150128_Q.X42000Y26500L2LRATS" "2") ("CRESCENT_CITY_195_20150128_Q.X42000Y23000L2LRATS" "1"))) ("CRESCENT_CITY_195_20150128_Q.T@@RATS@@R2058.1@@EU76.16" TLine (xy (5497 4229)) (refDes "TL134") (Props (_SXDesignName "CRESCENT_CITY_195_20150128_Q") (impedance "48.412 ohm") length("116.37 MIL") (propDelay "0.0209 ns") (traceCount "1") (traceGeometry "Microstrip") (velocity "5567.95 mil/ns")) (Terms ("CRESCENT_CITY_195_20150128_Q.X42000Y23000L2LRATS" "1") ("CRESCENT_CITY_195_20150128_Q.X38713Y14650L2LRATS" "2"))) ("CRESCENT_CITY_195_20150128_Q.@@R1282.1_SOURCE" Source (xy (5466 4215)) (refDes "PVCCIO_CPU1_1") (value "1 V") (Props (_SXDesignName "CRESCENT_CITY_195_20150128_Q")) (Terms ("CRESCENT_CITY_195_20150128_Q.X154642Y416200L30RATS" "1"))) ("CRESCENT_CITY_195_20150128_Q.T@@RATS@@U100.DJ44@@R1451.1" TLine (xy (5512 4222)) (mirror x) (refDes "TL135") (Props (_SXDesignName "CRESCENT_CITY_195_20150128_Q") (impedance "49.728 ohm") length("3031.84 MIL") (propDelay "0.54454 ns") (traceCount "1") (traceGeometry "Microstrip") (velocity "5567.72 mil/ns")) (Terms ("CRESCENT_CITY_195_20150128_Q.X408686Y367060L2LRATS" "1") ("CRESCENT_CITY_195_20150128_Q.X154642Y416200L2LRATS" "2"))) ("CRESCENT_CITY_195_20150128_Q.@@R2084.1.2" Resistor (xy (5473 4208)) (refDes "R9M7") (value "100 Ohm") (Props (_SXDesignName "CRESCENT_CITY_195_20150128_Q")) (Terms ("CRESCENT_CITY_195_20150128_Q.Xn9900Y506300L30RATS" "1") ("CRESCENT_CITY_195_20150128_Q.Xn13400Y506300L30LRATS" "2"))) ("CRESCENT_CITY_195_20150128_Q.@@R2063.1.2" Resistor (xy (5464 4229)) (refDes "R9U3") (value "100 Ohm") (Props (_SXDesignName "CRESCENT_CITY_195_20150128_Q")) (Terms ("CRESCENT_CITY_195_20150128_Q.X42000Y23000L30RATS" "1") ("CRESCENT_CITY_195_20150128_Q.X42000Y26500L30LRATS" "2"))) ("CRESCENT_CITY_195_20150128_Q.T@@RATS@@EU77.16@@R2079.1" TLine (xy (5506 4201)) (mirror x) (refDes "TL136") (Props (_SXDesignName "CRESCENT_CITY_195_20150128_Q") (impedance "48.412 ohm") length("116.37 MIL") (propDelay "0.0209 ns") (traceCount "1") (traceGeometry "Microstrip") (velocity "5567.95 mil/ns")) (Terms ("CRESCENT_CITY_195_20150128_Q.Xn1550Y503013L2LRATS" "1") ("CRESCENT_CITY_195_20150128_Q.Xn9900Y506300L2LRATS" "2"))) ("CRESCENT_CITY_195_20150128_Q.@@R2079.1.2" Resistor (xy (5491 4201)) (mirror x) (refDes "R1B10") (value "2.2e-007 Ohm") (Props (_SXDesignName "CRESCENT_CITY_195_20150128_Q")) (Terms ("CRESCENT_CITY_195_20150128_Q.Xn9900Y506300L2LRATS" "1") ("CRESCENT_CITY_195_20150128_Q.Xn13400Y506300L2LRATS" "2"))) ("CRESCENT_CITY_195_20150128_Q.T@@RATS@@R2058.2@@R2063.2" TLine (xy (5479 4229)) (mirror x) (refDes "TL137") (Props (_SXDesignName "CRESCENT_CITY_195_20150128_Q") (impedance "48.412 ohm") (propDelay "1.79607e-006 ns") (traceCount "1") (traceGeometry "Microstrip")) (Terms ("CRESCENT_CITY_195_20150128_Q.X42000Y26500L2LRATS" "1") ("CRESCENT_CITY_195_20150128_Q.X42000Y26500L30LRATS" "2"))) ("CRESCENT_CITY_195_20150128_Q.T@@RATS@@R1451.2@@R1282.2" TLine (xy (5488 4215)) (mirror x) (refDes "TL138") (Props (_SXDesignName "CRESCENT_CITY_195_20150128_Q") (impedance "48.412 ohm") (propDelay "1.79607e-006 ns") (traceCount "1") (traceGeometry "Microstrip")) (Terms ("CRESCENT_CITY_195_20150128_Q.X151142Y416200L2LRATS" "1") ("CRESCENT_CITY_195_20150128_Q.X151142Y416200L30LRATS" "2"))) ("CRESCENT_CITY_195_20150128_Q.@@R1282.1.2" Resistor (xy (5473 4215)) (refDes "R9N2") (value "100 Ohm") (Props (_SXDesignName "CRESCENT_CITY_195_20150128_Q")) (Terms ("CRESCENT_CITY_195_20150128_Q.X154642Y416200L30RATS" "1") ("CRESCENT_CITY_195_20150128_Q.X151142Y416200L30LRATS" "2"))) ("CRESCENT_CITY_195_20150128_Q.@@R2084.1_SOURCE" Source (xy (5466 4208)) (refDes "PVCCIO_CPU1_2") (value "1 V") (Props (_SXDesignName "CRESCENT_CITY_195_20150128_Q")) (Terms ("CRESCENT_CITY_195_20150128_Q.Xn9900Y506300L30RATS" "1"))) ("CRESCENT_CITY_195_20150128_Q.@@R2063.1_SOURCE" Source (xy (5457 4229)) (refDes "PVCCIO_CPU1") (value "1 V") (Props (_SXDesignName "CRESCENT_CITY_195_20150128_Q")) (Terms ("CRESCENT_CITY_195_20150128_Q.X42000Y23000L30RATS" "1"))) ("CRESCENT_CITY_195_20150128_Q.@@R1451.1.2" Resistor (xy (5497 4222)) (mirror x) (refDes "R1C2") (value "2.2e-007 Ohm") (Props (_SXDesignName "CRESCENT_CITY_195_20150128_Q")) (Terms ("CRESCENT_CITY_195_20150128_Q.X154642Y416200L2LRATS" "1") ("CRESCENT_CITY_195_20150128_Q.X151142Y416200L2LRATS" "2"))) ("CRESCENT_CITY_195_20150128_Q.T@@RATS@@R1451.2@@R2058.2" TLine (xy (5482 4222)) (mirror x) (refDes "TL139") (Props (_SXDesignName "CRESCENT_CITY_195_20150128_Q") (impedance "48.412 ohm") length("4988.43 MIL") (propDelay "0.89595 ns") (traceCount "1") (traceGeometry "Microstrip") (velocity "5567.76 mil/ns")) (Terms ("CRESCENT_CITY_195_20150128_Q.X151142Y416200L2LRATS" "1") ("CRESCENT_CITY_195_20150128_Q.X42000Y26500L2LRATS" "2")))) (Nodes ("CRESCENT_CITY_195_20150128_Q.X42000Y26500L30LRATS" (terms "CRESCENT_CITY_195_20150128_Q.T@@RATS@@R2058.2@@R2063.2.2" "CRESCENT_CITY_195_20150128_Q.@@R2063.1.2.2")) ("CRESCENT_CITY_195_20150128_Q.Xn1550Y503013L2LRATS" (terms "CRESCENT_CITY_195_20150128_Q.T@@RATS@@EU77.16@@R2079.1.1" "CRESCENT_CITY_195_20150128_Q.@@EU77.16.1")) ("CRESCENT_CITY_195_20150128_Q.X151142Y416200L2LRATS" (terms "CRESCENT_CITY_195_20150128_Q.T@@RATS@@R1451.2@@R2058.2.1" "CRESCENT_CITY_195_20150128_Q.@@R1451.1.2.2" "CRESCENT_CITY_195_20150128_Q.T@@RATS@@R1451.2@@R1282.2.1" "CRESCENT_CITY_195_20150128_Q.T@@RATS@@R2084.2@@R1451.2.2")) ("CRESCENT_CITY_195_20150128_Q.X42000Y23000L30RATS" (terms "CRESCENT_CITY_195_20150128_Q.@@R2063.1_SOURCE.1" "CRESCENT_CITY_195_20150128_Q.@@R2063.1.2.1")) ("CRESCENT_CITY_195_20150128_Q.Xn13400Y506300L2LRATS" (terms "CRESCENT_CITY_195_20150128_Q.@@R2079.1.2.2" "CRESCENT_CITY_195_20150128_Q.T@@RATS@@R2084.2@@R2079.2.2")) ("CRESCENT_CITY_195_20150128_Q.X42000Y26500L2LRATS" (terms "CRESCENT_CITY_195_20150128_Q.T@@RATS@@R1451.2@@R2058.2.2" "CRESCENT_CITY_195_20150128_Q.T@@RATS@@R2058.2@@R2063.2.1" "CRESCENT_CITY_195_20150128_Q.@@R2058.2.1.1")) ("CRESCENT_CITY_195_20150128_Q.X38713Y14650L2LRATS" (terms "CRESCENT_CITY_195_20150128_Q.T@@RATS@@R2058.1@@EU76.16.2" "CRESCENT_CITY_195_20150128_Q.@@EU76.16.1")) ("CRESCENT_CITY_195_20150128_Q.X151142Y416200L30LRATS" (terms "CRESCENT_CITY_195_20150128_Q.@@R1282.1.2.2" "CRESCENT_CITY_195_20150128_Q.T@@RATS@@R1451.2@@R1282.2.2")) ("CRESCENT_CITY_195_20150128_Q.Xn9900Y506300L30RATS" (terms "CRESCENT_CITY_195_20150128_Q.@@R2084.1_SOURCE.1" "CRESCENT_CITY_195_20150128_Q.@@R2084.1.2.1")) ("CRESCENT_CITY_195_20150128_Q.Xn13400Y506300L30LRATS" (terms "CRESCENT_CITY_195_20150128_Q.@@R2084.1.2.2" "CRESCENT_CITY_195_20150128_Q.T@@RATS@@R2084.2@@R1451.2.1" "CRESCENT_CITY_195_20150128_Q.T@@RATS@@R2084.2@@R2079.2.1")) ("CRESCENT_CITY_195_20150128_Q.X154642Y416200L2LRATS" (terms "CRESCENT_CITY_195_20150128_Q.@@R1451.1.2.1" "CRESCENT_CITY_195_20150128_Q.T@@RATS@@U100.DJ44@@R1451.1.2")) ("CRESCENT_CITY_195_20150128_Q.X154642Y416200L30RATS" (terms "CRESCENT_CITY_195_20150128_Q.@@R1282.1.2.1" "CRESCENT_CITY_195_20150128_Q.@@R1282.1_SOURCE.1")) ("CRESCENT_CITY_195_20150128_Q.X42000Y23000L2LRATS" (terms "CRESCENT_CITY_195_20150128_Q.T@@RATS@@R2058.1@@EU76.16.1" "CRESCENT_CITY_195_20150128_Q.@@R2058.2.1.2")) ("CRESCENT_CITY_195_20150128_Q.X408686Y367060L2LRATS" (terms "CRESCENT_CITY_195_20150128_Q.T@@RATS@@U100.DJ44@@R1451.1.1" "CRESCENT_CITY_195_20150128_Q.@@U100.DJ44.1")) ("CRESCENT_CITY_195_20150128_Q.Xn9900Y506300L2LRATS" (terms "CRESCENT_CITY_195_20150128_Q.@@R2079.1.2.1" "CRESCENT_CITY_195_20150128_Q.T@@RATS@@EU77.16@@R2079.1.2"))) (Ports) (Stimuli ("local92" (scope local) (stimType periodic) (Props (periodicFreq "5e+007") (periodicJitter "0") (periodicPattern "1"))) ("local90" (scope local) (stimType periodic) (Props (periodicFreq "5e+007") (periodicJitter "0") (periodicPattern "1"))) ("local94" (scope local) (stimType periodic) (Props (periodicFreq "5e+007") (periodicJitter "0") (periodicPattern "1"))) ("local89" (scope local) (stimType periodic) (Props (periodicFreq "5e+007") (periodicJitter "0") (periodicPattern "1"))) ("local91" (scope local) (stimType periodic) (Props (periodicFreq "5e+007") (periodicJitter "0") (periodicPattern "1"))) ("local93" (scope local) (stimType periodic) (Props (periodicFreq "5e+007") (periodicJitter "0") (periodicPattern "1")))) (Notes) (Constraints ("DELAY_RULE" ("CRESCENT_CITY_195_20150128_Q U100.DJ44" "CRESCENT_CITY_195_20150128_Q R1451.1" "LENGTH" "" "LENGTH" "0.1143") ("CRESCENT_CITY_195_20150128_Q R2084.2" "CRESCENT_CITY_195_20150128_Q R2079.2" "LENGTH" "" "LENGTH" "0.00508") ("CRESCENT_CITY_195_20150128_Q R2058.2" "CRESCENT_CITY_195_20150128_Q R2063.2" "LENGTH" "" "LENGTH" "0.00508") ("CRESCENT_CITY_195_20150128_Q R1451.2" "CRESCENT_CITY_195_20150128_Q R2058.2" "LENGTH" "" "LENGTH" "0.6858") ("CRESCENT_CITY_195_20150128_Q R1451.2" "CRESCENT_CITY_195_20150128_Q R1282.2" "LENGTH" "" "LENGTH" "0.01016") ("CRESCENT_CITY_195_20150128_Q EU77.16" "CRESCENT_CITY_195_20150128_Q R2079.1" "LENGTH" "" "LENGTH" "0.0254") ("CRESCENT_CITY_195_20150128_Q EU76.16" "CRESCENT_CITY_195_20150128_Q R2058.1" "LENGTH" "" "LENGTH" "0.0254")) ("RELATIVE_PROPAGATION_DELAY" ("#SVID_CPU1_1_U100-EU76" "CRESCENT_CITY_195_20150128_Q EU76.16" "CRESCENT_CITY_195_20150128_Q U100.DJ44" "GLOBAL" "LENGTH" "0.00635" "NONE" "") ("#SVID_CPU1_1_U100-EU77" "CRESCENT_CITY_195_20150128_Q EU77.16" "CRESCENT_CITY_195_20150128_Q U100.DJ44" "GLOBAL" "LENGTH" "0.00635" "NONE" ""))) (MeasurementSets ("EMI" ("EMIStatus" status("on")) ("PeakEmission" status("on")) ("PeakFrequency" status("on")) ("PulseFreq" status("on")) ("RiseTime" status("on")) ("VoltageSwing" status("on"))) ("Reflection" ("BufferDelayFall" status("off")) ("BufferDelayRise" status("off")) ("EyeHeight" status("off")) ("EyeJitter" status("off")) ("EyeWidth" status("off")) ("FirstIncidentFall" status("off")) ("FirstIncidentRise" status("off")) ("Glitch" status("on")) ("GlitchFall" status("off")) ("GlitchRise" status("off")) ("Monotonic" status("on")) ("MonotonicFall" status("off")) ("MonotonicRise" status("off")) ("NoiseMargin" status("on")) ("NoiseMarginHigh" status("off")) ("NoiseMarginLow" status("off")) ("OvershootHigh" status("on")) ("OvershootLow" status("on")) ("PropDelay" status("on")) ("SettleDelay" status("on")) ("SettleDelayFall" status("off")) ("SettleDelayRise" status("off")) ("SwitchDelay" status("on")) ("SwitchDelayFall" status("off")) ("SwitchDelayRise" status("off"))) ("Crosstalk" ("Crosstalk" status("on"))) ("Custom")) (VectorSets) (Props (XnetName "SVID_DIO1_CPU1") (allDrivers "active") (customSimType "Reflection") (ftsMode ("Typ")) (rcvrSelect "all") (tlineDelayMode "time") (userRevision "1.0")))) (Subckts) (CrossSections ("CRESCENT_CITY_195_20150128_Q" (Props (SXDesignName "CRESCENT_CITY_195_20150128_Q")) (Layers ("" (layerType "SURFACE") (material "AIR") (thickness "0 mil") (dielectricConstant "1.000000") (lossTangent "0") (etchFactor "0.000000") (elecCondVal "0 mho/cm") (thermCondVal "0 w/cm-degC")) ("" (layerType "DIELECTRIC") (material "CONFORMAL_COAT") (thickness "0.5 mil") (dielectricConstant "3.800000") (lossTangent "0.035") (etchFactor "0.000000") (elecCondVal "0 mho/cm") (thermCondVal "0.012 w/cm-degC")) ("TOP" (layerType "CONDUCTOR") (material "COPPER") (thickness "  2.100000 mil") (width "4.00 MIL") (dielectricConstant "4.500000") (lossTangent "0") (etchFactor "70.000000") (elecCondVal "595900.000000 mho/cm") (thermCondVal "0 w/cm-degC") (signalDieConstant "3.800000") (signalLossTangent "0.035")) ("" (layerType "DIELECTRIC") (material "FR-4") (thickness "  2.670000 mil") (dielectricConstant "4.000000") (lossTangent "0.035") (etchFactor "0.000000") (elecCondVal "0 mho/cm") (thermCondVal "0.012 w/cm-degC")) ("L2_GND1" (layerType "PLANE") (material "COPPER") (isShield t) (thickness "  1.250000 mil") (dielectricConstant "4.500000") (lossTangent "0.035") (etchFactor "90.000000") (elecCondVal "595900.000000 mho/cm") (thermCondVal "0.012 w/cm-degC")) ("" (layerType "DIELECTRIC") (material "FR-4") (thickness "  9.000000 mil") (dielectricConstant "4.100000") (lossTangent "0.035") (etchFactor "0.000000") (elecCondVal "0 mho/cm") (thermCondVal "0.012 w/cm-degC")) ("L3_SIG1" (layerType "CONDUCTOR") (material "COPPER") (thickness "  1.250000 mil") (width "4.00 MIL") (dielectricConstant "4.500000") (lossTangent "0.035") (etchFactor "90.000000") (elecCondVal "595900.000000 mho/cm") (thermCondVal "0.012 w/cm-degC") (signalDieConstant "4.100000") (signalLossTangent "0.035")) ("" (layerType "DIELECTRIC") (material "FR-4") (thickness "  3.000000 mil") (dielectricConstant "4.500000") (lossTangent "0.035") (etchFactor "0.000000") (elecCondVal "0 mho/cm") (thermCondVal "0 w/cm-degC")) ("L4_GND2" (layerType "PLANE") (material "COPPER") (isShield t) (thickness "  1.250000 mil") (dielectricConstant "4.500000") (lossTangent "0.035") (etchFactor "90.000000") (elecCondVal "595900.000000 mho/cm") (thermCondVal "0 w/cm-degC")) ("" (layerType "DIELECTRIC") (material "FR-4") (thickness "  9.000000 mil") (dielectricConstant "4.000000") (lossTangent "0.035") (etchFactor "0.000000") (elecCondVal "0 mho/cm") (thermCondVal "0.012 w/cm-degC")) ("L5_SIG2" (layerType "CONDUCTOR") (material "COPPER") (thickness "  1.250000 mil") (width "4.00 MIL") (dielectricConstant "4.500000") (lossTangent "0.035") (etchFactor "90.000000") (elecCondVal "595900.000000 mho/cm") (thermCondVal "0.012 w/cm-degC") (signalDieConstant "4.000000") (signalLossTangent "0.035")) ("" (layerType "DIELECTRIC") (material "FR-4") (thickness "  3.000000 mil") (dielectricConstant "4.500000") (lossTangent "0.035") (etchFactor "0.000000") (elecCondVal "0 mho/cm") (thermCondVal "0 w/cm-degC")) ("L6_GND3" (layerType "PLANE") (material "COPPER") (isShield t) (thickness "  1.250000 mil") (dielectricConstant "4.500000") (lossTangent "0.035") (etchFactor "90.000000") (elecCondVal "595900.000000 mho/cm") (thermCondVal "0 w/cm-degC")) ("" (layerType "DIELECTRIC") (material "FR-4") (thickness "  4.500000 mil") (dielectricConstant "4.100000") (lossTangent "0.035") (etchFactor "0.000000") (elecCondVal "0 mho/cm") (thermCondVal "0.012 w/cm-degC")) ("L7_PWR1-SIG" (layerType "PLANE") (material "COPPER") (isShield t) (thickness "  2.400000 mil") (dielectricConstant "4.500000") (lossTangent "0.035") (etchFactor "90.000000") (elecCondVal "595900.000000 mho/cm") (thermCondVal "0.012 w/cm-degC")) ("" (layerType "DIELECTRIC") (material "FR-4") (thickness "  4.600000 mil") (dielectricConstant "4.000000") (lossTangent "0.035") (etchFactor "0.000000") (elecCondVal "0 mho/cm") (thermCondVal "0.012 w/cm-degC")) ("L8_PWR2-SIG" (layerType "PLANE") (material "COPPER") (isShield t) (thickness "  2.400000 mil") (dielectricConstant "4.500000") (lossTangent "0.035") (etchFactor "90.000000") (elecCondVal "595900.000000 mho/cm") (thermCondVal "0.012 w/cm-degC")) ("" (layerType "DIELECTRIC") (material "FR-4") (thickness "  8.000000 mil") (dielectricConstant "4.500000") (lossTangent "0.035") (etchFactor "0.000000") (elecCondVal "0 mho/cm") (thermCondVal "0 w/cm-degC")) ("" (layerType "DIELECTRIC") (material "FR-4") (thickness "  8.000000 mil") (dielectricConstant "4.500000") (lossTangent "0.035") (etchFactor "0.000000") (elecCondVal "0 mho/cm") (thermCondVal "0 w/cm-degC")) ("" (layerType "DIELECTRIC") (material "FR-4") (thickness "  4.500000 mil") (dielectricConstant "4.500000") (lossTangent "0.035") (etchFactor "0.000000") (elecCondVal "0 mho/cm") (thermCondVal "0 w/cm-degC")) ("L9_GND4" (layerType "PLANE") (material "COPPER") (isShield t) (thickness "  1.250000 mil") (dielectricConstant "4.500000") (lossTangent "0.035") (etchFactor "90.000000") (elecCondVal "595900.000000 mho/cm") (thermCondVal "0 w/cm-degC")) ("" (layerType "DIELECTRIC") (material "FR-4") (thickness "  3.000000 mil") (dielectricConstant "4.100000") (lossTangent "0.035") (etchFactor "0.000000") (elecCondVal "0 mho/cm") (thermCondVal "0.012 w/cm-degC")) ("L10_SIG3" (layerType "CONDUCTOR") (material "COPPER") (thickness "  1.250000 mil") (width "4.00 MIL") (dielectricConstant "4.500000") (lossTangent "0.035") (etchFactor "90.000000") (elecCondVal "595900.000000 mho/cm") (thermCondVal "0.012 w/cm-degC") (signalDieConstant "4.100000") (signalLossTangent "0.035")) ("" (layerType "DIELECTRIC") (material "FR-4") (thickness "  9.000000 mil") (dielectricConstant "4.500000") (lossTangent "0.035") (etchFactor "0.000000") (elecCondVal "0 mho/cm") (thermCondVal "0 w/cm-degC")) ("L11_GND5" (layerType "PLANE") (material "COPPER") (isShield t) (thickness "  1.250000 mil") (dielectricConstant "4.500000") (lossTangent "0.035") (etchFactor "90.000000") (elecCondVal "595900.000000 mho/cm") (thermCondVal "0 w/cm-degC")) ("" (layerType "DIELECTRIC") (material "FR-4") (thickness "  3.000000 mil") (dielectricConstant "4.500000") (lossTangent "0.035") (etchFactor "0.000000") (elecCondVal "0 mho/cm") (thermCondVal "0.012 w/cm-degC")) ("L12_SIG4" (layerType "CONDUCTOR") (material "COPPER") (thickness "  1.250000 mil") (width "4.00 MIL") (dielectricConstant "4.500000") (lossTangent "0.035") (etchFactor "90.000000") (elecCondVal "595900.000000 mho/cm") (thermCondVal "0.012 w/cm-degC") (signalDieConstant "4.500000") (signalLossTangent "0.035")) ("" (layerType "DIELECTRIC") (material "FR-4") (thickness "  9.000000 mil") (dielectricConstant "4.500000") (lossTangent "0.035") (etchFactor "0.000000") (elecCondVal "0 mho/cm") (thermCondVal "0 w/cm-degC")) ("L13_GND6" (layerType "PLANE") (material "COPPER") (isShield t) (thickness "  1.250000 mil") (dielectricConstant "4.500000") (lossTangent "0.035") (etchFactor "90.000000") (elecCondVal "595900.000000 mho/cm") (thermCondVal "0.012 w/cm-degC")) ("" (layerType "DIELECTRIC") (material "FR-4") (thickness "  2.670000 mil") (dielectricConstant "4.500000") (lossTangent "0.035") (etchFactor "0.000000") (elecCondVal "0 mho/cm") (thermCondVal "0.012 w/cm-degC")) ("BOTTOM" (layerType "CONDUCTOR") (material "COPPER") (thickness "  2.100000 mil") (width "4.00 MIL") (dielectricConstant "4.500000") (lossTangent "0") (etchFactor "70.000000") (elecCondVal "595900.000000 mho/cm") (thermCondVal "0 w/cm-degC") (signalDieConstant "3.800000") (signalLossTangent "0.035")) ("" (layerType "DIELECTRIC") (material "CONFORMAL_COAT") (thickness "0.5 mil") (dielectricConstant "3.800000") (lossTangent "0.035") (etchFactor "0.000000") (elecCondVal "0 mho/cm") (thermCondVal "0.012 w/cm-degC")) ("" (layerType "SURFACE") (material "AIR") (thickness "0 mil") (dielectricConstant "1.000000") (lossTangent "0") (etchFactor "0.000000") (elecCondVal "0 mho/cm") (thermCondVal "0 w/cm-degC"))))) (Props (DesUnits "mils 2") (LayerStack ("DIELECTRIC" "DIELECTRIC" "BOTTOM" "DIELECTRIC" "L13_GND6" "DIELECTRIC" "L12_SIG4" "DIELECTRIC" "L11_GND5" "DIELECTRIC" "L10_SIG3" "DIELECTRIC" "L9_GND4" "DIELECTRIC" "DIELECTRIC" "DIELECTRIC" "L8_PWR2-SIG" "DIELECTRIC" "L7_PWR1-SIG" "DIELECTRIC" "L6_GND3" "DIELECTRIC" "L5_SIG2" "DIELECTRIC" "L4_GND2" "DIELECTRIC" "L3_SIG1" "DIELECTRIC" "L2_GND1" "DIELECTRIC" "TOP" "DIELECTRIC" "DIELECTRIC")) (Revision "16.600")) (Params (DiffOutputPkg ((temperature "27") (bufferModelNonInverting "CDSDefaultOutput_2p5v") (bufferModelInverting "CDSDefaultOutput_2p5v") (stimuli nil) (offsets nil) (state "tristate") (cycle "1") (termMap nil) (setup "0.9e-09") (hold "0.4e-09") (rise nil) (fall nil) (threshOutputHighMin "2.375  V") (threshOutputHighTyp "2.5  V") (threshOutputHighMax "2.625  V") (threshOutputLowMin "1.275  V") (threshOutputLowTyp "1.7  V") (threshOutputLowMax "1.985  V") (mappingTagNonInverting nil) (mappingTagInverting nil) (spice nil))) (HiClampTerm ((cutoffVoltage "0.7 V") (voltage "5 V") (maxDelay "0.1 ns"))) (LowClampTerm ((cutoffVoltage "0.7 V") (voltage "0 V") (maxDelay "0.1 ns"))) (DiffOutput ((temperature "27") (bufferModelNonInverting "CDSDefaultOutput_2p5v") (bufferModelInverting "CDSDefaultOutput_2p5v") (stimuli nil) (offsets nil) (state "tristate") (cycle "1") (termMap nil) (setup "0.9e-09") (hold "0.4e-09") (rise nil) (fall nil) (threshOutputHighMin "2.375  V") (threshOutputHighTyp "2.5  V") (threshOutputHighMax "2.625  V") (threshOutputLowMin "1.275  V") (threshOutputLowTyp "1.7  V") (threshOutputLowMax "1.985  V") (mappingTagNonInverting nil) (mappingTagInverting nil) (spice nil))) (Via ((model "Unknown") (viaOutputFormat "Unknown") (viaPadstack nil) (viaTopLayer nil) (viaBottomLayer nil) (viaIsPower nil) (viaIsGround nil))) (Resistor ((resistance "50 ohm") (orientation "0"))) (RCTerm ((resistance "50 ohm") (capacitance "20 pF") (voltage "5 V") (maxDelay "0.1 ns"))) (DiffIOPkg ((temperature "27") (bufferModelNonInverting "CDSDefaultIO_2p5v") (bufferModelInverting "CDSDefaultIO_2p5v") (stimuli nil) (offsets nil) (state "tristate") (cycle "1") (termMap nil) (setup "0.9e-09") (hold "0.4e-09") (rise nil) (fall nil) (threshInputHighMin "1.7 V") (threshInputHighTyp "1.7  V") (threshInputHighMax "1.7  V") (threshInputLowMin "0.7  V") (threshInputLowTyp "0.7  V") (threshInputLowMax "0.7 ") (threshOutputHighMin "2.365  V") (threshOutputHighTyp "2.5  V") (threshOutputHighMax "2.625  V") (threshOutputLowMin "1.275  V") (threshOutputLowTyp "1.7  V") (threshOutputLowMax "1.985  V") (mappingTagNonInverting nil) (mappingTagInverting nil) (spice nil))) (Trace ((d1Thickness "10 mil") (d1Constant "4.5") (d1LossTangent "0.035") (d2Thickness "10 mil") (d2Constant "4.5") (d2LossTangent "0.035") (d3Thickness "0.0") (d3Constant "1.0") (d3LossTangent "0") length("1000 mil") (spacing "5 mil") (spacing2 "5 mil") (spacing3 "5 mil") (spacing4 "5 mil") (spacing5 "5 mil") (traceConductivity "595900 mho/cm") (traceGeometry "microstrip") (traceLayerName "") (traceThickness "0.72 mil") (traceType "single") (traceWidth "5.0 mil") (traceWidth2 "5.0 mil") (traceWidth3 "5.0 mil") (traceWidth4 "5.0 mil") (traceWidth5 "5.0 mil") (traceWidth6 "5.0 mil") (offset "0 mil") (traceCount "1") (impedance nil))) (TheveninTerm ((resistanceUp "180 ohm") (resistanceDown "270 ohm") (voltageUp "5 V") (voltageDown "0 V") (maxDelay "0.1 ns"))) (DiffIO ((temperature "27") (bufferModelNonInverting "CDSDefaultIO_2p5v") (bufferModelInverting "CDSDefaultIO_2p5v") (stimuli nil) (offsets nil) (state "tristate") (cycle "1") (termMap nil) (setup "0.9e-09") (hold "0.4e-09") (rise nil) (fall nil) (threshInputHighMin "1.7 V") (threshInputHighTyp "1.7  V") (threshInputHighMax "1.7  V") (threshInputLowMin "0.7  V") (threshInputLowTyp "0.7  V") (threshInputLowMax "0.7 ") (threshOutputHighMin "2.365  V") (threshOutputHighTyp "2.5  V") (threshOutputHighMax "2.625  V") (threshOutputLowMin "1.275  V") (threshOutputLowTyp "1.7  V") (threshOutputLowMax "1.985  V") (mappingTagNonInverting nil) (mappingTagInverting nil) (spice nil))) (ShuntTerm ((resistance "50 ohm") (voltage "5 V") (maxDelay "0.1 ns"))) (Inductor ((inductance "5 nH") (orientation "0"))) (Capacitor ((capacitance "10 pF") (orientation "0"))) (RLGC (length("1000 mil"))) (Source ((voltage "5 V"))) (DiffInput ((temperature "27") (bufferModelNonInverting "CDSDefaultInput_2p5v") (bufferModelInverting "CDSDefaultInput_2p5v") (threshInputHighMin "1.7 V") (threshInputHighTyp "1.7  V") (threshInputHighMax "1.7  V") (threshInputLowMin "0.7  V") (threshInputLowTyp "0.7  V") (threshInputLowMax "0.7  V") (mappingTagNonInverting nil) (mappingTagInverting nil) (cycle "1"))) (Cable (length("1 m"))) (CPWSL ((d1Thickness "10 mil") (d1Constant "4.5") (d1LossTangent "0.035") (d2Thickness "0.72 mil") (d2Constant "4.5") (d2LossTangent "0.035") (d3Thickness "10 mil") (d3Constant "4.5") (d3LossTangent "0.035") length("1000 mil") (spacing "5 mil") (spacing2 "5 mil") (spacing3 "5 mil") (spacing4 "5 mil") (spacing5 "5 mil") (traceConductivity "595900 mho/cm") (traceGeometry "cpwms") (traceLayerName "") (traceThickness "0.72 mil") (traceType "single") (traceWidth "5.0 mil") (traceWidth2 "5.0 mil") (traceWidth3 "5.0 mil") (traceWidth4 "5.0 mil") (traceWidth5 "5.0 mil") (traceWidth6 "5.0 mil") (offset "0 mil") (traceCount "1") (impedance nil))) (ESpiceDevice nil) (CPWMS ((d1Thickness "10 mil") (d1Constant "4.5") (d1LossTangent "0.035") (d2Thickness "0.72 mil") (d2Constant "4.5") (d2LossTangent "0.035") (d3Thickness "0.0") (d3Constant "1") (d3LossTangent "0") length("1000 mil") (spacing "5 mil") (spacing2 "5 mil") (spacing3 "5 mil") (spacing4 "5 mil") (spacing5 "5 mil") (traceConductivity "595900 mho/cm") (traceGeometry "cpwms") (traceLayerName "") (traceThickness "0.72 mil") (traceType "single") (traceWidth "5.0 mil") (traceWidth2 "5.0 mil") (traceWidth3 "5.0 mil") (traceWidth4 "5.0 mil") (traceWidth5 "5.0 mil") (traceWidth6 "5.0 mil") (offset "0 mil") (traceCount "1") (impedance nil))) (Diode ((cutoffVoltage "0.7 V"))) (CPW ((d1Thickness "10 mil") (d1Constant "4.5") (d1LossTangent "0.035") (d2Thickness "0.72 mil") (d2Constant "1") (d2LossTangent "0") (d3Thickness "0.0") (d3Constant "1") (d3LossTangent "0") length("1000 mil") (spacing "5 mil") (spacing2 "5 mil") (spacing3 "5 mil") (spacing4 "5 mil") (spacing5 "5 mil") (traceConductivity "595900 mho/cm") (traceGeometry "cpwms") (traceLayerName "") (traceThickness "0.72 mil") (traceType "single") (traceWidth "5.0 mil") (traceWidth2 "5.0 mil") (traceWidth3 "5.0 mil") (traceWidth4 "5.0 mil") (traceWidth5 "5.0 mil") (traceWidth6 "5.0 mil") (offset "0 mil") (traceCount "1") (impedance nil))) (DualClampTerm ((cutoffVoltageUp "0.7 V") (cutoffVoltageDown "0.7 V") (voltageUp "5 V") (voltageDown "0 V") (maxDelay "0.1 ns"))) (IbisOutputPkg ((temperature "27") (bufferModel "CDSDefaultOutput_2p5v") (stimuli nil) (offsets nil) (state "tristate") (cycle "1") (termMap nil) (setup "2.0e-09") (hold "1.0e-09") (rise nil) (fall nil) (macroType nil) (voltage nil) (spice nil) (LEFDEFPinName nil) (LEFDEFPinType nil) (mappingTag nil))) (IbisIO_OpenPullDown ((temperature "27") (bufferModel "CDSDefaultIO_2p5v") (stimuli nil) (offsets nil) (state "tristate") (cycle "1") (termMap nil) (setup "2.0e-09") (hold "1.0e-09") (rise nil) (fall nil) (macroType nil) (voltage nil) (spice nil) (LEFDEFPinName nil) (LEFDEFPinType nil) (mappingTag nil))) (IbisInputPkg ((temperature "27") (bufferModel "CDSDefaultInput_2p5v") (cycle "1") (LEFDEFPinName nil) (LEFDEFPinType nil) (mappingTag nil))) (IbisIOMacro ((temperature "27") (bufferModel "CDSDefaultIO_2p5v") (stimuli nil) (offsets nil) (state "tristate") (cycle "1") (termMap nil) (setup "2.0e-09") (hold "1.0e-09") (rise nil) (fall nil) (macroType nil) (voltage nil) (spice nil) (LEFDEFPinName nil) (LEFDEFPinType nil) (mappingTag nil))) (IbisIO_OpenPullUp ((temperature "27") (bufferModel "CDSDefaultIO_2p5v") (stimuli nil) (offsets nil) (state "tristate") (cycle "1") (termMap nil) (setup "2.0e-09") (hold "1.0e-09") (rise nil) (fall nil) (macroType nil) (voltage nil) (spice nil) (LEFDEFPinName nil) (LEFDEFPinType nil) (mappingTag nil))) (IbisIOPkg ((temperature "27") (bufferModel "CDSDefaultIO_2p5v") (stimuli nil) (offsets nil) (state "tristate") (cycle "1") (termMap nil) (setup "2.0e-09") (hold "1.0e-09") (rise nil) (fall nil) (macroType nil) (voltage nil) (spice nil) (LEFDEFPinName nil) (LEFDEFPinType nil) (mappingTag nil))) (clocked ((clockRise "1e-09") (clockFall "1e-09") (clockFreq "100e6") (clockInitState "0") (clockDutyCycle "0.5") (clockJitter "0"))) (periodic ((periodicFreq "100e6") (periodicPattern "10") (periodicJitter "0"))) (IbisIO ((temperature "27") (bufferModel "CDSDefaultIO_2p5v") (stimuli nil) (offsets nil) (state "tristate") (cycle "1") (termMap nil) (setup "2.0e-09") (hold "1.0e-09") (rise nil) (fall nil) (macroType nil) (voltage nil) (spice nil) (LEFDEFPinName nil) (LEFDEFPinType nil) (mappingTag nil))) (async ((asyncTimePoints "") (asyncInitState "1"))) (IbisOutput ((temperature "27") (bufferModel "CDSDefaultOutput_2p5v") (stimuli nil) (offsets nil) (state "tristate") (cycle "1") (termMap nil) (setup "2.0e-09") (hold "1.0e-09") (rise nil) (fall nil) (macroType nil) (voltage nil) (spice nil) (LEFDEFPinName nil) (LEFDEFPinType nil) (mappingTag nil))) (TLine ((diffImpedance "100ohm") (diffVelocity "1.4142e+08M/s") (impedance "60ohm") length("2800 mil") (propDelay "0.5 ns") (velocity "5600 mil/ns") (traceCount "1") (traceGeometry "Microstrip") (impedanceMin nil) (impedanceMax nil) (lengthMin nil) (lengthMax nil) (propDelayMin nil) (propDelayMax nil) (impedanceSweepCount nil) (propDelaySweepCount nil) (velocitySweepCount nil) (lengthSweepCount nil) (matchSetName nil))) (CurrentProbe nil) (IbisInput ((temperature "27") (bufferModel "CDSDefaultInput_2p5v") (cycle "1") (LEFDEFPinName nil) (LEFDEFPinType nil) (mappingTag nil))) (SeriesTerm ((resistance "22 ohm") (maxDelay "0.1 ns"))) (Connector nil) (sync ((syncFreq "100e6") (syncInitState "1") (syncPattern "10") (syncEdgeSwitch "rise"))) (IbisOutput_OpenPullUp ((temperature "27") (bufferModel "CDSDefaultOutput_2p5v") (stimuli nil) (offsets nil) (state "tristate") (cycle "1") (termMap nil) (setup "2.0e-09") (hold "1.0e-09") (rise nil) (fall nil) (macroType nil) (voltage nil) (spice nil) (LEFDEFPinName nil) (LEFDEFPinType nil) (mappingTag nil))) (DiffInputPkg ((temperature "27") (bufferModelNonInverting "CDSDefaultInput_2p5v") (bufferModelInverting "CDSDefaultInput_2p5v") (threshInputHighMin "1.7 V") (threshInputHighTyp "1.7  V") (threshInputHighMax "1.7  V") (threshInputLowMin "0.7  V") (threshInputLowTyp "0.7  V") (threshInputLowMax "0.7  V") (mappingTagNonInverting nil) (mappingTagInverting nil) (cycle "1"))) (idlCircuit ((allDrivers "active") (ftsMode '("Typ")) (rcvrSelect "all") (simMode "Reflection") (tlineDelayMode "time") (userRevision "1.0") (autoSolve "On")))))
				)
				( objectStatus "SVID_DIO1_CPU1" )
			)
			( electricalCSet "@baseboard_fab2_lib.baseboard_fab2(sch_1):\CLS_SVID\"
				( groupRef "CLS_SVID:#SVID_CPU1_1_U100-EU76" )
				( groupRef "CLS_SVID:#SVID_CPU1_1_U100-EU77" )
				( pinPairRef "CLS_SVID:EU1G2.16:U2D1.DJ44" )
				( pinPairRef "CLS_SVID:EU1B1.16:U2D1.DJ44" )
				( pinPairRef "CLS_SVID:U2D1.DJ44:R1C2.1" )
				( pinPairRef "CLS_SVID:R1G10.1:EU1B1.16" )
				( pinPairRef "CLS_SVID:R1G10.1:EU1G2.16" )
				( pinPairRef "CLS_SVID:R1C2.2:R9N2.2" )
				( attribute "TOPOLOGY_TEMPLATE_REVISION" "1.0"
					( Origin gBackEnd )
				)
				( topologyData 31589
(SKIDL (Circuits ("MAIN" (Parts ("CRESCENT_CITY_195_20150128_Q.@@EU77.16" IbisIOPkg (xy (5521 4206)) (refDes "EU1B1") (model "Unknown") (Props (_SXDesignName "CRESCENT_CITY_195_20150128_Q") (brdx "-15.5 MIL") (brdy "5030.13 MIL") (bufferModel "CDSDefaultIO_2p5v") (cycle "1") (hold "1.0e-09") (mappingTag "") (offsets ("4" "0") ("5" "0")) (setup "2.0e-09") (state "tristate") (stimuli ("4" "local0") ("5" "local1")) (temperature "27") (termMap ("4" "Data") ("5" "Enable"))) (Terms ("CRESCENT_CITY_195_20150128_Q.Xn1550Y503013L2LRATS" "16"))) ("CRESCENT_CITY_195_20150128_Q.@@U100.DJ44" IbisIOPkg (xy (5527 4227)) (refDes "U2D1") (model "Unknown") (Props (_SXDesignName "CRESCENT_CITY_195_20150128_Q") (brdx "4086.86 MIL") (brdy "3670.6 MIL") (bufferModel "CDSDefaultIO_2p5v") (cycle "1") (hold "1.0e-09") (mappingTag "") (offsets ("4" "0") ("5" "0")) (setup "2.0e-09") (state "tristate") (stimuli ("4" "local2") ("5" "local3")) (temperature "27") (termMap ("4" "Data") ("5" "Enable"))) (Terms ("CRESCENT_CITY_195_20150128_Q.X408686Y367060L2LRATS" "DJ44"))) ("CRESCENT_CITY_195_20150128_Q.@@EU76.16" IbisIOPkg (xy (5502 4240)) (refDes "EU1G2") (model "Unknown") (Props (_SXDesignName "CRESCENT_CITY_195_20150128_Q") (brdx "387.13 MIL") (brdy "146.5 MIL") (bufferModel "CDSDefaultIO_2p5v") (cycle "1") (hold "1.0e-09") (mappingTag "") (offsets ("4" "0") ("5" "0")) (setup "2.0e-09") (state "tristate") (stimuli ("4" "local4") ("5" "local5")) (temperature "27") (termMap ("4" "Data") ("5" "Enable"))) (Terms ("CRESCENT_CITY_195_20150128_Q.X38713Y14650L2LRATS" "16"))) ("CRESCENT_CITY_195_20150128_Q.T@@RATS@@R2084.2@@R2079.2" TLine (xy (5482 4201)) (refDes "TL1") (Props (_SXDesignName "CRESCENT_CITY_195_20150128_Q") (impedance "48.412 ohm") (propDelay "1.79607e-006 ns") (traceCount "1") (traceGeometry "Microstrip")) (Terms ("CRESCENT_CITY_195_20150128_Q.Xn13400Y506300L30LRATS" "1") ("CRESCENT_CITY_195_20150128_Q.Xn13400Y506300L2LRATS" "2"))) ("CRESCENT_CITY_195_20150128_Q.T@@RATS@@R2084.2@@R1451.2" TLine (xy (5482 4208)) (refDes "TL2") (Props (_SXDesignName "CRESCENT_CITY_195_20150128_Q") (impedance "48.412 ohm") length("2546.42 MIL") (propDelay "0.45735 ns") (traceCount "1") (traceGeometry "Microstrip") (velocity "5567.76 mil/ns")) (Terms ("CRESCENT_CITY_195_20150128_Q.Xn13400Y506300L30LRATS" "1") ("CRESCENT_CITY_195_20150128_Q.X151142Y416200L2LRATS" "2"))) ("CRESCENT_CITY_195_20150128_Q.@@R2058.2.1" Resistor (xy (5488 4229)) (refDes "R1G10") (value "2.2e-007 Ohm") (Props (_SXDesignName "CRESCENT_CITY_195_20150128_Q")) (Terms ("CRESCENT_CITY_195_20150128_Q.X42000Y26500L2LRATS" "2") ("CRESCENT_CITY_195_20150128_Q.X42000Y23000L2LRATS" "1"))) ("CRESCENT_CITY_195_20150128_Q.T@@RATS@@R2058.1@@EU76.16" TLine (xy (5497 4229)) (refDes "TL3") (Props (_SXDesignName "CRESCENT_CITY_195_20150128_Q") (impedance "48.412 ohm") length("116.37 MIL") (propDelay "0.0209 ns") (traceCount "1") (traceGeometry "Microstrip") (velocity "5567.95 mil/ns")) (Terms ("CRESCENT_CITY_195_20150128_Q.X42000Y23000L2LRATS" "1") ("CRESCENT_CITY_195_20150128_Q.X38713Y14650L2LRATS" "2"))) ("CRESCENT_CITY_195_20150128_Q.@@R1282.1_SOURCE" Source (xy (5466 4215)) (refDes "PVCCIO_CPU1_1") (value "1 V") (Props (_SXDesignName "CRESCENT_CITY_195_20150128_Q")) (Terms ("CRESCENT_CITY_195_20150128_Q.X154642Y416200L30RATS" "1"))) ("CRESCENT_CITY_195_20150128_Q.T@@RATS@@U100.DJ44@@R1451.1" TLine (xy (5512 4222)) (mirror x) (refDes "TL4") (Props (_SXDesignName "CRESCENT_CITY_195_20150128_Q") (impedance "49.728 ohm") length("3031.84 MIL") (propDelay "0.54454 ns") (traceCount "1") (traceGeometry "Microstrip") (velocity "5567.72 mil/ns")) (Terms ("CRESCENT_CITY_195_20150128_Q.X408686Y367060L2LRATS" "1") ("CRESCENT_CITY_195_20150128_Q.X154642Y416200L2LRATS" "2"))) ("CRESCENT_CITY_195_20150128_Q.@@R2084.1.2" Resistor (xy (5473 4208)) (refDes "R9M7") (value "100 Ohm") (Props (_SXDesignName "CRESCENT_CITY_195_20150128_Q")) (Terms ("CRESCENT_CITY_195_20150128_Q.Xn9900Y506300L30RATS" "1") ("CRESCENT_CITY_195_20150128_Q.Xn13400Y506300L30LRATS" "2"))) ("CRESCENT_CITY_195_20150128_Q.@@R2063.1.2" Resistor (xy (5464 4229)) (refDes "R9U3") (value "100 Ohm") (Props (_SXDesignName "CRESCENT_CITY_195_20150128_Q")) (Terms ("CRESCENT_CITY_195_20150128_Q.X42000Y23000L30RATS" "1") ("CRESCENT_CITY_195_20150128_Q.X42000Y26500L30LRATS" "2"))) ("CRESCENT_CITY_195_20150128_Q.T@@RATS@@EU77.16@@R2079.1" TLine (xy (5506 4201)) (mirror x) (refDes "TL5") (Props (_SXDesignName "CRESCENT_CITY_195_20150128_Q") (impedance "48.412 ohm") length("116.37 MIL") (propDelay "0.0209 ns") (traceCount "1") (traceGeometry "Microstrip") (velocity "5567.95 mil/ns")) (Terms ("CRESCENT_CITY_195_20150128_Q.Xn1550Y503013L2LRATS" "1") ("CRESCENT_CITY_195_20150128_Q.Xn9900Y506300L2LRATS" "2"))) ("CRESCENT_CITY_195_20150128_Q.@@R2079.1.2" Resistor (xy (5491 4201)) (mirror x) (refDes "R1B10") (value "2.2e-007 Ohm") (Props (_SXDesignName "CRESCENT_CITY_195_20150128_Q")) (Terms ("CRESCENT_CITY_195_20150128_Q.Xn9900Y506300L2LRATS" "1") ("CRESCENT_CITY_195_20150128_Q.Xn13400Y506300L2LRATS" "2"))) ("CRESCENT_CITY_195_20150128_Q.T@@RATS@@R2058.2@@R2063.2" TLine (xy (5479 4229)) (mirror x) (refDes "TL6") (Props (_SXDesignName "CRESCENT_CITY_195_20150128_Q") (impedance "48.412 ohm") (propDelay "1.79607e-006 ns") (traceCount "1") (traceGeometry "Microstrip")) (Terms ("CRESCENT_CITY_195_20150128_Q.X42000Y26500L2LRATS" "1") ("CRESCENT_CITY_195_20150128_Q.X42000Y26500L30LRATS" "2"))) ("CRESCENT_CITY_195_20150128_Q.T@@RATS@@R1451.2@@R1282.2" TLine (xy (5488 4215)) (mirror x) (refDes "TL7") (Props (_SXDesignName "CRESCENT_CITY_195_20150128_Q") (impedance "48.412 ohm") (propDelay "1.79607e-006 ns") (traceCount "1") (traceGeometry "Microstrip")) (Terms ("CRESCENT_CITY_195_20150128_Q.X151142Y416200L2LRATS" "1") ("CRESCENT_CITY_195_20150128_Q.X151142Y416200L30LRATS" "2"))) ("CRESCENT_CITY_195_20150128_Q.@@R1282.1.2" Resistor (xy (5473 4215)) (refDes "R9N2") (value "100 Ohm") (Props (_SXDesignName "CRESCENT_CITY_195_20150128_Q")) (Terms ("CRESCENT_CITY_195_20150128_Q.X154642Y416200L30RATS" "1") ("CRESCENT_CITY_195_20150128_Q.X151142Y416200L30LRATS" "2"))) ("CRESCENT_CITY_195_20150128_Q.@@R2084.1_SOURCE" Source (xy (5466 4208)) (refDes "PVCCIO_CPU1_2") (value "1 V") (Props (_SXDesignName "CRESCENT_CITY_195_20150128_Q")) (Terms ("CRESCENT_CITY_195_20150128_Q.Xn9900Y506300L30RATS" "1"))) ("CRESCENT_CITY_195_20150128_Q.@@R2063.1_SOURCE" Source (xy (5457 4229)) (refDes "PVCCIO_CPU1") (value "1 V") (Props (_SXDesignName "CRESCENT_CITY_195_20150128_Q")) (Terms ("CRESCENT_CITY_195_20150128_Q.X42000Y23000L30RATS" "1"))) ("CRESCENT_CITY_195_20150128_Q.@@R1451.1.2" Resistor (xy (5497 4222)) (mirror x) (refDes "R1C2") (value "2.2e-007 Ohm") (Props (_SXDesignName "CRESCENT_CITY_195_20150128_Q")) (Terms ("CRESCENT_CITY_195_20150128_Q.X154642Y416200L2LRATS" "1") ("CRESCENT_CITY_195_20150128_Q.X151142Y416200L2LRATS" "2"))) ("CRESCENT_CITY_195_20150128_Q.T@@RATS@@R1451.2@@R2058.2" TLine (xy (5482 4222)) (mirror x) (refDes "TL8") (Props (_SXDesignName "CRESCENT_CITY_195_20150128_Q") (impedance "48.412 ohm") length("4988.43 MIL") (propDelay "0.89595 ns") (traceCount "1") (traceGeometry "Microstrip") (velocity "5567.76 mil/ns")) (Terms ("CRESCENT_CITY_195_20150128_Q.X151142Y416200L2LRATS" "1") ("CRESCENT_CITY_195_20150128_Q.X42000Y26500L2LRATS" "2")))) (Nodes ("CRESCENT_CITY_195_20150128_Q.X42000Y26500L30LRATS" (terms "CRESCENT_CITY_195_20150128_Q.T@@RATS@@R2058.2@@R2063.2.2" "CRESCENT_CITY_195_20150128_Q.@@R2063.1.2.2")) ("CRESCENT_CITY_195_20150128_Q.Xn1550Y503013L2LRATS" (terms "CRESCENT_CITY_195_20150128_Q.T@@RATS@@EU77.16@@R2079.1.1" "CRESCENT_CITY_195_20150128_Q.@@EU77.16.1")) ("CRESCENT_CITY_195_20150128_Q.X151142Y416200L2LRATS" (terms "CRESCENT_CITY_195_20150128_Q.T@@RATS@@R1451.2@@R2058.2.1" "CRESCENT_CITY_195_20150128_Q.@@R1451.1.2.2" "CRESCENT_CITY_195_20150128_Q.T@@RATS@@R1451.2@@R1282.2.1" "CRESCENT_CITY_195_20150128_Q.T@@RATS@@R2084.2@@R1451.2.2")) ("CRESCENT_CITY_195_20150128_Q.X42000Y23000L30RATS" (terms "CRESCENT_CITY_195_20150128_Q.@@R2063.1_SOURCE.1" "CRESCENT_CITY_195_20150128_Q.@@R2063.1.2.1")) ("CRESCENT_CITY_195_20150128_Q.Xn13400Y506300L2LRATS" (terms "CRESCENT_CITY_195_20150128_Q.@@R2079.1.2.2" "CRESCENT_CITY_195_20150128_Q.T@@RATS@@R2084.2@@R2079.2.2")) ("CRESCENT_CITY_195_20150128_Q.X42000Y26500L2LRATS" (terms "CRESCENT_CITY_195_20150128_Q.T@@RATS@@R1451.2@@R2058.2.2" "CRESCENT_CITY_195_20150128_Q.T@@RATS@@R2058.2@@R2063.2.1" "CRESCENT_CITY_195_20150128_Q.@@R2058.2.1.1")) ("CRESCENT_CITY_195_20150128_Q.X38713Y14650L2LRATS" (terms "CRESCENT_CITY_195_20150128_Q.T@@RATS@@R2058.1@@EU76.16.2" "CRESCENT_CITY_195_20150128_Q.@@EU76.16.1")) ("CRESCENT_CITY_195_20150128_Q.X151142Y416200L30LRATS" (terms "CRESCENT_CITY_195_20150128_Q.@@R1282.1.2.2" "CRESCENT_CITY_195_20150128_Q.T@@RATS@@R1451.2@@R1282.2.2")) ("CRESCENT_CITY_195_20150128_Q.Xn9900Y506300L30RATS" (terms "CRESCENT_CITY_195_20150128_Q.@@R2084.1_SOURCE.1" "CRESCENT_CITY_195_20150128_Q.@@R2084.1.2.1")) ("CRESCENT_CITY_195_20150128_Q.Xn13400Y506300L30LRATS" (terms "CRESCENT_CITY_195_20150128_Q.@@R2084.1.2.2" "CRESCENT_CITY_195_20150128_Q.T@@RATS@@R2084.2@@R1451.2.1" "CRESCENT_CITY_195_20150128_Q.T@@RATS@@R2084.2@@R2079.2.1")) ("CRESCENT_CITY_195_20150128_Q.X154642Y416200L2LRATS" (terms "CRESCENT_CITY_195_20150128_Q.@@R1451.1.2.1" "CRESCENT_CITY_195_20150128_Q.T@@RATS@@U100.DJ44@@R1451.1.2")) ("CRESCENT_CITY_195_20150128_Q.X154642Y416200L30RATS" (terms "CRESCENT_CITY_195_20150128_Q.@@R1282.1.2.1" "CRESCENT_CITY_195_20150128_Q.@@R1282.1_SOURCE.1")) ("CRESCENT_CITY_195_20150128_Q.X42000Y23000L2LRATS" (terms "CRESCENT_CITY_195_20150128_Q.T@@RATS@@R2058.1@@EU76.16.1" "CRESCENT_CITY_195_20150128_Q.@@R2058.2.1.2")) ("CRESCENT_CITY_195_20150128_Q.X408686Y367060L2LRATS" (terms "CRESCENT_CITY_195_20150128_Q.T@@RATS@@U100.DJ44@@R1451.1.1" "CRESCENT_CITY_195_20150128_Q.@@U100.DJ44.1")) ("CRESCENT_CITY_195_20150128_Q.Xn9900Y506300L2LRATS" (terms "CRESCENT_CITY_195_20150128_Q.@@R2079.1.2.1" "CRESCENT_CITY_195_20150128_Q.T@@RATS@@EU77.16@@R2079.1.2"))) (Ports) (Stimuli ("local2" (scope local) (stimType periodic) (Props (periodicFreq "5e+007") (periodicJitter "0") (periodicPattern "1"))) ("local0" (scope local) (stimType periodic) (Props (periodicFreq "5e+007") (periodicJitter "0") (periodicPattern "1"))) ("local1" (scope local) (stimType periodic) (Props (periodicFreq "5e+007") (periodicJitter "0") (periodicPattern "1"))) ("local3" (scope local) (stimType periodic) (Props (periodicFreq "5e+007") (periodicJitter "0") (periodicPattern "1"))) ("local4" (scope local) (stimType periodic) (Props (periodicFreq "5e+007") (periodicJitter "0") (periodicPattern "1"))) ("local5" (scope local) (stimType periodic) (Props (periodicFreq "5e+007") (periodicJitter "0") (periodicPattern "1")))) (Notes) (Constraints ("DELAY_RULE" ("CRESCENT_CITY_195_20150128_Q U100.DJ44" "CRESCENT_CITY_195_20150128_Q R1451.1" "LENGTH" "" "LENGTH" "0.1143") ("CRESCENT_CITY_195_20150128_Q R2058.1" "CRESCENT_CITY_195_20150128_Q EU77.16" "LENGTH" "" "LENGTH" "0.0254") ("CRESCENT_CITY_195_20150128_Q R2058.1" "CRESCENT_CITY_195_20150128_Q EU76.16" "LENGTH" "" "LENGTH" "0.0254") ("CRESCENT_CITY_195_20150128_Q R1451.2" "CRESCENT_CITY_195_20150128_Q R1282.2" "LENGTH" "" "LENGTH" "0.01016")) ("RELATIVE_PROPAGATION_DELAY" ("#SVID_CPU1_1_U100-EU76" "CRESCENT_CITY_195_20150128_Q EU76.16" "CRESCENT_CITY_195_20150128_Q U100.DJ44" "GLOBAL" "LENGTH" "0.00635" "NONE" "") ("#SVID_CPU1_1_U100-EU77" "CRESCENT_CITY_195_20150128_Q EU77.16" "CRESCENT_CITY_195_20150128_Q U100.DJ44" "GLOBAL" "LENGTH" "0.00635" "NONE" ""))) (MeasurementSets ("EMI" ("EMIStatus" status("on")) ("PeakEmission" status("on")) ("PeakFrequency" status("on")) ("PulseFreq" status("on")) ("RiseTime" status("on")) ("VoltageSwing" status("on"))) ("Reflection" ("BufferDelayFall" status("off")) ("BufferDelayRise" status("off")) ("EyeHeight" status("off")) ("EyeJitter" status("off")) ("EyeWidth" status("off")) ("FirstIncidentFall" status("off")) ("FirstIncidentRise" status("off")) ("Glitch" status("on")) ("GlitchFall" status("off")) ("GlitchRise" status("off")) ("Monotonic" status("on")) ("MonotonicFall" status("off")) ("MonotonicRise" status("off")) ("NoiseMargin" status("on")) ("NoiseMarginHigh" status("off")) ("NoiseMarginLow" status("off")) ("OvershootHigh" status("on")) ("OvershootLow" status("on")) ("PropDelay" status("on")) ("SettleDelay" status("on")) ("SettleDelayFall" status("off")) ("SettleDelayRise" status("off")) ("SwitchDelay" status("on")) ("SwitchDelayFall" status("off")) ("SwitchDelayRise" status("off"))) ("Crosstalk" ("Crosstalk" status("on"))) ("Custom")) (VectorSets) (Props (XnetName "SVID_DIO1_CPU1") (allDrivers "active") (customSimType "Reflection") (ftsMode ("Typ")) (rcvrSelect "all") (tlineDelayMode "time") (userRevision "1.0")))) (Subckts) (CrossSections ("CRESCENT_CITY_195_20150128_Q" (Props (SXDesignName "CRESCENT_CITY_195_20150128_Q")) (Layers ("" (layerType "SURFACE") (material "AIR") (thickness "0 mil") (dielectricConstant "1.000000") (lossTangent "0") (etchFactor "0.000000") (elecCondVal "0 mho/cm") (thermCondVal "0 w/cm-degC")) ("" (layerType "DIELECTRIC") (material "CONFORMAL_COAT") (thickness "0.5 mil") (dielectricConstant "3.800000") (lossTangent "0.035") (etchFactor "0.000000") (elecCondVal "0 mho/cm") (thermCondVal "0.012 w/cm-degC")) ("TOP" (layerType "CONDUCTOR") (material "COPPER") (thickness "  2.100000 mil") (width "4.00 MIL") (dielectricConstant "4.500000") (lossTangent "0") (etchFactor "70.000000") (elecCondVal "595900.000000 mho/cm") (thermCondVal "0 w/cm-degC") (signalDieConstant "3.800000") (signalLossTangent "0.035")) ("" (layerType "DIELECTRIC") (material "FR-4") (thickness "  2.670000 mil") (dielectricConstant "4.000000") (lossTangent "0.035") (etchFactor "0.000000") (elecCondVal "0 mho/cm") (thermCondVal "0.012 w/cm-degC")) ("L2_GND1" (layerType "PLANE") (material "COPPER") (isShield t) (thickness "  1.250000 mil") (dielectricConstant "4.500000") (lossTangent "0.035") (etchFactor "90.000000") (elecCondVal "595900.000000 mho/cm") (thermCondVal "0.012 w/cm-degC")) ("" (layerType "DIELECTRIC") (material "FR-4") (thickness "  9.000000 mil") (dielectricConstant "4.100000") (lossTangent "0.035") (etchFactor "0.000000") (elecCondVal "0 mho/cm") (thermCondVal "0.012 w/cm-degC")) ("L3_SIG1" (layerType "CONDUCTOR") (material "COPPER") (thickness "  1.250000 mil") (width "4.00 MIL") (dielectricConstant "4.500000") (lossTangent "0.035") (etchFactor "90.000000") (elecCondVal "595900.000000 mho/cm") (thermCondVal "0.012 w/cm-degC") (signalDieConstant "4.100000") (signalLossTangent "0.035")) ("" (layerType "DIELECTRIC") (material "FR-4") (thickness "  3.000000 mil") (dielectricConstant "4.500000") (lossTangent "0.035") (etchFactor "0.000000") (elecCondVal "0 mho/cm") (thermCondVal "0 w/cm-degC")) ("L4_GND2" (layerType "PLANE") (material "COPPER") (isShield t) (thickness "  1.250000 mil") (dielectricConstant "4.500000") (lossTangent "0.035") (etchFactor "90.000000") (elecCondVal "595900.000000 mho/cm") (thermCondVal "0 w/cm-degC")) ("" (layerType "DIELECTRIC") (material "FR-4") (thickness "  9.000000 mil") (dielectricConstant "4.000000") (lossTangent "0.035") (etchFactor "0.000000") (elecCondVal "0 mho/cm") (thermCondVal "0.012 w/cm-degC")) ("L5_SIG2" (layerType "CONDUCTOR") (material "COPPER") (thickness "  1.250000 mil") (width "4.00 MIL") (dielectricConstant "4.500000") (lossTangent "0.035") (etchFactor "90.000000") (elecCondVal "595900.000000 mho/cm") (thermCondVal "0.012 w/cm-degC") (signalDieConstant "4.000000") (signalLossTangent "0.035")) ("" (layerType "DIELECTRIC") (material "FR-4") (thickness "  3.000000 mil") (dielectricConstant "4.500000") (lossTangent "0.035") (etchFactor "0.000000") (elecCondVal "0 mho/cm") (thermCondVal "0 w/cm-degC")) ("L6_GND3" (layerType "PLANE") (material "COPPER") (isShield t) (thickness "  1.250000 mil") (dielectricConstant "4.500000") (lossTangent "0.035") (etchFactor "90.000000") (elecCondVal "595900.000000 mho/cm") (thermCondVal "0 w/cm-degC")) ("" (layerType "DIELECTRIC") (material "FR-4") (thickness "  4.500000 mil") (dielectricConstant "4.100000") (lossTangent "0.035") (etchFactor "0.000000") (elecCondVal "0 mho/cm") (thermCondVal "0.012 w/cm-degC")) ("L7_PWR1-SIG" (layerType "PLANE") (material "COPPER") (isShield t) (thickness "  2.400000 mil") (dielectricConstant "4.500000") (lossTangent "0.035") (etchFactor "90.000000") (elecCondVal "595900.000000 mho/cm") (thermCondVal "0.012 w/cm-degC")) ("" (layerType "DIELECTRIC") (material "FR-4") (thickness "  4.600000 mil") (dielectricConstant "4.000000") (lossTangent "0.035") (etchFactor "0.000000") (elecCondVal "0 mho/cm") (thermCondVal "0.012 w/cm-degC")) ("L8_PWR2-SIG" (layerType "PLANE") (material "COPPER") (isShield t) (thickness "  2.400000 mil") (dielectricConstant "4.500000") (lossTangent "0.035") (etchFactor "90.000000") (elecCondVal "595900.000000 mho/cm") (thermCondVal "0.012 w/cm-degC")) ("" (layerType "DIELECTRIC") (material "FR-4") (thickness "  8.000000 mil") (dielectricConstant "4.500000") (lossTangent "0.035") (etchFactor "0.000000") (elecCondVal "0 mho/cm") (thermCondVal "0 w/cm-degC")) ("" (layerType "DIELECTRIC") (material "FR-4") (thickness "  8.000000 mil") (dielectricConstant "4.500000") (lossTangent "0.035") (etchFactor "0.000000") (elecCondVal "0 mho/cm") (thermCondVal "0 w/cm-degC")) ("" (layerType "DIELECTRIC") (material "FR-4") (thickness "  4.500000 mil") (dielectricConstant "4.500000") (lossTangent "0.035") (etchFactor "0.000000") (elecCondVal "0 mho/cm") (thermCondVal "0 w/cm-degC")) ("L9_GND4" (layerType "PLANE") (material "COPPER") (isShield t) (thickness "  1.250000 mil") (dielectricConstant "4.500000") (lossTangent "0.035") (etchFactor "90.000000") (elecCondVal "595900.000000 mho/cm") (thermCondVal "0 w/cm-degC")) ("" (layerType "DIELECTRIC") (material "FR-4") (thickness "  3.000000 mil") (dielectricConstant "4.100000") (lossTangent "0.035") (etchFactor "0.000000") (elecCondVal "0 mho/cm") (thermCondVal "0.012 w/cm-degC")) ("L10_SIG3" (layerType "CONDUCTOR") (material "COPPER") (thickness "  1.250000 mil") (width "4.00 MIL") (dielectricConstant "4.500000") (lossTangent "0.035") (etchFactor "90.000000") (elecCondVal "595900.000000 mho/cm") (thermCondVal "0.012 w/cm-degC") (signalDieConstant "4.100000") (signalLossTangent "0.035")) ("" (layerType "DIELECTRIC") (material "FR-4") (thickness "  9.000000 mil") (dielectricConstant "4.500000") (lossTangent "0.035") (etchFactor "0.000000") (elecCondVal "0 mho/cm") (thermCondVal "0 w/cm-degC")) ("L11_GND5" (layerType "PLANE") (material "COPPER") (isShield t) (thickness "  1.250000 mil") (dielectricConstant "4.500000") (lossTangent "0.035") (etchFactor "90.000000") (elecCondVal "595900.000000 mho/cm") (thermCondVal "0 w/cm-degC")) ("" (layerType "DIELECTRIC") (material "FR-4") (thickness "  3.000000 mil") (dielectricConstant "4.500000") (lossTangent "0.035") (etchFactor "0.000000") (elecCondVal "0 mho/cm") (thermCondVal "0.012 w/cm-degC")) ("L12_SIG4" (layerType "CONDUCTOR") (material "COPPER") (thickness "  1.250000 mil") (width "4.00 MIL") (dielectricConstant "4.500000") (lossTangent "0.035") (etchFactor "90.000000") (elecCondVal "595900.000000 mho/cm") (thermCondVal "0.012 w/cm-degC") (signalDieConstant "4.500000") (signalLossTangent "0.035")) ("" (layerType "DIELECTRIC") (material "FR-4") (thickness "  9.000000 mil") (dielectricConstant "4.500000") (lossTangent "0.035") (etchFactor "0.000000") (elecCondVal "0 mho/cm") (thermCondVal "0 w/cm-degC")) ("L13_GND6" (layerType "PLANE") (material "COPPER") (isShield t) (thickness "  1.250000 mil") (dielectricConstant "4.500000") (lossTangent "0.035") (etchFactor "90.000000") (elecCondVal "595900.000000 mho/cm") (thermCondVal "0.012 w/cm-degC")) ("" (layerType "DIELECTRIC") (material "FR-4") (thickness "  2.670000 mil") (dielectricConstant "4.500000") (lossTangent "0.035") (etchFactor "0.000000") (elecCondVal "0 mho/cm") (thermCondVal "0.012 w/cm-degC")) ("BOTTOM" (layerType "CONDUCTOR") (material "COPPER") (thickness "  2.100000 mil") (width "4.00 MIL") (dielectricConstant "4.500000") (lossTangent "0") (etchFactor "70.000000") (elecCondVal "595900.000000 mho/cm") (thermCondVal "0 w/cm-degC") (signalDieConstant "3.800000") (signalLossTangent "0.035")) ("" (layerType "DIELECTRIC") (material "CONFORMAL_COAT") (thickness "0.5 mil") (dielectricConstant "3.800000") (lossTangent "0.035") (etchFactor "0.000000") (elecCondVal "0 mho/cm") (thermCondVal "0.012 w/cm-degC")) ("" (layerType "SURFACE") (material "AIR") (thickness "0 mil") (dielectricConstant "1.000000") (lossTangent "0") (etchFactor "0.000000") (elecCondVal "0 mho/cm") (thermCondVal "0 w/cm-degC"))))) (Props (DesUnits "mils 2") (LayerStack ("DIELECTRIC" "DIELECTRIC" "BOTTOM" "DIELECTRIC" "L13_GND6" "DIELECTRIC" "L12_SIG4" "DIELECTRIC" "L11_GND5" "DIELECTRIC" "L10_SIG3" "DIELECTRIC" "L9_GND4" "DIELECTRIC" "DIELECTRIC" "DIELECTRIC" "L8_PWR2-SIG" "DIELECTRIC" "L7_PWR1-SIG" "DIELECTRIC" "L6_GND3" "DIELECTRIC" "L5_SIG2" "DIELECTRIC" "L4_GND2" "DIELECTRIC" "L3_SIG1" "DIELECTRIC" "L2_GND1" "DIELECTRIC" "TOP" "DIELECTRIC" "DIELECTRIC")) (Revision "16.600")) (Params (DiffOutputPkg ((temperature "27") (bufferModelNonInverting "CDSDefaultOutput_2p5v") (bufferModelInverting "CDSDefaultOutput_2p5v") (stimuli nil) (offsets nil) (state "tristate") (cycle "1") (termMap nil) (setup "0.9e-09") (hold "0.4e-09") (rise nil) (fall nil) (threshOutputHighMin "2.375  V") (threshOutputHighTyp "2.5  V") (threshOutputHighMax "2.625  V") (threshOutputLowMin "1.275  V") (threshOutputLowTyp "1.7  V") (threshOutputLowMax "1.985  V") (mappingTagNonInverting nil) (mappingTagInverting nil) (spice nil))) (HiClampTerm ((cutoffVoltage "0.7 V") (voltage "5 V") (maxDelay "0.1 ns"))) (LowClampTerm ((cutoffVoltage "0.7 V") (voltage "0 V") (maxDelay "0.1 ns"))) (DiffOutput ((temperature "27") (bufferModelNonInverting "CDSDefaultOutput_2p5v") (bufferModelInverting "CDSDefaultOutput_2p5v") (stimuli nil) (offsets nil) (state "tristate") (cycle "1") (termMap nil) (setup "0.9e-09") (hold "0.4e-09") (rise nil) (fall nil) (threshOutputHighMin "2.375  V") (threshOutputHighTyp "2.5  V") (threshOutputHighMax "2.625  V") (threshOutputLowMin "1.275  V") (threshOutputLowTyp "1.7  V") (threshOutputLowMax "1.985  V") (mappingTagNonInverting nil) (mappingTagInverting nil) (spice nil))) (Via ((model "Unknown") (viaOutputFormat "Unknown") (viaPadstack nil) (viaTopLayer nil) (viaBottomLayer nil) (viaIsPower nil) (viaIsGround nil))) (Resistor ((resistance "50 ohm") (orientation "0"))) (RCTerm ((resistance "50 ohm") (capacitance "20 pF") (voltage "5 V") (maxDelay "0.1 ns"))) (DiffIOPkg ((temperature "27") (bufferModelNonInverting "CDSDefaultIO_2p5v") (bufferModelInverting "CDSDefaultIO_2p5v") (stimuli nil) (offsets nil) (state "tristate") (cycle "1") (termMap nil) (setup "0.9e-09") (hold "0.4e-09") (rise nil) (fall nil) (threshInputHighMin "1.7 V") (threshInputHighTyp "1.7  V") (threshInputHighMax "1.7  V") (threshInputLowMin "0.7  V") (threshInputLowTyp "0.7  V") (threshInputLowMax "0.7 ") (threshOutputHighMin "2.365  V") (threshOutputHighTyp "2.5  V") (threshOutputHighMax "2.625  V") (threshOutputLowMin "1.275  V") (threshOutputLowTyp "1.7  V") (threshOutputLowMax "1.985  V") (mappingTagNonInverting nil) (mappingTagInverting nil) (spice nil))) (Trace ((d1Thickness "10 mil") (d1Constant "4.5") (d1LossTangent "0.035") (d2Thickness "10 mil") (d2Constant "4.5") (d2LossTangent "0.035") (d3Thickness "0.0") (d3Constant "1.0") (d3LossTangent "0") length("1000 mil") (spacing "5 mil") (spacing2 "5 mil") (spacing3 "5 mil") (spacing4 "5 mil") (spacing5 "5 mil") (traceConductivity "595900 mho/cm") (traceGeometry "microstrip") (traceLayerName "") (traceThickness "0.72 mil") (traceType "single") (traceWidth "5.0 mil") (traceWidth2 "5.0 mil") (traceWidth3 "5.0 mil") (traceWidth4 "5.0 mil") (traceWidth5 "5.0 mil") (traceWidth6 "5.0 mil") (offset "0 mil") (traceCount "1") (impedance nil))) (TheveninTerm ((resistanceUp "180 ohm") (resistanceDown "270 ohm") (voltageUp "5 V") (voltageDown "0 V") (maxDelay "0.1 ns"))) (DiffIO ((temperature "27") (bufferModelNonInverting "CDSDefaultIO_2p5v") (bufferModelInverting "CDSDefaultIO_2p5v") (stimuli nil) (offsets nil) (state "tristate") (cycle "1") (termMap nil) (setup "0.9e-09") (hold "0.4e-09") (rise nil) (fall nil) (threshInputHighMin "1.7 V") (threshInputHighTyp "1.7  V") (threshInputHighMax "1.7  V") (threshInputLowMin "0.7  V") (threshInputLowTyp "0.7  V") (threshInputLowMax "0.7 ") (threshOutputHighMin "2.365  V") (threshOutputHighTyp "2.5  V") (threshOutputHighMax "2.625  V") (threshOutputLowMin "1.275  V") (threshOutputLowTyp "1.7  V") (threshOutputLowMax "1.985  V") (mappingTagNonInverting nil) (mappingTagInverting nil) (spice nil))) (ShuntTerm ((resistance "50 ohm") (voltage "5 V") (maxDelay "0.1 ns"))) (Inductor ((inductance "5 nH") (orientation "0"))) (Capacitor ((capacitance "10 pF") (orientation "0"))) (RLGC (length("1000 mil"))) (Source ((voltage "5 V"))) (DiffInput ((temperature "27") (bufferModelNonInverting "CDSDefaultInput_2p5v") (bufferModelInverting "CDSDefaultInput_2p5v") (threshInputHighMin "1.7 V") (threshInputHighTyp "1.7  V") (threshInputHighMax "1.7  V") (threshInputLowMin "0.7  V") (threshInputLowTyp "0.7  V") (threshInputLowMax "0.7  V") (mappingTagNonInverting nil) (mappingTagInverting nil) (cycle "1"))) (Cable (length("1 m"))) (CPWSL ((d1Thickness "10 mil") (d1Constant "4.5") (d1LossTangent "0.035") (d2Thickness "0.72 mil") (d2Constant "4.5") (d2LossTangent "0.035") (d3Thickness "10 mil") (d3Constant "4.5") (d3LossTangent "0.035") length("1000 mil") (spacing "5 mil") (spacing2 "5 mil") (spacing3 "5 mil") (spacing4 "5 mil") (spacing5 "5 mil") (traceConductivity "595900 mho/cm") (traceGeometry "cpwms") (traceLayerName "") (traceThickness "0.72 mil") (traceType "single") (traceWidth "5.0 mil") (traceWidth2 "5.0 mil") (traceWidth3 "5.0 mil") (traceWidth4 "5.0 mil") (traceWidth5 "5.0 mil") (traceWidth6 "5.0 mil") (offset "0 mil") (traceCount "1") (impedance nil))) (ESpiceDevice nil) (CPWMS ((d1Thickness "10 mil") (d1Constant "4.5") (d1LossTangent "0.035") (d2Thickness "0.72 mil") (d2Constant "4.5") (d2LossTangent "0.035") (d3Thickness "0.0") (d3Constant "1") (d3LossTangent "0") length("1000 mil") (spacing "5 mil") (spacing2 "5 mil") (spacing3 "5 mil") (spacing4 "5 mil") (spacing5 "5 mil") (traceConductivity "595900 mho/cm") (traceGeometry "cpwms") (traceLayerName "") (traceThickness "0.72 mil") (traceType "single") (traceWidth "5.0 mil") (traceWidth2 "5.0 mil") (traceWidth3 "5.0 mil") (traceWidth4 "5.0 mil") (traceWidth5 "5.0 mil") (traceWidth6 "5.0 mil") (offset "0 mil") (traceCount "1") (impedance nil))) (Diode ((cutoffVoltage "0.7 V"))) (CPW ((d1Thickness "10 mil") (d1Constant "4.5") (d1LossTangent "0.035") (d2Thickness "0.72 mil") (d2Constant "1") (d2LossTangent "0") (d3Thickness "0.0") (d3Constant "1") (d3LossTangent "0") length("1000 mil") (spacing "5 mil") (spacing2 "5 mil") (spacing3 "5 mil") (spacing4 "5 mil") (spacing5 "5 mil") (traceConductivity "595900 mho/cm") (traceGeometry "cpwms") (traceLayerName "") (traceThickness "0.72 mil") (traceType "single") (traceWidth "5.0 mil") (traceWidth2 "5.0 mil") (traceWidth3 "5.0 mil") (traceWidth4 "5.0 mil") (traceWidth5 "5.0 mil") (traceWidth6 "5.0 mil") (offset "0 mil") (traceCount "1") (impedance nil))) (DualClampTerm ((cutoffVoltageUp "0.7 V") (cutoffVoltageDown "0.7 V") (voltageUp "5 V") (voltageDown "0 V") (maxDelay "0.1 ns"))) (IbisOutputPkg ((temperature "27") (bufferModel "CDSDefaultOutput_2p5v") (stimuli nil) (offsets nil) (state "tristate") (cycle "1") (termMap nil) (setup "2.0e-09") (hold "1.0e-09") (rise nil) (fall nil) (macroType nil) (voltage nil) (spice nil) (LEFDEFPinName nil) (LEFDEFPinType nil) (mappingTag nil))) (IbisIO_OpenPullDown ((temperature "27") (bufferModel "CDSDefaultIO_2p5v") (stimuli nil) (offsets nil) (state "tristate") (cycle "1") (termMap nil) (setup "2.0e-09") (hold "1.0e-09") (rise nil) (fall nil) (macroType nil) (voltage nil) (spice nil) (LEFDEFPinName nil) (LEFDEFPinType nil) (mappingTag nil))) (IbisInputPkg ((temperature "27") (bufferModel "CDSDefaultInput_2p5v") (cycle "1") (LEFDEFPinName nil) (LEFDEFPinType nil) (mappingTag nil))) (IbisIOMacro ((temperature "27") (bufferModel "CDSDefaultIO_2p5v") (stimuli nil) (offsets nil) (state "tristate") (cycle "1") (termMap nil) (setup "2.0e-09") (hold "1.0e-09") (rise nil) (fall nil) (macroType nil) (voltage nil) (spice nil) (LEFDEFPinName nil) (LEFDEFPinType nil) (mappingTag nil))) (IbisIO_OpenPullUp ((temperature "27") (bufferModel "CDSDefaultIO_2p5v") (stimuli nil) (offsets nil) (state "tristate") (cycle "1") (termMap nil) (setup "2.0e-09") (hold "1.0e-09") (rise nil) (fall nil) (macroType nil) (voltage nil) (spice nil) (LEFDEFPinName nil) (LEFDEFPinType nil) (mappingTag nil))) (IbisIOPkg ((temperature "27") (bufferModel "CDSDefaultIO_2p5v") (stimuli nil) (offsets nil) (state "tristate") (cycle "1") (termMap nil) (setup "2.0e-09") (hold "1.0e-09") (rise nil) (fall nil) (macroType nil) (voltage nil) (spice nil) (LEFDEFPinName nil) (LEFDEFPinType nil) (mappingTag nil))) (clocked ((clockRise "1e-09") (clockFall "1e-09") (clockFreq "100e6") (clockInitState "0") (clockDutyCycle "0.5") (clockJitter "0"))) (periodic ((periodicFreq "100e6") (periodicPattern "10") (periodicJitter "0"))) (IbisIO ((temperature "27") (bufferModel "CDSDefaultIO_2p5v") (stimuli nil) (offsets nil) (state "tristate") (cycle "1") (termMap nil) (setup "2.0e-09") (hold "1.0e-09") (rise nil) (fall nil) (macroType nil) (voltage nil) (spice nil) (LEFDEFPinName nil) (LEFDEFPinType nil) (mappingTag nil))) (async ((asyncTimePoints "") (asyncInitState "1"))) (IbisOutput ((temperature "27") (bufferModel "CDSDefaultOutput_2p5v") (stimuli nil) (offsets nil) (state "tristate") (cycle "1") (termMap nil) (setup "2.0e-09") (hold "1.0e-09") (rise nil) (fall nil) (macroType nil) (voltage nil) (spice nil) (LEFDEFPinName nil) (LEFDEFPinType nil) (mappingTag nil))) (TLine ((diffImpedance "100ohm") (diffVelocity "1.4142e+08M/s") (impedance "60ohm") length("2800 mil") (propDelay "0.5 ns") (velocity "5600 mil/ns") (traceCount "1") (traceGeometry "Microstrip") (impedanceMin nil) (impedanceMax nil) (lengthMin nil) (lengthMax nil) (propDelayMin nil) (propDelayMax nil) (impedanceSweepCount nil) (propDelaySweepCount nil) (velocitySweepCount nil) (lengthSweepCount nil) (matchSetName nil))) (CurrentProbe nil) (IbisInput ((temperature "27") (bufferModel "CDSDefaultInput_2p5v") (cycle "1") (LEFDEFPinName nil) (LEFDEFPinType nil) (mappingTag nil))) (SeriesTerm ((resistance "22 ohm") (maxDelay "0.1 ns"))) (Connector nil) (sync ((syncFreq "100e6") (syncInitState "1") (syncPattern "10") (syncEdgeSwitch "rise"))) (IbisOutput_OpenPullUp ((temperature "27") (bufferModel "CDSDefaultOutput_2p5v") (stimuli nil) (offsets nil) (state "tristate") (cycle "1") (termMap nil) (setup "2.0e-09") (hold "1.0e-09") (rise nil) (fall nil) (macroType nil) (voltage nil) (spice nil) (LEFDEFPinName nil) (LEFDEFPinType nil) (mappingTag nil))) (DiffInputPkg ((temperature "27") (bufferModelNonInverting "CDSDefaultInput_2p5v") (bufferModelInverting "CDSDefaultInput_2p5v") (threshInputHighMin "1.7 V") (threshInputHighTyp "1.7  V") (threshInputHighMax "1.7  V") (threshInputLowMin "0.7  V") (threshInputLowTyp "0.7  V") (threshInputLowMax "0.7  V") (mappingTagNonInverting nil) (mappingTagInverting nil) (cycle "1"))) (idlCircuit ((allDrivers "active") (ftsMode '("Typ")) (rcvrSelect "all") (simMode "Reflection") (tlineDelayMode "time") (userRevision "1.0") (autoSolve "On")))))
				)
				( objectStatus "CLS_SVID" )
			)
			( electricalCSet "@baseboard_fab2_lib.baseboard_fab2(sch_1):\SVID_CLK0_CPU1\"
				( groupRef "SVID_CLK0_CPU1:#SVID_CPU0_1_U100-EU111" )
				( groupRef "SVID_CLK0_CPU1:#SVID_CPU0_1_U100-EU47" )
				( pinPairRef "SVID_CLK0_CPU1:U2D1.DC44:EU4D5.15" )
				( pinPairRef "SVID_CLK0_CPU1:U2D1.DC44:EU1C2.17" )
				( pinPairRef "SVID_CLK0_CPU1:U2D1.DC44:R3B5.1" )
				( pinPairRef "SVID_CLK0_CPU1:R3B5.2:R1D9.1" )
				( pinPairRef "SVID_CLK0_CPU1:R1D9.1:R9P2.2" )
				( pinPairRef "SVID_CLK0_CPU1:EU4D5.15:R4D51.2" )
				( pinPairRef "SVID_CLK0_CPU1:EU1C2.17:R1D9.2" )
				( attribute "TOPOLOGY_TEMPLATE_REVISION" "1.0"
					( Origin gBackEnd )
				)
				( topologyData 30865
(SKIDL (Circuits ("MAIN" (Parts ("CRESCENT_CITY_195_20150128_Q.@@J128.A20" IbisIOPkg (xy (5539 4205)) (refDes "J4B2") (model "Unknown") (Props (_SXDesignName "CRESCENT_CITY_195_20150128_Q") (brdx "7431 MIL") (brdy "4550 MIL") (bufferModel "CDSDefaultIO_2p5v") (cycle "1") (hold "1.0e-09") (mappingTag "") (offsets ("4" "0") ("5" "0")) (setup "2.0e-09") (state "tristate") (stimuli ("4" "local36") ("5" "local37")) (temperature "27") (termMap ("4" "Data") ("5" "Enable"))) (Terms ("CRESCENT_CITY_195_20150128_Q.X743100Y455000L2LRATS" "A20"))) ("CRESCENT_CITY_195_20150128_Q.@@EU111.15" IbisInputPkg (xy (5563 4221)) (refDes "EU4D5") (model "Unknown") (Props (_SXDesignName "CRESCENT_CITY_195_20150128_Q") (brdx "6564.5 MIL") (brdy "2637.87 MIL") (bufferModel "CDSDefaultInput_2p5v") (mappingTag "") (temperature "27")) (Terms ("CRESCENT_CITY_195_20150128_Q.X656450Y263787L2LRATS" "15"))) ("CRESCENT_CITY_195_20150128_Q.@@U100.DC44" IbisOutputPkg (xy (5498 4235)) (refDes "U2D1") (model "Unknown") (Props (_SXDesignName "CRESCENT_CITY_195_20150128_Q") (brdx "4086.86 MIL") (brdy "3553.6 MIL") (bufferModel "CDSDefaultOutput_2p5v") (cycle "1") (hold "1.0e-09") (mappingTag "") (offsets ("4" "0")) (setup "2.0e-09") (state "tristate") (stimuli ("4" "local38")) (temperature "27") (termMap ("4" "Data"))) (Terms ("CRESCENT_CITY_195_20150128_Q.X408686Y355360L2LRATS" "DC44"))) ("CRESCENT_CITY_195_20150128_Q.@@EU47.17" IbisInputPkg (xy (5563 4235)) (refDes "EU1C2") (model "Unknown") (Props (_SXDesignName "CRESCENT_CITY_195_20150128_Q") (brdx "670 MIL") (brdy "3659.62 MIL") (bufferModel "CDSDefaultInput_2p5v") (mappingTag "") (temperature "27")) (Terms ("CRESCENT_CITY_195_20150128_Q.X67000Y365962L2LRATS" "17"))) ("CRESCENT_CITY_195_20150128_Q.T@@RATS@@EU111.15@@R657.2" TLine (xy (5549 4221)) (mirror x) (refDes "TL42") (Props (_SXDesignName "CRESCENT_CITY_195_20150128_Q") (impedance "48.412 ohm") length("151.63 MIL") (propDelay "0.02723 ns") (traceCount "1") (traceGeometry "Microstrip") (velocity "5568.5 mil/ns")) (Terms ("CRESCENT_CITY_195_20150128_Q.X656450Y263787L2LRATS" "1") ("CRESCENT_CITY_195_20150128_Q.X649500Y272000L2LRATS" "2"))) ("CRESCENT_CITY_195_20150128_Q.T@@RATS@@J128.A20@@R1454.2" TLine (xy (5524 4200)) (mirror x) (refDes "TL43") (Props (_SXDesignName "CRESCENT_CITY_195_20150128_Q") (impedance "48.412 ohm") length("1378.00 MIL") (propDelay "0.2475 ns") (traceCount "1") (traceGeometry "Microstrip") (velocity "5567.68 mil/ns")) (Terms ("CRESCENT_CITY_195_20150128_Q.X743100Y455000L2LRATS" "1") ("CRESCENT_CITY_195_20150128_Q.X616300Y466000L2LRATS" "2"))) ("CRESCENT_CITY_195_20150128_Q.@@R1394.1.2" Resistor (xy (5525 4228)) (refDes "R9P2") (value "110 Ohm") (Props (_SXDesignName "CRESCENT_CITY_195_20150128_Q")) (Terms ("CRESCENT_CITY_195_20150128_Q.X57000Y375500L30RATS" "1") ("CRESCENT_CITY_195_20150128_Q.X53500Y375500L30LRATS" "2"))) ("CRESCENT_CITY_195_20150128_Q.@@R2849.1.2" Resistor (xy (5525 4214)) (refDes "R6P33") (value "1 Ohm") (Props (_SXDesignName "CRESCENT_CITY_195_20150128_Q")) (Terms ("CRESCENT_CITY_195_20150128_Q.X649500Y272000L30RATS" "1") ("CRESCENT_CITY_195_20150128_Q.X646000Y272000L30LRATS" "2"))) ("CRESCENT_CITY_195_20150128_Q.T@@RATS@@U100.DC44@@R1454.1" TLine (xy (5506 4235)) (refDes "TL44") (Props (_SXDesignName "CRESCENT_CITY_195_20150128_Q") (impedance "49.728 ohm") length("3147.54 MIL") (propDelay "0.56532 ns") (traceCount "1") (traceGeometry "Microstrip") (velocity "5567.72 mil/ns")) (Terms ("CRESCENT_CITY_195_20150128_Q.X408686Y355360L2LRATS" "1") ("CRESCENT_CITY_195_20150128_Q.X612800Y466000L2LRATS" "2"))) ("CRESCENT_CITY_195_20150128_Q.T@@RATS@@R1454.2@@R657.1" TLine (xy (5524 4221)) (refDes "TL45") (Props (_SXDesignName "CRESCENT_CITY_195_20150128_Q") (impedance "48.412 ohm") length("2237.00 MIL") (propDelay "0.40178 ns") (traceCount "1") (traceGeometry "Microstrip") (velocity "5567.72 mil/ns")) (Terms ("CRESCENT_CITY_195_20150128_Q.X616300Y466000L2LRATS" "1") ("CRESCENT_CITY_195_20150128_Q.X646000Y272000L2LRATS" "2"))) ("CRESCENT_CITY_195_20150128_Q.T@@RATS@@R1454.2@@R1413.1" TLine (xy (5524 4235)) (refDes "TL46") (Props (_SXDesignName "CRESCENT_CITY_195_20150128_Q") (impedance "48.412 ohm") length("6532.99 MIL") (propDelay "1.17337 ns") (traceCount "1") (traceGeometry "Microstrip") (velocity "5567.72 mil/ns")) (Terms ("CRESCENT_CITY_195_20150128_Q.X616300Y466000L2LRATS" "1") ("CRESCENT_CITY_195_20150128_Q.X53500Y375500L2LRATS" "2"))) ("CRESCENT_CITY_195_20150128_Q.T@@RATS@@R657.1@@R2849.2" TLine (xy (5540 4214)) (mirror x) (refDes "TL47") (Props (_SXDesignName "CRESCENT_CITY_195_20150128_Q") (impedance "48.412 ohm") (propDelay "1.79607e-006 ns") (traceCount "1") (traceGeometry "Microstrip")) (Terms ("CRESCENT_CITY_195_20150128_Q.X646000Y272000L2LRATS" "1") ("CRESCENT_CITY_195_20150128_Q.X646000Y272000L30LRATS" "2"))) ("CRESCENT_CITY_195_20150128_Q.T@@RATS@@R1413.1@@R1394.2" TLine (xy (5540 4228)) (mirror x) (refDes "TL48") (Props (_SXDesignName "CRESCENT_CITY_195_20150128_Q") (impedance "48.412 ohm") (propDelay "1.79607e-006 ns") (traceCount "1") (traceGeometry "Microstrip")) (Terms ("CRESCENT_CITY_195_20150128_Q.X53500Y375500L2LRATS" "1") ("CRESCENT_CITY_195_20150128_Q.X53500Y375500L30LRATS" "2"))) ("CRESCENT_CITY_195_20150128_Q.@@R1454.1.2" Resistor (xy (5515 4235)) (refDes "R3B5") (value "2.2e-007 Ohm") (Props (_SXDesignName "CRESCENT_CITY_195_20150128_Q")) (Terms ("CRESCENT_CITY_195_20150128_Q.X612800Y466000L2LRATS" "1") ("CRESCENT_CITY_195_20150128_Q.X616300Y466000L2LRATS" "2"))) ("CRESCENT_CITY_195_20150128_Q.@@R1394.1_SOURCE" Source (xy (5518 4228)) (refDes "PVCCIO_CPU1_1") (value "1 V") (Props (_SXDesignName "CRESCENT_CITY_195_20150128_Q")) (Terms ("CRESCENT_CITY_195_20150128_Q.X57000Y375500L30RATS" "1"))) ("CRESCENT_CITY_195_20150128_Q.@@R2849.1_SOURCE" Source (xy (5518 4214)) (refDes "PVCCIO_CPU1") (value "1 V") (Props (_SXDesignName "CRESCENT_CITY_195_20150128_Q")) (Terms ("CRESCENT_CITY_195_20150128_Q.X649500Y272000L30RATS" "1"))) ("CRESCENT_CITY_195_20150128_Q.@@R657.2.1" Resistor (xy (5534 4221)) (mirror x) (refDes "R4D51") (value "150 Ohm") (Props (_SXDesignName "CRESCENT_CITY_195_20150128_Q")) (Terms ("CRESCENT_CITY_195_20150128_Q.X649500Y272000L2LRATS" "2") ("CRESCENT_CITY_195_20150128_Q.X646000Y272000L2LRATS" "1"))) ("CRESCENT_CITY_195_20150128_Q.T@@RATS@@EU47.17@@R1413.2" TLine (xy (5549 4235)) (mirror x) (refDes "TL49") (Props (_SXDesignName "CRESCENT_CITY_195_20150128_Q") (impedance "48.412 ohm") length("195.38 MIL") (propDelay "0.03509 ns") (traceCount "1") (traceGeometry "Microstrip") (velocity "5567.95 mil/ns")) (Terms ("CRESCENT_CITY_195_20150128_Q.X67000Y365962L2LRATS" "1") ("CRESCENT_CITY_195_20150128_Q.X57000Y375500L2LRATS" "2"))) ("CRESCENT_CITY_195_20150128_Q.@@R1413.2.1" Resistor (xy (5534 4235)) (mirror x) (refDes "R1D9") (value "150 Ohm") (Props (_SXDesignName "CRESCENT_CITY_195_20150128_Q")) (Terms ("CRESCENT_CITY_195_20150128_Q.X57000Y375500L2LRATS" "2") ("CRESCENT_CITY_195_20150128_Q.X53500Y375500L2LRATS" "1")))) (Nodes ("CRESCENT_CITY_195_20150128_Q.X656450Y263787L2LRATS" (terms "CRESCENT_CITY_195_20150128_Q.T@@RATS@@EU111.15@@R657.2.1" "CRESCENT_CITY_195_20150128_Q.@@EU111.15.1")) ("CRESCENT_CITY_195_20150128_Q.X408686Y355360L2LRATS" (terms "CRESCENT_CITY_195_20150128_Q.T@@RATS@@U100.DC44@@R1454.1.1" "CRESCENT_CITY_195_20150128_Q.@@U100.DC44.1")) ("CRESCENT_CITY_195_20150128_Q.X67000Y365962L2LRATS" (terms "CRESCENT_CITY_195_20150128_Q.T@@RATS@@EU47.17@@R1413.2.1" "CRESCENT_CITY_195_20150128_Q.@@EU47.17.1")) ("CRESCENT_CITY_195_20150128_Q.X57000Y375500L30RATS" (terms "CRESCENT_CITY_195_20150128_Q.@@R1394.1_SOURCE.1" "CRESCENT_CITY_195_20150128_Q.@@R1394.1.2.1")) ("CRESCENT_CITY_195_20150128_Q.X616300Y466000L2LRATS" (terms "CRESCENT_CITY_195_20150128_Q.@@R1454.1.2.2" "CRESCENT_CITY_195_20150128_Q.T@@RATS@@R1454.2@@R1413.1.1" "CRESCENT_CITY_195_20150128_Q.T@@RATS@@R1454.2@@R657.1.1" "CRESCENT_CITY_195_20150128_Q.T@@RATS@@J128.A20@@R1454.2.2")) ("CRESCENT_CITY_195_20150128_Q.X646000Y272000L2LRATS" (terms "CRESCENT_CITY_195_20150128_Q.@@R657.2.1.2" "CRESCENT_CITY_195_20150128_Q.T@@RATS@@R657.1@@R2849.2.1" "CRESCENT_CITY_195_20150128_Q.T@@RATS@@R1454.2@@R657.1.2")) ("CRESCENT_CITY_195_20150128_Q.X53500Y375500L2LRATS" (terms "CRESCENT_CITY_195_20150128_Q.@@R1413.2.1.2" "CRESCENT_CITY_195_20150128_Q.T@@RATS@@R1413.1@@R1394.2.1" "CRESCENT_CITY_195_20150128_Q.T@@RATS@@R1454.2@@R1413.1.2")) ("CRESCENT_CITY_195_20150128_Q.X649500Y272000L30RATS" (terms "CRESCENT_CITY_195_20150128_Q.@@R2849.1_SOURCE.1" "CRESCENT_CITY_195_20150128_Q.@@R2849.1.2.1")) ("CRESCENT_CITY_195_20150128_Q.X646000Y272000L30LRATS" (terms "CRESCENT_CITY_195_20150128_Q.T@@RATS@@R657.1@@R2849.2.2" "CRESCENT_CITY_195_20150128_Q.@@R2849.1.2.2")) ("CRESCENT_CITY_195_20150128_Q.X649500Y272000L2LRATS" (terms "CRESCENT_CITY_195_20150128_Q.@@R657.2.1.1" "CRESCENT_CITY_195_20150128_Q.T@@RATS@@EU111.15@@R657.2.2")) ("CRESCENT_CITY_195_20150128_Q.X612800Y466000L2LRATS" (terms "CRESCENT_CITY_195_20150128_Q.@@R1454.1.2.1" "CRESCENT_CITY_195_20150128_Q.T@@RATS@@U100.DC44@@R1454.1.2")) ("CRESCENT_CITY_195_20150128_Q.X743100Y455000L2LRATS" (terms "CRESCENT_CITY_195_20150128_Q.T@@RATS@@J128.A20@@R1454.2.1" "CRESCENT_CITY_195_20150128_Q.@@J128.A20.1")) ("CRESCENT_CITY_195_20150128_Q.X53500Y375500L30LRATS" (terms "CRESCENT_CITY_195_20150128_Q.T@@RATS@@R1413.1@@R1394.2.2" "CRESCENT_CITY_195_20150128_Q.@@R1394.1.2.2")) ("CRESCENT_CITY_195_20150128_Q.X57000Y375500L2LRATS" (terms "CRESCENT_CITY_195_20150128_Q.@@R1413.2.1.1" "CRESCENT_CITY_195_20150128_Q.T@@RATS@@EU47.17@@R1413.2.2"))) (Ports) (Stimuli ("local36" (scope local) (stimType periodic) (Props (periodicFreq "5e+007") (periodicJitter "0") (periodicPattern "1"))) ("local37" (scope local) (stimType periodic) (Props (periodicFreq "5e+007") (periodicJitter "0") (periodicPattern "1"))) ("local38" (scope local) (stimType periodic) (Props (periodicFreq "5e+007") (periodicJitter "0") (periodicPattern "1")))) (Notes) (Constraints ("DELAY_RULE" ("CRESCENT_CITY_195_20150128_Q U100.DC44" "CRESCENT_CITY_195_20150128_Q R1454.1" "LENGTH" "" "LENGTH" "0.1143") ("CRESCENT_CITY_195_20150128_Q R1454.2" "CRESCENT_CITY_195_20150128_Q R1413.1" "LENGTH" "" "LENGTH" "0.6858") ("CRESCENT_CITY_195_20150128_Q R1413.1" "CRESCENT_CITY_195_20150128_Q R1394.2" "LENGTH" "" "LENGTH" "0.00508") ("CRESCENT_CITY_195_20150128_Q EU111.15" "CRESCENT_CITY_195_20150128_Q R657.2" "LENGTH" "" "LENGTH" "0.0254") ("CRESCENT_CITY_195_20150128_Q EU47.17" "CRESCENT_CITY_195_20150128_Q R1413.2" "LENGTH" "" "LENGTH" "0.0254")) ("RELATIVE_PROPAGATION_DELAY" ("#SVID_CPU0_1_U100-EU111" "CRESCENT_CITY_195_20150128_Q U100.DC44" "CRESCENT_CITY_195_20150128_Q EU111.15" "GLOBAL" "LENGTH" "0.00635" "NONE" "") ("#SVID_CPU0_1_U100-EU47" "CRESCENT_CITY_195_20150128_Q U100.DC44" "CRESCENT_CITY_195_20150128_Q EU47.17" "GLOBAL" "LENGTH" "0.00635" "NONE" ""))) (MeasurementSets ("EMI" ("EMIStatus" status("on")) ("PeakEmission" status("on")) ("PeakFrequency" status("on")) ("PulseFreq" status("on")) ("RiseTime" status("on")) ("VoltageSwing" status("on"))) ("Reflection" ("BufferDelayFall" status("off")) ("BufferDelayRise" status("off")) ("EyeHeight" status("off")) ("EyeJitter" status("off")) ("EyeWidth" status("off")) ("FirstIncidentFall" status("off")) ("FirstIncidentRise" status("off")) ("Glitch" status("on")) ("GlitchFall" status("off")) ("GlitchRise" status("off")) ("Monotonic" status("on")) ("MonotonicFall" status("off")) ("MonotonicRise" status("off")) ("NoiseMargin" status("on")) ("NoiseMarginHigh" status("off")) ("NoiseMarginLow" status("off")) ("OvershootHigh" status("on")) ("OvershootLow" status("on")) ("PropDelay" status("on")) ("SettleDelay" status("on")) ("SettleDelayFall" status("off")) ("SettleDelayRise" status("off")) ("SwitchDelay" status("on")) ("SwitchDelayFall" status("off")) ("SwitchDelayRise" status("off"))) ("Crosstalk" ("Crosstalk" status("on"))) ("Custom")) (VectorSets) (Props (XnetName "SVID_CLK0_CPU1") (allDrivers "active") (customSimType "Reflection") (ftsMode ("Typ")) (rcvrSelect "all") (tlineDelayMode "time") (userRevision "1.0")))) (Subckts) (CrossSections ("CRESCENT_CITY_195_20150128_Q" (Props (SXDesignName "CRESCENT_CITY_195_20150128_Q")) (Layers ("" (layerType "SURFACE") (material "AIR") (thickness "0 mil") (dielectricConstant "1.000000") (lossTangent "0") (etchFactor "0.000000") (elecCondVal "0 mho/cm") (thermCondVal "0 w/cm-degC")) ("" (layerType "DIELECTRIC") (material "CONFORMAL_COAT") (thickness "0.5 mil") (dielectricConstant "3.800000") (lossTangent "0.035") (etchFactor "0.000000") (elecCondVal "0 mho/cm") (thermCondVal "0.012 w/cm-degC")) ("TOP" (layerType "CONDUCTOR") (material "COPPER") (thickness "  2.100000 mil") (width "4.00 MIL") (dielectricConstant "4.500000") (lossTangent "0") (etchFactor "70.000000") (elecCondVal "595900.000000 mho/cm") (thermCondVal "0 w/cm-degC") (signalDieConstant "3.800000") (signalLossTangent "0.035")) ("" (layerType "DIELECTRIC") (material "FR-4") (thickness "  2.670000 mil") (dielectricConstant "4.000000") (lossTangent "0.035") (etchFactor "0.000000") (elecCondVal "0 mho/cm") (thermCondVal "0.012 w/cm-degC")) ("L2_GND1" (layerType "PLANE") (material "COPPER") (isShield t) (thickness "  1.250000 mil") (dielectricConstant "4.500000") (lossTangent "0.035") (etchFactor "90.000000") (elecCondVal "595900.000000 mho/cm") (thermCondVal "0.012 w/cm-degC")) ("" (layerType "DIELECTRIC") (material "FR-4") (thickness "  9.000000 mil") (dielectricConstant "4.100000") (lossTangent "0.035") (etchFactor "0.000000") (elecCondVal "0 mho/cm") (thermCondVal "0.012 w/cm-degC")) ("L3_SIG1" (layerType "CONDUCTOR") (material "COPPER") (thickness "  1.250000 mil") (width "4.00 MIL") (dielectricConstant "4.500000") (lossTangent "0.035") (etchFactor "90.000000") (elecCondVal "595900.000000 mho/cm") (thermCondVal "0.012 w/cm-degC") (signalDieConstant "4.100000") (signalLossTangent "0.035")) ("" (layerType "DIELECTRIC") (material "FR-4") (thickness "  3.000000 mil") (dielectricConstant "4.500000") (lossTangent "0.035") (etchFactor "0.000000") (elecCondVal "0 mho/cm") (thermCondVal "0 w/cm-degC")) ("L4_GND2" (layerType "PLANE") (material "COPPER") (isShield t) (thickness "  1.250000 mil") (dielectricConstant "4.500000") (lossTangent "0.035") (etchFactor "90.000000") (elecCondVal "595900.000000 mho/cm") (thermCondVal "0 w/cm-degC")) ("" (layerType "DIELECTRIC") (material "FR-4") (thickness "  9.000000 mil") (dielectricConstant "4.000000") (lossTangent "0.035") (etchFactor "0.000000") (elecCondVal "0 mho/cm") (thermCondVal "0.012 w/cm-degC")) ("L5_SIG2" (layerType "CONDUCTOR") (material "COPPER") (thickness "  1.250000 mil") (width "4.00 MIL") (dielectricConstant "4.500000") (lossTangent "0.035") (etchFactor "90.000000") (elecCondVal "595900.000000 mho/cm") (thermCondVal "0.012 w/cm-degC") (signalDieConstant "4.000000") (signalLossTangent "0.035")) ("" (layerType "DIELECTRIC") (material "FR-4") (thickness "  3.000000 mil") (dielectricConstant "4.500000") (lossTangent "0.035") (etchFactor "0.000000") (elecCondVal "0 mho/cm") (thermCondVal "0 w/cm-degC")) ("L6_GND3" (layerType "PLANE") (material "COPPER") (isShield t) (thickness "  1.250000 mil") (dielectricConstant "4.500000") (lossTangent "0.035") (etchFactor "90.000000") (elecCondVal "595900.000000 mho/cm") (thermCondVal "0 w/cm-degC")) ("" (layerType "DIELECTRIC") (material "FR-4") (thickness "  4.500000 mil") (dielectricConstant "4.100000") (lossTangent "0.035") (etchFactor "0.000000") (elecCondVal "0 mho/cm") (thermCondVal "0.012 w/cm-degC")) ("L7_PWR1-SIG" (layerType "PLANE") (material "COPPER") (isShield t) (thickness "  2.400000 mil") (dielectricConstant "4.500000") (lossTangent "0.035") (etchFactor "90.000000") (elecCondVal "595900.000000 mho/cm") (thermCondVal "0.012 w/cm-degC")) ("" (layerType "DIELECTRIC") (material "FR-4") (thickness "  4.600000 mil") (dielectricConstant "4.000000") (lossTangent "0.035") (etchFactor "0.000000") (elecCondVal "0 mho/cm") (thermCondVal "0.012 w/cm-degC")) ("L8_PWR2-SIG" (layerType "PLANE") (material "COPPER") (isShield t) (thickness "  2.400000 mil") (dielectricConstant "4.500000") (lossTangent "0.035") (etchFactor "90.000000") (elecCondVal "595900.000000 mho/cm") (thermCondVal "0.012 w/cm-degC")) ("" (layerType "DIELECTRIC") (material "FR-4") (thickness "  8.000000 mil") (dielectricConstant "4.500000") (lossTangent "0.035") (etchFactor "0.000000") (elecCondVal "0 mho/cm") (thermCondVal "0 w/cm-degC")) ("" (layerType "DIELECTRIC") (material "FR-4") (thickness "  8.000000 mil") (dielectricConstant "4.500000") (lossTangent "0.035") (etchFactor "0.000000") (elecCondVal "0 mho/cm") (thermCondVal "0 w/cm-degC")) ("" (layerType "DIELECTRIC") (material "FR-4") (thickness "  4.500000 mil") (dielectricConstant "4.500000") (lossTangent "0.035") (etchFactor "0.000000") (elecCondVal "0 mho/cm") (thermCondVal "0 w/cm-degC")) ("L9_GND4" (layerType "PLANE") (material "COPPER") (isShield t) (thickness "  1.250000 mil") (dielectricConstant "4.500000") (lossTangent "0.035") (etchFactor "90.000000") (elecCondVal "595900.000000 mho/cm") (thermCondVal "0 w/cm-degC")) ("" (layerType "DIELECTRIC") (material "FR-4") (thickness "  3.000000 mil") (dielectricConstant "4.100000") (lossTangent "0.035") (etchFactor "0.000000") (elecCondVal "0 mho/cm") (thermCondVal "0.012 w/cm-degC")) ("L10_SIG3" (layerType "CONDUCTOR") (material "COPPER") (thickness "  1.250000 mil") (width "4.00 MIL") (dielectricConstant "4.500000") (lossTangent "0.035") (etchFactor "90.000000") (elecCondVal "595900.000000 mho/cm") (thermCondVal "0.012 w/cm-degC") (signalDieConstant "4.100000") (signalLossTangent "0.035")) ("" (layerType "DIELECTRIC") (material "FR-4") (thickness "  9.000000 mil") (dielectricConstant "4.500000") (lossTangent "0.035") (etchFactor "0.000000") (elecCondVal "0 mho/cm") (thermCondVal "0 w/cm-degC")) ("L11_GND5" (layerType "PLANE") (material "COPPER") (isShield t) (thickness "  1.250000 mil") (dielectricConstant "4.500000") (lossTangent "0.035") (etchFactor "90.000000") (elecCondVal "595900.000000 mho/cm") (thermCondVal "0 w/cm-degC")) ("" (layerType "DIELECTRIC") (material "FR-4") (thickness "  3.000000 mil") (dielectricConstant "4.500000") (lossTangent "0.035") (etchFactor "0.000000") (elecCondVal "0 mho/cm") (thermCondVal "0.012 w/cm-degC")) ("L12_SIG4" (layerType "CONDUCTOR") (material "COPPER") (thickness "  1.250000 mil") (width "4.00 MIL") (dielectricConstant "4.500000") (lossTangent "0.035") (etchFactor "90.000000") (elecCondVal "595900.000000 mho/cm") (thermCondVal "0.012 w/cm-degC") (signalDieConstant "4.500000") (signalLossTangent "0.035")) ("" (layerType "DIELECTRIC") (material "FR-4") (thickness "  9.000000 mil") (dielectricConstant "4.500000") (lossTangent "0.035") (etchFactor "0.000000") (elecCondVal "0 mho/cm") (thermCondVal "0 w/cm-degC")) ("L13_GND6" (layerType "PLANE") (material "COPPER") (isShield t) (thickness "  1.250000 mil") (dielectricConstant "4.500000") (lossTangent "0.035") (etchFactor "90.000000") (elecCondVal "595900.000000 mho/cm") (thermCondVal "0.012 w/cm-degC")) ("" (layerType "DIELECTRIC") (material "FR-4") (thickness "  2.670000 mil") (dielectricConstant "4.500000") (lossTangent "0.035") (etchFactor "0.000000") (elecCondVal "0 mho/cm") (thermCondVal "0.012 w/cm-degC")) ("BOTTOM" (layerType "CONDUCTOR") (material "COPPER") (thickness "  2.100000 mil") (width "4.00 MIL") (dielectricConstant "4.500000") (lossTangent "0") (etchFactor "70.000000") (elecCondVal "595900.000000 mho/cm") (thermCondVal "0 w/cm-degC") (signalDieConstant "3.800000") (signalLossTangent "0.035")) ("" (layerType "DIELECTRIC") (material "CONFORMAL_COAT") (thickness "0.5 mil") (dielectricConstant "3.800000") (lossTangent "0.035") (etchFactor "0.000000") (elecCondVal "0 mho/cm") (thermCondVal "0.012 w/cm-degC")) ("" (layerType "SURFACE") (material "AIR") (thickness "0 mil") (dielectricConstant "1.000000") (lossTangent "0") (etchFactor "0.000000") (elecCondVal "0 mho/cm") (thermCondVal "0 w/cm-degC"))))) (Props (DesUnits "mils 2") (LayerStack ("DIELECTRIC" "DIELECTRIC" "BOTTOM" "DIELECTRIC" "L13_GND6" "DIELECTRIC" "L12_SIG4" "DIELECTRIC" "L11_GND5" "DIELECTRIC" "L10_SIG3" "DIELECTRIC" "L9_GND4" "DIELECTRIC" "DIELECTRIC" "DIELECTRIC" "L8_PWR2-SIG" "DIELECTRIC" "L7_PWR1-SIG" "DIELECTRIC" "L6_GND3" "DIELECTRIC" "L5_SIG2" "DIELECTRIC" "L4_GND2" "DIELECTRIC" "L3_SIG1" "DIELECTRIC" "L2_GND1" "DIELECTRIC" "TOP" "DIELECTRIC" "DIELECTRIC")) (Revision "16.600")) (Params (DiffOutputPkg ((temperature "27") (bufferModelNonInverting "CDSDefaultOutput_2p5v") (bufferModelInverting "CDSDefaultOutput_2p5v") (stimuli nil) (offsets nil) (state "tristate") (cycle "1") (termMap nil) (setup "0.9e-09") (hold "0.4e-09") (rise nil) (fall nil) (threshOutputHighMin "2.375  V") (threshOutputHighTyp "2.5  V") (threshOutputHighMax "2.625  V") (threshOutputLowMin "1.275  V") (threshOutputLowTyp "1.7  V") (threshOutputLowMax "1.985  V") (mappingTagNonInverting nil) (mappingTagInverting nil) (spice nil))) (HiClampTerm ((cutoffVoltage "0.7 V") (voltage "5 V") (maxDelay "0.1 ns"))) (LowClampTerm ((cutoffVoltage "0.7 V") (voltage "0 V") (maxDelay "0.1 ns"))) (DiffOutput ((temperature "27") (bufferModelNonInverting "CDSDefaultOutput_2p5v") (bufferModelInverting "CDSDefaultOutput_2p5v") (stimuli nil) (offsets nil) (state "tristate") (cycle "1") (termMap nil) (setup "0.9e-09") (hold "0.4e-09") (rise nil) (fall nil) (threshOutputHighMin "2.375  V") (threshOutputHighTyp "2.5  V") (threshOutputHighMax "2.625  V") (threshOutputLowMin "1.275  V") (threshOutputLowTyp "1.7  V") (threshOutputLowMax "1.985  V") (mappingTagNonInverting nil) (mappingTagInverting nil) (spice nil))) (Via ((model "Unknown") (viaOutputFormat "Unknown") (viaPadstack nil) (viaTopLayer nil) (viaBottomLayer nil) (viaIsPower nil) (viaIsGround nil))) (Resistor ((resistance "50 ohm") (orientation "0"))) (RCTerm ((resistance "50 ohm") (capacitance "20 pF") (voltage "5 V") (maxDelay "0.1 ns"))) (DiffIOPkg ((temperature "27") (bufferModelNonInverting "CDSDefaultIO_2p5v") (bufferModelInverting "CDSDefaultIO_2p5v") (stimuli nil) (offsets nil) (state "tristate") (cycle "1") (termMap nil) (setup "0.9e-09") (hold "0.4e-09") (rise nil) (fall nil) (threshInputHighMin "1.7 V") (threshInputHighTyp "1.7  V") (threshInputHighMax "1.7  V") (threshInputLowMin "0.7  V") (threshInputLowTyp "0.7  V") (threshInputLowMax "0.7 ") (threshOutputHighMin "2.365  V") (threshOutputHighTyp "2.5  V") (threshOutputHighMax "2.625  V") (threshOutputLowMin "1.275  V") (threshOutputLowTyp "1.7  V") (threshOutputLowMax "1.985  V") (mappingTagNonInverting nil) (mappingTagInverting nil) (spice nil))) (Trace ((d1Thickness "10 mil") (d1Constant "4.5") (d1LossTangent "0.035") (d2Thickness "10 mil") (d2Constant "4.5") (d2LossTangent "0.035") (d3Thickness "0.0") (d3Constant "1.0") (d3LossTangent "0") length("1000 mil") (spacing "5 mil") (spacing2 "5 mil") (spacing3 "5 mil") (spacing4 "5 mil") (spacing5 "5 mil") (traceConductivity "595900 mho/cm") (traceGeometry "microstrip") (traceLayerName "") (traceThickness "0.72 mil") (traceType "single") (traceWidth "5.0 mil") (traceWidth2 "5.0 mil") (traceWidth3 "5.0 mil") (traceWidth4 "5.0 mil") (traceWidth5 "5.0 mil") (traceWidth6 "5.0 mil") (offset "0 mil") (traceCount "1") (impedance nil))) (TheveninTerm ((resistanceUp "180 ohm") (resistanceDown "270 ohm") (voltageUp "5 V") (voltageDown "0 V") (maxDelay "0.1 ns"))) (DiffIO ((temperature "27") (bufferModelNonInverting "CDSDefaultIO_2p5v") (bufferModelInverting "CDSDefaultIO_2p5v") (stimuli nil) (offsets nil) (state "tristate") (cycle "1") (termMap nil) (setup "0.9e-09") (hold "0.4e-09") (rise nil) (fall nil) (threshInputHighMin "1.7 V") (threshInputHighTyp "1.7  V") (threshInputHighMax "1.7  V") (threshInputLowMin "0.7  V") (threshInputLowTyp "0.7  V") (threshInputLowMax "0.7 ") (threshOutputHighMin "2.365  V") (threshOutputHighTyp "2.5  V") (threshOutputHighMax "2.625  V") (threshOutputLowMin "1.275  V") (threshOutputLowTyp "1.7  V") (threshOutputLowMax "1.985  V") (mappingTagNonInverting nil) (mappingTagInverting nil) (spice nil))) (ShuntTerm ((resistance "50 ohm") (voltage "5 V") (maxDelay "0.1 ns"))) (Inductor ((inductance "5 nH") (orientation "0"))) (Capacitor ((capacitance "10 pF") (orientation "0"))) (RLGC (length("1000 mil"))) (Source ((voltage "5 V"))) (DiffInput ((temperature "27") (bufferModelNonInverting "CDSDefaultInput_2p5v") (bufferModelInverting "CDSDefaultInput_2p5v") (threshInputHighMin "1.7 V") (threshInputHighTyp "1.7  V") (threshInputHighMax "1.7  V") (threshInputLowMin "0.7  V") (threshInputLowTyp "0.7  V") (threshInputLowMax "0.7  V") (mappingTagNonInverting nil) (mappingTagInverting nil) (cycle "1"))) (Cable (length("1 m"))) (CPWSL ((d1Thickness "10 mil") (d1Constant "4.5") (d1LossTangent "0.035") (d2Thickness "0.72 mil") (d2Constant "4.5") (d2LossTangent "0.035") (d3Thickness "10 mil") (d3Constant "4.5") (d3LossTangent "0.035") length("1000 mil") (spacing "5 mil") (spacing2 "5 mil") (spacing3 "5 mil") (spacing4 "5 mil") (spacing5 "5 mil") (traceConductivity "595900 mho/cm") (traceGeometry "cpwms") (traceLayerName "") (traceThickness "0.72 mil") (traceType "single") (traceWidth "5.0 mil") (traceWidth2 "5.0 mil") (traceWidth3 "5.0 mil") (traceWidth4 "5.0 mil") (traceWidth5 "5.0 mil") (traceWidth6 "5.0 mil") (offset "0 mil") (traceCount "1") (impedance nil))) (ESpiceDevice nil) (CPWMS ((d1Thickness "10 mil") (d1Constant "4.5") (d1LossTangent "0.035") (d2Thickness "0.72 mil") (d2Constant "4.5") (d2LossTangent "0.035") (d3Thickness "0.0") (d3Constant "1") (d3LossTangent "0") length("1000 mil") (spacing "5 mil") (spacing2 "5 mil") (spacing3 "5 mil") (spacing4 "5 mil") (spacing5 "5 mil") (traceConductivity "595900 mho/cm") (traceGeometry "cpwms") (traceLayerName "") (traceThickness "0.72 mil") (traceType "single") (traceWidth "5.0 mil") (traceWidth2 "5.0 mil") (traceWidth3 "5.0 mil") (traceWidth4 "5.0 mil") (traceWidth5 "5.0 mil") (traceWidth6 "5.0 mil") (offset "0 mil") (traceCount "1") (impedance nil))) (Diode ((cutoffVoltage "0.7 V"))) (CPW ((d1Thickness "10 mil") (d1Constant "4.5") (d1LossTangent "0.035") (d2Thickness "0.72 mil") (d2Constant "1") (d2LossTangent "0") (d3Thickness "0.0") (d3Constant "1") (d3LossTangent "0") length("1000 mil") (spacing "5 mil") (spacing2 "5 mil") (spacing3 "5 mil") (spacing4 "5 mil") (spacing5 "5 mil") (traceConductivity "595900 mho/cm") (traceGeometry "cpwms") (traceLayerName "") (traceThickness "0.72 mil") (traceType "single") (traceWidth "5.0 mil") (traceWidth2 "5.0 mil") (traceWidth3 "5.0 mil") (traceWidth4 "5.0 mil") (traceWidth5 "5.0 mil") (traceWidth6 "5.0 mil") (offset "0 mil") (traceCount "1") (impedance nil))) (DualClampTerm ((cutoffVoltageUp "0.7 V") (cutoffVoltageDown "0.7 V") (voltageUp "5 V") (voltageDown "0 V") (maxDelay "0.1 ns"))) (IbisOutputPkg ((temperature "27") (bufferModel "CDSDefaultOutput_2p5v") (stimuli nil) (offsets nil) (state "tristate") (cycle "1") (termMap nil) (setup "2.0e-09") (hold "1.0e-09") (rise nil) (fall nil) (macroType nil) (voltage nil) (spice nil) (LEFDEFPinName nil) (LEFDEFPinType nil) (mappingTag nil))) (IbisIO_OpenPullDown ((temperature "27") (bufferModel "CDSDefaultIO_2p5v") (stimuli nil) (offsets nil) (state "tristate") (cycle "1") (termMap nil) (setup "2.0e-09") (hold "1.0e-09") (rise nil) (fall nil) (macroType nil) (voltage nil) (spice nil) (LEFDEFPinName nil) (LEFDEFPinType nil) (mappingTag nil))) (IbisInputPkg ((temperature "27") (bufferModel "CDSDefaultInput_2p5v") (cycle "1") (LEFDEFPinName nil) (LEFDEFPinType nil) (mappingTag nil))) (IbisIOMacro ((temperature "27") (bufferModel "CDSDefaultIO_2p5v") (stimuli nil) (offsets nil) (state "tristate") (cycle "1") (termMap nil) (setup "2.0e-09") (hold "1.0e-09") (rise nil) (fall nil) (macroType nil) (voltage nil) (spice nil) (LEFDEFPinName nil) (LEFDEFPinType nil) (mappingTag nil))) (IbisIO_OpenPullUp ((temperature "27") (bufferModel "CDSDefaultIO_2p5v") (stimuli nil) (offsets nil) (state "tristate") (cycle "1") (termMap nil) (setup "2.0e-09") (hold "1.0e-09") (rise nil) (fall nil) (macroType nil) (voltage nil) (spice nil) (LEFDEFPinName nil) (LEFDEFPinType nil) (mappingTag nil))) (IbisIOPkg ((temperature "27") (bufferModel "CDSDefaultIO_2p5v") (stimuli nil) (offsets nil) (state "tristate") (cycle "1") (termMap nil) (setup "2.0e-09") (hold "1.0e-09") (rise nil) (fall nil) (macroType nil) (voltage nil) (spice nil) (LEFDEFPinName nil) (LEFDEFPinType nil) (mappingTag nil))) (clocked ((clockRise "1e-09") (clockFall "1e-09") (clockFreq "100e6") (clockInitState "0") (clockDutyCycle "0.5") (clockJitter "0"))) (periodic ((periodicFreq "100e6") (periodicPattern "10") (periodicJitter "0"))) (IbisIO ((temperature "27") (bufferModel "CDSDefaultIO_2p5v") (stimuli nil) (offsets nil) (state "tristate") (cycle "1") (termMap nil) (setup "2.0e-09") (hold "1.0e-09") (rise nil) (fall nil) (macroType nil) (voltage nil) (spice nil) (LEFDEFPinName nil) (LEFDEFPinType nil) (mappingTag nil))) (async ((asyncTimePoints "") (asyncInitState "1"))) (IbisOutput ((temperature "27") (bufferModel "CDSDefaultOutput_2p5v") (stimuli nil) (offsets nil) (state "tristate") (cycle "1") (termMap nil) (setup "2.0e-09") (hold "1.0e-09") (rise nil) (fall nil) (macroType nil) (voltage nil) (spice nil) (LEFDEFPinName nil) (LEFDEFPinType nil) (mappingTag nil))) (TLine ((diffImpedance "100ohm") (diffVelocity "1.4142e+08M/s") (impedance "60ohm") length("2800 mil") (propDelay "0.5 ns") (velocity "5600 mil/ns") (traceCount "1") (traceGeometry "Microstrip") (impedanceMin nil) (impedanceMax nil) (lengthMin nil) (lengthMax nil) (propDelayMin nil) (propDelayMax nil) (impedanceSweepCount nil) (propDelaySweepCount nil) (velocitySweepCount nil) (lengthSweepCount nil) (matchSetName nil))) (CurrentProbe nil) (IbisInput ((temperature "27") (bufferModel "CDSDefaultInput_2p5v") (cycle "1") (LEFDEFPinName nil) (LEFDEFPinType nil) (mappingTag nil))) (SeriesTerm ((resistance "22 ohm") (maxDelay "0.1 ns"))) (Connector nil) (sync ((syncFreq "100e6") (syncInitState "1") (syncPattern "10") (syncEdgeSwitch "rise"))) (IbisOutput_OpenPullUp ((temperature "27") (bufferModel "CDSDefaultOutput_2p5v") (stimuli nil) (offsets nil) (state "tristate") (cycle "1") (termMap nil) (setup "2.0e-09") (hold "1.0e-09") (rise nil) (fall nil) (macroType nil) (voltage nil) (spice nil) (LEFDEFPinName nil) (LEFDEFPinType nil) (mappingTag nil))) (DiffInputPkg ((temperature "27") (bufferModelNonInverting "CDSDefaultInput_2p5v") (bufferModelInverting "CDSDefaultInput_2p5v") (threshInputHighMin "1.7 V") (threshInputHighTyp "1.7  V") (threshInputHighMax "1.7  V") (threshInputLowMin "0.7  V") (threshInputLowTyp "0.7  V") (threshInputLowMax "0.7  V") (mappingTagNonInverting nil) (mappingTagInverting nil) (cycle "1"))) (idlCircuit ((allDrivers "active") (ftsMode '("Typ")) (rcvrSelect "all") (simMode "Reflection") (tlineDelayMode "time") (userRevision "1.0") (autoSolve "On")))))
				)
				( objectStatus "SVID_CLK0_CPU1" )
			)
			( electricalCSet "@baseboard_fab2_lib.baseboard_fab2(sch_1):\SVID_DIO0_CPU1\"
				( groupRef "SVID_DIO0_CPU1:#SVID_CPU0_1_U100-EU111" )
				( groupRef "SVID_DIO0_CPU1:#SVID_CPU0_1_U100-EU47" )
				( pinPairRef "SVID_DIO0_CPU1:EU4D5.16:U2D1.DB45" )
				( pinPairRef "SVID_DIO0_CPU1:EU1C2.18:U2D1.DB45" )
				( pinPairRef "SVID_DIO0_CPU1:U2D1.DB45:R3B3.1" )
				( pinPairRef "SVID_DIO0_CPU1:R3B3.2:R1D2.2" )
				( pinPairRef "SVID_DIO0_CPU1:R3B3.2:R3B4.1" )
				( pinPairRef "SVID_DIO0_CPU1:R1D2.2:R9P1.2" )
				( pinPairRef "SVID_DIO0_CPU1:EU4D5.16:R4D54.2" )
				( pinPairRef "SVID_DIO0_CPU1:EU1C2.18:R1D2.1" )
				( attribute "TOPOLOGY_TEMPLATE_REVISION" "1.0"
					( Origin gBackEnd )
				)
				( topologyData 33397
(SKIDL (Circuits ("MAIN" (Parts ("CRESCENT_CITY_195_20150128_Q.@@EU47.18" IbisIOPkg (xy (5532.5 4194.5)) (refDes "EU1C2") (model "Unknown") (Props (_SXDesignName "CRESCENT_CITY_195_20150128_Q") (brdx "670 MIL") (brdy "3643.87 MIL") (bufferModel "CDSDefaultIO_2p5v") (cycle "1") (hold "1.0e-09") (mappingTag "") (offsets ("4" "0") ("5" "0")) (setup "2.0e-09") (state "tristate") (stimuli ("5" "local70") ("4" "local69")) (temperature "27") (termMap ("4" "Data") ("5" "Enable"))) (Terms ("CRESCENT_CITY_195_20150128_Q.X67000Y364387L2LRATS" "18"))) ("CRESCENT_CITY_195_20150128_Q.@@U100.DB45" IbisIOPkg (xy (5576.5 4200.5)) (refDes "U2D1") (model "Unknown") (Props (_SXDesignName "CRESCENT_CITY_195_20150128_Q") (brdx "4053.06 MIL") (brdy "3534.09 MIL") (bufferModel "CDSDefaultIO_2p5v") (cycle "1") (hold "1.0e-09") (mappingTag "") (offsets ("4" "0") ("5" "0")) (setup "2.0e-09") (state "tristate") (stimuli ("5" "local72") ("4" "local71")) (temperature "27") (termMap ("4" "Data") ("5" "Enable"))) (Terms ("CRESCENT_CITY_195_20150128_Q.X405306Y353409L2LRATS" "DB45"))) ("CRESCENT_CITY_195_20150128_Q.@@EU111.16" IbisIOPkg (xy (5502 4240)) (refDes "EU4D5") (model "Unknown") (Props (_SXDesignName "CRESCENT_CITY_195_20150128_Q") (brdx "6564.5 MIL") (brdy "2622.13 MIL") (bufferModel "CDSDefaultIO_2p5v") (cycle "1") (hold "1.0e-09") (mappingTag "") (offsets ("4" "0") ("5" "0")) (setup "2.0e-09") (state "tristate") (stimuli ("5" "local74") ("4" "local73")) (temperature "27") (termMap ("4" "Data") ("5" "Enable"))) (Terms ("CRESCENT_CITY_195_20150128_Q.X656450Y262213L2LRATS" "16"))) ("CRESCENT_CITY_195_20150128_Q.@@J128.B20" IbisIOPkg (xy (5578 4227)) (refDes "J4B2") (model "Unknown") (Props (_SXDesignName "CRESCENT_CITY_195_20150128_Q") (brdx "7431 MIL") (brdy "4500 MIL") (bufferModel "CDSDefaultIO_2p5v") (cycle "1") (hold "1.0e-09") (mappingTag "") (offsets ("4" "0") ("5" "0")) (setup "2.0e-09") (state "tristate") (stimuli ("5" "local76") ("4" "local75")) (temperature "27") (termMap ("4" "Data") ("5" "Enable"))) (Terms ("CRESCENT_CITY_195_20150128_Q.X743100Y450000L2LRATS" "B20"))) ("CRESCENT_CITY_195_20150128_Q.T@@RATS@@EU47.18@@R1387.1" TLine (xy (5525.5 4190.0)) (mirror x) (refDes "TL91") (Props (_SXDesignName "CRESCENT_CITY_195_20150128_Q") (impedance "48.412 ohm") length("171.13 MIL") (propDelay "0.03074 ns") (traceCount "1") (traceGeometry "Microstrip") (velocity "5567.01 mil/ns")) (Terms ("CRESCENT_CITY_195_20150128_Q.X67000Y364387L2LRATS" "1") ("CRESCENT_CITY_195_20150128_Q.X57000Y371500L2LRATS" "2"))) ("CRESCENT_CITY_195_20150128_Q.@@R2864.1_SOURCE" Source (xy (5475 4216)) (refDes "PVCCIO_CPU1_1") (value "1 V") (Props (_SXDesignName "CRESCENT_CITY_195_20150128_Q")) (Terms ("CRESCENT_CITY_195_20150128_Q.X649500Y268500L30RATS" "1"))) ("CRESCENT_CITY_195_20150128_Q.@@R2864.1.2" Resistor (xy (5482 4216)) (refDes "R6P35") (value "100 Ohm") (Props (_SXDesignName "CRESCENT_CITY_195_20150128_Q")) (Terms ("CRESCENT_CITY_195_20150128_Q.X649500Y268500L30RATS" "1") ("CRESCENT_CITY_195_20150128_Q.X646000Y268500L30LRATS" "2"))) ("CRESCENT_CITY_195_20150128_Q.@@R2865.2.1" Resistor (xy (5488 4229)) (mirror x) (refDes "R4D54") (value "2.2e-007 Ohm") (Props (_SXDesignName "CRESCENT_CITY_195_20150128_Q")) (Terms ("CRESCENT_CITY_195_20150128_Q.X649500Y268500L2LRATS" "2") ("CRESCENT_CITY_195_20150128_Q.X646000Y268500L2LRATS" "1"))) ("CRESCENT_CITY_195_20150128_Q.T@@RATS@@U100.DB45@@R1453.1" TLine (xy (5563.0 4195.0)) (mirror x) (refDes "TL92") (Props (_SXDesignName "CRESCENT_CITY_195_20150128_Q") (impedance "49.728 ohm") length("3233.78 MIL") (propDelay "0.58081 ns") (traceCount "1") (traceGeometry "Microstrip") (velocity "5567.72 mil/ns")) (Terms ("CRESCENT_CITY_195_20150128_Q.X405306Y353409L2LRATS" "1") ("CRESCENT_CITY_195_20150128_Q.X612534Y469559L2LRATS" "2"))) ("CRESCENT_CITY_195_20150128_Q.@@R1283.2.1" Resistor (xy (5572.0 4215.0)) (refDes "R3B4") (orientation "90") (value "100 Ohm") (Props (_SXDesignName "CRESCENT_CITY_195_20150128_Q")) (Terms ("CRESCENT_CITY_195_20150128_Q.X625500Y469159L2RATS" "2") ("CRESCENT_CITY_195_20150128_Q.X622000Y469159L2LRATS" "1"))) ("CRESCENT_CITY_195_20150128_Q.T@@RATS@@R1283.1@@R2864.2" TLine (xy (5497 4222)) (mirror x) (refDes "TL93") (Props (_SXDesignName "CRESCENT_CITY_195_20150128_Q") (impedance "48.412 ohm") length("2246.59 MIL") (propDelay "0.4035 ns") (traceCount "1") (traceGeometry "Microstrip") (velocity "5567.76 mil/ns")) (Terms ("CRESCENT_CITY_195_20150128_Q.X622000Y469159L2LRATS" "1") ("CRESCENT_CITY_195_20150128_Q.X646000Y268500L30LRATS" "2"))) ("CRESCENT_CITY_195_20150128_Q.T@@RATS@@R1453.2@@R1402.2" TLine (xy (5547 4215)) (mirror x) (refDes "TL94") (Props (_SXDesignName "CRESCENT_CITY_195_20150128_Q") (impedance "48.412 ohm") length("6605.94 MIL") (propDelay "1.18647 ns") (traceCount "1") (traceGeometry "Microstrip") (velocity "5567.72 mil/ns")) (Terms ("CRESCENT_CITY_195_20150128_Q.X616034Y469559L2LRATS" "1") ("CRESCENT_CITY_195_20150128_Q.X53500Y371500L30LRATS" "2"))) ("CRESCENT_CITY_195_20150128_Q.@@R1402.1_SOURCE" Source (xy (5497 4215)) (refDes "PVCCIO_CPU1_2") (value "1 V") (Props (_SXDesignName "CRESCENT_CITY_195_20150128_Q")) (Terms ("CRESCENT_CITY_195_20150128_Q.X57000Y371500L30RATS" "1"))) ("CRESCENT_CITY_195_20150128_Q.@@R1283.2_SOURCE" Source (xy (5580.5 4215.0)) (refDes "PVCCIO_CPU1") (value "1 V") (Props (_SXDesignName "CRESCENT_CITY_195_20150128_Q")) (Terms ("CRESCENT_CITY_195_20150128_Q.X625500Y469159L2RATS" "1"))) ("CRESCENT_CITY_195_20150128_Q.T@@RATS@@EU111.16@@R2865.2" TLine (xy (5503 4229)) (mirror x) (refDes "TL95") (Props (_SXDesignName "CRESCENT_CITY_195_20150128_Q") (impedance "48.412 ohm") length("132.37 MIL") (propDelay "0.02377 ns") (traceCount "1") (traceGeometry "Microstrip") (velocity "5568.78 mil/ns")) (Terms ("CRESCENT_CITY_195_20150128_Q.X656450Y262213L2LRATS" "1") ("CRESCENT_CITY_195_20150128_Q.X649500Y268500L2LRATS" "2"))) ("CRESCENT_CITY_195_20150128_Q.T@@RATS@@R1453.2@@R1283.1" TLine (xy (5563 4215)) (refDes "TL96") (Props (_SXDesignName "CRESCENT_CITY_195_20150128_Q") (impedance "48.412 ohm") length("63.66 MIL") (propDelay "0.01143 ns") (traceCount "1") (traceGeometry "Microstrip") (velocity "5569.57 mil/ns")) (Terms ("CRESCENT_CITY_195_20150128_Q.X616034Y469559L2LRATS" "1") ("CRESCENT_CITY_195_20150128_Q.X622000Y469159L2LRATS" "2"))) ("CRESCENT_CITY_195_20150128_Q.T@@RATS@@R2864.2@@R2865.1" TLine (xy (5482 4222)) (mirror x) (refDes "TL97") (Props (_SXDesignName "CRESCENT_CITY_195_20150128_Q") (impedance "48.412 ohm") (propDelay "1.79607e-006 ns") (traceCount "1") (traceGeometry "Microstrip")) (Terms ("CRESCENT_CITY_195_20150128_Q.X646000Y268500L30LRATS" "1") ("CRESCENT_CITY_195_20150128_Q.X646000Y268500L2LRATS" "2"))) ("CRESCENT_CITY_195_20150128_Q.@@R1387.1.2" Resistor (xy (5519 4201)) (mirror x) (refDes "R1D2") (value "2.2e-007 Ohm") (Props (_SXDesignName "CRESCENT_CITY_195_20150128_Q")) (Terms ("CRESCENT_CITY_195_20150128_Q.X57000Y371500L2LRATS" "1") ("CRESCENT_CITY_195_20150128_Q.X53500Y371500L2LRATS" "2"))) ("CRESCENT_CITY_195_20150128_Q.@@R1453.1.2" Resistor (xy (5559.5 4203.5)) (mirror x) (refDes "R3B3") (orientation "270") (value "2.2e-007 Ohm") (Props (_SXDesignName "CRESCENT_CITY_195_20150128_Q")) (Terms ("CRESCENT_CITY_195_20150128_Q.X612534Y469559L2LRATS" "1") ("CRESCENT_CITY_195_20150128_Q.X616034Y469559L2LRATS" "2"))) ("CRESCENT_CITY_195_20150128_Q.T@@RATS@@R1283.1@@J128.B20" TLine (xy (5569 4222)) (refDes "TL98") (Props (_SXDesignName "CRESCENT_CITY_195_20150128_Q") (impedance "48.412 ohm") length("1402.59 MIL") (propDelay "0.25191 ns") (traceCount "1") (traceGeometry "Microstrip") (velocity "5567.83 mil/ns")) (Terms ("CRESCENT_CITY_195_20150128_Q.X622000Y469159L2LRATS" "1") ("CRESCENT_CITY_195_20150128_Q.X743100Y450000L2LRATS" "2"))) ("CRESCENT_CITY_195_20150128_Q.T@@RATS@@R1402.2@@R1387.2" TLine (xy (5510 4201)) (refDes "TL99") (Props (_SXDesignName "CRESCENT_CITY_195_20150128_Q") (impedance "48.412 ohm") (propDelay "1.79607e-006 ns") (traceCount "1") (traceGeometry "Microstrip")) (Terms ("CRESCENT_CITY_195_20150128_Q.X53500Y371500L30LRATS" "1") ("CRESCENT_CITY_195_20150128_Q.X53500Y371500L2LRATS" "2"))) ("CRESCENT_CITY_195_20150128_Q.@@R1402.1.2" Resistor (xy (5504 4215)) (refDes "R9P1") (value "100 Ohm") (Props (_SXDesignName "CRESCENT_CITY_195_20150128_Q")) (Terms ("CRESCENT_CITY_195_20150128_Q.X57000Y371500L30RATS" "1") ("CRESCENT_CITY_195_20150128_Q.X53500Y371500L30LRATS" "2")))) (Nodes ("CRESCENT_CITY_195_20150128_Q.X405306Y353409L2LRATS" (terms "CRESCENT_CITY_195_20150128_Q.T@@RATS@@U100.DB45@@R1453.1.1" "CRESCENT_CITY_195_20150128_Q.@@U100.DB45.1")) ("CRESCENT_CITY_195_20150128_Q.X57000Y371500L2LRATS" (terms "CRESCENT_CITY_195_20150128_Q.@@R1387.1.2.1" "CRESCENT_CITY_195_20150128_Q.T@@RATS@@EU47.18@@R1387.1.2")) ("CRESCENT_CITY_195_20150128_Q.X649500Y268500L30RATS" (terms "CRESCENT_CITY_195_20150128_Q.@@R2864.1.2.1" "CRESCENT_CITY_195_20150128_Q.@@R2864.1_SOURCE.1")) ("CRESCENT_CITY_195_20150128_Q.X622000Y469159L2LRATS" (terms "CRESCENT_CITY_195_20150128_Q.T@@RATS@@R1283.1@@J128.B20.1" "CRESCENT_CITY_195_20150128_Q.T@@RATS@@R1453.2@@R1283.1.2" "CRESCENT_CITY_195_20150128_Q.T@@RATS@@R1283.1@@R2864.2.1" "CRESCENT_CITY_195_20150128_Q.@@R1283.2.1.2")) ("CRESCENT_CITY_195_20150128_Q.X646000Y268500L2LRATS" (terms "CRESCENT_CITY_195_20150128_Q.T@@RATS@@R2864.2@@R2865.1.2" "CRESCENT_CITY_195_20150128_Q.@@R2865.2.1.2")) ("CRESCENT_CITY_195_20150128_Q.X53500Y371500L30LRATS" (terms "CRESCENT_CITY_195_20150128_Q.@@R1402.1.2.2" "CRESCENT_CITY_195_20150128_Q.T@@RATS@@R1402.2@@R1387.2.1" "CRESCENT_CITY_195_20150128_Q.T@@RATS@@R1453.2@@R1402.2.2")) ("CRESCENT_CITY_195_20150128_Q.X649500Y268500L2LRATS" (terms "CRESCENT_CITY_195_20150128_Q.T@@RATS@@EU111.16@@R2865.2.2" "CRESCENT_CITY_195_20150128_Q.@@R2865.2.1.1")) ("CRESCENT_CITY_195_20150128_Q.X625500Y469159L2RATS" (terms "CRESCENT_CITY_195_20150128_Q.@@R1283.2_SOURCE.1" "CRESCENT_CITY_195_20150128_Q.@@R1283.2.1.1")) ("CRESCENT_CITY_195_20150128_Q.X656450Y262213L2LRATS" (terms "CRESCENT_CITY_195_20150128_Q.T@@RATS@@EU111.16@@R2865.2.1" "CRESCENT_CITY_195_20150128_Q.@@EU111.16.1")) ("CRESCENT_CITY_195_20150128_Q.X743100Y450000L2LRATS" (terms "CRESCENT_CITY_195_20150128_Q.T@@RATS@@R1283.1@@J128.B20.2" "CRESCENT_CITY_195_20150128_Q.@@J128.B20.1")) ("CRESCENT_CITY_195_20150128_Q.X646000Y268500L30LRATS" (terms "CRESCENT_CITY_195_20150128_Q.T@@RATS@@R2864.2@@R2865.1.1" "CRESCENT_CITY_195_20150128_Q.T@@RATS@@R1283.1@@R2864.2.2" "CRESCENT_CITY_195_20150128_Q.@@R2864.1.2.2")) ("CRESCENT_CITY_195_20150128_Q.X616034Y469559L2LRATS" (terms "CRESCENT_CITY_195_20150128_Q.@@R1453.1.2.2" "CRESCENT_CITY_195_20150128_Q.T@@RATS@@R1453.2@@R1283.1.1" "CRESCENT_CITY_195_20150128_Q.T@@RATS@@R1453.2@@R1402.2.1")) ("CRESCENT_CITY_195_20150128_Q.X57000Y371500L30RATS" (terms "CRESCENT_CITY_195_20150128_Q.@@R1402.1.2.1" "CRESCENT_CITY_195_20150128_Q.@@R1402.1_SOURCE.1")) ("CRESCENT_CITY_195_20150128_Q.X612534Y469559L2LRATS" (terms "CRESCENT_CITY_195_20150128_Q.@@R1453.1.2.1" "CRESCENT_CITY_195_20150128_Q.T@@RATS@@U100.DB45@@R1453.1.2")) ("CRESCENT_CITY_195_20150128_Q.X53500Y371500L2LRATS" (terms "CRESCENT_CITY_195_20150128_Q.T@@RATS@@R1402.2@@R1387.2.2" "CRESCENT_CITY_195_20150128_Q.@@R1387.1.2.2")) ("CRESCENT_CITY_195_20150128_Q.X67000Y364387L2LRATS" (terms "CRESCENT_CITY_195_20150128_Q.T@@RATS@@EU47.18@@R1387.1.1" "CRESCENT_CITY_195_20150128_Q.@@EU47.18.1"))) (Ports) (Stimuli ("local71" (scope local) (stimType periodic) (Props (periodicFreq "5e+007") (periodicJitter "0") (periodicPattern "1"))) ("local73" (scope local) (stimType periodic) (Props (periodicFreq "5e+007") (periodicJitter "0") (periodicPattern "1"))) ("local75" (scope local) (stimType periodic) (Props (periodicFreq "5e+007") (periodicJitter "0") (periodicPattern "1"))) ("local72" (scope local) (stimType periodic) (Props (periodicFreq "5e+007") (periodicJitter "0") (periodicPattern "1"))) ("local74" (scope local) (stimType periodic) (Props (periodicFreq "5e+007") (periodicJitter "0") (periodicPattern "1"))) ("local69" (scope local) (stimType periodic) (Props (periodicFreq "5e+007") (periodicJitter "0") (periodicPattern "1"))) ("local70" (scope local) (stimType periodic) (Props (periodicFreq "5e+007") (periodicJitter "0") (periodicPattern "1"))) ("local76" (scope local) (stimType periodic) (Props (periodicFreq "5e+007") (periodicJitter "0") (periodicPattern "1")))) (Notes) (Constraints ("DELAY_RULE" ("CRESCENT_CITY_195_20150128_Q U100.DB45" "CRESCENT_CITY_195_20150128_Q R1453.1" "LENGTH" "" "LENGTH" "0.1143") ("CRESCENT_CITY_195_20150128_Q R1453.2" "CRESCENT_CITY_195_20150128_Q R1387.2" "LENGTH" "" "LENGTH" "0.6858") ("CRESCENT_CITY_195_20150128_Q R1453.2" "CRESCENT_CITY_195_20150128_Q R1283.1" "LENGTH" "" "LENGTH" "0.01016") ("CRESCENT_CITY_195_20150128_Q R1387.2" "CRESCENT_CITY_195_20150128_Q R1402.2" "LENGTH" "" "LENGTH" "0.00508") ("CRESCENT_CITY_195_20150128_Q EU111.16" "CRESCENT_CITY_195_20150128_Q R2865.2" "LENGTH" "" "LENGTH" "0.0254") ("CRESCENT_CITY_195_20150128_Q EU47.18" "CRESCENT_CITY_195_20150128_Q R1387.1" "LENGTH" "" "LENGTH" "0.0254")) ("RELATIVE_PROPAGATION_DELAY" ("#SVID_CPU0_1_U100-EU111" "CRESCENT_CITY_195_20150128_Q EU111.16" "CRESCENT_CITY_195_20150128_Q U100.DB45" "GLOBAL" "LENGTH" "0.00635" "NONE" "") ("#SVID_CPU0_1_U100-EU47" "CRESCENT_CITY_195_20150128_Q EU47.18" "CRESCENT_CITY_195_20150128_Q U100.DB45" "GLOBAL" "LENGTH" "0.00635" "NONE" ""))) (MeasurementSets ("EMI" ("EMIStatus" status("on")) ("PeakEmission" status("on")) ("PeakFrequency" status("on")) ("PulseFreq" status("on")) ("RiseTime" status("on")) ("VoltageSwing" status("on"))) ("Reflection" ("BufferDelayFall" status("off")) ("BufferDelayRise" status("off")) ("EyeHeight" status("off")) ("EyeJitter" status("off")) ("EyeWidth" status("off")) ("FirstIncidentFall" status("off")) ("FirstIncidentRise" status("off")) ("Glitch" status("on")) ("GlitchFall" status("off")) ("GlitchRise" status("off")) ("Monotonic" status("on")) ("MonotonicFall" status("off")) ("MonotonicRise" status("off")) ("NoiseMargin" status("on")) ("NoiseMarginHigh" status("off")) ("NoiseMarginLow" status("off")) ("OvershootHigh" status("on")) ("OvershootLow" status("on")) ("PropDelay" status("on")) ("SettleDelay" status("on")) ("SettleDelayFall" status("off")) ("SettleDelayRise" status("off")) ("SwitchDelay" status("on")) ("SwitchDelayFall" status("off")) ("SwitchDelayRise" status("off"))) ("Crosstalk" ("Crosstalk" status("on"))) ("Custom")) (VectorSets) (Props (XnetName "SVID_DIO0_CPU1") (allDrivers "active") (customSimType "Reflection") (ftsMode ("Typ")) (rcvrSelect "all") (tlineDelayMode "time") (userRevision "1.0")))) (Subckts) (CrossSections ("CRESCENT_CITY_195_20150128_Q" (Props (SXDesignName "CRESCENT_CITY_195_20150128_Q")) (Layers ("" (layerType "SURFACE") (material "AIR") (thickness "0 mil") (dielectricConstant "1.000000") (lossTangent "0") (etchFactor "0.000000") (elecCondVal "0 mho/cm") (thermCondVal "0 w/cm-degC")) ("" (layerType "DIELECTRIC") (material "CONFORMAL_COAT") (thickness "0.5 mil") (dielectricConstant "3.800000") (lossTangent "0.035") (etchFactor "0.000000") (elecCondVal "0 mho/cm") (thermCondVal "0.012 w/cm-degC")) ("TOP" (layerType "CONDUCTOR") (material "COPPER") (thickness "  2.100000 mil") (width "4.00 MIL") (dielectricConstant "4.500000") (lossTangent "0") (etchFactor "70.000000") (elecCondVal "595900.000000 mho/cm") (thermCondVal "0 w/cm-degC") (signalDieConstant "3.800000") (signalLossTangent "0.035")) ("" (layerType "DIELECTRIC") (material "FR-4") (thickness "  2.670000 mil") (dielectricConstant "4.000000") (lossTangent "0.035") (etchFactor "0.000000") (elecCondVal "0 mho/cm") (thermCondVal "0.012 w/cm-degC")) ("L2_GND1" (layerType "PLANE") (material "COPPER") (isShield t) (thickness "  1.250000 mil") (dielectricConstant "4.500000") (lossTangent "0.035") (etchFactor "90.000000") (elecCondVal "595900.000000 mho/cm") (thermCondVal "0.012 w/cm-degC")) ("" (layerType "DIELECTRIC") (material "FR-4") (thickness "  9.000000 mil") (dielectricConstant "4.100000") (lossTangent "0.035") (etchFactor "0.000000") (elecCondVal "0 mho/cm") (thermCondVal "0.012 w/cm-degC")) ("L3_SIG1" (layerType "CONDUCTOR") (material "COPPER") (thickness "  1.250000 mil") (width "4.00 MIL") (dielectricConstant "4.500000") (lossTangent "0.035") (etchFactor "90.000000") (elecCondVal "595900.000000 mho/cm") (thermCondVal "0.012 w/cm-degC") (signalDieConstant "4.100000") (signalLossTangent "0.035")) ("" (layerType "DIELECTRIC") (material "FR-4") (thickness "  3.000000 mil") (dielectricConstant "4.500000") (lossTangent "0.035") (etchFactor "0.000000") (elecCondVal "0 mho/cm") (thermCondVal "0 w/cm-degC")) ("L4_GND2" (layerType "PLANE") (material "COPPER") (isShield t) (thickness "  1.250000 mil") (dielectricConstant "4.500000") (lossTangent "0.035") (etchFactor "90.000000") (elecCondVal "595900.000000 mho/cm") (thermCondVal "0 w/cm-degC")) ("" (layerType "DIELECTRIC") (material "FR-4") (thickness "  9.000000 mil") (dielectricConstant "4.000000") (lossTangent "0.035") (etchFactor "0.000000") (elecCondVal "0 mho/cm") (thermCondVal "0.012 w/cm-degC")) ("L5_SIG2" (layerType "CONDUCTOR") (material "COPPER") (thickness "  1.250000 mil") (width "4.00 MIL") (dielectricConstant "4.500000") (lossTangent "0.035") (etchFactor "90.000000") (elecCondVal "595900.000000 mho/cm") (thermCondVal "0.012 w/cm-degC") (signalDieConstant "4.000000") (signalLossTangent "0.035")) ("" (layerType "DIELECTRIC") (material "FR-4") (thickness "  3.000000 mil") (dielectricConstant "4.500000") (lossTangent "0.035") (etchFactor "0.000000") (elecCondVal "0 mho/cm") (thermCondVal "0 w/cm-degC")) ("L6_GND3" (layerType "PLANE") (material "COPPER") (isShield t) (thickness "  1.250000 mil") (dielectricConstant "4.500000") (lossTangent "0.035") (etchFactor "90.000000") (elecCondVal "595900.000000 mho/cm") (thermCondVal "0 w/cm-degC")) ("" (layerType "DIELECTRIC") (material "FR-4") (thickness "  4.500000 mil") (dielectricConstant "4.100000") (lossTangent "0.035") (etchFactor "0.000000") (elecCondVal "0 mho/cm") (thermCondVal "0.012 w/cm-degC")) ("L7_PWR1-SIG" (layerType "PLANE") (material "COPPER") (isShield t) (thickness "  2.400000 mil") (dielectricConstant "4.500000") (lossTangent "0.035") (etchFactor "90.000000") (elecCondVal "595900.000000 mho/cm") (thermCondVal "0.012 w/cm-degC")) ("" (layerType "DIELECTRIC") (material "FR-4") (thickness "  4.600000 mil") (dielectricConstant "4.000000") (lossTangent "0.035") (etchFactor "0.000000") (elecCondVal "0 mho/cm") (thermCondVal "0.012 w/cm-degC")) ("L8_PWR2-SIG" (layerType "PLANE") (material "COPPER") (isShield t) (thickness "  2.400000 mil") (dielectricConstant "4.500000") (lossTangent "0.035") (etchFactor "90.000000") (elecCondVal "595900.000000 mho/cm") (thermCondVal "0.012 w/cm-degC")) ("" (layerType "DIELECTRIC") (material "FR-4") (thickness "  8.000000 mil") (dielectricConstant "4.500000") (lossTangent "0.035") (etchFactor "0.000000") (elecCondVal "0 mho/cm") (thermCondVal "0 w/cm-degC")) ("" (layerType "DIELECTRIC") (material "FR-4") (thickness "  8.000000 mil") (dielectricConstant "4.500000") (lossTangent "0.035") (etchFactor "0.000000") (elecCondVal "0 mho/cm") (thermCondVal "0 w/cm-degC")) ("" (layerType "DIELECTRIC") (material "FR-4") (thickness "  4.500000 mil") (dielectricConstant "4.500000") (lossTangent "0.035") (etchFactor "0.000000") (elecCondVal "0 mho/cm") (thermCondVal "0 w/cm-degC")) ("L9_GND4" (layerType "PLANE") (material "COPPER") (isShield t) (thickness "  1.250000 mil") (dielectricConstant "4.500000") (lossTangent "0.035") (etchFactor "90.000000") (elecCondVal "595900.000000 mho/cm") (thermCondVal "0 w/cm-degC")) ("" (layerType "DIELECTRIC") (material "FR-4") (thickness "  3.000000 mil") (dielectricConstant "4.100000") (lossTangent "0.035") (etchFactor "0.000000") (elecCondVal "0 mho/cm") (thermCondVal "0.012 w/cm-degC")) ("L10_SIG3" (layerType "CONDUCTOR") (material "COPPER") (thickness "  1.250000 mil") (width "4.00 MIL") (dielectricConstant "4.500000") (lossTangent "0.035") (etchFactor "90.000000") (elecCondVal "595900.000000 mho/cm") (thermCondVal "0.012 w/cm-degC") (signalDieConstant "4.100000") (signalLossTangent "0.035")) ("" (layerType "DIELECTRIC") (material "FR-4") (thickness "  9.000000 mil") (dielectricConstant "4.500000") (lossTangent "0.035") (etchFactor "0.000000") (elecCondVal "0 mho/cm") (thermCondVal "0 w/cm-degC")) ("L11_GND5" (layerType "PLANE") (material "COPPER") (isShield t) (thickness "  1.250000 mil") (dielectricConstant "4.500000") (lossTangent "0.035") (etchFactor "90.000000") (elecCondVal "595900.000000 mho/cm") (thermCondVal "0 w/cm-degC")) ("" (layerType "DIELECTRIC") (material "FR-4") (thickness "  3.000000 mil") (dielectricConstant "4.500000") (lossTangent "0.035") (etchFactor "0.000000") (elecCondVal "0 mho/cm") (thermCondVal "0.012 w/cm-degC")) ("L12_SIG4" (layerType "CONDUCTOR") (material "COPPER") (thickness "  1.250000 mil") (width "4.00 MIL") (dielectricConstant "4.500000") (lossTangent "0.035") (etchFactor "90.000000") (elecCondVal "595900.000000 mho/cm") (thermCondVal "0.012 w/cm-degC") (signalDieConstant "4.500000") (signalLossTangent "0.035")) ("" (layerType "DIELECTRIC") (material "FR-4") (thickness "  9.000000 mil") (dielectricConstant "4.500000") (lossTangent "0.035") (etchFactor "0.000000") (elecCondVal "0 mho/cm") (thermCondVal "0 w/cm-degC")) ("L13_GND6" (layerType "PLANE") (material "COPPER") (isShield t) (thickness "  1.250000 mil") (dielectricConstant "4.500000") (lossTangent "0.035") (etchFactor "90.000000") (elecCondVal "595900.000000 mho/cm") (thermCondVal "0.012 w/cm-degC")) ("" (layerType "DIELECTRIC") (material "FR-4") (thickness "  2.670000 mil") (dielectricConstant "4.500000") (lossTangent "0.035") (etchFactor "0.000000") (elecCondVal "0 mho/cm") (thermCondVal "0.012 w/cm-degC")) ("BOTTOM" (layerType "CONDUCTOR") (material "COPPER") (thickness "  2.100000 mil") (width "4.00 MIL") (dielectricConstant "4.500000") (lossTangent "0") (etchFactor "70.000000") (elecCondVal "595900.000000 mho/cm") (thermCondVal "0 w/cm-degC") (signalDieConstant "3.800000") (signalLossTangent "0.035")) ("" (layerType "DIELECTRIC") (material "CONFORMAL_COAT") (thickness "0.5 mil") (dielectricConstant "3.800000") (lossTangent "0.035") (etchFactor "0.000000") (elecCondVal "0 mho/cm") (thermCondVal "0.012 w/cm-degC")) ("" (layerType "SURFACE") (material "AIR") (thickness "0 mil") (dielectricConstant "1.000000") (lossTangent "0") (etchFactor "0.000000") (elecCondVal "0 mho/cm") (thermCondVal "0 w/cm-degC"))))) (Props (DesUnits "mils 2") (LayerStack ("DIELECTRIC" "DIELECTRIC" "BOTTOM" "DIELECTRIC" "L13_GND6" "DIELECTRIC" "L12_SIG4" "DIELECTRIC" "L11_GND5" "DIELECTRIC" "L10_SIG3" "DIELECTRIC" "L9_GND4" "DIELECTRIC" "DIELECTRIC" "DIELECTRIC" "L8_PWR2-SIG" "DIELECTRIC" "L7_PWR1-SIG" "DIELECTRIC" "L6_GND3" "DIELECTRIC" "L5_SIG2" "DIELECTRIC" "L4_GND2" "DIELECTRIC" "L3_SIG1" "DIELECTRIC" "L2_GND1" "DIELECTRIC" "TOP" "DIELECTRIC" "DIELECTRIC")) (Revision "16.600")) (Params (DiffOutputPkg ((temperature "27") (bufferModelNonInverting "CDSDefaultOutput_2p5v") (bufferModelInverting "CDSDefaultOutput_2p5v") (stimuli nil) (offsets nil) (state "tristate") (cycle "1") (termMap nil) (setup "0.9e-09") (hold "0.4e-09") (rise nil) (fall nil) (threshOutputHighMin "2.375  V") (threshOutputHighTyp "2.5  V") (threshOutputHighMax "2.625  V") (threshOutputLowMin "1.275  V") (threshOutputLowTyp "1.7  V") (threshOutputLowMax "1.985  V") (mappingTagNonInverting nil) (mappingTagInverting nil) (spice nil))) (HiClampTerm ((cutoffVoltage "0.7 V") (voltage "5 V") (maxDelay "0.1 ns"))) (LowClampTerm ((cutoffVoltage "0.7 V") (voltage "0 V") (maxDelay "0.1 ns"))) (DiffOutput ((temperature "27") (bufferModelNonInverting "CDSDefaultOutput_2p5v") (bufferModelInverting "CDSDefaultOutput_2p5v") (stimuli nil) (offsets nil) (state "tristate") (cycle "1") (termMap nil) (setup "0.9e-09") (hold "0.4e-09") (rise nil) (fall nil) (threshOutputHighMin "2.375  V") (threshOutputHighTyp "2.5  V") (threshOutputHighMax "2.625  V") (threshOutputLowMin "1.275  V") (threshOutputLowTyp "1.7  V") (threshOutputLowMax "1.985  V") (mappingTagNonInverting nil) (mappingTagInverting nil) (spice nil))) (Via ((model "Unknown") (viaOutputFormat "Unknown") (viaPadstack nil) (viaTopLayer nil) (viaBottomLayer nil) (viaIsPower nil) (viaIsGround nil))) (Resistor ((resistance "50 ohm") (orientation "0"))) (RCTerm ((resistance "50 ohm") (capacitance "20 pF") (voltage "5 V") (maxDelay "0.1 ns"))) (DiffIOPkg ((temperature "27") (bufferModelNonInverting "CDSDefaultIO_2p5v") (bufferModelInverting "CDSDefaultIO_2p5v") (stimuli nil) (offsets nil) (state "tristate") (cycle "1") (termMap nil) (setup "0.9e-09") (hold "0.4e-09") (rise nil) (fall nil) (threshInputHighMin "1.7 V") (threshInputHighTyp "1.7  V") (threshInputHighMax "1.7  V") (threshInputLowMin "0.7  V") (threshInputLowTyp "0.7  V") (threshInputLowMax "0.7 ") (threshOutputHighMin "2.365  V") (threshOutputHighTyp "2.5  V") (threshOutputHighMax "2.625  V") (threshOutputLowMin "1.275  V") (threshOutputLowTyp "1.7  V") (threshOutputLowMax "1.985  V") (mappingTagNonInverting nil) (mappingTagInverting nil) (spice nil))) (Trace ((d1Thickness "10 mil") (d1Constant "4.5") (d1LossTangent "0.035") (d2Thickness "10 mil") (d2Constant "4.5") (d2LossTangent "0.035") (d3Thickness "0.0") (d3Constant "1.0") (d3LossTangent "0") length("1000 mil") (spacing "5 mil") (spacing2 "5 mil") (spacing3 "5 mil") (spacing4 "5 mil") (spacing5 "5 mil") (traceConductivity "595900 mho/cm") (traceGeometry "microstrip") (traceLayerName "") (traceThickness "0.72 mil") (traceType "single") (traceWidth "5.0 mil") (traceWidth2 "5.0 mil") (traceWidth3 "5.0 mil") (traceWidth4 "5.0 mil") (traceWidth5 "5.0 mil") (traceWidth6 "5.0 mil") (offset "0 mil") (traceCount "1") (impedance nil))) (TheveninTerm ((resistanceUp "180 ohm") (resistanceDown "270 ohm") (voltageUp "5 V") (voltageDown "0 V") (maxDelay "0.1 ns"))) (DiffIO ((temperature "27") (bufferModelNonInverting "CDSDefaultIO_2p5v") (bufferModelInverting "CDSDefaultIO_2p5v") (stimuli nil) (offsets nil) (state "tristate") (cycle "1") (termMap nil) (setup "0.9e-09") (hold "0.4e-09") (rise nil) (fall nil) (threshInputHighMin "1.7 V") (threshInputHighTyp "1.7  V") (threshInputHighMax "1.7  V") (threshInputLowMin "0.7  V") (threshInputLowTyp "0.7  V") (threshInputLowMax "0.7 ") (threshOutputHighMin "2.365  V") (threshOutputHighTyp "2.5  V") (threshOutputHighMax "2.625  V") (threshOutputLowMin "1.275  V") (threshOutputLowTyp "1.7  V") (threshOutputLowMax "1.985  V") (mappingTagNonInverting nil) (mappingTagInverting nil) (spice nil))) (ShuntTerm ((resistance "50 ohm") (voltage "5 V") (maxDelay "0.1 ns"))) (Inductor ((inductance "5 nH") (orientation "0"))) (Capacitor ((capacitance "10 pF") (orientation "0"))) (RLGC (length("1000 mil"))) (Source ((voltage "5 V"))) (DiffInput ((temperature "27") (bufferModelNonInverting "CDSDefaultInput_2p5v") (bufferModelInverting "CDSDefaultInput_2p5v") (threshInputHighMin "1.7 V") (threshInputHighTyp "1.7  V") (threshInputHighMax "1.7  V") (threshInputLowMin "0.7  V") (threshInputLowTyp "0.7  V") (threshInputLowMax "0.7  V") (mappingTagNonInverting nil) (mappingTagInverting nil) (cycle "1"))) (Cable (length("1 m"))) (CPWSL ((d1Thickness "10 mil") (d1Constant "4.5") (d1LossTangent "0.035") (d2Thickness "0.72 mil") (d2Constant "4.5") (d2LossTangent "0.035") (d3Thickness "10 mil") (d3Constant "4.5") (d3LossTangent "0.035") length("1000 mil") (spacing "5 mil") (spacing2 "5 mil") (spacing3 "5 mil") (spacing4 "5 mil") (spacing5 "5 mil") (traceConductivity "595900 mho/cm") (traceGeometry "cpwms") (traceLayerName "") (traceThickness "0.72 mil") (traceType "single") (traceWidth "5.0 mil") (traceWidth2 "5.0 mil") (traceWidth3 "5.0 mil") (traceWidth4 "5.0 mil") (traceWidth5 "5.0 mil") (traceWidth6 "5.0 mil") (offset "0 mil") (traceCount "1") (impedance nil))) (ESpiceDevice nil) (CPWMS ((d1Thickness "10 mil") (d1Constant "4.5") (d1LossTangent "0.035") (d2Thickness "0.72 mil") (d2Constant "4.5") (d2LossTangent "0.035") (d3Thickness "0.0") (d3Constant "1") (d3LossTangent "0") length("1000 mil") (spacing "5 mil") (spacing2 "5 mil") (spacing3 "5 mil") (spacing4 "5 mil") (spacing5 "5 mil") (traceConductivity "595900 mho/cm") (traceGeometry "cpwms") (traceLayerName "") (traceThickness "0.72 mil") (traceType "single") (traceWidth "5.0 mil") (traceWidth2 "5.0 mil") (traceWidth3 "5.0 mil") (traceWidth4 "5.0 mil") (traceWidth5 "5.0 mil") (traceWidth6 "5.0 mil") (offset "0 mil") (traceCount "1") (impedance nil))) (Diode ((cutoffVoltage "0.7 V"))) (CPW ((d1Thickness "10 mil") (d1Constant "4.5") (d1LossTangent "0.035") (d2Thickness "0.72 mil") (d2Constant "1") (d2LossTangent "0") (d3Thickness "0.0") (d3Constant "1") (d3LossTangent "0") length("1000 mil") (spacing "5 mil") (spacing2 "5 mil") (spacing3 "5 mil") (spacing4 "5 mil") (spacing5 "5 mil") (traceConductivity "595900 mho/cm") (traceGeometry "cpwms") (traceLayerName "") (traceThickness "0.72 mil") (traceType "single") (traceWidth "5.0 mil") (traceWidth2 "5.0 mil") (traceWidth3 "5.0 mil") (traceWidth4 "5.0 mil") (traceWidth5 "5.0 mil") (traceWidth6 "5.0 mil") (offset "0 mil") (traceCount "1") (impedance nil))) (DualClampTerm ((cutoffVoltageUp "0.7 V") (cutoffVoltageDown "0.7 V") (voltageUp "5 V") (voltageDown "0 V") (maxDelay "0.1 ns"))) (IbisOutputPkg ((temperature "27") (bufferModel "CDSDefaultOutput_2p5v") (stimuli nil) (offsets nil) (state "tristate") (cycle "1") (termMap nil) (setup "2.0e-09") (hold "1.0e-09") (rise nil) (fall nil) (macroType nil) (voltage nil) (spice nil) (LEFDEFPinName nil) (LEFDEFPinType nil) (mappingTag nil))) (IbisIO_OpenPullDown ((temperature "27") (bufferModel "CDSDefaultIO_2p5v") (stimuli nil) (offsets nil) (state "tristate") (cycle "1") (termMap nil) (setup "2.0e-09") (hold "1.0e-09") (rise nil) (fall nil) (macroType nil) (voltage nil) (spice nil) (LEFDEFPinName nil) (LEFDEFPinType nil) (mappingTag nil))) (IbisInputPkg ((temperature "27") (bufferModel "CDSDefaultInput_2p5v") (cycle "1") (LEFDEFPinName nil) (LEFDEFPinType nil) (mappingTag nil))) (IbisIOMacro ((temperature "27") (bufferModel "CDSDefaultIO_2p5v") (stimuli nil) (offsets nil) (state "tristate") (cycle "1") (termMap nil) (setup "2.0e-09") (hold "1.0e-09") (rise nil) (fall nil) (macroType nil) (voltage nil) (spice nil) (LEFDEFPinName nil) (LEFDEFPinType nil) (mappingTag nil))) (IbisIO_OpenPullUp ((temperature "27") (bufferModel "CDSDefaultIO_2p5v") (stimuli nil) (offsets nil) (state "tristate") (cycle "1") (termMap nil) (setup "2.0e-09") (hold "1.0e-09") (rise nil) (fall nil) (macroType nil) (voltage nil) (spice nil) (LEFDEFPinName nil) (LEFDEFPinType nil) (mappingTag nil))) (IbisIOPkg ((temperature "27") (bufferModel "CDSDefaultIO_2p5v") (stimuli nil) (offsets nil) (state "tristate") (cycle "1") (termMap nil) (setup "2.0e-09") (hold "1.0e-09") (rise nil) (fall nil) (macroType nil) (voltage nil) (spice nil) (LEFDEFPinName nil) (LEFDEFPinType nil) (mappingTag nil))) (clocked ((clockRise "1e-09") (clockFall "1e-09") (clockFreq "100e6") (clockInitState "0") (clockDutyCycle "0.5") (clockJitter "0"))) (periodic ((periodicFreq "100e6") (periodicPattern "10") (periodicJitter "0"))) (IbisIO ((temperature "27") (bufferModel "CDSDefaultIO_2p5v") (stimuli nil) (offsets nil) (state "tristate") (cycle "1") (termMap nil) (setup "2.0e-09") (hold "1.0e-09") (rise nil) (fall nil) (macroType nil) (voltage nil) (spice nil) (LEFDEFPinName nil) (LEFDEFPinType nil) (mappingTag nil))) (async ((asyncTimePoints "") (asyncInitState "1"))) (IbisOutput ((temperature "27") (bufferModel "CDSDefaultOutput_2p5v") (stimuli nil) (offsets nil) (state "tristate") (cycle "1") (termMap nil) (setup "2.0e-09") (hold "1.0e-09") (rise nil) (fall nil) (macroType nil) (voltage nil) (spice nil) (LEFDEFPinName nil) (LEFDEFPinType nil) (mappingTag nil))) (TLine ((diffImpedance "100ohm") (diffVelocity "1.4142e+08M/s") (impedance "60ohm") length("2800 mil") (propDelay "0.5 ns") (velocity "5600 mil/ns") (traceCount "1") (traceGeometry "Microstrip") (impedanceMin nil) (impedanceMax nil) (lengthMin nil) (lengthMax nil) (propDelayMin nil) (propDelayMax nil) (impedanceSweepCount nil) (propDelaySweepCount nil) (velocitySweepCount nil) (lengthSweepCount nil) (matchSetName nil))) (CurrentProbe nil) (IbisInput ((temperature "27") (bufferModel "CDSDefaultInput_2p5v") (cycle "1") (LEFDEFPinName nil) (LEFDEFPinType nil) (mappingTag nil))) (SeriesTerm ((resistance "22 ohm") (maxDelay "0.1 ns"))) (Connector nil) (sync ((syncFreq "100e6") (syncInitState "1") (syncPattern "10") (syncEdgeSwitch "rise"))) (IbisOutput_OpenPullUp ((temperature "27") (bufferModel "CDSDefaultOutput_2p5v") (stimuli nil) (offsets nil) (state "tristate") (cycle "1") (termMap nil) (setup "2.0e-09") (hold "1.0e-09") (rise nil) (fall nil) (macroType nil) (voltage nil) (spice nil) (LEFDEFPinName nil) (LEFDEFPinType nil) (mappingTag nil))) (DiffInputPkg ((temperature "27") (bufferModelNonInverting "CDSDefaultInput_2p5v") (bufferModelInverting "CDSDefaultInput_2p5v") (threshInputHighMin "1.7 V") (threshInputHighTyp "1.7  V") (threshInputHighMax "1.7  V") (threshInputLowMin "0.7  V") (threshInputLowTyp "0.7  V") (threshInputLowMax "0.7  V") (mappingTagNonInverting nil) (mappingTagInverting nil) (cycle "1"))) (idlCircuit ((allDrivers "active") (ftsMode '("Typ")) (rcvrSelect "all") (simMode "Reflection") (tlineDelayMode "time") (userRevision "1.0") (autoSolve "On")))))
				)
				( objectStatus "SVID_DIO0_CPU1" )
			)
			( electricalCSet "@baseboard_fab2_lib.baseboard_fab2(sch_1):\SVID_CPU1\"
				( pinPairRef "SVID_CPU1:U2D1.DL44:R1C1.1" )
				( pinPairRef "SVID_CPU1:R1C1.2:R9N1.2" )
				( attribute "RATSNEST_SCHEDULE" "TEMPLATE"
					( Status sLocked )
					( Origin gBackEnd )
				)
				( attribute "TOPOLOGY_TEMPLATE_REVISION" "1.0"
					( Origin gBackEnd )
				)
				( topologyData 28916
(SKIDL (Circuits ("MAIN" (Parts ("CRESCENT_CITY_191_20150122_Q.@@EU76.17" IbisOutputPkg (xy (5498 4221)) (refDes "EU1G2") (model "Unknown") (Props (_SXDesignName "CRESCENT_CITY_191_20150122_Q") (brdx "371.38 MIL") (brdy "146.5 MIL") (bufferModel "CDSDefaultOutput_2p5v") (cycle "1") (hold "1.0e-09") (mappingTag "") (offsets ("4" "0")) (setup "2.0e-09") (state "tristate") (stimuli ("4" "local49")) (temperature "27") (termMap ("4" "Data"))) (Terms ("CRESCENT_CITY_191_20150122_Q.X37138Y14650L2LRATS" "17"))) ("CRESCENT_CITY_191_20150122_Q.@@U100.DL44" IbisInputPkg (xy (5574 4229)) (refDes "U2D1") (model "Unknown") (Props (_SXDesignName "CRESCENT_CITY_191_20150122_Q") (brdx "4086.86 MIL") (brdy "3709.59 MIL") (bufferModel "CDSDefaultInput_2p5v") (mappingTag "") (temperature "27")) (Terms ("CRESCENT_CITY_191_20150122_Q.X408686Y370959L2LRATS" "DL44"))) ("CRESCENT_CITY_191_20150122_Q.@@J128.C20" IbisIOPkg (xy (5560 4240)) (refDes "J4B2") (model "Unknown") (Props (_SXDesignName "CRESCENT_CITY_191_20150122_Q") (brdx "7431 MIL") (brdy "4450 MIL") (bufferModel "CDSDefaultIO_2p5v") (cycle "1") (hold "1.0e-09") (mappingTag "") (offsets ("4" "0") ("5" "0")) (setup "2.0e-09") (state "tristate") (stimuli ("4" "local50") ("5" "local51")) (temperature "27") (termMap ("4" "Data") ("5" "Enable"))) (Terms ("CRESCENT_CITY_191_20150122_Q.X743100Y445000L2LRATS" "C20"))) ("CRESCENT_CITY_191_20150122_Q.@@EU77.17" IbisOutputPkg (xy (5498 4235)) (refDes "EU1B1") (model "Unknown") (Props (_SXDesignName "CRESCENT_CITY_191_20150122_Q") (brdx "-15.5 MIL") (brdy "5014.38 MIL") (bufferModel "CDSDefaultOutput_2p5v") (cycle "1") (hold "1.0e-09") (mappingTag "") (offsets ("4" "0")) (setup "2.0e-09") (state "tristate") (stimuli ("4" "local52")) (temperature "27") (termMap ("4" "Data"))) (Terms ("CRESCENT_CITY_191_20150122_Q.Xn1550Y501438L2LRATS" "17"))) ("CRESCENT_CITY_191_20150122_Q.@@R1286.1.2" Resistor (xy (5521 4228)) (refDes "R9N1") (value "49.9 Ohm") (Props (_SXDesignName "CRESCENT_CITY_191_20150122_Q")) (Terms ("CRESCENT_CITY_191_20150122_Q.X154642Y419700L28RATS" "1") ("CRESCENT_CITY_191_20150122_Q.X151142Y419700L28LRATS" "2"))) ("CRESCENT_CITY_191_20150122_Q.@@R2077.1.2" Resistor (xy (5521 4235)) (refDes "R1B11") (value "2.2e-007 Ohm") (Props (_SXDesignName "CRESCENT_CITY_191_20150122_Q")) (Terms ("CRESCENT_CITY_191_20150122_Q.Xn9900Y502800L2LRATS" "1") ("CRESCENT_CITY_191_20150122_Q.Xn13400Y502800L2LRATS" "2"))) ("CRESCENT_CITY_191_20150122_Q.@@R2056.1.2" Resistor (xy (5521 4221)) (refDes "R1G9") (value "2.2e-007 Ohm") (Props (_SXDesignName "CRESCENT_CITY_191_20150122_Q")) (Terms ("CRESCENT_CITY_191_20150122_Q.X38500Y23000L2LRATS" "1") ("CRESCENT_CITY_191_20150122_Q.X38500Y26500L2LRATS" "2"))) ("CRESCENT_CITY_191_20150122_Q.T@@RATS@@J128.C20@@R1452.2" TLine (xy (5545 4235)) (mirror x) (refDes "TL15") (Props (_SXDesignName "CRESCENT_CITY_191_20150122_Q") (impedance "60 ohm") length("6172.56 MIL") (propDelay "1.10864 ns") (traceCount "1") (traceGeometry "Microstrip") (velocity "5567.72 mil/ns")) (Terms ("CRESCENT_CITY_191_20150122_Q.X743100Y445000L2LRATS" "1") ("idlNode_11" "2"))) ("CRESCENT_CITY_191_20150122_Q.T@@RATS@@R1452.2@@R2077.2" TLine (xy (5530 4235)) (mirror x) (refDes "TL16") (Props (_SXDesignName "CRESCENT_CITY_191_20150122_Q") (impedance "48.412 ohm") length("2476.42 MIL") (propDelay "0.44478 ns") (traceCount "1") (traceGeometry "Microstrip") (velocity "5567.76 mil/ns")) (Terms ("idlNode_11" "1") ("CRESCENT_CITY_191_20150122_Q.Xn13400Y502800L2LRATS" "2"))) ("CRESCENT_CITY_191_20150122_Q.@@R1286.1_SOURCE" Source (xy (5514 4228)) (refDes "PVCCIO_CPU1") (value "1 V") (Props (_SXDesignName "CRESCENT_CITY_191_20150122_Q")) (Terms ("CRESCENT_CITY_191_20150122_Q.X154642Y419700L28RATS" "1"))) ("CRESCENT_CITY_191_20150122_Q.T@@RATS@@R2077.1@@EU77.17" TLine (xy (5506 4235)) (mirror x) (refDes "TL17") (Props (_SXDesignName "CRESCENT_CITY_191_20150122_Q") (impedance "48.412 ohm") length("97.12 MIL") (propDelay "0.01744 ns") (traceCount "1") (traceGeometry "Microstrip") (velocity "5568.82 mil/ns")) (Terms ("CRESCENT_CITY_191_20150122_Q.Xn9900Y502800L2LRATS" "1") ("CRESCENT_CITY_191_20150122_Q.Xn1550Y501438L2LRATS" "2"))) ("CRESCENT_CITY_191_20150122_Q.T@@RATS@@U100.DL44@@R1452.1" TLine (xy (5560 4229)) (mirror x) (refDes "TL18") (Props (_SXDesignName "CRESCENT_CITY_191_20150122_Q") (impedance "49.728 ohm") length("3027.85 MIL") (propDelay "0.54382 ns") (traceCount "1") (traceGeometry "Microstrip") (velocity "5567.76 mil/ns")) (Terms ("CRESCENT_CITY_191_20150122_Q.X408686Y370959L2LRATS" "1") ("CRESCENT_CITY_191_20150122_Q.X154642Y419700L2LRATS" "2"))) ("CRESCENT_CITY_191_20150122_Q.T@@RATS@@R1452.2@@R2056.2" TLine (xy (5536 4221)) (mirror x) (refDes "TL19") (Props (_SXDesignName "CRESCENT_CITY_191_20150122_Q") (impedance "48.412 ohm") length("5058.43 MIL") (propDelay "0.90853 ns") (traceCount "1") (traceGeometry "Microstrip") (velocity "5567.72 mil/ns")) (Terms ("idlNode_11" "1") ("CRESCENT_CITY_191_20150122_Q.X38500Y26500L2LRATS" "2"))) ("idlPart_7" TLine (xy (5545.0 4225.5)) (mirror x) (refDes "TL22") (Props (_SXDesignName "CRESCENT_CITY_191_20150122_Q") (impedance "48.412 ohm") (propDelay "1.79607e-006 ns") (traceCount "1") (traceGeometry "Microstrip")) (Terms ("idlNode_9" "1") ("idlNode_11" "2"))) ("CRESCENT_CITY_191_20150122_Q.@@R1452.1.2" Resistor (xy (5549.5 4229.0)) (mirror x) (refDes "R1C1") (value "220 Ohm") (Props (_SXDesignName "CRESCENT_CITY_191_20150122_Q")) (Terms ("CRESCENT_CITY_191_20150122_Q.X154642Y419700L2LRATS" "1") ("idlNode_9" "2"))) ("CRESCENT_CITY_191_20150122_Q.T@@RATS@@R1452.2@@R1286.2" TLine (xy (5536 4228)) (mirror x) (refDes "TL20") (Props (_SXDesignName "CRESCENT_CITY_191_20150122_Q") (impedance "48.412 ohm") (propDelay "1.79607e-006 ns") (traceCount "1") (traceGeometry "Microstrip")) (Terms ("idlNode_11" "1") ("CRESCENT_CITY_191_20150122_Q.X151142Y419700L28LRATS" "2"))) ("CRESCENT_CITY_191_20150122_Q.T@@RATS@@R2056.1@@EU76.17" TLine (xy (5512 4221)) (mirror x) (refDes "TL21") (Props (_SXDesignName "CRESCENT_CITY_191_20150122_Q") (impedance "48.412 ohm") length("97.12 MIL") (propDelay "0.01744 ns") (traceCount "1") (traceGeometry "Microstrip") (velocity "5568.82 mil/ns")) (Terms ("CRESCENT_CITY_191_20150122_Q.X38500Y23000L2LRATS" "1") ("CRESCENT_CITY_191_20150122_Q.X37138Y14650L2LRATS" "2")))) (Nodes ("CRESCENT_CITY_191_20150122_Q.X743100Y445000L2LRATS" (terms "CRESCENT_CITY_191_20150122_Q.T@@RATS@@J128.C20@@R1452.2.1" "CRESCENT_CITY_191_20150122_Q.@@J128.C20.1")) ("CRESCENT_CITY_191_20150122_Q.X151142Y419700L28LRATS" (terms "CRESCENT_CITY_191_20150122_Q.T@@RATS@@R1452.2@@R1286.2.2" "CRESCENT_CITY_191_20150122_Q.@@R1286.1.2.2")) ("CRESCENT_CITY_191_20150122_Q.Xn9900Y502800L2LRATS" (terms "CRESCENT_CITY_191_20150122_Q.T@@RATS@@R2077.1@@EU77.17.1" "CRESCENT_CITY_191_20150122_Q.@@R2077.1.2.1")) ("CRESCENT_CITY_191_20150122_Q.X37138Y14650L2LRATS" (terms "CRESCENT_CITY_191_20150122_Q.T@@RATS@@R2056.1@@EU76.17.2" "CRESCENT_CITY_191_20150122_Q.@@EU76.17.1")) ("CRESCENT_CITY_191_20150122_Q.X408686Y370959L2LRATS" (terms "CRESCENT_CITY_191_20150122_Q.T@@RATS@@U100.DL44@@R1452.1.1" "CRESCENT_CITY_191_20150122_Q.@@U100.DL44.1")) ("CRESCENT_CITY_191_20150122_Q.Xn1550Y501438L2LRATS" (terms "CRESCENT_CITY_191_20150122_Q.T@@RATS@@R2077.1@@EU77.17.2" "CRESCENT_CITY_191_20150122_Q.@@EU77.17.1")) ("idlNode_11" (terms "idlPart_7.2" "CRESCENT_CITY_191_20150122_Q.T@@RATS@@J128.C20@@R1452.2.2" "CRESCENT_CITY_191_20150122_Q.T@@RATS@@R1452.2@@R2077.2.1" "CRESCENT_CITY_191_20150122_Q.T@@RATS@@R1452.2@@R2056.2.1" "CRESCENT_CITY_191_20150122_Q.T@@RATS@@R1452.2@@R1286.2.1") (tee "CRESCENT_CITY_191_20150122_Q NET.T.1")) ("CRESCENT_CITY_191_20150122_Q.X38500Y23000L2LRATS" (terms "CRESCENT_CITY_191_20150122_Q.T@@RATS@@R2056.1@@EU76.17.1" "CRESCENT_CITY_191_20150122_Q.@@R2056.1.2.1")) ("CRESCENT_CITY_191_20150122_Q.Xn13400Y502800L2LRATS" (terms "CRESCENT_CITY_191_20150122_Q.T@@RATS@@R1452.2@@R2077.2.2" "CRESCENT_CITY_191_20150122_Q.@@R2077.1.2.2")) ("CRESCENT_CITY_191_20150122_Q.X154642Y419700L2LRATS" (terms "CRESCENT_CITY_191_20150122_Q.@@R1452.1.2.1" "CRESCENT_CITY_191_20150122_Q.T@@RATS@@U100.DL44@@R1452.1.2")) ("idlNode_9" (terms "idlPart_7.1" "CRESCENT_CITY_191_20150122_Q.@@R1452.1.2.2")) ("CRESCENT_CITY_191_20150122_Q.X38500Y26500L2LRATS" (terms "CRESCENT_CITY_191_20150122_Q.T@@RATS@@R1452.2@@R2056.2.2" "CRESCENT_CITY_191_20150122_Q.@@R2056.1.2.2")) ("CRESCENT_CITY_191_20150122_Q.X154642Y419700L28RATS" (terms "CRESCENT_CITY_191_20150122_Q.@@R1286.1_SOURCE.1" "CRESCENT_CITY_191_20150122_Q.@@R1286.1.2.1"))) (Ports) (Stimuli ("local51" (scope local) (stimType periodic) (Props (periodicFreq "5e+007") (periodicJitter "0") (periodicPattern "1"))) ("local49" (scope local) (stimType periodic) (Props (periodicFreq "5e+007") (periodicJitter "0") (periodicPattern "1"))) ("local50" (scope local) (stimType periodic) (Props (periodicFreq "5e+007") (periodicJitter "0") (periodicPattern "1"))) ("local52" (scope local) (stimType periodic) (Props (periodicFreq "5e+007") (periodicJitter "0") (periodicPattern "1")))) (Notes) (Constraints ("DELAY_RULE" ("CRESCENT_CITY_191_20150122_Q U100.DL44" "CRESCENT_CITY_191_20150122_Q R1452.1" "LENGTH" "" "LENGTH" "0.1143") ("CRESCENT_CITY_191_20150122_Q R1452.2" "CRESCENT_CITY_191_20150122_Q R1286.2" "LENGTH" "" "LENGTH" "0.01016")) ("RATSNEST_SCHEDULE" "TEMPLATE")) (MeasurementSets ("EMI" ("EMIStatus" status("on")) ("PeakEmission" status("on")) ("PeakFrequency" status("on")) ("PulseFreq" status("on")) ("RiseTime" status("on")) ("VoltageSwing" status("on"))) ("Reflection" ("BufferDelayFall" status("off")) ("BufferDelayRise" status("off")) ("EyeHeight" status("off")) ("EyeJitter" status("off")) ("EyeWidth" status("off")) ("FirstIncidentFall" status("off")) ("FirstIncidentRise" status("off")) ("Glitch" status("on")) ("GlitchFall" status("off")) ("GlitchRise" status("off")) ("Monotonic" status("on")) ("MonotonicFall" status("off")) ("MonotonicRise" status("off")) ("NoiseMargin" status("on")) ("NoiseMarginHigh" status("off")) ("NoiseMarginLow" status("off")) ("OvershootHigh" status("on")) ("OvershootLow" status("on")) ("PropDelay" status("on")) ("SettleDelay" status("on")) ("SettleDelayFall" status("off")) ("SettleDelayRise" status("off")) ("SwitchDelay" status("on")) ("SwitchDelayFall" status("off")) ("SwitchDelayRise" status("off"))) ("Crosstalk" ("Crosstalk" status("on"))) ("Custom")) (VectorSets) (Props (XnetName "SVID_ALERT1_CPU1_N") (allDrivers "active") (customSimType "Reflection") (ftsMode ("Typ")) (rcvrSelect "all") (tlineDelayMode "time") (userRevision "1.0")))) (Subckts) (CrossSections ("CRESCENT_CITY_191_20150122_Q" (Props (SXDesignName "CRESCENT_CITY_191_20150122_Q")) (Layers ("" (layerType "SURFACE") (material "AIR") (thickness "0 mil") (dielectricConstant "1.000000") (lossTangent "0") (etchFactor "0.000000") (elecCondVal "0 mho/cm") (thermCondVal "0 w/cm-degC")) ("" (layerType "DIELECTRIC") (material "CONFORMAL_COAT") (thickness "0.5 mil") (dielectricConstant "3.800000") (lossTangent "0.035") (etchFactor "0.000000") (elecCondVal "0 mho/cm") (thermCondVal "0.012 w/cm-degC")) ("TOP" (layerType "CONDUCTOR") (material "COPPER") (thickness "  2.100000 mil") (width "4.00 MIL") (dielectricConstant "4.500000") (lossTangent "0") (etchFactor "70.000000") (elecCondVal "595900.000000 mho/cm") (thermCondVal "0 w/cm-degC") (signalDieConstant "3.800000") (signalLossTangent "0.035")) ("" (layerType "DIELECTRIC") (material "FR-4") (thickness "  2.670000 mil") (dielectricConstant "4.000000") (lossTangent "0.035") (etchFactor "0.000000") (elecCondVal "0 mho/cm") (thermCondVal "0.012 w/cm-degC")) ("L2_GND1" (layerType "PLANE") (material "COPPER") (isShield t) (thickness "  1.250000 mil") (dielectricConstant "4.500000") (lossTangent "0.035") (etchFactor "90.000000") (elecCondVal "595900.000000 mho/cm") (thermCondVal "0.012 w/cm-degC")) ("" (layerType "DIELECTRIC") (material "FR-4") (thickness "  9.000000 mil") (dielectricConstant "4.100000") (lossTangent "0.035") (etchFactor "0.000000") (elecCondVal "0 mho/cm") (thermCondVal "0.012 w/cm-degC")) ("L3_SIG1" (layerType "CONDUCTOR") (material "COPPER") (thickness "  1.250000 mil") (width "4.00 MIL") (dielectricConstant "4.500000") (lossTangent "0.035") (etchFactor "90.000000") (elecCondVal "595900.000000 mho/cm") (thermCondVal "0.012 w/cm-degC") (signalDieConstant "4.100000") (signalLossTangent "0.035")) ("" (layerType "DIELECTRIC") (material "FR-4") (thickness "  3.000000 mil") (dielectricConstant "4.500000") (lossTangent "0.035") (etchFactor "0.000000") (elecCondVal "0 mho/cm") (thermCondVal "0 w/cm-degC")) ("L4_GND2" (layerType "PLANE") (material "COPPER") (isShield t) (thickness "  1.250000 mil") (dielectricConstant "4.500000") (lossTangent "0.035") (etchFactor "90.000000") (elecCondVal "595900.000000 mho/cm") (thermCondVal "0 w/cm-degC")) ("" (layerType "DIELECTRIC") (material "FR-4") (thickness "  9.000000 mil") (dielectricConstant "4.000000") (lossTangent "0.035") (etchFactor "0.000000") (elecCondVal "0 mho/cm") (thermCondVal "0.012 w/cm-degC")) ("L5_SIG2" (layerType "CONDUCTOR") (material "COPPER") (thickness "  1.250000 mil") (width "4.00 MIL") (dielectricConstant "4.500000") (lossTangent "0.035") (etchFactor "90.000000") (elecCondVal "595900.000000 mho/cm") (thermCondVal "0.012 w/cm-degC") (signalDieConstant "4.000000") (signalLossTangent "0.035")) ("" (layerType "DIELECTRIC") (material "FR-4") (thickness "  3.000000 mil") (dielectricConstant "4.500000") (lossTangent "0.035") (etchFactor "0.000000") (elecCondVal "0 mho/cm") (thermCondVal "0 w/cm-degC")) ("L6_GND3" (layerType "PLANE") (material "COPPER") (isShield t) (thickness "  1.250000 mil") (dielectricConstant "4.500000") (lossTangent "0.035") (etchFactor "90.000000") (elecCondVal "595900.000000 mho/cm") (thermCondVal "0 w/cm-degC")) ("" (layerType "DIELECTRIC") (material "FR-4") (thickness "  4.500000 mil") (dielectricConstant "4.100000") (lossTangent "0.035") (etchFactor "0.000000") (elecCondVal "0 mho/cm") (thermCondVal "0.012 w/cm-degC")) ("L7_PWR1-SIG" (layerType "PLANE") (material "COPPER") (isShield t) (thickness "  2.400000 mil") (dielectricConstant "4.500000") (lossTangent "0.035") (etchFactor "90.000000") (elecCondVal "595900.000000 mho/cm") (thermCondVal "0.012 w/cm-degC")) ("" (layerType "DIELECTRIC") (material "FR-4") (thickness "  4.600000 mil") (dielectricConstant "4.000000") (lossTangent "0.035") (etchFactor "0.000000") (elecCondVal "0 mho/cm") (thermCondVal "0.012 w/cm-degC")) ("L8_PWR2-SIG" (layerType "PLANE") (material "COPPER") (isShield t) (thickness "  2.400000 mil") (dielectricConstant "4.500000") (lossTangent "0.035") (etchFactor "90.000000") (elecCondVal "595900.000000 mho/cm") (thermCondVal "0.012 w/cm-degC")) ("" (layerType "DIELECTRIC") (material "FR-4") (thickness "  4.500000 mil") (dielectricConstant "4.500000") (lossTangent "0.035") (etchFactor "0.000000") (elecCondVal "0 mho/cm") (thermCondVal "0 w/cm-degC")) ("L9_GND4" (layerType "PLANE") (material "COPPER") (isShield t) (thickness "  1.250000 mil") (dielectricConstant "4.500000") (lossTangent "0.035") (etchFactor "90.000000") (elecCondVal "595900.000000 mho/cm") (thermCondVal "0 w/cm-degC")) ("" (layerType "DIELECTRIC") (material "FR-4") (thickness "  3.000000 mil") (dielectricConstant "4.100000") (lossTangent "0.035") (etchFactor "0.000000") (elecCondVal "0 mho/cm") (thermCondVal "0.012 w/cm-degC")) ("L10_SIG3" (layerType "CONDUCTOR") (material "COPPER") (thickness "  1.250000 mil") (width "4.00 MIL") (dielectricConstant "4.500000") (lossTangent "0.035") (etchFactor "90.000000") (elecCondVal "595900.000000 mho/cm") (thermCondVal "0.012 w/cm-degC") (signalDieConstant "4.100000") (signalLossTangent "0.035")) ("" (layerType "DIELECTRIC") (material "FR-4") (thickness "  9.000000 mil") (dielectricConstant "4.500000") (lossTangent "0.035") (etchFactor "0.000000") (elecCondVal "0 mho/cm") (thermCondVal "0 w/cm-degC")) ("L11_GND5" (layerType "PLANE") (material "COPPER") (isShield t) (thickness "  1.250000 mil") (dielectricConstant "4.500000") (lossTangent "0.035") (etchFactor "90.000000") (elecCondVal "595900.000000 mho/cm") (thermCondVal "0 w/cm-degC")) ("" (layerType "DIELECTRIC") (material "FR-4") (thickness "  3.000000 mil") (dielectricConstant "4.500000") (lossTangent "0.035") (etchFactor "0.000000") (elecCondVal "0 mho/cm") (thermCondVal "0.012 w/cm-degC")) ("L12_SIG4" (layerType "CONDUCTOR") (material "COPPER") (thickness "  1.250000 mil") (width "4.00 MIL") (dielectricConstant "4.500000") (lossTangent "0.035") (etchFactor "90.000000") (elecCondVal "595900.000000 mho/cm") (thermCondVal "0.012 w/cm-degC") (signalDieConstant "4.500000") (signalLossTangent "0.035")) ("" (layerType "DIELECTRIC") (material "FR-4") (thickness "  9.000000 mil") (dielectricConstant "4.500000") (lossTangent "0.035") (etchFactor "0.000000") (elecCondVal "0 mho/cm") (thermCondVal "0 w/cm-degC")) ("L13_GND6" (layerType "PLANE") (material "COPPER") (isShield t) (thickness "  1.250000 mil") (dielectricConstant "4.500000") (lossTangent "0.035") (etchFactor "90.000000") (elecCondVal "595900.000000 mho/cm") (thermCondVal "0.012 w/cm-degC")) ("" (layerType "DIELECTRIC") (material "FR-4") (thickness "  2.670000 mil") (dielectricConstant "4.500000") (lossTangent "0.035") (etchFactor "0.000000") (elecCondVal "0 mho/cm") (thermCondVal "0.012 w/cm-degC")) ("BOTTOM" (layerType "CONDUCTOR") (material "COPPER") (thickness "  2.100000 mil") (width "4.00 MIL") (dielectricConstant "4.500000") (lossTangent "0") (etchFactor "70.000000") (elecCondVal "595900.000000 mho/cm") (thermCondVal "0 w/cm-degC") (signalDieConstant "3.800000") (signalLossTangent "0.035")) ("" (layerType "DIELECTRIC") (material "CONFORMAL_COAT") (thickness "0.5 mil") (dielectricConstant "3.800000") (lossTangent "0.035") (etchFactor "0.000000") (elecCondVal "0 mho/cm") (thermCondVal "0.012 w/cm-degC")) ("" (layerType "SURFACE") (material "AIR") (thickness "0 mil") (dielectricConstant "1.000000") (lossTangent "0") (etchFactor "0.000000") (elecCondVal "0 mho/cm") (thermCondVal "0 w/cm-degC"))))) (Props (DesUnits "mils 2") (LayerStack ("DIELECTRIC" "DIELECTRIC" "BOTTOM" "DIELECTRIC" "L13_GND6" "DIELECTRIC" "L12_SIG4" "DIELECTRIC" "L11_GND5" "DIELECTRIC" "L10_SIG3" "DIELECTRIC" "L9_GND4" "DIELECTRIC" "L8_PWR2-SIG" "DIELECTRIC" "L7_PWR1-SIG" "DIELECTRIC" "L6_GND3" "DIELECTRIC" "L5_SIG2" "DIELECTRIC" "L4_GND2" "DIELECTRIC" "L3_SIG1" "DIELECTRIC" "L2_GND1" "DIELECTRIC" "TOP" "DIELECTRIC" "DIELECTRIC")) (Revision "16.600")) (Params (periodic ((periodicFreq "100e6") (periodicPattern "10") (periodicJitter "0"))) (clocked ((clockRise "1e-09") (clockFall "1e-09") (clockFreq "100e6") (clockInitState "0") (clockDutyCycle "0.5") (clockJitter "0"))) (IbisInputPkg ((temperature "27") (bufferModel "CDSDefaultInput_2p5v") (cycle "1") (LEFDEFPinName nil) (LEFDEFPinType nil) (mappingTag nil))) (IbisOutputPkg ((temperature "27") (bufferModel "CDSDefaultOutput_2p5v") (stimuli nil) (offsets nil) (state "tristate") (cycle "1") (termMap nil) (setup "2.0e-09") (hold "1.0e-09") (rise nil) (fall nil) (macroType nil) (voltage nil) (spice nil) (LEFDEFPinName nil) (LEFDEFPinType nil) (mappingTag nil))) (IbisIOPkg ((temperature "27") (bufferModel "CDSDefaultIO_2p5v") (stimuli nil) (offsets nil) (state "tristate") (cycle "1") (termMap nil) (setup "2.0e-09") (hold "1.0e-09") (rise nil) (fall nil) (macroType nil) (voltage nil) (spice nil) (LEFDEFPinName nil) (LEFDEFPinType nil) (mappingTag nil))) (IbisIOMacro ((temperature "27") (bufferModel "CDSDefaultIO_2p5v") (stimuli nil) (offsets nil) (state "tristate") (cycle "1") (termMap nil) (setup "2.0e-09") (hold "1.0e-09") (rise nil) (fall nil) (macroType nil) (voltage nil) (spice nil) (LEFDEFPinName nil) (LEFDEFPinType nil) (mappingTag nil))) (IbisInput ((temperature "27") (bufferModel "CDSDefaultInput_2p5v") (cycle "1") (LEFDEFPinName nil) (LEFDEFPinType nil) (mappingTag nil))) (DiffInputPkg ((temperature "27") (bufferModelNonInverting "CDSDefaultInput_2p5v") (bufferModelInverting "CDSDefaultInput_2p5v") (threshInputHighMin "1.7 V") (threshInputHighTyp "1.7  V") (threshInputHighMax "1.7  V") (threshInputLowMin "0.7  V") (threshInputLowTyp "0.7  V") (threshInputLowMax "0.7  V") (mappingTagNonInverting nil) (mappingTagInverting nil) (cycle "1"))) (Diode ((cutoffVoltage "0.7 V"))) (Via ((model "Unknown") (viaOutputFormat "Unknown") (viaPadstack nil) (viaTopLayer nil) (viaBottomLayer nil) (viaIsPower nil) (viaIsGround nil))) (Cable (length("1 m"))) (DualClampTerm ((cutoffVoltageUp "0.7 V") (cutoffVoltageDown "0.7 V") (voltageUp "5 V") (voltageDown "0 V") (maxDelay "0.1 ns"))) (HiClampTerm ((cutoffVoltage "0.7 V") (voltage "5 V") (maxDelay "0.1 ns"))) (LowClampTerm ((cutoffVoltage "0.7 V") (voltage "0 V") (maxDelay "0.1 ns"))) (ShuntTerm ((resistance "50 ohm") (voltage "5 V") (maxDelay "0.1 ns"))) (ESpiceDevice nil) (sync ((syncFreq "100e6") (syncInitState "1") (syncPattern "10") (syncEdgeSwitch "rise"))) (RCTerm ((resistance "50 ohm") (capacitance "20 pF") (voltage "5 V") (maxDelay "0.1 ns"))) (Trace ((d1Thickness "10 mil") (d1Constant "4.5") (d1LossTangent "0.035") (d2Thickness "10 mil") (d2Constant "4.5") (d2LossTangent "0.035") (d3Thickness "0.0") (d3Constant "1.0") (d3LossTangent "0") length("1000 mil") (spacing "5 mil") (spacing2 "5 mil") (spacing3 "5 mil") (spacing4 "5 mil") (spacing5 "5 mil") (traceConductivity "595900 mho/cm") (traceGeometry "microstrip") (traceLayerName "") (traceThickness "0.72 mil") (traceType "single") (traceWidth "5.0 mil") (traceWidth2 "5.0 mil") (traceWidth3 "5.0 mil") (traceWidth4 "5.0 mil") (traceWidth5 "5.0 mil") (traceWidth6 "5.0 mil") (offset "0 mil") (traceCount "1") (impedance nil))) (TheveninTerm ((resistanceUp "180 ohm") (resistanceDown "270 ohm") (voltageUp "5 V") (voltageDown "0 V") (maxDelay "0.1 ns"))) (DiffInput ((temperature "27") (bufferModelNonInverting "CDSDefaultInput_2p5v") (bufferModelInverting "CDSDefaultInput_2p5v") (threshInputHighMin "1.7 V") (threshInputHighTyp "1.7  V") (threshInputHighMax "1.7  V") (threshInputLowMin "0.7  V") (threshInputLowTyp "0.7  V") (threshInputLowMax "0.7  V") (mappingTagNonInverting nil) (mappingTagInverting nil) (cycle "1"))) (DiffOutputPkg ((temperature "27") (bufferModelNonInverting "CDSDefaultOutput_2p5v") (bufferModelInverting "CDSDefaultOutput_2p5v") (stimuli nil) (offsets nil) (state "tristate") (cycle "1") (termMap nil) (setup "0.9e-09") (hold "0.4e-09") (rise nil) (fall nil) (threshOutputHighMin "2.375  V") (threshOutputHighTyp "2.5  V") (threshOutputHighMax "2.625  V") (threshOutputLowMin "1.275  V") (threshOutputLowTyp "1.7  V") (threshOutputLowMax "1.985  V") (mappingTagNonInverting nil) (mappingTagInverting nil) (spice nil))) (DiffOutput ((temperature "27") (bufferModelNonInverting "CDSDefaultOutput_2p5v") (bufferModelInverting "CDSDefaultOutput_2p5v") (stimuli nil) (offsets nil) (state "tristate") (cycle "1") (termMap nil) (setup "0.9e-09") (hold "0.4e-09") (rise nil) (fall nil) (threshOutputHighMin "2.375  V") (threshOutputHighTyp "2.5  V") (threshOutputHighMax "2.625  V") (threshOutputLowMin "1.275  V") (threshOutputLowTyp "1.7  V") (threshOutputLowMax "1.985  V") (mappingTagNonInverting nil) (mappingTagInverting nil) (spice nil))) (async ((asyncTimePoints "") (asyncInitState "1"))) (DiffIOPkg ((temperature "27") (bufferModelNonInverting "CDSDefaultIO_2p5v") (bufferModelInverting "CDSDefaultIO_2p5v") (stimuli nil) (offsets nil) (state "tristate") (cycle "1") (termMap nil) (setup "0.9e-09") (hold "0.4e-09") (rise nil) (fall nil) (threshInputHighMin "1.7 V") (threshInputHighTyp "1.7  V") (threshInputHighMax "1.7  V") (threshInputLowMin "0.7  V") (threshInputLowTyp "0.7  V") (threshInputLowMax "0.7 ") (threshOutputHighMin "2.365  V") (threshOutputHighTyp "2.5  V") (threshOutputHighMax "2.625  V") (threshOutputLowMin "1.275  V") (threshOutputLowTyp "1.7  V") (threshOutputLowMax "1.985  V") (mappingTagNonInverting nil) (mappingTagInverting nil) (spice nil))) (SeriesTerm ((resistance "22 ohm") (maxDelay "0.1 ns"))) (CurrentProbe nil) (DiffIO ((temperature "27") (bufferModelNonInverting "CDSDefaultIO_2p5v") (bufferModelInverting "CDSDefaultIO_2p5v") (stimuli nil) (offsets nil) (state "tristate") (cycle "1") (termMap nil) (setup "0.9e-09") (hold "0.4e-09") (rise nil) (fall nil) (threshInputHighMin "1.7 V") (threshInputHighTyp "1.7  V") (threshInputHighMax "1.7  V") (threshInputLowMin "0.7  V") (threshInputLowTyp "0.7  V") (threshInputLowMax "0.7 ") (threshOutputHighMin "2.365  V") (threshOutputHighTyp "2.5  V") (threshOutputHighMax "2.625  V") (threshOutputLowMin "1.275  V") (threshOutputLowTyp "1.7  V") (threshOutputLowMax "1.985  V") (mappingTagNonInverting nil) (mappingTagInverting nil) (spice nil))) (CPWSL ((d1Thickness "10 mil") (d1Constant "4.5") (d1LossTangent "0.035") (d2Thickness "0.72 mil") (d2Constant "4.5") (d2LossTangent "0.035") (d3Thickness "10 mil") (d3Constant "4.5") (d3LossTangent "0.035") length("1000 mil") (spacing "5 mil") (spacing2 "5 mil") (spacing3 "5 mil") (spacing4 "5 mil") (spacing5 "5 mil") (traceConductivity "595900 mho/cm") (traceGeometry "cpwms") (traceLayerName "") (traceThickness "0.72 mil") (traceType "single") (traceWidth "5.0 mil") (traceWidth2 "5.0 mil") (traceWidth3 "5.0 mil") (traceWidth4 "5.0 mil") (traceWidth5 "5.0 mil") (traceWidth6 "5.0 mil") (offset "0 mil") (traceCount "1") (impedance nil))) (RLGC (length("1000 mil"))) (Source ((voltage "5 V"))) (IbisIO_OpenPullDown ((temperature "27") (bufferModel "CDSDefaultIO_2p5v") (stimuli nil) (offsets nil) (state "tristate") (cycle "1") (termMap nil) (setup "2.0e-09") (hold "1.0e-09") (rise nil) (fall nil) (macroType nil) (voltage nil) (spice nil) (LEFDEFPinName nil) (LEFDEFPinType nil) (mappingTag nil))) (CPW ((d1Thickness "10 mil") (d1Constant "4.5") (d1LossTangent "0.035") (d2Thickness "0.72 mil") (d2Constant "1") (d2LossTangent "0") (d3Thickness "0.0") (d3Constant "1") (d3LossTangent "0") length("1000 mil") (spacing "5 mil") (spacing2 "5 mil") (spacing3 "5 mil") (spacing4 "5 mil") (spacing5 "5 mil") (traceConductivity "595900 mho/cm") (traceGeometry "cpwms") (traceLayerName "") (traceThickness "0.72 mil") (traceType "single") (traceWidth "5.0 mil") (traceWidth2 "5.0 mil") (traceWidth3 "5.0 mil") (traceWidth4 "5.0 mil") (traceWidth5 "5.0 mil") (traceWidth6 "5.0 mil") (offset "0 mil") (traceCount "1") (impedance nil))) (Inductor ((inductance "5 nH") (orientation "0"))) (IbisIO_OpenPullUp ((temperature "27") (bufferModel "CDSDefaultIO_2p5v") (stimuli nil) (offsets nil) (state "tristate") (cycle "1") (termMap nil) (setup "2.0e-09") (hold "1.0e-09") (rise nil) (fall nil) (macroType nil) (voltage nil) (spice nil) (LEFDEFPinName nil) (LEFDEFPinType nil) (mappingTag nil))) (idlCircuit ((allDrivers "active") (ftsMode '("Typ")) (rcvrSelect "all") (simMode "Reflection") (tlineDelayMode "time") (userRevision "1.0") (autoSolve "On"))) (IbisIO ((temperature "27") (bufferModel "CDSDefaultIO_2p5v") (stimuli nil) (offsets nil) (state "tristate") (cycle "1") (termMap nil) (setup "2.0e-09") (hold "1.0e-09") (rise nil) (fall nil) (macroType nil) (voltage nil) (spice nil) (LEFDEFPinName nil) (LEFDEFPinType nil) (mappingTag nil))) (CPWMS ((d1Thickness "10 mil") (d1Constant "4.5") (d1LossTangent "0.035") (d2Thickness "0.72 mil") (d2Constant "4.5") (d2LossTangent "0.035") (d3Thickness "0.0") (d3Constant "1") (d3LossTangent "0") length("1000 mil") (spacing "5 mil") (spacing2 "5 mil") (spacing3 "5 mil") (spacing4 "5 mil") (spacing5 "5 mil") (traceConductivity "595900 mho/cm") (traceGeometry "cpwms") (traceLayerName "") (traceThickness "0.72 mil") (traceType "single") (traceWidth "5.0 mil") (traceWidth2 "5.0 mil") (traceWidth3 "5.0 mil") (traceWidth4 "5.0 mil") (traceWidth5 "5.0 mil") (traceWidth6 "5.0 mil") (offset "0 mil") (traceCount "1") (impedance nil))) (TLine ((diffImpedance "100ohm") (diffVelocity "1.4142e+08M/s") (impedance "60ohm") length("2800 mil") (propDelay "0.5 ns") (velocity "5600 mil/ns") (traceCount "1") (traceGeometry "Microstrip") (impedanceMin nil) (impedanceMax nil) (lengthMin nil) (lengthMax nil) (propDelayMin nil) (propDelayMax nil) (impedanceSweepCount nil) (propDelaySweepCount nil) (velocitySweepCount nil) (lengthSweepCount nil) (matchSetName nil))) (Capacitor ((capacitance "10 pF") (orientation "0"))) (IbisOutput ((temperature "27") (bufferModel "CDSDefaultOutput_2p5v") (stimuli nil) (offsets nil) (state "tristate") (cycle "1") (termMap nil) (setup "2.0e-09") (hold "1.0e-09") (rise nil) (fall nil) (macroType nil) (voltage nil) (spice nil) (LEFDEFPinName nil) (LEFDEFPinType nil) (mappingTag nil))) (Resistor ((resistance "50 ohm") (orientation "0"))) (IbisOutput_OpenPullUp ((temperature "27") (bufferModel "CDSDefaultOutput_2p5v") (stimuli nil) (offsets nil) (state "tristate") (cycle "1") (termMap nil) (setup "2.0e-09") (hold "1.0e-09") (rise nil) (fall nil) (macroType nil) (voltage nil) (spice nil) (LEFDEFPinName nil) (LEFDEFPinType nil) (mappingTag nil))) (Connector nil)))
				)
				( objectStatus "SVID_CPU1" )
			)
			( electricalCSet "@baseboard_fab2_lib.baseboard_fab2(sch_1):\SVID_ALERT1_CPU1_N\"
				( groupRef "SVID_ALERT1_CPU1_N:#SVID_CPU1_1_U100-EU76" )
				( groupRef "SVID_ALERT1_CPU1_N:#SVID_CPU1_1_U100-EU77" )
				( pinPairRef "SVID_ALERT1_CPU1_N:EU1G2.17:U2D1.DL44" )
				( pinPairRef "SVID_ALERT1_CPU1_N:EU1B1.17:U2D1.DL44" )
				( pinPairRef "SVID_ALERT1_CPU1_N:U2D1.DL44:R1C1.1" )
				( pinPairRef "SVID_ALERT1_CPU1_N:R1G9.2:R1C1.2" )
				( pinPairRef "SVID_ALERT1_CPU1_N:R1C1.2:R9N1.2" )
				( pinPairRef "SVID_ALERT1_CPU1_N:EU1B1.17:R1B11.1" )
				( pinPairRef "SVID_ALERT1_CPU1_N:EU1G2.17:R1G9.1" )
				( attribute "TOPOLOGY_TEMPLATE_REVISION" "1.0"
					( Origin gBackEnd )
				)
				( topologyData 28436
(SKIDL (Circuits ("MAIN" (Parts ("CRESCENT_CITY_195_20150128_Q.@@EU76.17" IbisOutputPkg (xy (5492 4226)) (refDes "EU1G2") (model "Unknown") (Props (_SXDesignName "CRESCENT_CITY_195_20150128_Q") (brdx "371.38 MIL") (brdy "146.5 MIL") (bufferModel "CDSDefaultOutput_2p5v") (cycle "1") (hold "1.0e-09") (mappingTag "") (offsets ("4" "0")) (setup "2.0e-09") (state "tristate") (stimuli ("4" "local99")) (temperature "27") (termMap ("4" "Data"))) (Terms ("CRESCENT_CITY_195_20150128_Q.X37138Y14650L2LRATS" "17"))) ("CRESCENT_CITY_195_20150128_Q.@@EU77.17" IbisOutputPkg (xy (5498 4235)) (refDes "EU1B1") (model "Unknown") (Props (_SXDesignName "CRESCENT_CITY_195_20150128_Q") (brdx "-15.5 MIL") (brdy "5014.38 MIL") (bufferModel "CDSDefaultOutput_2p5v") (cycle "1") (hold "1.0e-09") (mappingTag "") (offsets ("4" "0")) (setup "2.0e-09") (state "tristate") (stimuli ("4" "local100")) (temperature "27") (termMap ("4" "Data"))) (Terms ("CRESCENT_CITY_195_20150128_Q.Xn1550Y501438L2LRATS" "17"))) ("CRESCENT_CITY_195_20150128_Q.@@U100.DL44" IbisInputPkg (xy (5583 4235)) (refDes "U2D1") (model "Unknown") (Props (_SXDesignName "CRESCENT_CITY_195_20150128_Q") (brdx "4086.86 MIL") (brdy "3709.59 MIL") (bufferModel "CDSDefaultInput_2p5v") (mappingTag "") (temperature "27")) (Terms ("CRESCENT_CITY_195_20150128_Q.X408686Y370959L2LRATS" "DL44"))) ("CRESCENT_CITY_195_20150128_Q.T@@RATS@@R2077.1@@EU77.17" TLine (xy (5506 4235)) (mirror x) (refDes "TL152") (Props (_SXDesignName "CRESCENT_CITY_195_20150128_Q") (impedance "48.412 ohm") length("97.12 MIL") (propDelay "0.01744 ns") (traceCount "1") (traceGeometry "Microstrip") (velocity "5568.82 mil/ns")) (Terms ("CRESCENT_CITY_195_20150128_Q.Xn9900Y502800L2LRATS" "1") ("CRESCENT_CITY_195_20150128_Q.Xn1550Y501438L2LRATS" "2"))) ("CRESCENT_CITY_195_20150128_Q.T@@RATS@@R1286.2@@R1452.2" TLine (xy (5545 4235)) (refDes "TL153") (Props (_SXDesignName "CRESCENT_CITY_195_20150128_Q") (impedance "48.412 ohm") (propDelay "1.79607e-006 ns") (traceCount "1") (traceGeometry "Microstrip")) (Terms ("CRESCENT_CITY_195_20150128_Q.X151142Y419700L30LRATS" "1") ("CRESCENT_CITY_195_20150128_Q.X151142Y419700L2LRATS" "2"))) ("CRESCENT_CITY_195_20150128_Q.@@R2056.2.1" Resistor (xy (5521 4226)) (mirror x) (refDes "R1G9") (value "2.2e-007 Ohm") (Props (_SXDesignName "CRESCENT_CITY_195_20150128_Q")) (Terms ("CRESCENT_CITY_195_20150128_Q.X38500Y26500L2LRATS" "2") ("CRESCENT_CITY_195_20150128_Q.X38500Y23000L2LRATS" "1"))) ("CRESCENT_CITY_195_20150128_Q.T@@RATS@@R2056.1@@EU76.17" TLine (xy (5506 4226)) (mirror x) (refDes "TL154") (Props (_SXDesignName "CRESCENT_CITY_195_20150128_Q") (impedance "48.412 ohm") length("97.12 MIL") (propDelay "0.01744 ns") (traceCount "1") (traceGeometry "Microstrip") (velocity "5568.82 mil/ns")) (Terms ("CRESCENT_CITY_195_20150128_Q.X38500Y23000L2LRATS" "1") ("CRESCENT_CITY_195_20150128_Q.X37138Y14650L2LRATS" "2"))) ("CRESCENT_CITY_195_20150128_Q.@@R1286.1_SOURCE" Source (xy (5523 4220)) (refDes "PVCCIO_CPU1") (value "1 V") (Props (_SXDesignName "CRESCENT_CITY_195_20150128_Q")) (Terms ("CRESCENT_CITY_195_20150128_Q.X154642Y419700L30RATS" "1"))) ("CRESCENT_CITY_195_20150128_Q.@@R2077.1.2" Resistor (xy (5521 4235)) (refDes "R1B11") (value "2.2e-007 Ohm") (Props (_SXDesignName "CRESCENT_CITY_195_20150128_Q")) (Terms ("CRESCENT_CITY_195_20150128_Q.Xn9900Y502800L2LRATS" "1") ("CRESCENT_CITY_195_20150128_Q.Xn13400Y502800L2LRATS" "2"))) ("CRESCENT_CITY_195_20150128_Q.T@@RATS@@R2056.2@@R1286.2" TLine (xy (5530 4226)) (refDes "TL155") (Props (_SXDesignName "CRESCENT_CITY_195_20150128_Q") (impedance "48.412 ohm") length("5058.43 MIL") (propDelay "0.90853 ns") (traceCount "1") (traceGeometry "Microstrip") (velocity "5567.72 mil/ns")) (Terms ("CRESCENT_CITY_195_20150128_Q.X38500Y26500L2LRATS" "1") ("CRESCENT_CITY_195_20150128_Q.X151142Y419700L30LRATS" "2"))) ("CRESCENT_CITY_195_20150128_Q.T@@RATS@@U100.DL44@@R1452.1" TLine (xy (5569 4235)) (mirror x) (refDes "TL156") (Props (_SXDesignName "CRESCENT_CITY_195_20150128_Q") (impedance "49.728 ohm") length("3027.85 MIL") (propDelay "0.54382 ns") (traceCount "1") (traceGeometry "Microstrip") (velocity "5567.76 mil/ns")) (Terms ("CRESCENT_CITY_195_20150128_Q.X408686Y370959L2LRATS" "1") ("CRESCENT_CITY_195_20150128_Q.X154642Y419700L2LRATS" "2"))) ("CRESCENT_CITY_195_20150128_Q.@@R1452.1.2" Resistor (xy (5554 4235)) (mirror x) (refDes "R1C1") (value "220 Ohm") (Props (_SXDesignName "CRESCENT_CITY_195_20150128_Q")) (Terms ("CRESCENT_CITY_195_20150128_Q.X154642Y419700L2LRATS" "1") ("CRESCENT_CITY_195_20150128_Q.X151142Y419700L2LRATS" "2"))) ("CRESCENT_CITY_195_20150128_Q.T@@RATS@@R1286.2@@R2077.2" TLine (xy (5530 4235)) (mirror x) (refDes "TL157") (Props (_SXDesignName "CRESCENT_CITY_195_20150128_Q") (impedance "48.412 ohm") length("2476.42 MIL") (propDelay "0.44478 ns") (traceCount "1") (traceGeometry "Microstrip") (velocity "5567.76 mil/ns")) (Terms ("CRESCENT_CITY_195_20150128_Q.X151142Y419700L30LRATS" "1") ("CRESCENT_CITY_195_20150128_Q.Xn13400Y502800L2LRATS" "2"))) ("CRESCENT_CITY_195_20150128_Q.@@R1286.1.2" Resistor (xy (5530 4220)) (refDes "R9N1") (value "49.9 Ohm") (Props (_SXDesignName "CRESCENT_CITY_195_20150128_Q")) (Terms ("CRESCENT_CITY_195_20150128_Q.X154642Y419700L30RATS" "1") ("CRESCENT_CITY_195_20150128_Q.X151142Y419700L30LRATS" "2")))) (Nodes ("CRESCENT_CITY_195_20150128_Q.Xn13400Y502800L2LRATS" (terms "CRESCENT_CITY_195_20150128_Q.T@@RATS@@R1286.2@@R2077.2.2" "CRESCENT_CITY_195_20150128_Q.@@R2077.1.2.2")) ("CRESCENT_CITY_195_20150128_Q.X37138Y14650L2LRATS" (terms "CRESCENT_CITY_195_20150128_Q.T@@RATS@@R2056.1@@EU76.17.2" "CRESCENT_CITY_195_20150128_Q.@@EU76.17.1")) ("CRESCENT_CITY_195_20150128_Q.X408686Y370959L2LRATS" (terms "CRESCENT_CITY_195_20150128_Q.T@@RATS@@U100.DL44@@R1452.1.1" "CRESCENT_CITY_195_20150128_Q.@@U100.DL44.1")) ("CRESCENT_CITY_195_20150128_Q.Xn1550Y501438L2LRATS" (terms "CRESCENT_CITY_195_20150128_Q.T@@RATS@@R2077.1@@EU77.17.2" "CRESCENT_CITY_195_20150128_Q.@@EU77.17.1")) ("CRESCENT_CITY_195_20150128_Q.X154642Y419700L30RATS" (terms "CRESCENT_CITY_195_20150128_Q.@@R1286.1.2.1" "CRESCENT_CITY_195_20150128_Q.@@R1286.1_SOURCE.1")) ("CRESCENT_CITY_195_20150128_Q.X151142Y419700L30LRATS" (terms "CRESCENT_CITY_195_20150128_Q.@@R1286.1.2.2" "CRESCENT_CITY_195_20150128_Q.T@@RATS@@R1286.2@@R2077.2.1" "CRESCENT_CITY_195_20150128_Q.T@@RATS@@R2056.2@@R1286.2.2" "CRESCENT_CITY_195_20150128_Q.T@@RATS@@R1286.2@@R1452.2.1")) ("CRESCENT_CITY_195_20150128_Q.Xn9900Y502800L2LRATS" (terms "CRESCENT_CITY_195_20150128_Q.@@R2077.1.2.1" "CRESCENT_CITY_195_20150128_Q.T@@RATS@@R2077.1@@EU77.17.1")) ("CRESCENT_CITY_195_20150128_Q.X154642Y419700L2LRATS" (terms "CRESCENT_CITY_195_20150128_Q.@@R1452.1.2.1" "CRESCENT_CITY_195_20150128_Q.T@@RATS@@U100.DL44@@R1452.1.2")) ("CRESCENT_CITY_195_20150128_Q.X38500Y23000L2LRATS" (terms "CRESCENT_CITY_195_20150128_Q.T@@RATS@@R2056.1@@EU76.17.1" "CRESCENT_CITY_195_20150128_Q.@@R2056.2.1.2")) ("CRESCENT_CITY_195_20150128_Q.X151142Y419700L2LRATS" (terms "CRESCENT_CITY_195_20150128_Q.@@R1452.1.2.2" "CRESCENT_CITY_195_20150128_Q.T@@RATS@@R1286.2@@R1452.2.2")) ("CRESCENT_CITY_195_20150128_Q.X38500Y26500L2LRATS" (terms "CRESCENT_CITY_195_20150128_Q.T@@RATS@@R2056.2@@R1286.2.1" "CRESCENT_CITY_195_20150128_Q.@@R2056.2.1.1"))) (Ports) (Stimuli ("local99" (scope local) (stimType periodic) (Props (periodicFreq "5e+007") (periodicJitter "0") (periodicPattern "1"))) ("local100" (scope local) (stimType periodic) (Props (periodicFreq "5e+007") (periodicJitter "0") (periodicPattern "1")))) (Notes) (Constraints ("DELAY_RULE" ("CRESCENT_CITY_195_20150128_Q U100.DL44" "CRESCENT_CITY_195_20150128_Q R1452.1" "LENGTH" "" "LENGTH" "0.1143") ("CRESCENT_CITY_195_20150128_Q R2077.1" "CRESCENT_CITY_195_20150128_Q EU77.17" "LENGTH" "" "LENGTH" "0.254") ("CRESCENT_CITY_195_20150128_Q R2056.2" "CRESCENT_CITY_195_20150128_Q R1452.2" "LENGTH" "" "LENGTH" "0.6858") ("CRESCENT_CITY_195_20150128_Q R2056.1" "CRESCENT_CITY_195_20150128_Q EU76.17" "LENGTH" "" "LENGTH" "0.254") ("CRESCENT_CITY_195_20150128_Q R1452.2" "CRESCENT_CITY_195_20150128_Q R1286.2" "LENGTH" "" "LENGTH" "0.01016")) ("RELATIVE_PROPAGATION_DELAY" ("#SVID_CPU1_1_U100-EU76" "CRESCENT_CITY_195_20150128_Q EU76.17" "CRESCENT_CITY_195_20150128_Q U100.DL44" "GLOBAL" "LENGTH" "0.00635" "NONE" "") ("#SVID_CPU1_1_U100-EU77" "CRESCENT_CITY_195_20150128_Q EU77.17" "CRESCENT_CITY_195_20150128_Q U100.DL44" "GLOBAL" "LENGTH" "0.00635" "NONE" ""))) (MeasurementSets ("EMI" ("EMIStatus" status("on")) ("PeakEmission" status("on")) ("PeakFrequency" status("on")) ("PulseFreq" status("on")) ("RiseTime" status("on")) ("VoltageSwing" status("on"))) ("Reflection" ("BufferDelayFall" status("off")) ("BufferDelayRise" status("off")) ("EyeHeight" status("off")) ("EyeJitter" status("off")) ("EyeWidth" status("off")) ("FirstIncidentFall" status("off")) ("FirstIncidentRise" status("off")) ("Glitch" status("on")) ("GlitchFall" status("off")) ("GlitchRise" status("off")) ("Monotonic" status("on")) ("MonotonicFall" status("off")) ("MonotonicRise" status("off")) ("NoiseMargin" status("on")) ("NoiseMarginHigh" status("off")) ("NoiseMarginLow" status("off")) ("OvershootHigh" status("on")) ("OvershootLow" status("on")) ("PropDelay" status("on")) ("SettleDelay" status("on")) ("SettleDelayFall" status("off")) ("SettleDelayRise" status("off")) ("SwitchDelay" status("on")) ("SwitchDelayFall" status("off")) ("SwitchDelayRise" status("off"))) ("Crosstalk" ("Crosstalk" status("on"))) ("Custom")) (VectorSets) (Props (XnetName "SVID_ALERT1_CPU1_N") (allDrivers "active") (customSimType "Reflection") (ftsMode ("Typ")) (rcvrSelect "all") (tlineDelayMode "time") (userRevision "1.0")))) (Subckts) (CrossSections ("CRESCENT_CITY_195_20150128_Q" (Props (SXDesignName "CRESCENT_CITY_195_20150128_Q")) (Layers ("" (layerType "SURFACE") (material "AIR") (thickness "0 mil") (dielectricConstant "1.000000") (lossTangent "0") (etchFactor "0.000000") (elecCondVal "0 mho/cm") (thermCondVal "0 w/cm-degC")) ("" (layerType "DIELECTRIC") (material "CONFORMAL_COAT") (thickness "0.5 mil") (dielectricConstant "3.800000") (lossTangent "0.035") (etchFactor "0.000000") (elecCondVal "0 mho/cm") (thermCondVal "0.012 w/cm-degC")) ("TOP" (layerType "CONDUCTOR") (material "COPPER") (thickness "  2.100000 mil") (width "4.00 MIL") (dielectricConstant "4.500000") (lossTangent "0") (etchFactor "70.000000") (elecCondVal "595900.000000 mho/cm") (thermCondVal "0 w/cm-degC") (signalDieConstant "3.800000") (signalLossTangent "0.035")) ("" (layerType "DIELECTRIC") (material "FR-4") (thickness "  2.670000 mil") (dielectricConstant "4.000000") (lossTangent "0.035") (etchFactor "0.000000") (elecCondVal "0 mho/cm") (thermCondVal "0.012 w/cm-degC")) ("L2_GND1" (layerType "PLANE") (material "COPPER") (isShield t) (thickness "  1.250000 mil") (dielectricConstant "4.500000") (lossTangent "0.035") (etchFactor "90.000000") (elecCondVal "595900.000000 mho/cm") (thermCondVal "0.012 w/cm-degC")) ("" (layerType "DIELECTRIC") (material "FR-4") (thickness "  9.000000 mil") (dielectricConstant "4.100000") (lossTangent "0.035") (etchFactor "0.000000") (elecCondVal "0 mho/cm") (thermCondVal "0.012 w/cm-degC")) ("L3_SIG1" (layerType "CONDUCTOR") (material "COPPER") (thickness "  1.250000 mil") (width "4.00 MIL") (dielectricConstant "4.500000") (lossTangent "0.035") (etchFactor "90.000000") (elecCondVal "595900.000000 mho/cm") (thermCondVal "0.012 w/cm-degC") (signalDieConstant "4.100000") (signalLossTangent "0.035")) ("" (layerType "DIELECTRIC") (material "FR-4") (thickness "  3.000000 mil") (dielectricConstant "4.500000") (lossTangent "0.035") (etchFactor "0.000000") (elecCondVal "0 mho/cm") (thermCondVal "0 w/cm-degC")) ("L4_GND2" (layerType "PLANE") (material "COPPER") (isShield t) (thickness "  1.250000 mil") (dielectricConstant "4.500000") (lossTangent "0.035") (etchFactor "90.000000") (elecCondVal "595900.000000 mho/cm") (thermCondVal "0 w/cm-degC")) ("" (layerType "DIELECTRIC") (material "FR-4") (thickness "  9.000000 mil") (dielectricConstant "4.000000") (lossTangent "0.035") (etchFactor "0.000000") (elecCondVal "0 mho/cm") (thermCondVal "0.012 w/cm-degC")) ("L5_SIG2" (layerType "CONDUCTOR") (material "COPPER") (thickness "  1.250000 mil") (width "4.00 MIL") (dielectricConstant "4.500000") (lossTangent "0.035") (etchFactor "90.000000") (elecCondVal "595900.000000 mho/cm") (thermCondVal "0.012 w/cm-degC") (signalDieConstant "4.000000") (signalLossTangent "0.035")) ("" (layerType "DIELECTRIC") (material "FR-4") (thickness "  3.000000 mil") (dielectricConstant "4.500000") (lossTangent "0.035") (etchFactor "0.000000") (elecCondVal "0 mho/cm") (thermCondVal "0 w/cm-degC")) ("L6_GND3" (layerType "PLANE") (material "COPPER") (isShield t) (thickness "  1.250000 mil") (dielectricConstant "4.500000") (lossTangent "0.035") (etchFactor "90.000000") (elecCondVal "595900.000000 mho/cm") (thermCondVal "0 w/cm-degC")) ("" (layerType "DIELECTRIC") (material "FR-4") (thickness "  4.500000 mil") (dielectricConstant "4.100000") (lossTangent "0.035") (etchFactor "0.000000") (elecCondVal "0 mho/cm") (thermCondVal "0.012 w/cm-degC")) ("L7_PWR1-SIG" (layerType "PLANE") (material "COPPER") (isShield t) (thickness "  2.400000 mil") (dielectricConstant "4.500000") (lossTangent "0.035") (etchFactor "90.000000") (elecCondVal "595900.000000 mho/cm") (thermCondVal "0.012 w/cm-degC")) ("" (layerType "DIELECTRIC") (material "FR-4") (thickness "  4.600000 mil") (dielectricConstant "4.000000") (lossTangent "0.035") (etchFactor "0.000000") (elecCondVal "0 mho/cm") (thermCondVal "0.012 w/cm-degC")) ("L8_PWR2-SIG" (layerType "PLANE") (material "COPPER") (isShield t) (thickness "  2.400000 mil") (dielectricConstant "4.500000") (lossTangent "0.035") (etchFactor "90.000000") (elecCondVal "595900.000000 mho/cm") (thermCondVal "0.012 w/cm-degC")) ("" (layerType "DIELECTRIC") (material "FR-4") (thickness "  8.000000 mil") (dielectricConstant "4.500000") (lossTangent "0.035") (etchFactor "0.000000") (elecCondVal "0 mho/cm") (thermCondVal "0 w/cm-degC")) ("" (layerType "DIELECTRIC") (material "FR-4") (thickness "  8.000000 mil") (dielectricConstant "4.500000") (lossTangent "0.035") (etchFactor "0.000000") (elecCondVal "0 mho/cm") (thermCondVal "0 w/cm-degC")) ("" (layerType "DIELECTRIC") (material "FR-4") (thickness "  4.500000 mil") (dielectricConstant "4.500000") (lossTangent "0.035") (etchFactor "0.000000") (elecCondVal "0 mho/cm") (thermCondVal "0 w/cm-degC")) ("L9_GND4" (layerType "PLANE") (material "COPPER") (isShield t) (thickness "  1.250000 mil") (dielectricConstant "4.500000") (lossTangent "0.035") (etchFactor "90.000000") (elecCondVal "595900.000000 mho/cm") (thermCondVal "0 w/cm-degC")) ("" (layerType "DIELECTRIC") (material "FR-4") (thickness "  3.000000 mil") (dielectricConstant "4.100000") (lossTangent "0.035") (etchFactor "0.000000") (elecCondVal "0 mho/cm") (thermCondVal "0.012 w/cm-degC")) ("L10_SIG3" (layerType "CONDUCTOR") (material "COPPER") (thickness "  1.250000 mil") (width "4.00 MIL") (dielectricConstant "4.500000") (lossTangent "0.035") (etchFactor "90.000000") (elecCondVal "595900.000000 mho/cm") (thermCondVal "0.012 w/cm-degC") (signalDieConstant "4.100000") (signalLossTangent "0.035")) ("" (layerType "DIELECTRIC") (material "FR-4") (thickness "  9.000000 mil") (dielectricConstant "4.500000") (lossTangent "0.035") (etchFactor "0.000000") (elecCondVal "0 mho/cm") (thermCondVal "0 w/cm-degC")) ("L11_GND5" (layerType "PLANE") (material "COPPER") (isShield t) (thickness "  1.250000 mil") (dielectricConstant "4.500000") (lossTangent "0.035") (etchFactor "90.000000") (elecCondVal "595900.000000 mho/cm") (thermCondVal "0 w/cm-degC")) ("" (layerType "DIELECTRIC") (material "FR-4") (thickness "  3.000000 mil") (dielectricConstant "4.500000") (lossTangent "0.035") (etchFactor "0.000000") (elecCondVal "0 mho/cm") (thermCondVal "0.012 w/cm-degC")) ("L12_SIG4" (layerType "CONDUCTOR") (material "COPPER") (thickness "  1.250000 mil") (width "4.00 MIL") (dielectricConstant "4.500000") (lossTangent "0.035") (etchFactor "90.000000") (elecCondVal "595900.000000 mho/cm") (thermCondVal "0.012 w/cm-degC") (signalDieConstant "4.500000") (signalLossTangent "0.035")) ("" (layerType "DIELECTRIC") (material "FR-4") (thickness "  9.000000 mil") (dielectricConstant "4.500000") (lossTangent "0.035") (etchFactor "0.000000") (elecCondVal "0 mho/cm") (thermCondVal "0 w/cm-degC")) ("L13_GND6" (layerType "PLANE") (material "COPPER") (isShield t) (thickness "  1.250000 mil") (dielectricConstant "4.500000") (lossTangent "0.035") (etchFactor "90.000000") (elecCondVal "595900.000000 mho/cm") (thermCondVal "0.012 w/cm-degC")) ("" (layerType "DIELECTRIC") (material "FR-4") (thickness "  2.670000 mil") (dielectricConstant "4.500000") (lossTangent "0.035") (etchFactor "0.000000") (elecCondVal "0 mho/cm") (thermCondVal "0.012 w/cm-degC")) ("BOTTOM" (layerType "CONDUCTOR") (material "COPPER") (thickness "  2.100000 mil") (width "4.00 MIL") (dielectricConstant "4.500000") (lossTangent "0") (etchFactor "70.000000") (elecCondVal "595900.000000 mho/cm") (thermCondVal "0 w/cm-degC") (signalDieConstant "3.800000") (signalLossTangent "0.035")) ("" (layerType "DIELECTRIC") (material "CONFORMAL_COAT") (thickness "0.5 mil") (dielectricConstant "3.800000") (lossTangent "0.035") (etchFactor "0.000000") (elecCondVal "0 mho/cm") (thermCondVal "0.012 w/cm-degC")) ("" (layerType "SURFACE") (material "AIR") (thickness "0 mil") (dielectricConstant "1.000000") (lossTangent "0") (etchFactor "0.000000") (elecCondVal "0 mho/cm") (thermCondVal "0 w/cm-degC"))))) (Props (DesUnits "mils 2") (LayerStack ("DIELECTRIC" "DIELECTRIC" "BOTTOM" "DIELECTRIC" "L13_GND6" "DIELECTRIC" "L12_SIG4" "DIELECTRIC" "L11_GND5" "DIELECTRIC" "L10_SIG3" "DIELECTRIC" "L9_GND4" "DIELECTRIC" "DIELECTRIC" "DIELECTRIC" "L8_PWR2-SIG" "DIELECTRIC" "L7_PWR1-SIG" "DIELECTRIC" "L6_GND3" "DIELECTRIC" "L5_SIG2" "DIELECTRIC" "L4_GND2" "DIELECTRIC" "L3_SIG1" "DIELECTRIC" "L2_GND1" "DIELECTRIC" "TOP" "DIELECTRIC" "DIELECTRIC")) (Revision "16.600")) (Params (DiffOutputPkg ((temperature "27") (bufferModelNonInverting "CDSDefaultOutput_2p5v") (bufferModelInverting "CDSDefaultOutput_2p5v") (stimuli nil) (offsets nil) (state "tristate") (cycle "1") (termMap nil) (setup "0.9e-09") (hold "0.4e-09") (rise nil) (fall nil) (threshOutputHighMin "2.375  V") (threshOutputHighTyp "2.5  V") (threshOutputHighMax "2.625  V") (threshOutputLowMin "1.275  V") (threshOutputLowTyp "1.7  V") (threshOutputLowMax "1.985  V") (mappingTagNonInverting nil) (mappingTagInverting nil) (spice nil))) (HiClampTerm ((cutoffVoltage "0.7 V") (voltage "5 V") (maxDelay "0.1 ns"))) (LowClampTerm ((cutoffVoltage "0.7 V") (voltage "0 V") (maxDelay "0.1 ns"))) (DiffOutput ((temperature "27") (bufferModelNonInverting "CDSDefaultOutput_2p5v") (bufferModelInverting "CDSDefaultOutput_2p5v") (stimuli nil) (offsets nil) (state "tristate") (cycle "1") (termMap nil) (setup "0.9e-09") (hold "0.4e-09") (rise nil) (fall nil) (threshOutputHighMin "2.375  V") (threshOutputHighTyp "2.5  V") (threshOutputHighMax "2.625  V") (threshOutputLowMin "1.275  V") (threshOutputLowTyp "1.7  V") (threshOutputLowMax "1.985  V") (mappingTagNonInverting nil) (mappingTagInverting nil) (spice nil))) (Via ((model "Unknown") (viaOutputFormat "Unknown") (viaPadstack nil) (viaTopLayer nil) (viaBottomLayer nil) (viaIsPower nil) (viaIsGround nil))) (Resistor ((resistance "50 ohm") (orientation "0"))) (RCTerm ((resistance "50 ohm") (capacitance "20 pF") (voltage "5 V") (maxDelay "0.1 ns"))) (DiffIOPkg ((temperature "27") (bufferModelNonInverting "CDSDefaultIO_2p5v") (bufferModelInverting "CDSDefaultIO_2p5v") (stimuli nil) (offsets nil) (state "tristate") (cycle "1") (termMap nil) (setup "0.9e-09") (hold "0.4e-09") (rise nil) (fall nil) (threshInputHighMin "1.7 V") (threshInputHighTyp "1.7  V") (threshInputHighMax "1.7  V") (threshInputLowMin "0.7  V") (threshInputLowTyp "0.7  V") (threshInputLowMax "0.7 ") (threshOutputHighMin "2.365  V") (threshOutputHighTyp "2.5  V") (threshOutputHighMax "2.625  V") (threshOutputLowMin "1.275  V") (threshOutputLowTyp "1.7  V") (threshOutputLowMax "1.985  V") (mappingTagNonInverting nil) (mappingTagInverting nil) (spice nil))) (Trace ((d1Thickness "10 mil") (d1Constant "4.5") (d1LossTangent "0.035") (d2Thickness "10 mil") (d2Constant "4.5") (d2LossTangent "0.035") (d3Thickness "0.0") (d3Constant "1.0") (d3LossTangent "0") length("1000 mil") (spacing "5 mil") (spacing2 "5 mil") (spacing3 "5 mil") (spacing4 "5 mil") (spacing5 "5 mil") (traceConductivity "595900 mho/cm") (traceGeometry "microstrip") (traceLayerName "") (traceThickness "0.72 mil") (traceType "single") (traceWidth "5.0 mil") (traceWidth2 "5.0 mil") (traceWidth3 "5.0 mil") (traceWidth4 "5.0 mil") (traceWidth5 "5.0 mil") (traceWidth6 "5.0 mil") (offset "0 mil") (traceCount "1") (impedance nil))) (TheveninTerm ((resistanceUp "180 ohm") (resistanceDown "270 ohm") (voltageUp "5 V") (voltageDown "0 V") (maxDelay "0.1 ns"))) (DiffIO ((temperature "27") (bufferModelNonInverting "CDSDefaultIO_2p5v") (bufferModelInverting "CDSDefaultIO_2p5v") (stimuli nil) (offsets nil) (state "tristate") (cycle "1") (termMap nil) (setup "0.9e-09") (hold "0.4e-09") (rise nil) (fall nil) (threshInputHighMin "1.7 V") (threshInputHighTyp "1.7  V") (threshInputHighMax "1.7  V") (threshInputLowMin "0.7  V") (threshInputLowTyp "0.7  V") (threshInputLowMax "0.7 ") (threshOutputHighMin "2.365  V") (threshOutputHighTyp "2.5  V") (threshOutputHighMax "2.625  V") (threshOutputLowMin "1.275  V") (threshOutputLowTyp "1.7  V") (threshOutputLowMax "1.985  V") (mappingTagNonInverting nil) (mappingTagInverting nil) (spice nil))) (ShuntTerm ((resistance "50 ohm") (voltage "5 V") (maxDelay "0.1 ns"))) (Inductor ((inductance "5 nH") (orientation "0"))) (Capacitor ((capacitance "10 pF") (orientation "0"))) (RLGC (length("1000 mil"))) (Source ((voltage "5 V"))) (DiffInput ((temperature "27") (bufferModelNonInverting "CDSDefaultInput_2p5v") (bufferModelInverting "CDSDefaultInput_2p5v") (threshInputHighMin "1.7 V") (threshInputHighTyp "1.7  V") (threshInputHighMax "1.7  V") (threshInputLowMin "0.7  V") (threshInputLowTyp "0.7  V") (threshInputLowMax "0.7  V") (mappingTagNonInverting nil) (mappingTagInverting nil) (cycle "1"))) (Cable (length("1 m"))) (CPWSL ((d1Thickness "10 mil") (d1Constant "4.5") (d1LossTangent "0.035") (d2Thickness "0.72 mil") (d2Constant "4.5") (d2LossTangent "0.035") (d3Thickness "10 mil") (d3Constant "4.5") (d3LossTangent "0.035") length("1000 mil") (spacing "5 mil") (spacing2 "5 mil") (spacing3 "5 mil") (spacing4 "5 mil") (spacing5 "5 mil") (traceConductivity "595900 mho/cm") (traceGeometry "cpwms") (traceLayerName "") (traceThickness "0.72 mil") (traceType "single") (traceWidth "5.0 mil") (traceWidth2 "5.0 mil") (traceWidth3 "5.0 mil") (traceWidth4 "5.0 mil") (traceWidth5 "5.0 mil") (traceWidth6 "5.0 mil") (offset "0 mil") (traceCount "1") (impedance nil))) (ESpiceDevice nil) (CPWMS ((d1Thickness "10 mil") (d1Constant "4.5") (d1LossTangent "0.035") (d2Thickness "0.72 mil") (d2Constant "4.5") (d2LossTangent "0.035") (d3Thickness "0.0") (d3Constant "1") (d3LossTangent "0") length("1000 mil") (spacing "5 mil") (spacing2 "5 mil") (spacing3 "5 mil") (spacing4 "5 mil") (spacing5 "5 mil") (traceConductivity "595900 mho/cm") (traceGeometry "cpwms") (traceLayerName "") (traceThickness "0.72 mil") (traceType "single") (traceWidth "5.0 mil") (traceWidth2 "5.0 mil") (traceWidth3 "5.0 mil") (traceWidth4 "5.0 mil") (traceWidth5 "5.0 mil") (traceWidth6 "5.0 mil") (offset "0 mil") (traceCount "1") (impedance nil))) (Diode ((cutoffVoltage "0.7 V"))) (CPW ((d1Thickness "10 mil") (d1Constant "4.5") (d1LossTangent "0.035") (d2Thickness "0.72 mil") (d2Constant "1") (d2LossTangent "0") (d3Thickness "0.0") (d3Constant "1") (d3LossTangent "0") length("1000 mil") (spacing "5 mil") (spacing2 "5 mil") (spacing3 "5 mil") (spacing4 "5 mil") (spacing5 "5 mil") (traceConductivity "595900 mho/cm") (traceGeometry "cpwms") (traceLayerName "") (traceThickness "0.72 mil") (traceType "single") (traceWidth "5.0 mil") (traceWidth2 "5.0 mil") (traceWidth3 "5.0 mil") (traceWidth4 "5.0 mil") (traceWidth5 "5.0 mil") (traceWidth6 "5.0 mil") (offset "0 mil") (traceCount "1") (impedance nil))) (DualClampTerm ((cutoffVoltageUp "0.7 V") (cutoffVoltageDown "0.7 V") (voltageUp "5 V") (voltageDown "0 V") (maxDelay "0.1 ns"))) (IbisOutputPkg ((temperature "27") (bufferModel "CDSDefaultOutput_2p5v") (stimuli nil) (offsets nil) (state "tristate") (cycle "1") (termMap nil) (setup "2.0e-09") (hold "1.0e-09") (rise nil) (fall nil) (macroType nil) (voltage nil) (spice nil) (LEFDEFPinName nil) (LEFDEFPinType nil) (mappingTag nil))) (IbisIO_OpenPullDown ((temperature "27") (bufferModel "CDSDefaultIO_2p5v") (stimuli nil) (offsets nil) (state "tristate") (cycle "1") (termMap nil) (setup "2.0e-09") (hold "1.0e-09") (rise nil) (fall nil) (macroType nil) (voltage nil) (spice nil) (LEFDEFPinName nil) (LEFDEFPinType nil) (mappingTag nil))) (IbisInputPkg ((temperature "27") (bufferModel "CDSDefaultInput_2p5v") (cycle "1") (LEFDEFPinName nil) (LEFDEFPinType nil) (mappingTag nil))) (IbisIOMacro ((temperature "27") (bufferModel "CDSDefaultIO_2p5v") (stimuli nil) (offsets nil) (state "tristate") (cycle "1") (termMap nil) (setup "2.0e-09") (hold "1.0e-09") (rise nil) (fall nil) (macroType nil) (voltage nil) (spice nil) (LEFDEFPinName nil) (LEFDEFPinType nil) (mappingTag nil))) (IbisIO_OpenPullUp ((temperature "27") (bufferModel "CDSDefaultIO_2p5v") (stimuli nil) (offsets nil) (state "tristate") (cycle "1") (termMap nil) (setup "2.0e-09") (hold "1.0e-09") (rise nil) (fall nil) (macroType nil) (voltage nil) (spice nil) (LEFDEFPinName nil) (LEFDEFPinType nil) (mappingTag nil))) (IbisIOPkg ((temperature "27") (bufferModel "CDSDefaultIO_2p5v") (stimuli nil) (offsets nil) (state "tristate") (cycle "1") (termMap nil) (setup "2.0e-09") (hold "1.0e-09") (rise nil) (fall nil) (macroType nil) (voltage nil) (spice nil) (LEFDEFPinName nil) (LEFDEFPinType nil) (mappingTag nil))) (clocked ((clockRise "1e-09") (clockFall "1e-09") (clockFreq "100e6") (clockInitState "0") (clockDutyCycle "0.5") (clockJitter "0"))) (periodic ((periodicFreq "100e6") (periodicPattern "10") (periodicJitter "0"))) (IbisIO ((temperature "27") (bufferModel "CDSDefaultIO_2p5v") (stimuli nil) (offsets nil) (state "tristate") (cycle "1") (termMap nil) (setup "2.0e-09") (hold "1.0e-09") (rise nil) (fall nil) (macroType nil) (voltage nil) (spice nil) (LEFDEFPinName nil) (LEFDEFPinType nil) (mappingTag nil))) (async ((asyncTimePoints "") (asyncInitState "1"))) (IbisOutput ((temperature "27") (bufferModel "CDSDefaultOutput_2p5v") (stimuli nil) (offsets nil) (state "tristate") (cycle "1") (termMap nil) (setup "2.0e-09") (hold "1.0e-09") (rise nil) (fall nil) (macroType nil) (voltage nil) (spice nil) (LEFDEFPinName nil) (LEFDEFPinType nil) (mappingTag nil))) (TLine ((diffImpedance "100ohm") (diffVelocity "1.4142e+08M/s") (impedance "60ohm") length("2800 mil") (propDelay "0.5 ns") (velocity "5600 mil/ns") (traceCount "1") (traceGeometry "Microstrip") (impedanceMin nil) (impedanceMax nil) (lengthMin nil) (lengthMax nil) (propDelayMin nil) (propDelayMax nil) (impedanceSweepCount nil) (propDelaySweepCount nil) (velocitySweepCount nil) (lengthSweepCount nil) (matchSetName nil))) (CurrentProbe nil) (IbisInput ((temperature "27") (bufferModel "CDSDefaultInput_2p5v") (cycle "1") (LEFDEFPinName nil) (LEFDEFPinType nil) (mappingTag nil))) (SeriesTerm ((resistance "22 ohm") (maxDelay "0.1 ns"))) (Connector nil) (sync ((syncFreq "100e6") (syncInitState "1") (syncPattern "10") (syncEdgeSwitch "rise"))) (IbisOutput_OpenPullUp ((temperature "27") (bufferModel "CDSDefaultOutput_2p5v") (stimuli nil) (offsets nil) (state "tristate") (cycle "1") (termMap nil) (setup "2.0e-09") (hold "1.0e-09") (rise nil) (fall nil) (macroType nil) (voltage nil) (spice nil) (LEFDEFPinName nil) (LEFDEFPinType nil) (mappingTag nil))) (DiffInputPkg ((temperature "27") (bufferModelNonInverting "CDSDefaultInput_2p5v") (bufferModelInverting "CDSDefaultInput_2p5v") (threshInputHighMin "1.7 V") (threshInputHighTyp "1.7  V") (threshInputHighMax "1.7  V") (threshInputLowMin "0.7  V") (threshInputLowTyp "0.7  V") (threshInputLowMax "0.7  V") (mappingTagNonInverting nil) (mappingTagInverting nil) (cycle "1"))) (idlCircuit ((allDrivers "active") (ftsMode '("Typ")) (rcvrSelect "all") (simMode "Reflection") (tlineDelayMode "time") (userRevision "1.0") (autoSolve "On")))))
				)
				( objectStatus "SVID_ALERT1_CPU1_N" )
			)
			( electricalCSet "@crescent_city_bb_fab1_lib.crescent_city_bb_fab1(sch_1):\NIC_MDI_0-1\"
				( attribute "PROPAGATION_DELAY_PATH_TYPE" "D:R"
					( Origin gBackEnd )
				)
				( attribute "PROPAGATION_DELAY_MAX" "3500.00 MIL"
					( Units "uMaxMinProp" "ns" 1.000000)
					( Origin gBackEnd )
				)
				( attribute "DIFFP_GATHER_CONTROL" "IGNORE"
					( Origin gBackEnd )
				)
				( attribute "DIFFP_UNCOUPLED_LENGTH" "10.00"
					( Origin gBackEnd )
				)
				( attribute "DIFFP_COUPLED_PLUS" "0.10"
					( Origin gBackEnd )
				)
				( attribute "DIFFP_COUPLED_MINUS" "0.10"
					( Origin gBackEnd )
				)
				( attribute "DIFFP_PHASE_TOL" "30 mil"
					( Units "uPhaseTol" "ns" 1.000000)
					( Origin gBackEnd )
				)
				( attribute "DIFFP_PHASE_MAX_LENGTH" "600.00"
					( Origin gBackEnd )
				)
				( attribute "DIFFP_PHASE_TOL_DYNAMIC" "30 mil"
					( Units "uPhaseTol" "mil" 1.000000)
					( Origin gBackEnd )
				)
				( attribute "TOPOLOGY_TEMPLATE_REVISION" "1.0"
					( Origin gBackEnd )
				)
				( topologyData 23293
(SKIDL (Circuits ("MAIN" (Parts ("CRESCENT_CITY_181_20150105_A.@@EU46.57" IbisIOPkg (xy (5521 4228)) (refDes "EU9E1") (model "Unknown") (Props (_SXDesignName "CRESCENT_CITY_181_20150105_A") (brdx "19189.84 MIL") (brdy "1593 MIL") (bufferModel "CDSDefaultIO_2p5v") (cycle "1") (hold "1.0e-09") (mappingTag "") (offsets ("4" "0") ("5" "0")) (setup "2.0e-09") (state "tristate") (stimuli ("4" "local19") ("5" "local20")) (temperature "27") (termMap ("4" "Data") ("5" "Enable"))) (Terms ("CRESCENT_CITY_181_20150105_A.X1918984Y159300L2LRATS" "57"))) ("CRESCENT_CITY_181_20150105_A.@@JA4.10" IbisIOPkg (xy (5502 4240)) (refDes "JA9G1") (model "Unknown") (Props (_SXDesignName "CRESCENT_CITY_181_20150105_A") (brdx "18970 MIL") (brdy "71.9 MIL") (bufferModel "CDSDefaultIO_2p5v") (cycle "1") (hold "1.0e-09") (mappingTag "") (offsets ("4" "0") ("5" "0")) (setup "2.0e-09") (state "tristate") (stimuli ("4" "local21") ("5" "local22")) (temperature "27") (termMap ("4" "Data") ("5" "Enable"))) (Terms ("CRESCENT_CITY_181_20150105_A.X1897000Y7190L2LRATS" "10"))) ("CRESCENT_CITY_181_20150105_A.@@R34.1.2" Resistor (xy (5491 4223)) (mirror x) (refDes "R9G22") (value "0.001 Ohm") (Props (_SXDesignName "CRESCENT_CITY_181_20150105_A")) (Terms ("CRESCENT_CITY_181_20150105_A.X1883000Y10500L2LRATS" "1") ("CRESCENT_CITY_181_20150105_A.X1886500Y10500L2LRATS" "2"))) ("CRESCENT_CITY_181_20150105_A.T@@RATS@@EU46.57@@R34.1" TLine (xy (5506 4223)) (mirror x) (refDes "TL1") (Props (_SXDesignName "CRESCENT_CITY_181_20150105_A") (impedance "49.675 ohm") length("1847.84 MIL") (propDelay "0.33188 ns") (traceCount "1") (traceGeometry "Microstrip") (velocity "5567.8 mil/ns")) (Terms ("CRESCENT_CITY_181_20150105_A.X1918984Y159300L2LRATS" "1") ("CRESCENT_CITY_181_20150105_A.X1883000Y10500L2LRATS" "2"))) ("CRESCENT_CITY_181_20150105_A.T@@RATS@@R34.2@@JA4.10" TLine (xy (5497 4229)) (refDes "TL2") (Props (_SXDesignName "CRESCENT_CITY_181_20150105_A") (impedance "49.675 ohm") length("138.10 MIL") (propDelay "0.0248 ns") (traceCount "1") (traceGeometry "Microstrip") (velocity "5568.54 mil/ns")) (Terms ("CRESCENT_CITY_181_20150105_A.X1886500Y10500L2LRATS" "1") ("CRESCENT_CITY_181_20150105_A.X1897000Y7190L2LRATS" "2")))) (Nodes ("CRESCENT_CITY_181_20150105_A.X1918984Y159300L2LRATS" (terms "CRESCENT_CITY_181_20150105_A.T@@RATS@@EU46.57@@R34.1.1" "CRESCENT_CITY_181_20150105_A.@@EU46.57.1")) ("CRESCENT_CITY_181_20150105_A.X1883000Y10500L2LRATS" (terms "CRESCENT_CITY_181_20150105_A.T@@RATS@@EU46.57@@R34.1.2" "CRESCENT_CITY_181_20150105_A.@@R34.1.2.1")) ("CRESCENT_CITY_181_20150105_A.X1886500Y10500L2LRATS" (terms "CRESCENT_CITY_181_20150105_A.T@@RATS@@R34.2@@JA4.10.1" "CRESCENT_CITY_181_20150105_A.@@R34.1.2.2")) ("CRESCENT_CITY_181_20150105_A.X1897000Y7190L2LRATS" (terms "CRESCENT_CITY_181_20150105_A.T@@RATS@@R34.2@@JA4.10.2" "CRESCENT_CITY_181_20150105_A.@@JA4.10.1"))) (Ports) (Stimuli ("local22" (scope local) (stimType periodic) (Props (periodicFreq "5e+007") (periodicJitter "0") (periodicPattern "1"))) ("local20" (scope local) (stimType periodic) (Props (periodicFreq "5e+007") (periodicJitter "0") (periodicPattern "1"))) ("local21" (scope local) (stimType periodic) (Props (periodicFreq "5e+007") (periodicJitter "0") (periodicPattern "1"))) ("local19" (scope local) (stimType periodic) (Props (periodicFreq "5e+007") (periodicJitter "0") (periodicPattern "1")))) (Notes) (Constraints ("DELAY_RULE" ("DRIVER" "RECEIVER" "LENGTH" "" "LENGTH" "0.0889")) ("DP_GATHER_CONTROL" "IGNORE") ("DP_NEGATIVE_COUPLED_TOLERANCE" "2.54e-006") ("DP_PHASE_MAX_LENGTH" "0.01524") ("DP_PHASE_TOLERANCE" ("LENGTH" "0.000762")) ("DP_PHASE_TOLERANCE_DYNAMIC" ("LENGTH" "0.000762")) ("DP_POSITIVE_COUPLED_TOLERANCE" "2.54e-006")) (MeasurementSets ("EMI" ("EMIStatus" status("on")) ("PeakEmission" status("on")) ("PeakFrequency" status("on")) ("PulseFreq" status("on")) ("RiseTime" status("on")) ("VoltageSwing" status("on"))) ("Reflection" ("BufferDelayFall" status("off")) ("BufferDelayRise" status("off")) ("EyeHeight" status("off")) ("EyeJitter" status("off")) ("EyeWidth" status("off")) ("FirstIncidentFall" status("off")) ("FirstIncidentRise" status("off")) ("Glitch" status("on")) ("GlitchFall" status("off")) ("GlitchRise" status("off")) ("Monotonic" status("on")) ("MonotonicFall" status("off")) ("MonotonicRise" status("off")) ("NoiseMargin" status("on")) ("NoiseMarginHigh" status("off")) ("NoiseMarginLow" status("off")) ("OvershootHigh" status("on")) ("OvershootLow" status("on")) ("PropDelay" status("on")) ("SettleDelay" status("on")) ("SettleDelayFall" status("off")) ("SettleDelayRise" status("off")) ("SwitchDelay" status("on")) ("SwitchDelayFall" status("off")) ("SwitchDelayRise" status("off"))) ("Crosstalk" ("Crosstalk" status("on"))) ("Custom")) (VectorSets) (Props (XnetName "NIC_MDI_SPRV_RJ45_0_DN") (allDrivers "active") (customSimType "Reflection") (ftsMode ("Typ")) (rcvrSelect "all") (tlineDelayMode "time") (userRevision "1.0")))) (Subckts) (CrossSections ("CRESCENT_CITY_181_20150105_A" (Props (SXDesignName "CRESCENT_CITY_181_20150105_A")) (Layers ("" (layerType "SURFACE") (material "AIR") (thickness "0 mil") (dielectricConstant "1.000000") (lossTangent "0") (etchFactor "0.000000") (elecCondVal "0 mho/cm") (thermCondVal "0 w/cm-degC")) ("" (layerType "DIELECTRIC") (material "CONFORMAL_COAT") (thickness "0.5 mil") (dielectricConstant "3.800000") (lossTangent "0.035") (etchFactor "0.000000") (elecCondVal "0 mho/cm") (thermCondVal "0.012 w/cm-degC")) ("TOP" (layerType "CONDUCTOR") (material "COPPER") (thickness "  2.100000 mil") (width "4.00 MIL") (dielectricConstant "4.500000") (lossTangent "0") (etchFactor "70.000000") (elecCondVal "595900.000000 mho/cm") (thermCondVal "0 w/cm-degC") (signalDieConstant "3.800000") (signalLossTangent "0.035")) ("" (layerType "DIELECTRIC") (material "FR-4") (thickness "  2.670000 mil") (dielectricConstant "4.000000") (lossTangent "0.035") (etchFactor "0.000000") (elecCondVal "0 mho/cm") (thermCondVal "0.012 w/cm-degC")) ("L2_GND1" (layerType "PLANE") (material "COPPER") (isShield t) (thickness "  1.250000 mil") (dielectricConstant "4.500000") (lossTangent "0.035") (etchFactor "90.000000") (elecCondVal "595900.000000 mho/cm") (thermCondVal "0.012 w/cm-degC")) ("" (layerType "DIELECTRIC") (material "FR-4") (thickness "  9.000000 mil") (dielectricConstant "4.100000") (lossTangent "0.035") (etchFactor "0.000000") (elecCondVal "0 mho/cm") (thermCondVal "0.012 w/cm-degC")) ("L3_SIG1" (layerType "CONDUCTOR") (material "COPPER") (thickness "  1.250000 mil") (width "4.00 MIL") (dielectricConstant "4.500000") (lossTangent "0.035") (etchFactor "90.000000") (elecCondVal "595900.000000 mho/cm") (thermCondVal "0.012 w/cm-degC") (signalDieConstant "4.100000") (signalLossTangent "0.035")) ("" (layerType "DIELECTRIC") (material "FR-4") (thickness "  3.000000 mil") (dielectricConstant "4.500000") (lossTangent "0.035") (etchFactor "0.000000") (elecCondVal "0 mho/cm") (thermCondVal "0 w/cm-degC")) ("L4_GND2" (layerType "PLANE") (material "COPPER") (isShield t) (thickness "  1.250000 mil") (dielectricConstant "4.500000") (lossTangent "0.035") (etchFactor "90.000000") (elecCondVal "595900.000000 mho/cm") (thermCondVal "0 w/cm-degC")) ("" (layerType "DIELECTRIC") (material "FR-4") (thickness "  9.000000 mil") (dielectricConstant "4.000000") (lossTangent "0.035") (etchFactor "0.000000") (elecCondVal "0 mho/cm") (thermCondVal "0.012 w/cm-degC")) ("L5_SIG2" (layerType "CONDUCTOR") (material "COPPER") (thickness "  1.250000 mil") (width "4.00 MIL") (dielectricConstant "4.500000") (lossTangent "0.035") (etchFactor "90.000000") (elecCondVal "595900.000000 mho/cm") (thermCondVal "0.012 w/cm-degC") (signalDieConstant "4.000000") (signalLossTangent "0.035")) ("" (layerType "DIELECTRIC") (material "FR-4") (thickness "  3.000000 mil") (dielectricConstant "4.500000") (lossTangent "0.035") (etchFactor "0.000000") (elecCondVal "0 mho/cm") (thermCondVal "0 w/cm-degC")) ("L6_GND3" (layerType "PLANE") (material "COPPER") (isShield t) (thickness "  1.250000 mil") (dielectricConstant "4.500000") (lossTangent "0.035") (etchFactor "90.000000") (elecCondVal "595900.000000 mho/cm") (thermCondVal "0 w/cm-degC")) ("" (layerType "DIELECTRIC") (material "FR-4") (thickness "  4.500000 mil") (dielectricConstant "4.100000") (lossTangent "0.035") (etchFactor "0.000000") (elecCondVal "0 mho/cm") (thermCondVal "0.012 w/cm-degC")) ("L7_PWR1-SIG" (layerType "PLANE") (material "COPPER") (isShield t) (thickness "  2.400000 mil") (dielectricConstant "4.500000") (lossTangent "0.035") (etchFactor "90.000000") (elecCondVal "595900.000000 mho/cm") (thermCondVal "0.012 w/cm-degC")) ("" (layerType "DIELECTRIC") (material "FR-4") (thickness "  4.600000 mil") (dielectricConstant "4.000000") (lossTangent "0.035") (etchFactor "0.000000") (elecCondVal "0 mho/cm") (thermCondVal "0.012 w/cm-degC")) ("L8_PWR2-SIG" (layerType "PLANE") (material "COPPER") (isShield t) (thickness "  2.400000 mil") (dielectricConstant "4.500000") (lossTangent "0.035") (etchFactor "90.000000") (elecCondVal "595900.000000 mho/cm") (thermCondVal "0.012 w/cm-degC")) ("" (layerType "DIELECTRIC") (material "FR-4") (thickness "  4.500000 mil") (dielectricConstant "4.500000") (lossTangent "0.035") (etchFactor "0.000000") (elecCondVal "0 mho/cm") (thermCondVal "0 w/cm-degC")) ("L9_GND4" (layerType "PLANE") (material "COPPER") (isShield t) (thickness "  1.250000 mil") (dielectricConstant "4.500000") (lossTangent "0.035") (etchFactor "90.000000") (elecCondVal "595900.000000 mho/cm") (thermCondVal "0 w/cm-degC")) ("" (layerType "DIELECTRIC") (material "FR-4") (thickness "  3.000000 mil") (dielectricConstant "4.100000") (lossTangent "0.035") (etchFactor "0.000000") (elecCondVal "0 mho/cm") (thermCondVal "0.012 w/cm-degC")) ("L10_SIG3" (layerType "CONDUCTOR") (material "COPPER") (thickness "  1.250000 mil") (width "4.00 MIL") (dielectricConstant "4.500000") (lossTangent "0.035") (etchFactor "90.000000") (elecCondVal "595900.000000 mho/cm") (thermCondVal "0.012 w/cm-degC") (signalDieConstant "4.100000") (signalLossTangent "0.035")) ("" (layerType "DIELECTRIC") (material "FR-4") (thickness "  9.000000 mil") (dielectricConstant "4.500000") (lossTangent "0.035") (etchFactor "0.000000") (elecCondVal "0 mho/cm") (thermCondVal "0 w/cm-degC")) ("L11_GND5" (layerType "PLANE") (material "COPPER") (isShield t) (thickness "  1.250000 mil") (dielectricConstant "4.500000") (lossTangent "0.035") (etchFactor "90.000000") (elecCondVal "595900.000000 mho/cm") (thermCondVal "0 w/cm-degC")) ("" (layerType "DIELECTRIC") (material "FR-4") (thickness "  3.000000 mil") (dielectricConstant "4.500000") (lossTangent "0.035") (etchFactor "0.000000") (elecCondVal "0 mho/cm") (thermCondVal "0.012 w/cm-degC")) ("L12_SIG4" (layerType "CONDUCTOR") (material "COPPER") (thickness "  1.250000 mil") (width "4.00 MIL") (dielectricConstant "4.500000") (lossTangent "0.035") (etchFactor "90.000000") (elecCondVal "595900.000000 mho/cm") (thermCondVal "0.012 w/cm-degC") (signalDieConstant "4.500000") (signalLossTangent "0.035")) ("" (layerType "DIELECTRIC") (material "FR-4") (thickness "  9.000000 mil") (dielectricConstant "4.500000") (lossTangent "0.035") (etchFactor "0.000000") (elecCondVal "0 mho/cm") (thermCondVal "0 w/cm-degC")) ("L13_GND6" (layerType "PLANE") (material "COPPER") (isShield t) (thickness "  1.250000 mil") (dielectricConstant "4.500000") (lossTangent "0.035") (etchFactor "90.000000") (elecCondVal "595900.000000 mho/cm") (thermCondVal "0.012 w/cm-degC")) ("" (layerType "DIELECTRIC") (material "FR-4") (thickness "  2.670000 mil") (dielectricConstant "4.500000") (lossTangent "0.035") (etchFactor "0.000000") (elecCondVal "0 mho/cm") (thermCondVal "0.012 w/cm-degC")) ("BOTTOM" (layerType "CONDUCTOR") (material "COPPER") (thickness "  2.100000 mil") (width "4.00 MIL") (dielectricConstant "4.500000") (lossTangent "0") (etchFactor "70.000000") (elecCondVal "595900.000000 mho/cm") (thermCondVal "0 w/cm-degC") (signalDieConstant "3.800000") (signalLossTangent "0.035")) ("" (layerType "DIELECTRIC") (material "CONFORMAL_COAT") (thickness "0.5 mil") (dielectricConstant "3.800000") (lossTangent "0.035") (etchFactor "0.000000") (elecCondVal "0 mho/cm") (thermCondVal "0.012 w/cm-degC")) ("" (layerType "SURFACE") (material "AIR") (thickness "0 mil") (dielectricConstant "1.000000") (lossTangent "0") (etchFactor "0.000000") (elecCondVal "0 mho/cm") (thermCondVal "0 w/cm-degC"))))) (Props (DesUnits "mils 2") (LayerStack ("DIELECTRIC" "DIELECTRIC" "BOTTOM" "DIELECTRIC" "L13_GND6" "DIELECTRIC" "L12_SIG4" "DIELECTRIC" "L11_GND5" "DIELECTRIC" "L10_SIG3" "DIELECTRIC" "L9_GND4" "DIELECTRIC" "L8_PWR2-SIG" "DIELECTRIC" "L7_PWR1-SIG" "DIELECTRIC" "L6_GND3" "DIELECTRIC" "L5_SIG2" "DIELECTRIC" "L4_GND2" "DIELECTRIC" "L3_SIG1" "DIELECTRIC" "L2_GND1" "DIELECTRIC" "TOP" "DIELECTRIC" "DIELECTRIC")) (Revision "16.600")) (Params (LowClampTerm ((cutoffVoltage "0.7 V") (voltage "0 V") (maxDelay "0.1 ns"))) (IbisInputPkg ((temperature "27") (bufferModel "CDSDefaultInput_2p5v") (cycle "1") (LEFDEFPinName nil) (LEFDEFPinType nil) (mappingTag nil))) (SeriesTerm ((resistance "22 ohm") (maxDelay "0.1 ns"))) (RCTerm ((resistance "50 ohm") (capacitance "20 pF") (voltage "5 V") (maxDelay "0.1 ns"))) (TheveninTerm ((resistanceUp "180 ohm") (resistanceDown "270 ohm") (voltageUp "5 V") (voltageDown "0 V") (maxDelay "0.1 ns"))) (CurrentProbe nil) (IbisIOPkg ((temperature "27") (bufferModel "CDSDefaultIO_2p5v") (stimuli nil) (offsets nil) (state "tristate") (cycle "1") (termMap nil) (setup "2.0e-09") (hold "1.0e-09") (rise nil) (fall nil) (macroType nil) (voltage nil) (spice nil) (LEFDEFPinName nil) (LEFDEFPinType nil) (mappingTag nil))) (ShuntTerm ((resistance "50 ohm") (voltage "5 V") (maxDelay "0.1 ns"))) (IbisOutputPkg ((temperature "27") (bufferModel "CDSDefaultOutput_2p5v") (stimuli nil) (offsets nil) (state "tristate") (cycle "1") (termMap nil) (setup "2.0e-09") (hold "1.0e-09") (rise nil) (fall nil) (macroType nil) (voltage nil) (spice nil) (LEFDEFPinName nil) (LEFDEFPinType nil) (mappingTag nil))) (clocked ((clockRise "1e-09") (clockFall "1e-09") (clockFreq "100e6") (clockInitState "0") (clockDutyCycle "0.5") (clockJitter "0"))) (Diode ((cutoffVoltage "0.7 V"))) (IbisOutput_OpenPullUp ((temperature "27") (bufferModel "CDSDefaultOutput_2p5v") (stimuli nil) (offsets nil) (state "tristate") (cycle "1") (termMap nil) (setup "2.0e-09") (hold "1.0e-09") (rise nil) (fall nil) (macroType nil) (voltage nil) (spice nil) (LEFDEFPinName nil) (LEFDEFPinType nil) (mappingTag nil))) (Trace ((d1Thickness "10 mil") (d1Constant "4.5") (d1LossTangent "0.035") (d2Thickness "10 mil") (d2Constant "4.5") (d2LossTangent "0.035") (d3Thickness "0.0") (d3Constant "1.0") (d3LossTangent "0") length("1000 mil") (spacing "5 mil") (spacing2 "5 mil") (spacing3 "5 mil") (spacing4 "5 mil") (spacing5 "5 mil") (traceConductivity "595900 mho/cm") (traceGeometry "microstrip") (traceLayerName "") (traceThickness "0.72 mil") (traceType "single") (traceWidth "5.0 mil") (traceWidth2 "5.0 mil") (traceWidth3 "5.0 mil") (traceWidth4 "5.0 mil") (traceWidth5 "5.0 mil") (traceWidth6 "5.0 mil") (offset "0 mil") (traceCount "1") (impedance nil))) (DualClampTerm ((cutoffVoltageUp "0.7 V") (cutoffVoltageDown "0.7 V") (voltageUp "5 V") (voltageDown "0 V") (maxDelay "0.1 ns"))) (Via ((model "Unknown") (viaOutputFormat "Unknown") (viaPadstack nil) (viaTopLayer nil) (viaBottomLayer nil) (viaIsPower nil) (viaIsGround nil))) (periodic ((periodicFreq "100e6") (periodicPattern "10") (periodicJitter "0"))) (IbisIO_OpenPullDown ((temperature "27") (bufferModel "CDSDefaultIO_2p5v") (stimuli nil) (offsets nil) (state "tristate") (cycle "1") (termMap nil) (setup "2.0e-09") (hold "1.0e-09") (rise nil) (fall nil) (macroType nil) (voltage nil) (spice nil) (LEFDEFPinName nil) (LEFDEFPinType nil) (mappingTag nil))) (IbisIO_OpenPullUp ((temperature "27") (bufferModel "CDSDefaultIO_2p5v") (stimuli nil) (offsets nil) (state "tristate") (cycle "1") (termMap nil) (setup "2.0e-09") (hold "1.0e-09") (rise nil) (fall nil) (macroType nil) (voltage nil) (spice nil) (LEFDEFPinName nil) (LEFDEFPinType nil) (mappingTag nil))) (HiClampTerm ((cutoffVoltage "0.7 V") (voltage "5 V") (maxDelay "0.1 ns"))) (CPWMS ((d1Thickness "10 mil") (d1Constant "4.5") (d1LossTangent "0.035") (d2Thickness "0.72 mil") (d2Constant "4.5") (d2LossTangent "0.035") (d3Thickness "0.0") (d3Constant "1") (d3LossTangent "0") length("1000 mil") (spacing "5 mil") (spacing2 "5 mil") (spacing3 "5 mil") (spacing4 "5 mil") (spacing5 "5 mil") (traceConductivity "595900 mho/cm") (traceGeometry "cpwms") (traceLayerName "") (traceThickness "0.72 mil") (traceType "single") (traceWidth "5.0 mil") (traceWidth2 "5.0 mil") (traceWidth3 "5.0 mil") (traceWidth4 "5.0 mil") (traceWidth5 "5.0 mil") (traceWidth6 "5.0 mil") (offset "0 mil") (traceCount "1") (impedance nil))) (Cable (length("1 m"))) (ESpiceDevice nil) (CPW ((d1Thickness "10 mil") (d1Constant "4.5") (d1LossTangent "0.035") (d2Thickness "0.72 mil") (d2Constant "1") (d2LossTangent "0") (d3Thickness "0.0") (d3Constant "1") (d3LossTangent "0") length("1000 mil") (spacing "5 mil") (spacing2 "5 mil") (spacing3 "5 mil") (spacing4 "5 mil") (spacing5 "5 mil") (traceConductivity "595900 mho/cm") (traceGeometry "cpwms") (traceLayerName "") (traceThickness "0.72 mil") (traceType "single") (traceWidth "5.0 mil") (traceWidth2 "5.0 mil") (traceWidth3 "5.0 mil") (traceWidth4 "5.0 mil") (traceWidth5 "5.0 mil") (traceWidth6 "5.0 mil") (offset "0 mil") (traceCount "1") (impedance nil))) (IbisInput ((temperature "27") (bufferModel "CDSDefaultInput_2p5v") (cycle "1") (LEFDEFPinName nil) (LEFDEFPinType nil) (mappingTag nil))) (Inductor ((inductance "5 nH") (orientation "0"))) (DiffOutput ((temperature "27") (bufferModelNonInverting "CDSDefaultOutput_2p5v") (bufferModelInverting "CDSDefaultOutput_2p5v") (stimuli nil) (offsets nil) (state "tristate") (cycle "1") (termMap nil) (setup "0.9e-09") (hold "0.4e-09") (rise nil) (fall nil) (threshOutputHighMin "2.375  V") (threshOutputHighTyp "2.5  V") (threshOutputHighMax "2.625  V") (threshOutputLowMin "1.275  V") (threshOutputLowTyp "1.7  V") (threshOutputLowMax "1.985  V") (mappingTagNonInverting nil) (mappingTagInverting nil) (spice nil))) (Capacitor ((capacitance "10 pF") (orientation "0"))) (DiffOutputPkg ((temperature "27") (bufferModelNonInverting "CDSDefaultOutput_2p5v") (bufferModelInverting "CDSDefaultOutput_2p5v") (stimuli nil) (offsets nil) (state "tristate") (cycle "1") (termMap nil) (setup "0.9e-09") (hold "0.4e-09") (rise nil) (fall nil) (threshOutputHighMin "2.375  V") (threshOutputHighTyp "2.5  V") (threshOutputHighMax "2.625  V") (threshOutputLowMin "1.275  V") (threshOutputLowTyp "1.7  V") (threshOutputLowMax "1.985  V") (mappingTagNonInverting nil) (mappingTagInverting nil) (spice nil))) (RLGC (length("1000 mil"))) (DiffIO ((temperature "27") (bufferModelNonInverting "CDSDefaultIO_2p5v") (bufferModelInverting "CDSDefaultIO_2p5v") (stimuli nil) (offsets nil) (state "tristate") (cycle "1") (termMap nil) (setup "0.9e-09") (hold "0.4e-09") (rise nil) (fall nil) (threshInputHighMin "1.7 V") (threshInputHighTyp "1.7  V") (threshInputHighMax "1.7  V") (threshInputLowMin "0.7  V") (threshInputLowTyp "0.7  V") (threshInputLowMax "0.7 ") (threshOutputHighMin "2.365  V") (threshOutputHighTyp "2.5  V") (threshOutputHighMax "2.625  V") (threshOutputLowMin "1.275  V") (threshOutputLowTyp "1.7  V") (threshOutputLowMax "1.985  V") (mappingTagNonInverting nil) (mappingTagInverting nil) (spice nil))) (IbisOutput ((temperature "27") (bufferModel "CDSDefaultOutput_2p5v") (stimuli nil) (offsets nil) (state "tristate") (cycle "1") (termMap nil) (setup "2.0e-09") (hold "1.0e-09") (rise nil) (fall nil) (macroType nil) (voltage nil) (spice nil) (LEFDEFPinName nil) (LEFDEFPinType nil) (mappingTag nil))) (IbisIO ((temperature "27") (bufferModel "CDSDefaultIO_2p5v") (stimuli nil) (offsets nil) (state "tristate") (cycle "1") (termMap nil) (setup "2.0e-09") (hold "1.0e-09") (rise nil) (fall nil) (macroType nil) (voltage nil) (spice nil) (LEFDEFPinName nil) (LEFDEFPinType nil) (mappingTag nil))) (Source ((voltage "5 V"))) (DiffIOPkg ((temperature "27") (bufferModelNonInverting "CDSDefaultIO_2p5v") (bufferModelInverting "CDSDefaultIO_2p5v") (stimuli nil) (offsets nil) (state "tristate") (cycle "1") (termMap nil) (setup "0.9e-09") (hold "0.4e-09") (rise nil) (fall nil) (threshInputHighMin "1.7 V") (threshInputHighTyp "1.7  V") (threshInputHighMax "1.7  V") (threshInputLowMin "0.7  V") (threshInputLowTyp "0.7  V") (threshInputLowMax "0.7 ") (threshOutputHighMin "2.365  V") (threshOutputHighTyp "2.5  V") (threshOutputHighMax "2.625  V") (threshOutputLowMin "1.275  V") (threshOutputLowTyp "1.7  V") (threshOutputLowMax "1.985  V") (mappingTagNonInverting nil) (mappingTagInverting nil) (spice nil))) (Connector nil) (Resistor ((resistance "50 ohm") (orientation "0"))) (DiffInput ((temperature "27") (bufferModelNonInverting "CDSDefaultInput_2p5v") (bufferModelInverting "CDSDefaultInput_2p5v") (threshInputHighMin "1.7 V") (threshInputHighTyp "1.7  V") (threshInputHighMax "1.7  V") (threshInputLowMin "0.7  V") (threshInputLowTyp "0.7  V") (threshInputLowMax "0.7  V") (mappingTagNonInverting nil) (mappingTagInverting nil) (cycle "1"))) (CPWSL ((d1Thickness "10 mil") (d1Constant "4.5") (d1LossTangent "0.035") (d2Thickness "0.72 mil") (d2Constant "4.5") (d2LossTangent "0.035") (d3Thickness "10 mil") (d3Constant "4.5") (d3LossTangent "0.035") length("1000 mil") (spacing "5 mil") (spacing2 "5 mil") (spacing3 "5 mil") (spacing4 "5 mil") (spacing5 "5 mil") (traceConductivity "595900 mho/cm") (traceGeometry "cpwms") (traceLayerName "") (traceThickness "0.72 mil") (traceType "single") (traceWidth "5.0 mil") (traceWidth2 "5.0 mil") (traceWidth3 "5.0 mil") (traceWidth4 "5.0 mil") (traceWidth5 "5.0 mil") (traceWidth6 "5.0 mil") (offset "0 mil") (traceCount "1") (impedance nil))) (TLine ((diffImpedance "100ohm") (diffVelocity "1.4142e+08M/s") (impedance "60ohm") length("2800 mil") (propDelay "0.5 ns") (velocity "5600 mil/ns") (traceCount "1") (traceGeometry "Microstrip") (impedanceMin nil) (impedanceMax nil) (lengthMin nil) (lengthMax nil) (propDelayMin nil) (propDelayMax nil) (impedanceSweepCount nil) (propDelaySweepCount nil) (velocitySweepCount nil) (lengthSweepCount nil) (matchSetName nil))) (DiffInputPkg ((temperature "27") (bufferModelNonInverting "CDSDefaultInput_2p5v") (bufferModelInverting "CDSDefaultInput_2p5v") (threshInputHighMin "1.7 V") (threshInputHighTyp "1.7  V") (threshInputHighMax "1.7  V") (threshInputLowMin "0.7  V") (threshInputLowTyp "0.7  V") (threshInputLowMax "0.7  V") (mappingTagNonInverting nil) (mappingTagInverting nil) (cycle "1"))) (IbisIOMacro ((temperature "27") (bufferModel "CDSDefaultIO_2p5v") (stimuli nil) (offsets nil) (state "tristate") (cycle "1") (termMap nil) (setup "2.0e-09") (hold "1.0e-09") (rise nil) (fall nil) (macroType nil) (voltage nil) (spice nil) (LEFDEFPinName nil) (LEFDEFPinType nil) (mappingTag nil))) (async ((asyncTimePoints "") (asyncInitState "1"))) (sync ((syncFreq "100e6") (syncInitState "1") (syncPattern "10") (syncEdgeSwitch "rise"))) (idlCircuit ((allDrivers "active") (ftsMode '("Typ")) (rcvrSelect "all") (simMode "Reflection") (tlineDelayMode "time") (userRevision "1.0") (autoSolve "On")))))
				)
				( objectStatus "NIC_MDI_0-1" )
			)
			( electricalCSet "@crescent_city_bb_fab1_lib.crescent_city_bb_fab1(sch_1):\NIC_MDI_2-3\"
				( attribute "RATSNEST_SCHEDULE" "TEMPLATE"
					( Status sLocked )
					( Origin gBackEnd )
				)
				( attribute "PROPAGATION_DELAY_PATH_TYPE" "D:R"
					( Origin gBackEnd )
				)
				( attribute "PROPAGATION_DELAY_MAX" "3500.00 MIL"
					( Units "uMaxMinProp" "ns" 1.000000)
					( Origin gBackEnd )
				)
				( attribute "DIFFP_GATHER_CONTROL" "IGNORE"
					( Origin gBackEnd )
				)
				( attribute "DIFFP_UNCOUPLED_LENGTH" "250.00"
					( Origin gBackEnd )
				)
				( attribute "DIFFP_COUPLED_PLUS" "0.10"
					( Origin gBackEnd )
				)
				( attribute "DIFFP_COUPLED_MINUS" "0.10"
					( Origin gBackEnd )
				)
				( attribute "DIFFP_PHASE_TOL" "30 mil"
					( Units "uPhaseTol" "ns" 1.000000)
					( Origin gBackEnd )
				)
				( attribute "DIFFP_PHASE_MAX_LENGTH" "600.00"
					( Origin gBackEnd )
				)
				( attribute "DIFFP_PHASE_TOL_DYNAMIC" "30 mil"
					( Units "uPhaseTol" "mil" 1.000000)
					( Origin gBackEnd )
				)
				( attribute "TOPOLOGY_TEMPLATE_REVISION" "1.0"
					( Origin gBackEnd )
				)
				( topologyData 23754
(SKIDL (Circuits ("MAIN" (Parts ("CRESCENT_CITY_181_20150105_A.@@EU46.52" IbisIOPkg (xy (5515 4228)) (refDes "EU9E1") (model "Unknown") (Props (_SXDesignName "CRESCENT_CITY_181_20150105_A") (brdx "19091.42 MIL") (brdy "1593 MIL") (bufferModel "CDSDefaultIO_2p5v") (cycle "1") (hold "1.0e-09") (mappingTag "") (offsets ("4" "0") ("5" "0")) (setup "2.0e-09") (state "tristate") (stimuli ("4" "local32") ("5" "local33")) (temperature "27") (termMap ("4" "Data") ("5" "Enable"))) (Terms ("CRESCENT_CITY_181_20150105_A.X1909142Y159300L2LRATS" "52"))) ("CRESCENT_CITY_181_20150105_A.@@JA4.2" IbisIOPkg (xy (5502 4240)) (refDes "JA9G1") (model "Unknown") (Props (_SXDesignName "CRESCENT_CITY_181_20150105_A") (brdx "19070 MIL") (brdy "272.69 MIL") (bufferModel "CDSDefaultIO_2p5v") (cycle "1") (hold "1.0e-09") (mappingTag "") (offsets ("4" "0") ("5" "0")) (setup "2.0e-09") (state "tristate") (stimuli ("4" "local34") ("5" "local35")) (temperature "27") (termMap ("4" "Data") ("5" "Enable"))) (Terms ("CRESCENT_CITY_181_20150105_A.X1907000Y27269L2LRATS" "2"))) ("CRESCENT_CITY_181_20150105_A.@@C10.1.2" Resistor (xy (5497 4217)) (mirror x) (refDes "C9G13") (value "4700 Ohm") (Props (_SXDesignName "CRESCENT_CITY_181_20150105_A")) (Terms ("idlNode_17" "1") ("0" "2"))) ("CRESCENT_CITY_181_20150105_A.T@@RATS@@R28.2@@JA4.2" TLine (xy (5497 4229)) (refDes "TL3") (Props (_SXDesignName "CRESCENT_CITY_181_20150105_A") (impedance "49.675 ohm") length("217.69 MIL") (propDelay "0.0391 ns") (traceCount "1") (traceGeometry "Microstrip") (velocity "5567.52 mil/ns")) (Terms ("CRESCENT_CITY_181_20150105_A.X1886500Y26000L2LRATS" "1") ("CRESCENT_CITY_181_20150105_A.X1907000Y27269L2LRATS" "2"))) ("idlPart_13" TLine (xy (5498.5 4223.0)) (refDes "TL5") (Props (_SXDesignName "CRESCENT_CITY_181_20150105_A") (impedance "49.675 ohm") length("217.69 MIL") (propDelay "0.0391 ns") (traceCount "1") (traceGeometry "Microstrip") (velocity "5567.52 mil/ns")) (Terms ("idlNode_15" "1") ("idlNode_17" "2"))) ("CRESCENT_CITY_181_20150105_A.T@@RATS@@R28.1@@EU46.52" TLine (xy (5506.5 4223.0)) (refDes "TL4") (Props (_SXDesignName "CRESCENT_CITY_181_20150105_A") (impedance "49.675 ohm") length("1594.42 MIL") (propDelay "0.28637 ns") (traceCount "1") (traceGeometry "Microstrip") (velocity "5567.68 mil/ns")) (Terms ("idlNode_17" "1") ("CRESCENT_CITY_181_20150105_A.X1909142Y159300L2LRATS" "2"))) ("CRESCENT_CITY_181_20150105_A.@@R28.1.2" Resistor (xy (5491 4223)) (mirror x) (refDes "R9G17") (value "0.001 Ohm") (Props (_SXDesignName "CRESCENT_CITY_181_20150105_A")) (Terms ("idlNode_15" "1") ("CRESCENT_CITY_181_20150105_A.X1886500Y26000L2LRATS" "2")))) (Nodes ("CRESCENT_CITY_181_20150105_A.X1886500Y26000L2LRATS" (terms "CRESCENT_CITY_181_20150105_A.@@R28.1.2.2" "CRESCENT_CITY_181_20150105_A.T@@RATS@@R28.2@@JA4.2.1")) ("CRESCENT_CITY_181_20150105_A.X1909142Y159300L2LRATS" (terms "CRESCENT_CITY_181_20150105_A.T@@RATS@@R28.1@@EU46.52.2" "CRESCENT_CITY_181_20150105_A.@@EU46.52.1")) ("CRESCENT_CITY_181_20150105_A.X1907000Y27269L2LRATS" (terms "CRESCENT_CITY_181_20150105_A.T@@RATS@@R28.2@@JA4.2.2" "CRESCENT_CITY_181_20150105_A.@@JA4.2.1")) ("idlNode_17" (terms "CRESCENT_CITY_181_20150105_A.T@@RATS@@R28.1@@EU46.52.1" "idlPart_13.2" "CRESCENT_CITY_181_20150105_A.@@C10.1.2.1")) ("idlNode_15" (terms "CRESCENT_CITY_181_20150105_A.@@R28.1.2.1" "idlPart_13.1"))) (Ports) (Stimuli ("local34" (scope local) (stimType periodic) (Props (periodicFreq "5e+007") (periodicJitter "0") (periodicPattern "1"))) ("local35" (scope local) (stimType periodic) (Props (periodicFreq "5e+007") (periodicJitter "0") (periodicPattern "1"))) ("local32" (scope local) (stimType periodic) (Props (periodicFreq "5e+007") (periodicJitter "0") (periodicPattern "1"))) ("local33" (scope local) (stimType periodic) (Props (periodicFreq "5e+007") (periodicJitter "0") (periodicPattern "1")))) (Notes) (Constraints ("DELAY_RULE" ("DRIVER" "RECEIVER" "LENGTH" "" "LENGTH" "0.0889")) ("DP_GATHER_CONTROL" "IGNORE") ("DP_MAX_UNCOUPLED_LENGTH" "0.000254") ("DP_PHASE_MAX_LENGTH" "0.01524") ("DP_PHASE_TOLERANCE" ("LENGTH" "0.000762")) ("DP_PHASE_TOLERANCE_DYNAMIC" ("LENGTH" "0.000762")) ("RATSNEST_SCHEDULE" "TEMPLATE")) (MeasurementSets ("EMI" ("EMIStatus" status("on")) ("PeakEmission" status("on")) ("PeakFrequency" status("on")) ("PulseFreq" status("on")) ("RiseTime" status("on")) ("VoltageSwing" status("on"))) ("Reflection" ("BufferDelayFall" status("off")) ("BufferDelayRise" status("off")) ("EyeHeight" status("off")) ("EyeJitter" status("off")) ("EyeWidth" status("off")) ("FirstIncidentFall" status("off")) ("FirstIncidentRise" status("off")) ("Glitch" status("on")) ("GlitchFall" status("off")) ("GlitchRise" status("off")) ("Monotonic" status("on")) ("MonotonicFall" status("off")) ("MonotonicRise" status("off")) ("NoiseMargin" status("on")) ("NoiseMarginHigh" status("off")) ("NoiseMarginLow" status("off")) ("OvershootHigh" status("on")) ("OvershootLow" status("on")) ("PropDelay" status("on")) ("SettleDelay" status("on")) ("SettleDelayFall" status("off")) ("SettleDelayRise" status("off")) ("SwitchDelay" status("on")) ("SwitchDelayFall" status("off")) ("SwitchDelayRise" status("off"))) ("Crosstalk" ("Crosstalk" status("on"))) ("Custom")) (VectorSets) (Props (XnetName "NIC_MDI_SPRV_RJ45_2_R_DN") (allDrivers "active") (customSimType "Reflection") (ftsMode ("Typ")) (rcvrSelect "all") (tlineDelayMode "time") (userRevision "1.0")))) (Subckts) (CrossSections ("CRESCENT_CITY_181_20150105_A" (Props (SXDesignName "CRESCENT_CITY_181_20150105_A")) (Layers ("" (layerType "SURFACE") (material "AIR") (thickness "0 mil") (dielectricConstant "1.000000") (lossTangent "0") (etchFactor "0.000000") (elecCondVal "0 mho/cm") (thermCondVal "0 w/cm-degC")) ("" (layerType "DIELECTRIC") (material "CONFORMAL_COAT") (thickness "0.5 mil") (dielectricConstant "3.800000") (lossTangent "0.035") (etchFactor "0.000000") (elecCondVal "0 mho/cm") (thermCondVal "0.012 w/cm-degC")) ("TOP" (layerType "CONDUCTOR") (material "COPPER") (thickness "  2.100000 mil") (width "4.00 MIL") (dielectricConstant "4.500000") (lossTangent "0") (etchFactor "70.000000") (elecCondVal "595900.000000 mho/cm") (thermCondVal "0 w/cm-degC") (signalDieConstant "3.800000") (signalLossTangent "0.035")) ("" (layerType "DIELECTRIC") (material "FR-4") (thickness "  2.670000 mil") (dielectricConstant "4.000000") (lossTangent "0.035") (etchFactor "0.000000") (elecCondVal "0 mho/cm") (thermCondVal "0.012 w/cm-degC")) ("L2_GND1" (layerType "PLANE") (material "COPPER") (isShield t) (thickness "  1.250000 mil") (dielectricConstant "4.500000") (lossTangent "0.035") (etchFactor "90.000000") (elecCondVal "595900.000000 mho/cm") (thermCondVal "0.012 w/cm-degC")) ("" (layerType "DIELECTRIC") (material "FR-4") (thickness "  9.000000 mil") (dielectricConstant "4.100000") (lossTangent "0.035") (etchFactor "0.000000") (elecCondVal "0 mho/cm") (thermCondVal "0.012 w/cm-degC")) ("L3_SIG1" (layerType "CONDUCTOR") (material "COPPER") (thickness "  1.250000 mil") (width "4.00 MIL") (dielectricConstant "4.500000") (lossTangent "0.035") (etchFactor "90.000000") (elecCondVal "595900.000000 mho/cm") (thermCondVal "0.012 w/cm-degC") (signalDieConstant "4.100000") (signalLossTangent "0.035")) ("" (layerType "DIELECTRIC") (material "FR-4") (thickness "  3.000000 mil") (dielectricConstant "4.500000") (lossTangent "0.035") (etchFactor "0.000000") (elecCondVal "0 mho/cm") (thermCondVal "0 w/cm-degC")) ("L4_GND2" (layerType "PLANE") (material "COPPER") (isShield t) (thickness "  1.250000 mil") (dielectricConstant "4.500000") (lossTangent "0.035") (etchFactor "90.000000") (elecCondVal "595900.000000 mho/cm") (thermCondVal "0 w/cm-degC")) ("" (layerType "DIELECTRIC") (material "FR-4") (thickness "  9.000000 mil") (dielectricConstant "4.000000") (lossTangent "0.035") (etchFactor "0.000000") (elecCondVal "0 mho/cm") (thermCondVal "0.012 w/cm-degC")) ("L5_SIG2" (layerType "CONDUCTOR") (material "COPPER") (thickness "  1.250000 mil") (width "4.00 MIL") (dielectricConstant "4.500000") (lossTangent "0.035") (etchFactor "90.000000") (elecCondVal "595900.000000 mho/cm") (thermCondVal "0.012 w/cm-degC") (signalDieConstant "4.000000") (signalLossTangent "0.035")) ("" (layerType "DIELECTRIC") (material "FR-4") (thickness "  3.000000 mil") (dielectricConstant "4.500000") (lossTangent "0.035") (etchFactor "0.000000") (elecCondVal "0 mho/cm") (thermCondVal "0 w/cm-degC")) ("L6_GND3" (layerType "PLANE") (material "COPPER") (isShield t) (thickness "  1.250000 mil") (dielectricConstant "4.500000") (lossTangent "0.035") (etchFactor "90.000000") (elecCondVal "595900.000000 mho/cm") (thermCondVal "0 w/cm-degC")) ("" (layerType "DIELECTRIC") (material "FR-4") (thickness "  4.500000 mil") (dielectricConstant "4.100000") (lossTangent "0.035") (etchFactor "0.000000") (elecCondVal "0 mho/cm") (thermCondVal "0.012 w/cm-degC")) ("L7_PWR1-SIG" (layerType "PLANE") (material "COPPER") (isShield t) (thickness "  2.400000 mil") (dielectricConstant "4.500000") (lossTangent "0.035") (etchFactor "90.000000") (elecCondVal "595900.000000 mho/cm") (thermCondVal "0.012 w/cm-degC")) ("" (layerType "DIELECTRIC") (material "FR-4") (thickness "  4.600000 mil") (dielectricConstant "4.000000") (lossTangent "0.035") (etchFactor "0.000000") (elecCondVal "0 mho/cm") (thermCondVal "0.012 w/cm-degC")) ("L8_PWR2-SIG" (layerType "PLANE") (material "COPPER") (isShield t) (thickness "  2.400000 mil") (dielectricConstant "4.500000") (lossTangent "0.035") (etchFactor "90.000000") (elecCondVal "595900.000000 mho/cm") (thermCondVal "0.012 w/cm-degC")) ("" (layerType "DIELECTRIC") (material "FR-4") (thickness "  4.500000 mil") (dielectricConstant "4.500000") (lossTangent "0.035") (etchFactor "0.000000") (elecCondVal "0 mho/cm") (thermCondVal "0 w/cm-degC")) ("L9_GND4" (layerType "PLANE") (material "COPPER") (isShield t) (thickness "  1.250000 mil") (dielectricConstant "4.500000") (lossTangent "0.035") (etchFactor "90.000000") (elecCondVal "595900.000000 mho/cm") (thermCondVal "0 w/cm-degC")) ("" (layerType "DIELECTRIC") (material "FR-4") (thickness "  3.000000 mil") (dielectricConstant "4.100000") (lossTangent "0.035") (etchFactor "0.000000") (elecCondVal "0 mho/cm") (thermCondVal "0.012 w/cm-degC")) ("L10_SIG3" (layerType "CONDUCTOR") (material "COPPER") (thickness "  1.250000 mil") (width "4.00 MIL") (dielectricConstant "4.500000") (lossTangent "0.035") (etchFactor "90.000000") (elecCondVal "595900.000000 mho/cm") (thermCondVal "0.012 w/cm-degC") (signalDieConstant "4.100000") (signalLossTangent "0.035")) ("" (layerType "DIELECTRIC") (material "FR-4") (thickness "  9.000000 mil") (dielectricConstant "4.500000") (lossTangent "0.035") (etchFactor "0.000000") (elecCondVal "0 mho/cm") (thermCondVal "0 w/cm-degC")) ("L11_GND5" (layerType "PLANE") (material "COPPER") (isShield t) (thickness "  1.250000 mil") (dielectricConstant "4.500000") (lossTangent "0.035") (etchFactor "90.000000") (elecCondVal "595900.000000 mho/cm") (thermCondVal "0 w/cm-degC")) ("" (layerType "DIELECTRIC") (material "FR-4") (thickness "  3.000000 mil") (dielectricConstant "4.500000") (lossTangent "0.035") (etchFactor "0.000000") (elecCondVal "0 mho/cm") (thermCondVal "0.012 w/cm-degC")) ("L12_SIG4" (layerType "CONDUCTOR") (material "COPPER") (thickness "  1.250000 mil") (width "4.00 MIL") (dielectricConstant "4.500000") (lossTangent "0.035") (etchFactor "90.000000") (elecCondVal "595900.000000 mho/cm") (thermCondVal "0.012 w/cm-degC") (signalDieConstant "4.500000") (signalLossTangent "0.035")) ("" (layerType "DIELECTRIC") (material "FR-4") (thickness "  9.000000 mil") (dielectricConstant "4.500000") (lossTangent "0.035") (etchFactor "0.000000") (elecCondVal "0 mho/cm") (thermCondVal "0 w/cm-degC")) ("L13_GND6" (layerType "PLANE") (material "COPPER") (isShield t) (thickness "  1.250000 mil") (dielectricConstant "4.500000") (lossTangent "0.035") (etchFactor "90.000000") (elecCondVal "595900.000000 mho/cm") (thermCondVal "0.012 w/cm-degC")) ("" (layerType "DIELECTRIC") (material "FR-4") (thickness "  2.670000 mil") (dielectricConstant "4.500000") (lossTangent "0.035") (etchFactor "0.000000") (elecCondVal "0 mho/cm") (thermCondVal "0.012 w/cm-degC")) ("BOTTOM" (layerType "CONDUCTOR") (material "COPPER") (thickness "  2.100000 mil") (width "4.00 MIL") (dielectricConstant "4.500000") (lossTangent "0") (etchFactor "70.000000") (elecCondVal "595900.000000 mho/cm") (thermCondVal "0 w/cm-degC") (signalDieConstant "3.800000") (signalLossTangent "0.035")) ("" (layerType "DIELECTRIC") (material "CONFORMAL_COAT") (thickness "0.5 mil") (dielectricConstant "3.800000") (lossTangent "0.035") (etchFactor "0.000000") (elecCondVal "0 mho/cm") (thermCondVal "0.012 w/cm-degC")) ("" (layerType "SURFACE") (material "AIR") (thickness "0 mil") (dielectricConstant "1.000000") (lossTangent "0") (etchFactor "0.000000") (elecCondVal "0 mho/cm") (thermCondVal "0 w/cm-degC"))))) (Props (DesUnits "mils 2") (LayerStack ("DIELECTRIC" "DIELECTRIC" "BOTTOM" "DIELECTRIC" "L13_GND6" "DIELECTRIC" "L12_SIG4" "DIELECTRIC" "L11_GND5" "DIELECTRIC" "L10_SIG3" "DIELECTRIC" "L9_GND4" "DIELECTRIC" "L8_PWR2-SIG" "DIELECTRIC" "L7_PWR1-SIG" "DIELECTRIC" "L6_GND3" "DIELECTRIC" "L5_SIG2" "DIELECTRIC" "L4_GND2" "DIELECTRIC" "L3_SIG1" "DIELECTRIC" "L2_GND1" "DIELECTRIC" "TOP" "DIELECTRIC" "DIELECTRIC")) (Revision "16.600")) (Params (LowClampTerm ((cutoffVoltage "0.7 V") (voltage "0 V") (maxDelay "0.1 ns"))) (IbisInputPkg ((temperature "27") (bufferModel "CDSDefaultInput_2p5v") (cycle "1") (LEFDEFPinName nil) (LEFDEFPinType nil) (mappingTag nil))) (SeriesTerm ((resistance "22 ohm") (maxDelay "0.1 ns"))) (RCTerm ((resistance "50 ohm") (capacitance "20 pF") (voltage "5 V") (maxDelay "0.1 ns"))) (TheveninTerm ((resistanceUp "180 ohm") (resistanceDown "270 ohm") (voltageUp "5 V") (voltageDown "0 V") (maxDelay "0.1 ns"))) (CurrentProbe nil) (IbisIOPkg ((temperature "27") (bufferModel "CDSDefaultIO_2p5v") (stimuli nil) (offsets nil) (state "tristate") (cycle "1") (termMap nil) (setup "2.0e-09") (hold "1.0e-09") (rise nil) (fall nil) (macroType nil) (voltage nil) (spice nil) (LEFDEFPinName nil) (LEFDEFPinType nil) (mappingTag nil))) (ShuntTerm ((resistance "50 ohm") (voltage "5 V") (maxDelay "0.1 ns"))) (IbisOutputPkg ((temperature "27") (bufferModel "CDSDefaultOutput_2p5v") (stimuli nil) (offsets nil) (state "tristate") (cycle "1") (termMap nil) (setup "2.0e-09") (hold "1.0e-09") (rise nil) (fall nil) (macroType nil) (voltage nil) (spice nil) (LEFDEFPinName nil) (LEFDEFPinType nil) (mappingTag nil))) (clocked ((clockRise "1e-09") (clockFall "1e-09") (clockFreq "100e6") (clockInitState "0") (clockDutyCycle "0.5") (clockJitter "0"))) (Diode ((cutoffVoltage "0.7 V"))) (IbisOutput_OpenPullUp ((temperature "27") (bufferModel "CDSDefaultOutput_2p5v") (stimuli nil) (offsets nil) (state "tristate") (cycle "1") (termMap nil) (setup "2.0e-09") (hold "1.0e-09") (rise nil) (fall nil) (macroType nil) (voltage nil) (spice nil) (LEFDEFPinName nil) (LEFDEFPinType nil) (mappingTag nil))) (Trace ((d1Thickness "10 mil") (d1Constant "4.5") (d1LossTangent "0.035") (d2Thickness "10 mil") (d2Constant "4.5") (d2LossTangent "0.035") (d3Thickness "0.0") (d3Constant "1.0") (d3LossTangent "0") length("1000 mil") (spacing "5 mil") (spacing2 "5 mil") (spacing3 "5 mil") (spacing4 "5 mil") (spacing5 "5 mil") (traceConductivity "595900 mho/cm") (traceGeometry "microstrip") (traceLayerName "") (traceThickness "0.72 mil") (traceType "single") (traceWidth "5.0 mil") (traceWidth2 "5.0 mil") (traceWidth3 "5.0 mil") (traceWidth4 "5.0 mil") (traceWidth5 "5.0 mil") (traceWidth6 "5.0 mil") (offset "0 mil") (traceCount "1") (impedance nil))) (DualClampTerm ((cutoffVoltageUp "0.7 V") (cutoffVoltageDown "0.7 V") (voltageUp "5 V") (voltageDown "0 V") (maxDelay "0.1 ns"))) (Via ((model "Unknown") (viaOutputFormat "Unknown") (viaPadstack nil) (viaTopLayer nil) (viaBottomLayer nil) (viaIsPower nil) (viaIsGround nil))) (periodic ((periodicFreq "100e6") (periodicPattern "10") (periodicJitter "0"))) (IbisIO_OpenPullDown ((temperature "27") (bufferModel "CDSDefaultIO_2p5v") (stimuli nil) (offsets nil) (state "tristate") (cycle "1") (termMap nil) (setup "2.0e-09") (hold "1.0e-09") (rise nil) (fall nil) (macroType nil) (voltage nil) (spice nil) (LEFDEFPinName nil) (LEFDEFPinType nil) (mappingTag nil))) (IbisIO_OpenPullUp ((temperature "27") (bufferModel "CDSDefaultIO_2p5v") (stimuli nil) (offsets nil) (state "tristate") (cycle "1") (termMap nil) (setup "2.0e-09") (hold "1.0e-09") (rise nil) (fall nil) (macroType nil) (voltage nil) (spice nil) (LEFDEFPinName nil) (LEFDEFPinType nil) (mappingTag nil))) (HiClampTerm ((cutoffVoltage "0.7 V") (voltage "5 V") (maxDelay "0.1 ns"))) (CPWMS ((d1Thickness "10 mil") (d1Constant "4.5") (d1LossTangent "0.035") (d2Thickness "0.72 mil") (d2Constant "4.5") (d2LossTangent "0.035") (d3Thickness "0.0") (d3Constant "1") (d3LossTangent "0") length("1000 mil") (spacing "5 mil") (spacing2 "5 mil") (spacing3 "5 mil") (spacing4 "5 mil") (spacing5 "5 mil") (traceConductivity "595900 mho/cm") (traceGeometry "cpwms") (traceLayerName "") (traceThickness "0.72 mil") (traceType "single") (traceWidth "5.0 mil") (traceWidth2 "5.0 mil") (traceWidth3 "5.0 mil") (traceWidth4 "5.0 mil") (traceWidth5 "5.0 mil") (traceWidth6 "5.0 mil") (offset "0 mil") (traceCount "1") (impedance nil))) (Cable (length("1 m"))) (ESpiceDevice nil) (CPW ((d1Thickness "10 mil") (d1Constant "4.5") (d1LossTangent "0.035") (d2Thickness "0.72 mil") (d2Constant "1") (d2LossTangent "0") (d3Thickness "0.0") (d3Constant "1") (d3LossTangent "0") length("1000 mil") (spacing "5 mil") (spacing2 "5 mil") (spacing3 "5 mil") (spacing4 "5 mil") (spacing5 "5 mil") (traceConductivity "595900 mho/cm") (traceGeometry "cpwms") (traceLayerName "") (traceThickness "0.72 mil") (traceType "single") (traceWidth "5.0 mil") (traceWidth2 "5.0 mil") (traceWidth3 "5.0 mil") (traceWidth4 "5.0 mil") (traceWidth5 "5.0 mil") (traceWidth6 "5.0 mil") (offset "0 mil") (traceCount "1") (impedance nil))) (IbisInput ((temperature "27") (bufferModel "CDSDefaultInput_2p5v") (cycle "1") (LEFDEFPinName nil) (LEFDEFPinType nil) (mappingTag nil))) (Inductor ((inductance "5 nH") (orientation "0"))) (DiffOutput ((temperature "27") (bufferModelNonInverting "CDSDefaultOutput_2p5v") (bufferModelInverting "CDSDefaultOutput_2p5v") (stimuli nil) (offsets nil) (state "tristate") (cycle "1") (termMap nil) (setup "0.9e-09") (hold "0.4e-09") (rise nil) (fall nil) (threshOutputHighMin "2.375  V") (threshOutputHighTyp "2.5  V") (threshOutputHighMax "2.625  V") (threshOutputLowMin "1.275  V") (threshOutputLowTyp "1.7  V") (threshOutputLowMax "1.985  V") (mappingTagNonInverting nil) (mappingTagInverting nil) (spice nil))) (Capacitor ((capacitance "10 pF") (orientation "0"))) (DiffOutputPkg ((temperature "27") (bufferModelNonInverting "CDSDefaultOutput_2p5v") (bufferModelInverting "CDSDefaultOutput_2p5v") (stimuli nil) (offsets nil) (state "tristate") (cycle "1") (termMap nil) (setup "0.9e-09") (hold "0.4e-09") (rise nil) (fall nil) (threshOutputHighMin "2.375  V") (threshOutputHighTyp "2.5  V") (threshOutputHighMax "2.625  V") (threshOutputLowMin "1.275  V") (threshOutputLowTyp "1.7  V") (threshOutputLowMax "1.985  V") (mappingTagNonInverting nil) (mappingTagInverting nil) (spice nil))) (RLGC (length("1000 mil"))) (DiffIO ((temperature "27") (bufferModelNonInverting "CDSDefaultIO_2p5v") (bufferModelInverting "CDSDefaultIO_2p5v") (stimuli nil) (offsets nil) (state "tristate") (cycle "1") (termMap nil) (setup "0.9e-09") (hold "0.4e-09") (rise nil) (fall nil) (threshInputHighMin "1.7 V") (threshInputHighTyp "1.7  V") (threshInputHighMax "1.7  V") (threshInputLowMin "0.7  V") (threshInputLowTyp "0.7  V") (threshInputLowMax "0.7 ") (threshOutputHighMin "2.365  V") (threshOutputHighTyp "2.5  V") (threshOutputHighMax "2.625  V") (threshOutputLowMin "1.275  V") (threshOutputLowTyp "1.7  V") (threshOutputLowMax "1.985  V") (mappingTagNonInverting nil) (mappingTagInverting nil) (spice nil))) (IbisOutput ((temperature "27") (bufferModel "CDSDefaultOutput_2p5v") (stimuli nil) (offsets nil) (state "tristate") (cycle "1") (termMap nil) (setup "2.0e-09") (hold "1.0e-09") (rise nil) (fall nil) (macroType nil) (voltage nil) (spice nil) (LEFDEFPinName nil) (LEFDEFPinType nil) (mappingTag nil))) (IbisIO ((temperature "27") (bufferModel "CDSDefaultIO_2p5v") (stimuli nil) (offsets nil) (state "tristate") (cycle "1") (termMap nil) (setup "2.0e-09") (hold "1.0e-09") (rise nil) (fall nil) (macroType nil) (voltage nil) (spice nil) (LEFDEFPinName nil) (LEFDEFPinType nil) (mappingTag nil))) (Source ((voltage "5 V"))) (DiffIOPkg ((temperature "27") (bufferModelNonInverting "CDSDefaultIO_2p5v") (bufferModelInverting "CDSDefaultIO_2p5v") (stimuli nil) (offsets nil) (state "tristate") (cycle "1") (termMap nil) (setup "0.9e-09") (hold "0.4e-09") (rise nil) (fall nil) (threshInputHighMin "1.7 V") (threshInputHighTyp "1.7  V") (threshInputHighMax "1.7  V") (threshInputLowMin "0.7  V") (threshInputLowTyp "0.7  V") (threshInputLowMax "0.7 ") (threshOutputHighMin "2.365  V") (threshOutputHighTyp "2.5  V") (threshOutputHighMax "2.625  V") (threshOutputLowMin "1.275  V") (threshOutputLowTyp "1.7  V") (threshOutputLowMax "1.985  V") (mappingTagNonInverting nil) (mappingTagInverting nil) (spice nil))) (Connector nil) (Resistor ((resistance "50 ohm") (orientation "0"))) (DiffInput ((temperature "27") (bufferModelNonInverting "CDSDefaultInput_2p5v") (bufferModelInverting "CDSDefaultInput_2p5v") (threshInputHighMin "1.7 V") (threshInputHighTyp "1.7  V") (threshInputHighMax "1.7  V") (threshInputLowMin "0.7  V") (threshInputLowTyp "0.7  V") (threshInputLowMax "0.7  V") (mappingTagNonInverting nil) (mappingTagInverting nil) (cycle "1"))) (CPWSL ((d1Thickness "10 mil") (d1Constant "4.5") (d1LossTangent "0.035") (d2Thickness "0.72 mil") (d2Constant "4.5") (d2LossTangent "0.035") (d3Thickness "10 mil") (d3Constant "4.5") (d3LossTangent "0.035") length("1000 mil") (spacing "5 mil") (spacing2 "5 mil") (spacing3 "5 mil") (spacing4 "5 mil") (spacing5 "5 mil") (traceConductivity "595900 mho/cm") (traceGeometry "cpwms") (traceLayerName "") (traceThickness "0.72 mil") (traceType "single") (traceWidth "5.0 mil") (traceWidth2 "5.0 mil") (traceWidth3 "5.0 mil") (traceWidth4 "5.0 mil") (traceWidth5 "5.0 mil") (traceWidth6 "5.0 mil") (offset "0 mil") (traceCount "1") (impedance nil))) (TLine ((diffImpedance "100ohm") (diffVelocity "1.4142e+08M/s") (impedance "60ohm") length("2800 mil") (propDelay "0.5 ns") (velocity "5600 mil/ns") (traceCount "1") (traceGeometry "Microstrip") (impedanceMin nil) (impedanceMax nil) (lengthMin nil) (lengthMax nil) (propDelayMin nil) (propDelayMax nil) (impedanceSweepCount nil) (propDelaySweepCount nil) (velocitySweepCount nil) (lengthSweepCount nil) (matchSetName nil))) (DiffInputPkg ((temperature "27") (bufferModelNonInverting "CDSDefaultInput_2p5v") (bufferModelInverting "CDSDefaultInput_2p5v") (threshInputHighMin "1.7 V") (threshInputHighTyp "1.7  V") (threshInputHighMax "1.7  V") (threshInputLowMin "0.7  V") (threshInputLowTyp "0.7  V") (threshInputLowMax "0.7  V") (mappingTagNonInverting nil) (mappingTagInverting nil) (cycle "1"))) (IbisIOMacro ((temperature "27") (bufferModel "CDSDefaultIO_2p5v") (stimuli nil) (offsets nil) (state "tristate") (cycle "1") (termMap nil) (setup "2.0e-09") (hold "1.0e-09") (rise nil) (fall nil) (macroType nil) (voltage nil) (spice nil) (LEFDEFPinName nil) (LEFDEFPinType nil) (mappingTag nil))) (async ((asyncTimePoints "") (asyncInitState "1"))) (sync ((syncFreq "100e6") (syncInitState "1") (syncPattern "10") (syncEdgeSwitch "rise"))) (idlCircuit ((allDrivers "active") (ftsMode '("Typ")) (rcvrSelect "all") (simMode "Reflection") (tlineDelayMode "time") (userRevision "1.0") (autoSolve "On")))))
				)
				( objectStatus "NIC_MDI_2-3" )
			)
			( electricalCSet "@baseboard_fab2_lib.baseboard_fab2(sch_1):\SVID_ALERT0_CPU1_N\"
				( groupRef "SVID_ALERT0_CPU1_N:#SVID_CPU0_1_U100-EU111" )
				( groupRef "SVID_ALERT0_CPU1_N:#SVID_CPU0_1_U100-EU47" )
				( pinPairRef "SVID_ALERT0_CPU1_N:EU4D5.17:U2D1.DE44" )
				( pinPairRef "SVID_ALERT0_CPU1_N:EU1C2.19:U2D1.DE44" )
				( pinPairRef "SVID_ALERT0_CPU1_N:U2D1.DE44:R3B2.1" )
				( pinPairRef "SVID_ALERT0_CPU1_N:R3B1.2:R3B2.1" )
				( pinPairRef "SVID_ALERT0_CPU1_N:R1D3.2:R3B1.2" )
				( pinPairRef "SVID_ALERT0_CPU1_N:EU4D5.17:R4D56.1" )
				( pinPairRef "SVID_ALERT0_CPU1_N:EU1C2.19:R1D3.1" )
				( attribute "TOPOLOGY_TEMPLATE_REVISION" "1.0"
					( Origin gBackEnd )
				)
				( topologyData 29882
(SKIDL (Circuits ("MAIN" (Parts ("CRESCENT_CITY_195_20150128_Q.@@EU111.17" IbisOutputPkg (xy (5498 4235)) (refDes "EU4D5") (model "Unknown") (Props (_SXDesignName "CRESCENT_CITY_195_20150128_Q") (brdx "6564.5 MIL") (brdy "2606.38 MIL") (bufferModel "CDSDefaultOutput_2p5v") (cycle "1") (hold "1.0e-09") (mappingTag "") (offsets ("4" "0")) (setup "2.0e-09") (state "tristate") (stimuli ("4" "local10")) (temperature "27") (termMap ("4" "Data"))) (Terms ("CRESCENT_CITY_195_20150128_Q.X656450Y260638L2LRATS" "17"))) ("CRESCENT_CITY_195_20150128_Q.@@J128.C20" IbisIOPkg (xy (5548 4240)) (refDes "J4B2") (model "Unknown") (Props (_SXDesignName "CRESCENT_CITY_195_20150128_Q") (brdx "7431 MIL") (brdy "4450 MIL") (bufferModel "CDSDefaultIO_2p5v") (cycle "1") (hold "1.0e-09") (mappingTag "") (offsets ("4" "0") ("5" "0")) (setup "2.0e-09") (state "tristate") (stimuli ("4" "local11") ("5" "local12")) (temperature "27") (termMap ("4" "Data") ("5" "Enable"))) (Terms ("CRESCENT_CITY_195_20150128_Q.X743100Y445000L2LRATS" "C20"))) ("CRESCENT_CITY_195_20150128_Q.@@EU47.19" IbisOutputPkg (xy (5538 4220)) (refDes "EU1C2") (model "Unknown") (Props (_SXDesignName "CRESCENT_CITY_195_20150128_Q") (brdx "670 MIL") (brdy "3628.13 MIL") (bufferModel "CDSDefaultOutput_2p5v") (cycle "1") (hold "1.0e-09") (mappingTag "") (offsets ("4" "0")) (setup "2.0e-09") (state "tristate") (stimuli ("4" "local13")) (temperature "27") (termMap ("4" "Data"))) (Terms ("CRESCENT_CITY_195_20150128_Q.X67000Y362813L2LRATS" "19"))) ("CRESCENT_CITY_195_20150128_Q.@@U100.DE44" IbisInputPkg (xy (5593 4228)) (refDes "U2D1") (model "Unknown") (Props (_SXDesignName "CRESCENT_CITY_195_20150128_Q") (brdx "4086.86 MIL") (brdy "3592.6 MIL") (bufferModel "CDSDefaultInput_2p5v") (mappingTag "") (temperature "27")) (Terms ("CRESCENT_CITY_195_20150128_Q.X408686Y359260L2LRATS" "DE44"))) ("CRESCENT_CITY_195_20150128_Q.T@@RATS@@R1455.1@@U100.DE44" TLine (xy (5585 4228)) (refDes "TL16") (Props (_SXDesignName "CRESCENT_CITY_195_20150128_Q") (impedance "49.728 ohm") length("3173.47 MIL") (propDelay "0.56998 ns") (traceCount "1") (traceGeometry "Microstrip") (velocity "5567.68 mil/ns")) (Terms ("CRESCENT_CITY_195_20150128_Q.X612534Y472759L2LRATS" "1") ("CRESCENT_CITY_195_20150128_Q.X408686Y359260L2LRATS" "2"))) ("CRESCENT_CITY_195_20150128_Q.T@@RATS@@R1287.1@@R2851.2" TLine (xy (5524 4235)) (mirror x) (refDes "TL17") (Props (_SXDesignName "CRESCENT_CITY_195_20150128_Q") (impedance "48.412 ohm") length("2317.59 MIL") (propDelay "0.41626 ns") (traceCount "1") (traceGeometry "Microstrip") (velocity "5567.64 mil/ns")) (Terms ("CRESCENT_CITY_195_20150128_Q.X622000Y472759L2LRATS" "1") ("CRESCENT_CITY_195_20150128_Q.X646000Y265000L2LRATS" "2"))) ("CRESCENT_CITY_195_20150128_Q.@@R1287.2_SOURCE" Source (xy (5517 4229)) (refDes "PVCCIO_CPU1") (value "1 V") (Props (_SXDesignName "CRESCENT_CITY_195_20150128_Q")) (Terms ("CRESCENT_CITY_195_20150128_Q.X625500Y472759L2RATS" "1"))) ("CRESCENT_CITY_195_20150128_Q.@@R1398.1.2" Resistor (xy (5561 4220)) (refDes "R1D3") (value "2.2e-007 Ohm") (Props (_SXDesignName "CRESCENT_CITY_195_20150128_Q")) (Terms ("CRESCENT_CITY_195_20150128_Q.X57000Y367500L2LRATS" "1") ("CRESCENT_CITY_195_20150128_Q.X53500Y367500L2LRATS" "2"))) ("CRESCENT_CITY_195_20150128_Q.T@@RATS@@R1455.2@@R1287.1" TLine (xy (5539 4228)) (mirror x) (refDes "TL18") (Props (_SXDesignName "CRESCENT_CITY_195_20150128_Q") (impedance "48.412 ohm") length("59.66 MIL") (propDelay "0.01072 ns") (traceCount "1") (traceGeometry "Microstrip") (velocity "5565.31 mil/ns")) (Terms ("CRESCENT_CITY_195_20150128_Q.X616034Y472759L2LRATS" "1") ("CRESCENT_CITY_195_20150128_Q.X622000Y472759L2LRATS" "2"))) ("CRESCENT_CITY_195_20150128_Q.@@R1455.1.2" Resistor (xy (5570 4228)) (mirror x) (refDes "R3B1") (value "220 Ohm") (Props (_SXDesignName "CRESCENT_CITY_195_20150128_Q")) (Terms ("CRESCENT_CITY_195_20150128_Q.X612534Y472759L2LRATS" "1") ("CRESCENT_CITY_195_20150128_Q.X616034Y472759L2LRATS" "2"))) ("CRESCENT_CITY_195_20150128_Q.T@@RATS@@R1287.1@@J128.C20" TLine (xy (5539 4235)) (refDes "TL19") (Props (_SXDesignName "CRESCENT_CITY_195_20150128_Q") (impedance "48.412 ohm") length("1488.59 MIL") (propDelay "0.26736 ns") (traceCount "1") (traceGeometry "Microstrip") (velocity "5567.76 mil/ns")) (Terms ("CRESCENT_CITY_195_20150128_Q.X622000Y472759L2LRATS" "1") ("CRESCENT_CITY_195_20150128_Q.X743100Y445000L2LRATS" "2"))) ("CRESCENT_CITY_195_20150128_Q.@@R1287.2.1" Resistor (xy (5524 4229)) (refDes "R3B2") (value "49.9 Ohm") (Props (_SXDesignName "CRESCENT_CITY_195_20150128_Q")) (Terms ("CRESCENT_CITY_195_20150128_Q.X625500Y472759L2RATS" "2") ("CRESCENT_CITY_195_20150128_Q.X622000Y472759L2LRATS" "1"))) ("CRESCENT_CITY_195_20150128_Q.T@@RATS@@EU111.17@@R2851.1" TLine (xy (5506 4235)) (refDes "TL20") (Props (_SXDesignName "CRESCENT_CITY_195_20150128_Q") (impedance "48.412 ohm") length("113.12 MIL") (propDelay "0.02032 ns") (traceCount "1") (traceGeometry "Microstrip") (velocity "5566.93 mil/ns")) (Terms ("CRESCENT_CITY_195_20150128_Q.X656450Y260638L2LRATS" "1") ("CRESCENT_CITY_195_20150128_Q.X649500Y265000L2LRATS" "2"))) ("CRESCENT_CITY_195_20150128_Q.T@@RATS@@R1455.2@@R1398.2" TLine (xy (5576 4220)) (mirror x) (refDes "TL21") (Props (_SXDesignName "CRESCENT_CITY_195_20150128_Q") (impedance "48.412 ohm") length("6677.91 MIL") (propDelay "1.1994 ns") (traceCount "1") (traceGeometry "Microstrip") (velocity "5567.72 mil/ns")) (Terms ("CRESCENT_CITY_195_20150128_Q.X616034Y472759L2LRATS" "1") ("CRESCENT_CITY_195_20150128_Q.X53500Y367500L2LRATS" "2"))) ("CRESCENT_CITY_195_20150128_Q.@@R2851.1.2" Resistor (xy (5515 4235)) (refDes "R4D56") (value "2.2e-007 Ohm") (Props (_SXDesignName "CRESCENT_CITY_195_20150128_Q")) (Terms ("CRESCENT_CITY_195_20150128_Q.X649500Y265000L2LRATS" "1") ("CRESCENT_CITY_195_20150128_Q.X646000Y265000L2LRATS" "2"))) ("CRESCENT_CITY_195_20150128_Q.T@@RATS@@R1398.1@@EU47.19" TLine (xy (5552 4220)) (mirror x) (refDes "TL22") (Props (_SXDesignName "CRESCENT_CITY_195_20150128_Q") (impedance "48.412 ohm") length("146.87 MIL") (propDelay "0.02638 ns") (traceCount "1") (traceGeometry "Microstrip") (velocity "5567.48 mil/ns")) (Terms ("CRESCENT_CITY_195_20150128_Q.X57000Y367500L2LRATS" "1") ("CRESCENT_CITY_195_20150128_Q.X67000Y362813L2LRATS" "2")))) (Nodes ("CRESCENT_CITY_195_20150128_Q.X743100Y445000L2LRATS" (terms "CRESCENT_CITY_195_20150128_Q.T@@RATS@@R1287.1@@J128.C20.2" "CRESCENT_CITY_195_20150128_Q.@@J128.C20.1")) ("CRESCENT_CITY_195_20150128_Q.X408686Y359260L2LRATS" (terms "CRESCENT_CITY_195_20150128_Q.T@@RATS@@R1455.1@@U100.DE44.2" "CRESCENT_CITY_195_20150128_Q.@@U100.DE44.1")) ("CRESCENT_CITY_195_20150128_Q.X656450Y260638L2LRATS" (terms "CRESCENT_CITY_195_20150128_Q.T@@RATS@@EU111.17@@R2851.1.1" "CRESCENT_CITY_195_20150128_Q.@@EU111.17.1")) ("CRESCENT_CITY_195_20150128_Q.X646000Y265000L2LRATS" (terms "CRESCENT_CITY_195_20150128_Q.@@R2851.1.2.2" "CRESCENT_CITY_195_20150128_Q.T@@RATS@@R1287.1@@R2851.2.2")) ("CRESCENT_CITY_195_20150128_Q.X649500Y265000L2LRATS" (terms "CRESCENT_CITY_195_20150128_Q.@@R2851.1.2.1" "CRESCENT_CITY_195_20150128_Q.T@@RATS@@EU111.17@@R2851.1.2")) ("CRESCENT_CITY_195_20150128_Q.X616034Y472759L2LRATS" (terms "CRESCENT_CITY_195_20150128_Q.T@@RATS@@R1455.2@@R1398.2.1" "CRESCENT_CITY_195_20150128_Q.@@R1455.1.2.2" "CRESCENT_CITY_195_20150128_Q.T@@RATS@@R1455.2@@R1287.1.1")) ("CRESCENT_CITY_195_20150128_Q.X612534Y472759L2LRATS" (terms "CRESCENT_CITY_195_20150128_Q.@@R1455.1.2.1" "CRESCENT_CITY_195_20150128_Q.T@@RATS@@R1455.1@@U100.DE44.1")) ("CRESCENT_CITY_195_20150128_Q.X625500Y472759L2RATS" (terms "CRESCENT_CITY_195_20150128_Q.@@R1287.2.1.1" "CRESCENT_CITY_195_20150128_Q.@@R1287.2_SOURCE.1")) ("CRESCENT_CITY_195_20150128_Q.X622000Y472759L2LRATS" (terms "CRESCENT_CITY_195_20150128_Q.@@R1287.2.1.2" "CRESCENT_CITY_195_20150128_Q.T@@RATS@@R1287.1@@J128.C20.1" "CRESCENT_CITY_195_20150128_Q.T@@RATS@@R1455.2@@R1287.1.2" "CRESCENT_CITY_195_20150128_Q.T@@RATS@@R1287.1@@R2851.2.1")) ("CRESCENT_CITY_195_20150128_Q.X53500Y367500L2LRATS" (terms "CRESCENT_CITY_195_20150128_Q.T@@RATS@@R1455.2@@R1398.2.2" "CRESCENT_CITY_195_20150128_Q.@@R1398.1.2.2")) ("CRESCENT_CITY_195_20150128_Q.X57000Y367500L2LRATS" (terms "CRESCENT_CITY_195_20150128_Q.T@@RATS@@R1398.1@@EU47.19.1" "CRESCENT_CITY_195_20150128_Q.@@R1398.1.2.1")) ("CRESCENT_CITY_195_20150128_Q.X67000Y362813L2LRATS" (terms "CRESCENT_CITY_195_20150128_Q.T@@RATS@@R1398.1@@EU47.19.2" "CRESCENT_CITY_195_20150128_Q.@@EU47.19.1"))) (Ports) (Stimuli ("local10" (scope local) (stimType periodic) (Props (periodicFreq "5e+007") (periodicJitter "0") (periodicPattern "1"))) ("local13" (scope local) (stimType periodic) (Props (periodicFreq "5e+007") (periodicJitter "0") (periodicPattern "1"))) ("local11" (scope local) (stimType periodic) (Props (periodicFreq "5e+007") (periodicJitter "0") (periodicPattern "1"))) ("local12" (scope local) (stimType periodic) (Props (periodicFreq "5e+007") (periodicJitter "0") (periodicPattern "1")))) (Notes) (Constraints ("DELAY_RULE" ("CRESCENT_CITY_195_20150128_Q U100.DE44" "CRESCENT_CITY_195_20150128_Q R1287.1" "LENGTH" "" "LENGTH" "0.1143") ("CRESCENT_CITY_195_20150128_Q R1455.2" "CRESCENT_CITY_195_20150128_Q R1287.1" "LENGTH" "" "LENGTH" "0.01016") ("CRESCENT_CITY_195_20150128_Q R1398.2" "CRESCENT_CITY_195_20150128_Q R1455.2" "LENGTH" "" "LENGTH" "0.6858") ("CRESCENT_CITY_195_20150128_Q EU111.17" "CRESCENT_CITY_195_20150128_Q R2851.1" "LENGTH" "" "LENGTH" "0.0254") ("CRESCENT_CITY_195_20150128_Q EU47.19" "CRESCENT_CITY_195_20150128_Q R1398.1" "LENGTH" "" "LENGTH" "0.0254")) ("RELATIVE_PROPAGATION_DELAY" ("#SVID_CPU0_1_U100-EU111" "CRESCENT_CITY_195_20150128_Q EU111.17" "CRESCENT_CITY_195_20150128_Q U100.DE44" "GLOBAL" "LENGTH" "0.00635" "NONE" "") ("#SVID_CPU0_1_U100-EU47" "CRESCENT_CITY_195_20150128_Q EU47.19" "CRESCENT_CITY_195_20150128_Q U100.DE44" "GLOBAL" "LENGTH" "0.00635" "NONE" ""))) (MeasurementSets ("EMI" ("EMIStatus" status("on")) ("PeakEmission" status("on")) ("PeakFrequency" status("on")) ("PulseFreq" status("on")) ("RiseTime" status("on")) ("VoltageSwing" status("on"))) ("Reflection" ("BufferDelayFall" status("off")) ("BufferDelayRise" status("off")) ("EyeHeight" status("off")) ("EyeJitter" status("off")) ("EyeWidth" status("off")) ("FirstIncidentFall" status("off")) ("FirstIncidentRise" status("off")) ("Glitch" status("on")) ("GlitchFall" status("off")) ("GlitchRise" status("off")) ("Monotonic" status("on")) ("MonotonicFall" status("off")) ("MonotonicRise" status("off")) ("NoiseMargin" status("on")) ("NoiseMarginHigh" status("off")) ("NoiseMarginLow" status("off")) ("OvershootHigh" status("on")) ("OvershootLow" status("on")) ("PropDelay" status("on")) ("SettleDelay" status("on")) ("SettleDelayFall" status("off")) ("SettleDelayRise" status("off")) ("SwitchDelay" status("on")) ("SwitchDelayFall" status("off")) ("SwitchDelayRise" status("off"))) ("Crosstalk" ("Crosstalk" status("on"))) ("Custom")) (VectorSets) (Props (XnetName "SVID_ALERT0_CPU1_N") (allDrivers "active") (customSimType "Reflection") (ftsMode ("Typ")) (rcvrSelect "all") (tlineDelayMode "time") (userRevision "1.0")))) (Subckts) (CrossSections ("CRESCENT_CITY_195_20150128_Q" (Props (SXDesignName "CRESCENT_CITY_195_20150128_Q")) (Layers ("" (layerType "SURFACE") (material "AIR") (thickness "0 mil") (dielectricConstant "1.000000") (lossTangent "0") (etchFactor "0.000000") (elecCondVal "0 mho/cm") (thermCondVal "0 w/cm-degC")) ("" (layerType "DIELECTRIC") (material "CONFORMAL_COAT") (thickness "0.5 mil") (dielectricConstant "3.800000") (lossTangent "0.035") (etchFactor "0.000000") (elecCondVal "0 mho/cm") (thermCondVal "0.012 w/cm-degC")) ("TOP" (layerType "CONDUCTOR") (material "COPPER") (thickness "  2.100000 mil") (width "4.00 MIL") (dielectricConstant "4.500000") (lossTangent "0") (etchFactor "70.000000") (elecCondVal "595900.000000 mho/cm") (thermCondVal "0 w/cm-degC") (signalDieConstant "3.800000") (signalLossTangent "0.035")) ("" (layerType "DIELECTRIC") (material "FR-4") (thickness "  2.670000 mil") (dielectricConstant "4.000000") (lossTangent "0.035") (etchFactor "0.000000") (elecCondVal "0 mho/cm") (thermCondVal "0.012 w/cm-degC")) ("L2_GND1" (layerType "PLANE") (material "COPPER") (isShield t) (thickness "  1.250000 mil") (dielectricConstant "4.500000") (lossTangent "0.035") (etchFactor "90.000000") (elecCondVal "595900.000000 mho/cm") (thermCondVal "0.012 w/cm-degC")) ("" (layerType "DIELECTRIC") (material "FR-4") (thickness "  9.000000 mil") (dielectricConstant "4.100000") (lossTangent "0.035") (etchFactor "0.000000") (elecCondVal "0 mho/cm") (thermCondVal "0.012 w/cm-degC")) ("L3_SIG1" (layerType "CONDUCTOR") (material "COPPER") (thickness "  1.250000 mil") (width "4.00 MIL") (dielectricConstant "4.500000") (lossTangent "0.035") (etchFactor "90.000000") (elecCondVal "595900.000000 mho/cm") (thermCondVal "0.012 w/cm-degC") (signalDieConstant "4.100000") (signalLossTangent "0.035")) ("" (layerType "DIELECTRIC") (material "FR-4") (thickness "  3.000000 mil") (dielectricConstant "4.500000") (lossTangent "0.035") (etchFactor "0.000000") (elecCondVal "0 mho/cm") (thermCondVal "0 w/cm-degC")) ("L4_GND2" (layerType "PLANE") (material "COPPER") (isShield t) (thickness "  1.250000 mil") (dielectricConstant "4.500000") (lossTangent "0.035") (etchFactor "90.000000") (elecCondVal "595900.000000 mho/cm") (thermCondVal "0 w/cm-degC")) ("" (layerType "DIELECTRIC") (material "FR-4") (thickness "  9.000000 mil") (dielectricConstant "4.000000") (lossTangent "0.035") (etchFactor "0.000000") (elecCondVal "0 mho/cm") (thermCondVal "0.012 w/cm-degC")) ("L5_SIG2" (layerType "CONDUCTOR") (material "COPPER") (thickness "  1.250000 mil") (width "4.00 MIL") (dielectricConstant "4.500000") (lossTangent "0.035") (etchFactor "90.000000") (elecCondVal "595900.000000 mho/cm") (thermCondVal "0.012 w/cm-degC") (signalDieConstant "4.000000") (signalLossTangent "0.035")) ("" (layerType "DIELECTRIC") (material "FR-4") (thickness "  3.000000 mil") (dielectricConstant "4.500000") (lossTangent "0.035") (etchFactor "0.000000") (elecCondVal "0 mho/cm") (thermCondVal "0 w/cm-degC")) ("L6_GND3" (layerType "PLANE") (material "COPPER") (isShield t) (thickness "  1.250000 mil") (dielectricConstant "4.500000") (lossTangent "0.035") (etchFactor "90.000000") (elecCondVal "595900.000000 mho/cm") (thermCondVal "0 w/cm-degC")) ("" (layerType "DIELECTRIC") (material "FR-4") (thickness "  4.500000 mil") (dielectricConstant "4.100000") (lossTangent "0.035") (etchFactor "0.000000") (elecCondVal "0 mho/cm") (thermCondVal "0.012 w/cm-degC")) ("L7_PWR1-SIG" (layerType "PLANE") (material "COPPER") (isShield t) (thickness "  2.400000 mil") (dielectricConstant "4.500000") (lossTangent "0.035") (etchFactor "90.000000") (elecCondVal "595900.000000 mho/cm") (thermCondVal "0.012 w/cm-degC")) ("" (layerType "DIELECTRIC") (material "FR-4") (thickness "  4.600000 mil") (dielectricConstant "4.000000") (lossTangent "0.035") (etchFactor "0.000000") (elecCondVal "0 mho/cm") (thermCondVal "0.012 w/cm-degC")) ("L8_PWR2-SIG" (layerType "PLANE") (material "COPPER") (isShield t) (thickness "  2.400000 mil") (dielectricConstant "4.500000") (lossTangent "0.035") (etchFactor "90.000000") (elecCondVal "595900.000000 mho/cm") (thermCondVal "0.012 w/cm-degC")) ("" (layerType "DIELECTRIC") (material "FR-4") (thickness "  8.000000 mil") (dielectricConstant "4.500000") (lossTangent "0.035") (etchFactor "0.000000") (elecCondVal "0 mho/cm") (thermCondVal "0 w/cm-degC")) ("" (layerType "DIELECTRIC") (material "FR-4") (thickness "  8.000000 mil") (dielectricConstant "4.500000") (lossTangent "0.035") (etchFactor "0.000000") (elecCondVal "0 mho/cm") (thermCondVal "0 w/cm-degC")) ("" (layerType "DIELECTRIC") (material "FR-4") (thickness "  4.500000 mil") (dielectricConstant "4.500000") (lossTangent "0.035") (etchFactor "0.000000") (elecCondVal "0 mho/cm") (thermCondVal "0 w/cm-degC")) ("L9_GND4" (layerType "PLANE") (material "COPPER") (isShield t) (thickness "  1.250000 mil") (dielectricConstant "4.500000") (lossTangent "0.035") (etchFactor "90.000000") (elecCondVal "595900.000000 mho/cm") (thermCondVal "0 w/cm-degC")) ("" (layerType "DIELECTRIC") (material "FR-4") (thickness "  3.000000 mil") (dielectricConstant "4.100000") (lossTangent "0.035") (etchFactor "0.000000") (elecCondVal "0 mho/cm") (thermCondVal "0.012 w/cm-degC")) ("L10_SIG3" (layerType "CONDUCTOR") (material "COPPER") (thickness "  1.250000 mil") (width "4.00 MIL") (dielectricConstant "4.500000") (lossTangent "0.035") (etchFactor "90.000000") (elecCondVal "595900.000000 mho/cm") (thermCondVal "0.012 w/cm-degC") (signalDieConstant "4.100000") (signalLossTangent "0.035")) ("" (layerType "DIELECTRIC") (material "FR-4") (thickness "  9.000000 mil") (dielectricConstant "4.500000") (lossTangent "0.035") (etchFactor "0.000000") (elecCondVal "0 mho/cm") (thermCondVal "0 w/cm-degC")) ("L11_GND5" (layerType "PLANE") (material "COPPER") (isShield t) (thickness "  1.250000 mil") (dielectricConstant "4.500000") (lossTangent "0.035") (etchFactor "90.000000") (elecCondVal "595900.000000 mho/cm") (thermCondVal "0 w/cm-degC")) ("" (layerType "DIELECTRIC") (material "FR-4") (thickness "  3.000000 mil") (dielectricConstant "4.500000") (lossTangent "0.035") (etchFactor "0.000000") (elecCondVal "0 mho/cm") (thermCondVal "0.012 w/cm-degC")) ("L12_SIG4" (layerType "CONDUCTOR") (material "COPPER") (thickness "  1.250000 mil") (width "4.00 MIL") (dielectricConstant "4.500000") (lossTangent "0.035") (etchFactor "90.000000") (elecCondVal "595900.000000 mho/cm") (thermCondVal "0.012 w/cm-degC") (signalDieConstant "4.500000") (signalLossTangent "0.035")) ("" (layerType "DIELECTRIC") (material "FR-4") (thickness "  9.000000 mil") (dielectricConstant "4.500000") (lossTangent "0.035") (etchFactor "0.000000") (elecCondVal "0 mho/cm") (thermCondVal "0 w/cm-degC")) ("L13_GND6" (layerType "PLANE") (material "COPPER") (isShield t) (thickness "  1.250000 mil") (dielectricConstant "4.500000") (lossTangent "0.035") (etchFactor "90.000000") (elecCondVal "595900.000000 mho/cm") (thermCondVal "0.012 w/cm-degC")) ("" (layerType "DIELECTRIC") (material "FR-4") (thickness "  2.670000 mil") (dielectricConstant "4.500000") (lossTangent "0.035") (etchFactor "0.000000") (elecCondVal "0 mho/cm") (thermCondVal "0.012 w/cm-degC")) ("BOTTOM" (layerType "CONDUCTOR") (material "COPPER") (thickness "  2.100000 mil") (width "4.00 MIL") (dielectricConstant "4.500000") (lossTangent "0") (etchFactor "70.000000") (elecCondVal "595900.000000 mho/cm") (thermCondVal "0 w/cm-degC") (signalDieConstant "3.800000") (signalLossTangent "0.035")) ("" (layerType "DIELECTRIC") (material "CONFORMAL_COAT") (thickness "0.5 mil") (dielectricConstant "3.800000") (lossTangent "0.035") (etchFactor "0.000000") (elecCondVal "0 mho/cm") (thermCondVal "0.012 w/cm-degC")) ("" (layerType "SURFACE") (material "AIR") (thickness "0 mil") (dielectricConstant "1.000000") (lossTangent "0") (etchFactor "0.000000") (elecCondVal "0 mho/cm") (thermCondVal "0 w/cm-degC"))))) (Props (DesUnits "mils 2") (LayerStack ("DIELECTRIC" "DIELECTRIC" "BOTTOM" "DIELECTRIC" "L13_GND6" "DIELECTRIC" "L12_SIG4" "DIELECTRIC" "L11_GND5" "DIELECTRIC" "L10_SIG3" "DIELECTRIC" "L9_GND4" "DIELECTRIC" "DIELECTRIC" "DIELECTRIC" "L8_PWR2-SIG" "DIELECTRIC" "L7_PWR1-SIG" "DIELECTRIC" "L6_GND3" "DIELECTRIC" "L5_SIG2" "DIELECTRIC" "L4_GND2" "DIELECTRIC" "L3_SIG1" "DIELECTRIC" "L2_GND1" "DIELECTRIC" "TOP" "DIELECTRIC" "DIELECTRIC")) (Revision "16.600")) (Params (DiffOutputPkg ((temperature "27") (bufferModelNonInverting "CDSDefaultOutput_2p5v") (bufferModelInverting "CDSDefaultOutput_2p5v") (stimuli nil) (offsets nil) (state "tristate") (cycle "1") (termMap nil) (setup "0.9e-09") (hold "0.4e-09") (rise nil) (fall nil) (threshOutputHighMin "2.375  V") (threshOutputHighTyp "2.5  V") (threshOutputHighMax "2.625  V") (threshOutputLowMin "1.275  V") (threshOutputLowTyp "1.7  V") (threshOutputLowMax "1.985  V") (mappingTagNonInverting nil) (mappingTagInverting nil) (spice nil))) (HiClampTerm ((cutoffVoltage "0.7 V") (voltage "5 V") (maxDelay "0.1 ns"))) (LowClampTerm ((cutoffVoltage "0.7 V") (voltage "0 V") (maxDelay "0.1 ns"))) (DiffOutput ((temperature "27") (bufferModelNonInverting "CDSDefaultOutput_2p5v") (bufferModelInverting "CDSDefaultOutput_2p5v") (stimuli nil) (offsets nil) (state "tristate") (cycle "1") (termMap nil) (setup "0.9e-09") (hold "0.4e-09") (rise nil) (fall nil) (threshOutputHighMin "2.375  V") (threshOutputHighTyp "2.5  V") (threshOutputHighMax "2.625  V") (threshOutputLowMin "1.275  V") (threshOutputLowTyp "1.7  V") (threshOutputLowMax "1.985  V") (mappingTagNonInverting nil) (mappingTagInverting nil) (spice nil))) (Via ((model "Unknown") (viaOutputFormat "Unknown") (viaPadstack nil) (viaTopLayer nil) (viaBottomLayer nil) (viaIsPower nil) (viaIsGround nil))) (Resistor ((resistance "50 ohm") (orientation "0"))) (RCTerm ((resistance "50 ohm") (capacitance "20 pF") (voltage "5 V") (maxDelay "0.1 ns"))) (DiffIOPkg ((temperature "27") (bufferModelNonInverting "CDSDefaultIO_2p5v") (bufferModelInverting "CDSDefaultIO_2p5v") (stimuli nil) (offsets nil) (state "tristate") (cycle "1") (termMap nil) (setup "0.9e-09") (hold "0.4e-09") (rise nil) (fall nil) (threshInputHighMin "1.7 V") (threshInputHighTyp "1.7  V") (threshInputHighMax "1.7  V") (threshInputLowMin "0.7  V") (threshInputLowTyp "0.7  V") (threshInputLowMax "0.7 ") (threshOutputHighMin "2.365  V") (threshOutputHighTyp "2.5  V") (threshOutputHighMax "2.625  V") (threshOutputLowMin "1.275  V") (threshOutputLowTyp "1.7  V") (threshOutputLowMax "1.985  V") (mappingTagNonInverting nil) (mappingTagInverting nil) (spice nil))) (Trace ((d1Thickness "10 mil") (d1Constant "4.5") (d1LossTangent "0.035") (d2Thickness "10 mil") (d2Constant "4.5") (d2LossTangent "0.035") (d3Thickness "0.0") (d3Constant "1.0") (d3LossTangent "0") length("1000 mil") (spacing "5 mil") (spacing2 "5 mil") (spacing3 "5 mil") (spacing4 "5 mil") (spacing5 "5 mil") (traceConductivity "595900 mho/cm") (traceGeometry "microstrip") (traceLayerName "") (traceThickness "0.72 mil") (traceType "single") (traceWidth "5.0 mil") (traceWidth2 "5.0 mil") (traceWidth3 "5.0 mil") (traceWidth4 "5.0 mil") (traceWidth5 "5.0 mil") (traceWidth6 "5.0 mil") (offset "0 mil") (traceCount "1") (impedance nil))) (TheveninTerm ((resistanceUp "180 ohm") (resistanceDown "270 ohm") (voltageUp "5 V") (voltageDown "0 V") (maxDelay "0.1 ns"))) (DiffIO ((temperature "27") (bufferModelNonInverting "CDSDefaultIO_2p5v") (bufferModelInverting "CDSDefaultIO_2p5v") (stimuli nil) (offsets nil) (state "tristate") (cycle "1") (termMap nil) (setup "0.9e-09") (hold "0.4e-09") (rise nil) (fall nil) (threshInputHighMin "1.7 V") (threshInputHighTyp "1.7  V") (threshInputHighMax "1.7  V") (threshInputLowMin "0.7  V") (threshInputLowTyp "0.7  V") (threshInputLowMax "0.7 ") (threshOutputHighMin "2.365  V") (threshOutputHighTyp "2.5  V") (threshOutputHighMax "2.625  V") (threshOutputLowMin "1.275  V") (threshOutputLowTyp "1.7  V") (threshOutputLowMax "1.985  V") (mappingTagNonInverting nil) (mappingTagInverting nil) (spice nil))) (ShuntTerm ((resistance "50 ohm") (voltage "5 V") (maxDelay "0.1 ns"))) (Inductor ((inductance "5 nH") (orientation "0"))) (Capacitor ((capacitance "10 pF") (orientation "0"))) (RLGC (length("1000 mil"))) (Source ((voltage "5 V"))) (DiffInput ((temperature "27") (bufferModelNonInverting "CDSDefaultInput_2p5v") (bufferModelInverting "CDSDefaultInput_2p5v") (threshInputHighMin "1.7 V") (threshInputHighTyp "1.7  V") (threshInputHighMax "1.7  V") (threshInputLowMin "0.7  V") (threshInputLowTyp "0.7  V") (threshInputLowMax "0.7  V") (mappingTagNonInverting nil) (mappingTagInverting nil) (cycle "1"))) (Cable (length("1 m"))) (CPWSL ((d1Thickness "10 mil") (d1Constant "4.5") (d1LossTangent "0.035") (d2Thickness "0.72 mil") (d2Constant "4.5") (d2LossTangent "0.035") (d3Thickness "10 mil") (d3Constant "4.5") (d3LossTangent "0.035") length("1000 mil") (spacing "5 mil") (spacing2 "5 mil") (spacing3 "5 mil") (spacing4 "5 mil") (spacing5 "5 mil") (traceConductivity "595900 mho/cm") (traceGeometry "cpwms") (traceLayerName "") (traceThickness "0.72 mil") (traceType "single") (traceWidth "5.0 mil") (traceWidth2 "5.0 mil") (traceWidth3 "5.0 mil") (traceWidth4 "5.0 mil") (traceWidth5 "5.0 mil") (traceWidth6 "5.0 mil") (offset "0 mil") (traceCount "1") (impedance nil))) (ESpiceDevice nil) (CPWMS ((d1Thickness "10 mil") (d1Constant "4.5") (d1LossTangent "0.035") (d2Thickness "0.72 mil") (d2Constant "4.5") (d2LossTangent "0.035") (d3Thickness "0.0") (d3Constant "1") (d3LossTangent "0") length("1000 mil") (spacing "5 mil") (spacing2 "5 mil") (spacing3 "5 mil") (spacing4 "5 mil") (spacing5 "5 mil") (traceConductivity "595900 mho/cm") (traceGeometry "cpwms") (traceLayerName "") (traceThickness "0.72 mil") (traceType "single") (traceWidth "5.0 mil") (traceWidth2 "5.0 mil") (traceWidth3 "5.0 mil") (traceWidth4 "5.0 mil") (traceWidth5 "5.0 mil") (traceWidth6 "5.0 mil") (offset "0 mil") (traceCount "1") (impedance nil))) (Diode ((cutoffVoltage "0.7 V"))) (CPW ((d1Thickness "10 mil") (d1Constant "4.5") (d1LossTangent "0.035") (d2Thickness "0.72 mil") (d2Constant "1") (d2LossTangent "0") (d3Thickness "0.0") (d3Constant "1") (d3LossTangent "0") length("1000 mil") (spacing "5 mil") (spacing2 "5 mil") (spacing3 "5 mil") (spacing4 "5 mil") (spacing5 "5 mil") (traceConductivity "595900 mho/cm") (traceGeometry "cpwms") (traceLayerName "") (traceThickness "0.72 mil") (traceType "single") (traceWidth "5.0 mil") (traceWidth2 "5.0 mil") (traceWidth3 "5.0 mil") (traceWidth4 "5.0 mil") (traceWidth5 "5.0 mil") (traceWidth6 "5.0 mil") (offset "0 mil") (traceCount "1") (impedance nil))) (DualClampTerm ((cutoffVoltageUp "0.7 V") (cutoffVoltageDown "0.7 V") (voltageUp "5 V") (voltageDown "0 V") (maxDelay "0.1 ns"))) (IbisOutputPkg ((temperature "27") (bufferModel "CDSDefaultOutput_2p5v") (stimuli nil) (offsets nil) (state "tristate") (cycle "1") (termMap nil) (setup "2.0e-09") (hold "1.0e-09") (rise nil) (fall nil) (macroType nil) (voltage nil) (spice nil) (LEFDEFPinName nil) (LEFDEFPinType nil) (mappingTag nil))) (IbisIO_OpenPullDown ((temperature "27") (bufferModel "CDSDefaultIO_2p5v") (stimuli nil) (offsets nil) (state "tristate") (cycle "1") (termMap nil) (setup "2.0e-09") (hold "1.0e-09") (rise nil) (fall nil) (macroType nil) (voltage nil) (spice nil) (LEFDEFPinName nil) (LEFDEFPinType nil) (mappingTag nil))) (IbisInputPkg ((temperature "27") (bufferModel "CDSDefaultInput_2p5v") (cycle "1") (LEFDEFPinName nil) (LEFDEFPinType nil) (mappingTag nil))) (IbisIOMacro ((temperature "27") (bufferModel "CDSDefaultIO_2p5v") (stimuli nil) (offsets nil) (state "tristate") (cycle "1") (termMap nil) (setup "2.0e-09") (hold "1.0e-09") (rise nil) (fall nil) (macroType nil) (voltage nil) (spice nil) (LEFDEFPinName nil) (LEFDEFPinType nil) (mappingTag nil))) (IbisIO_OpenPullUp ((temperature "27") (bufferModel "CDSDefaultIO_2p5v") (stimuli nil) (offsets nil) (state "tristate") (cycle "1") (termMap nil) (setup "2.0e-09") (hold "1.0e-09") (rise nil) (fall nil) (macroType nil) (voltage nil) (spice nil) (LEFDEFPinName nil) (LEFDEFPinType nil) (mappingTag nil))) (IbisIOPkg ((temperature "27") (bufferModel "CDSDefaultIO_2p5v") (stimuli nil) (offsets nil) (state "tristate") (cycle "1") (termMap nil) (setup "2.0e-09") (hold "1.0e-09") (rise nil) (fall nil) (macroType nil) (voltage nil) (spice nil) (LEFDEFPinName nil) (LEFDEFPinType nil) (mappingTag nil))) (clocked ((clockRise "1e-09") (clockFall "1e-09") (clockFreq "100e6") (clockInitState "0") (clockDutyCycle "0.5") (clockJitter "0"))) (periodic ((periodicFreq "100e6") (periodicPattern "10") (periodicJitter "0"))) (IbisIO ((temperature "27") (bufferModel "CDSDefaultIO_2p5v") (stimuli nil) (offsets nil) (state "tristate") (cycle "1") (termMap nil) (setup "2.0e-09") (hold "1.0e-09") (rise nil) (fall nil) (macroType nil) (voltage nil) (spice nil) (LEFDEFPinName nil) (LEFDEFPinType nil) (mappingTag nil))) (async ((asyncTimePoints "") (asyncInitState "1"))) (IbisOutput ((temperature "27") (bufferModel "CDSDefaultOutput_2p5v") (stimuli nil) (offsets nil) (state "tristate") (cycle "1") (termMap nil) (setup "2.0e-09") (hold "1.0e-09") (rise nil) (fall nil) (macroType nil) (voltage nil) (spice nil) (LEFDEFPinName nil) (LEFDEFPinType nil) (mappingTag nil))) (TLine ((diffImpedance "100ohm") (diffVelocity "1.4142e+08M/s") (impedance "60ohm") length("2800 mil") (propDelay "0.5 ns") (velocity "5600 mil/ns") (traceCount "1") (traceGeometry "Microstrip") (impedanceMin nil) (impedanceMax nil) (lengthMin nil) (lengthMax nil) (propDelayMin nil) (propDelayMax nil) (impedanceSweepCount nil) (propDelaySweepCount nil) (velocitySweepCount nil) (lengthSweepCount nil) (matchSetName nil))) (CurrentProbe nil) (IbisInput ((temperature "27") (bufferModel "CDSDefaultInput_2p5v") (cycle "1") (LEFDEFPinName nil) (LEFDEFPinType nil) (mappingTag nil))) (SeriesTerm ((resistance "22 ohm") (maxDelay "0.1 ns"))) (Connector nil) (sync ((syncFreq "100e6") (syncInitState "1") (syncPattern "10") (syncEdgeSwitch "rise"))) (IbisOutput_OpenPullUp ((temperature "27") (bufferModel "CDSDefaultOutput_2p5v") (stimuli nil) (offsets nil) (state "tristate") (cycle "1") (termMap nil) (setup "2.0e-09") (hold "1.0e-09") (rise nil) (fall nil) (macroType nil) (voltage nil) (spice nil) (LEFDEFPinName nil) (LEFDEFPinType nil) (mappingTag nil))) (DiffInputPkg ((temperature "27") (bufferModelNonInverting "CDSDefaultInput_2p5v") (bufferModelInverting "CDSDefaultInput_2p5v") (threshInputHighMin "1.7 V") (threshInputHighTyp "1.7  V") (threshInputHighMax "1.7  V") (threshInputLowMin "0.7  V") (threshInputLowTyp "0.7  V") (threshInputLowMax "0.7  V") (mappingTagNonInverting nil) (mappingTagInverting nil) (cycle "1"))) (idlCircuit ((allDrivers "active") (ftsMode '("Typ")) (rcvrSelect "all") (simMode "Reflection") (tlineDelayMode "time") (userRevision "1.0") (autoSolve "On")))))
				)
				( objectStatus "SVID_ALERT0_CPU1_N" )
			)
			( electricalCSet "@crescent_city_bb_fab1_lib.crescent_city_bb_fab1(sch_1):\DDR_J_CMD_DLL1-13\"
				( groupRef "DDR_J_CMD_DLL1-13:MG_DDR_CMD_NEAR_DIMM" )
				( groupRef "DDR_J_CMD_DLL1-13:MG_DDR_FAR_DIMM-CLK0" )
				( groupRef "DDR_J_CMD_DLL1-13:MG_DDR_FAR_DIMM_CMD" )
				( groupRef "DDR_J_CMD_DLL1-13:MG_DDR_NEAR_DIMM-CLK1" )
				( pinPairRef "DDR_J_CMD_DLL1-13:U2D1.F51:J9U2.228" )
				( pinPairRef "DDR_J_CMD_DLL1-13:U2D1.F51:J1G3.228" )
				( attribute "TOPOLOGY_TEMPLATE_REVISION" "1.0"
					( Origin gBackEnd )
				)
				( topologyData 23957
(SKIDL (Circuits ("MAIN" (Parts ("CRESCENT_CITY_083_20140724_A.@@J1.228" IbisIOPkg (xy (5548 4240)) (refDes "J1G3") (model "Unknown") (Props (_SXDesignName "CRESCENT_CITY_083_20140724_A") (brdx "10643.7 MIL") (brdy "788.33 MIL") (bufferModel "CDSDefaultIO_2p5v") (cycle "1") (hold "1.0e-09") (mappingTag "") (offsets ("4" "0") ("5" "0")) (setup "2.0e-09") (state "tristate") (stimuli ("4" "local0") ("5" "local1")) (temperature "27") (termMap ("4" "Data") ("5" "Enable"))) (Terms ("CRESCENT_CITY_083_20140724_A.X1064370Y78833L2LRATS" "228"))) ("CRESCENT_CITY_083_20140724_A.@@J2.228" IbisIOPkg (xy (5528 4240)) (refDes "J9U2") (model "Unknown") (Props (_SXDesignName "CRESCENT_CITY_083_20140724_A") (brdx "10643.7 MIL") (brdy "796.23 MIL") (bufferModel "CDSDefaultIO_2p5v") (cycle "1") (hold "1.0e-09") (mappingTag "") (offsets ("4" "0") ("5" "0")) (setup "2.0e-09") (state "tristate") (stimuli ("4" "local2") ("5" "local15")) (temperature "27") (termMap ("4" "Data") ("5" "Enable"))) (Terms ("CRESCENT_CITY_083_20140724_A.X1064370Y79623L28LRATS" "228"))) ("CRESCENT_CITY_083_20140724_A.@@U36.F51" IbisIOPkg (xy (5502 4240)) (refDes "U2D1") (model "Unknown") (Props (_SXDesignName "CRESCENT_CITY_083_20140724_A") (brdx "10346.35 MIL") (brdy "2052.1 MIL") (bufferModel "CDSDefaultIO_2p5v") (cycle "1") (hold "1.0e-09") (mappingTag "") (offsets ("4" "0") ("5" "0")) (setup "2.0e-09") (state "tristate") (stimuli ("4" "local16") ("5" "local17")) (temperature "27") (termMap ("4" "Data") ("5" "Enable"))) (Terms ("CRESCENT_CITY_083_20140724_A.X1034635Y205210L2LRATS" "F51"))) ("CRESCENT_CITY_083_20140724_A.T@@RATS@@J2.228@@U36.F51" TLine (xy (5513 4235)) (mirror x) (refDes "TL1") (Props (_SXDesignName "CRESCENT_CITY_083_20140724_A") (impedance "53.474 ohm") length("1553.22 MIL") (propDelay "0.27897 ns") (traceCount "1") (traceGeometry "Microstrip") (velocity "5567.68 mil/ns")) (Terms ("CRESCENT_CITY_083_20140724_A.X1064370Y79623L28LRATS" "1") ("CRESCENT_CITY_083_20140724_A.X1034635Y205210L2LRATS" "2"))) ("CRESCENT_CITY_083_20140724_A.T@@RATS@@J2.228@@J1.228" TLine (xy (5539 4235)) (refDes "TL2") (Props (_SXDesignName "CRESCENT_CITY_083_20140724_A") (impedance "39.682 ohm") length("7.90 MIL") (propDelay "0.00142 ns") (traceCount "1") (traceGeometry "Microstrip") (velocity "5563.39 mil/ns")) (Terms ("CRESCENT_CITY_083_20140724_A.X1064370Y79623L28LRATS" "1") ("CRESCENT_CITY_083_20140724_A.X1064370Y78833L2LRATS" "2")))) (Nodes ("CRESCENT_CITY_083_20140724_A.X1034635Y205210L2LRATS" (terms "CRESCENT_CITY_083_20140724_A.T@@RATS@@J2.228@@U36.F51.2" "CRESCENT_CITY_083_20140724_A.@@U36.F51.1")) ("CRESCENT_CITY_083_20140724_A.X1064370Y78833L2LRATS" (terms "CRESCENT_CITY_083_20140724_A.T@@RATS@@J2.228@@J1.228.2" "CRESCENT_CITY_083_20140724_A.@@J1.228.1")) ("CRESCENT_CITY_083_20140724_A.X1064370Y79623L28LRATS" (terms "CRESCENT_CITY_083_20140724_A.T@@RATS@@J2.228@@J1.228.1" "CRESCENT_CITY_083_20140724_A.T@@RATS@@J2.228@@U36.F51.1" "CRESCENT_CITY_083_20140724_A.@@J2.228.1"))) (Ports) (Stimuli ("local2" (scope local) (stimType periodic) (Props (periodicFreq "5e+007") (periodicJitter "0") (periodicPattern "1"))) ("local15" (scope local) (stimType periodic) (Props (periodicFreq "5e+007") (periodicJitter "0") (periodicPattern "1"))) ("local0" (scope local) (stimType periodic) (Props (periodicFreq "5e+007") (periodicJitter "0") (periodicPattern "1"))) ("local16" (scope local) (stimType periodic) (Props (periodicFreq "5e+007") (periodicJitter "0") (periodicPattern "1"))) ("local1" (scope local) (stimType periodic) (Props (periodicFreq "5e+007") (periodicJitter "0") (periodicPattern "1"))) ("local17" (scope local) (stimType periodic) (Props (periodicFreq "5e+007") (periodicJitter "0") (periodicPattern "1")))) (Notes) (Constraints ("RELATIVE_PROPAGATION_DELAY" ("MG_DDR_CMD_NEAR_DIMM" "CRESCENT_CITY_083_20140724_A U100.F51" "CRESCENT_CITY_083_20140724_A J18.228" "NET GROUP" "LENGTH" "0.000635" "LENGTH" "0") ("MG_DDR_FAR_DIMM-CLK0" "CRESCENT_CITY_083_20140724_A U100.F51" "CRESCENT_CITY_083_20140724_A J17.228" "CLASS" "LENGTH" "0.01778" "LENGTH" "0") ("MG_DDR_FAR_DIMM_CMD" "CRESCENT_CITY_083_20140724_A U100.F51" "CRESCENT_CITY_083_20140724_A J17.228" "NET GROUP" "LENGTH" "0.000635" "LENGTH" "0") ("MG_DDR_NEAR_DIMM-CLK1" "CRESCENT_CITY_083_20140724_A U100.F51" "CRESCENT_CITY_083_20140724_A J18.228" "CLASS" "LENGTH" "0.01778" "LENGTH" "0"))) (MeasurementSets ("EMI" ("EMIStatus" status("on")) ("PeakEmission" status("on")) ("PeakFrequency" status("on")) ("PulseFreq" status("on")) ("RiseTime" status("on")) ("VoltageSwing" status("on"))) ("Reflection" ("BufferDelayFall" status("off")) ("BufferDelayRise" status("off")) ("EyeHeight" status("off")) ("EyeJitter" status("off")) ("EyeWidth" status("off")) ("FirstIncidentFall" status("off")) ("FirstIncidentRise" status("off")) ("Glitch" status("on")) ("GlitchFall" status("off")) ("GlitchRise" status("off")) ("Monotonic" status("on")) ("MonotonicFall" status("off")) ("MonotonicRise" status("off")) ("NoiseMargin" status("on")) ("NoiseMarginHigh" status("off")) ("NoiseMarginLow" status("off")) ("OvershootHigh" status("on")) ("OvershootLow" status("on")) ("PropDelay" status("on")) ("SettleDelay" status("on")) ("SettleDelayFall" status("off")) ("SettleDelayRise" status("off")) ("SwitchDelay" status("on")) ("SwitchDelayFall" status("off")) ("SwitchDelayRise" status("off"))) ("Crosstalk" ("Crosstalk" status("on"))) ("Custom")) (VectorSets) (Props (XnetName "M_A_MA<14>") (allDrivers "active") (autoSolve "Off") (customSimType "Reflection") (ftsMode ("Typ")) (rcvrSelect "all") (tlineDelayMode "time") (userRevision "1.0")))) (Subckts) (CrossSections ("CRESCENT_CITY_083_20140724_A" (Props (SXDesignName "CRESCENT_CITY_083_20140724_A")) (Layers ("" (layerType "SURFACE") (material "AIR") (thickness "0 mil") (dielectricConstant "1.000000") (lossTangent "0") (etchFactor "0.000000") (elecCondVal "0 mho/cm") (thermCondVal "0 w/cm-degC")) ("" (layerType "DIELECTRIC") (material "CONFORMAL_COAT") (thickness "0.5 mil") (dielectricConstant "3.800000") (lossTangent "0.035") (etchFactor "0.000000") (elecCondVal "0 mho/cm") (thermCondVal "0.012 w/cm-degC")) ("TOP" (layerType "CONDUCTOR") (material "COPPER") (thickness "  1.800000 mil") (width "4.00 MIL") (dielectricConstant "4.500000") (lossTangent "0") (etchFactor "70.000000") (elecCondVal "595900.000000 mho/cm") (thermCondVal "0 w/cm-degC") (signalDieConstant "3.800000") (signalLossTangent "0.035")) ("" (layerType "DIELECTRIC") (material "FR-4") (thickness "  2.700000 mil") (dielectricConstant "4.000000") (lossTangent "0.035") (etchFactor "0.000000") (elecCondVal "0 mho/cm") (thermCondVal "0.012 w/cm-degC")) ("L2_GND1" (layerType "PLANE") (material "COPPER") (isShield t) (thickness "  1.200000 mil") (dielectricConstant "4.500000") (lossTangent "0.035") (etchFactor "90.000000") (elecCondVal "595900.000000 mho/cm") (thermCondVal "0.012 w/cm-degC")) ("" (layerType "DIELECTRIC") (material "FR-4") (thickness "  9.900000 mil") (dielectricConstant "4.100000") (lossTangent "0.035") (etchFactor "0.000000") (elecCondVal "0 mho/cm") (thermCondVal "0.012 w/cm-degC")) ("L3_SIG1" (layerType "CONDUCTOR") (material "COPPER") (thickness "  1.200000 mil") (width "4.00 MIL") (dielectricConstant "4.500000") (lossTangent "0.035") (etchFactor "90.000000") (elecCondVal "595900.000000 mho/cm") (thermCondVal "0.012 w/cm-degC") (signalDieConstant "4.100000") (signalLossTangent "0.035")) ("" (layerType "DIELECTRIC") (material "FR-4") (thickness "  3.300000 mil") (dielectricConstant "4.500000") (lossTangent "0.035") (etchFactor "0.000000") (elecCondVal "0 mho/cm") (thermCondVal "0 w/cm-degC")) ("L4_GND2" (layerType "PLANE") (material "COPPER") (isShield t) (thickness "  1.200000 mil") (dielectricConstant "4.500000") (lossTangent "0.035") (etchFactor "90.000000") (elecCondVal "595900.000000 mho/cm") (thermCondVal "0 w/cm-degC")) ("" (layerType "DIELECTRIC") (material "FR-4") (thickness "  3.300000 mil") (dielectricConstant "4.000000") (lossTangent "0.035") (etchFactor "0.000000") (elecCondVal "0 mho/cm") (thermCondVal "0.012 w/cm-degC")) ("L5_SIG2" (layerType "CONDUCTOR") (material "COPPER") (thickness "  1.200000 mil") (width "4.00 MIL") (dielectricConstant "4.500000") (lossTangent "0.035") (etchFactor "90.000000") (elecCondVal "595900.000000 mho/cm") (thermCondVal "0.012 w/cm-degC") (signalDieConstant "4.000000") (signalLossTangent "0.035")) ("" (layerType "DIELECTRIC") (material "FR-4") (thickness "  9.900000 mil") (dielectricConstant "4.500000") (lossTangent "0.035") (etchFactor "0.000000") (elecCondVal "0 mho/cm") (thermCondVal "0 w/cm-degC")) ("L6_GND3" (layerType "PLANE") (material "COPPER") (isShield t) (thickness "  1.200000 mil") (dielectricConstant "4.500000") (lossTangent "0.035") (etchFactor "90.000000") (elecCondVal "595900.000000 mho/cm") (thermCondVal "0 w/cm-degC")) ("" (layerType "DIELECTRIC") (material "FR-4") (thickness "  3.300000 mil") (dielectricConstant "4.100000") (lossTangent "0.035") (etchFactor "0.000000") (elecCondVal "0 mho/cm") (thermCondVal "0.012 w/cm-degC")) ("L7_PWR1-SIG" (layerType "PLANE") (material "COPPER") (isShield t) (thickness "  1.200000 mil") (dielectricConstant "4.500000") (lossTangent "0.035") (etchFactor "90.000000") (elecCondVal "595900.000000 mho/cm") (thermCondVal "0.012 w/cm-degC")) ("" (layerType "DIELECTRIC") (material "FR-4") (thickness "  9.900000 mil") (dielectricConstant "4.000000") (lossTangent "0.035") (etchFactor "0.000000") (elecCondVal "0 mho/cm") (thermCondVal "0.012 w/cm-degC")) ("L8_PWR2-SIG" (layerType "PLANE") (material "COPPER") (isShield t) (thickness "  1.200000 mil") (dielectricConstant "4.500000") (lossTangent "0.035") (etchFactor "90.000000") (elecCondVal "595900.000000 mho/cm") (thermCondVal "0.012 w/cm-degC")) ("" (layerType "DIELECTRIC") (material "FR-4") (thickness "  3.300000 mil") (dielectricConstant "4.500000") (lossTangent "0.035") (etchFactor "0.000000") (elecCondVal "0 mho/cm") (thermCondVal "0 w/cm-degC")) ("L9_GND4" (layerType "PLANE") (material "COPPER") (isShield t) (thickness "  1.200000 mil") (dielectricConstant "4.500000") (lossTangent "0.035") (etchFactor "90.000000") (elecCondVal "595900.000000 mho/cm") (thermCondVal "0 w/cm-degC")) ("" (layerType "DIELECTRIC") (material "FR-4") (thickness "  9.900000 mil") (dielectricConstant "4.100000") (lossTangent "0.035") (etchFactor "0.000000") (elecCondVal "0 mho/cm") (thermCondVal "0.012 w/cm-degC")) ("L10_SIG3" (layerType "CONDUCTOR") (material "COPPER") (thickness "  1.200000 mil") (width "4.00 MIL") (dielectricConstant "4.500000") (lossTangent "0.035") (etchFactor "90.000000") (elecCondVal "595900.000000 mho/cm") (thermCondVal "0.012 w/cm-degC") (signalDieConstant "4.100000") (signalLossTangent "0.035")) ("" (layerType "DIELECTRIC") (material "FR-4") (thickness "  3.300000 mil") (dielectricConstant "4.500000") (lossTangent "0.035") (etchFactor "0.000000") (elecCondVal "0 mho/cm") (thermCondVal "0 w/cm-degC")) ("L11_GND5" (layerType "PLANE") (material "COPPER") (isShield t) (thickness "  1.200000 mil") (dielectricConstant "4.500000") (lossTangent "0.035") (etchFactor "90.000000") (elecCondVal "595900.000000 mho/cm") (thermCondVal "0 w/cm-degC")) ("" (layerType "DIELECTRIC") (material "FR-4") (thickness "  9.900000 mil") (dielectricConstant "4.500000") (lossTangent "0.035") (etchFactor "0.000000") (elecCondVal "0 mho/cm") (thermCondVal "0.012 w/cm-degC")) ("L12_SIG4" (layerType "CONDUCTOR") (material "COPPER") (thickness "  1.200000 mil") (width "4.00 MIL") (dielectricConstant "4.500000") (lossTangent "0.035") (etchFactor "90.000000") (elecCondVal "595900.000000 mho/cm") (thermCondVal "0.012 w/cm-degC") (signalDieConstant "4.500000") (signalLossTangent "0.035")) ("" (layerType "DIELECTRIC") (material "FR-4") (thickness "  3.300000 mil") (dielectricConstant "4.500000") (lossTangent "0.035") (etchFactor "0.000000") (elecCondVal "0 mho/cm") (thermCondVal "0 w/cm-degC")) ("L13_GND6" (layerType "PLANE") (material "COPPER") (isShield t) (thickness "  1.200000 mil") (dielectricConstant "4.500000") (lossTangent "0.035") (etchFactor "90.000000") (elecCondVal "595900.000000 mho/cm") (thermCondVal "0.012 w/cm-degC")) ("" (layerType "DIELECTRIC") (material "FR-4") (thickness "  2.700000 mil") (dielectricConstant "4.500000") (lossTangent "0.035") (etchFactor "0.000000") (elecCondVal "0 mho/cm") (thermCondVal "0.012 w/cm-degC")) ("BOTTOM" (layerType "CONDUCTOR") (material "COPPER") (thickness "  1.800000 mil") (width "4.00 MIL") (dielectricConstant "4.500000") (lossTangent "0") (etchFactor "70.000000") (elecCondVal "595900.000000 mho/cm") (thermCondVal "0 w/cm-degC") (signalDieConstant "3.800000") (signalLossTangent "0.035")) ("" (layerType "DIELECTRIC") (material "CONFORMAL_COAT") (thickness "0.5 mil") (dielectricConstant "3.800000") (lossTangent "0.035") (etchFactor "0.000000") (elecCondVal "0 mho/cm") (thermCondVal "0.012 w/cm-degC")) ("" (layerType "SURFACE") (material "AIR") (thickness "0 mil") (dielectricConstant "1.000000") (lossTangent "0") (etchFactor "0.000000") (elecCondVal "0 mho/cm") (thermCondVal "0 w/cm-degC"))))) (Props (DesUnits "mils 2") (LayerStack ("DIELECTRIC" "DIELECTRIC" "BOTTOM" "DIELECTRIC" "L13_GND6" "DIELECTRIC" "L12_SIG4" "DIELECTRIC" "L11_GND5" "DIELECTRIC" "L10_SIG3" "DIELECTRIC" "L9_GND4" "DIELECTRIC" "L8_PWR2-SIG" "DIELECTRIC" "L7_PWR1-SIG" "DIELECTRIC" "L6_GND3" "DIELECTRIC" "L5_SIG2" "DIELECTRIC" "L4_GND2" "DIELECTRIC" "L3_SIG1" "DIELECTRIC" "L2_GND1" "DIELECTRIC" "TOP" "DIELECTRIC" "DIELECTRIC")) (Revision "16.600")) (Params (DualClampTerm ((cutoffVoltageUp "0.7 V") (cutoffVoltageDown "0.7 V") (voltageUp "5 V") (voltageDown "0 V") (maxDelay "0.1 ns"))) (HiClampTerm ((cutoffVoltage "0.7 V") (voltage "5 V") (maxDelay "0.1 ns"))) (IbisInputPkg ((temperature "27") (bufferModel "CDSDefaultInput_2p5v") (cycle "1") (LEFDEFPinName nil) (LEFDEFPinType nil) (mappingTag nil))) (RCTerm ((resistance "50 ohm") (capacitance "20 pF") (voltage "5 V") (maxDelay "0.1 ns"))) (IbisIOMacro ((temperature "27") (bufferModel "CDSDefaultIO_2p5v") (stimuli nil) (offsets nil) (state "tristate") (cycle "1") (termMap nil) (setup "2.0e-09") (hold "1.0e-09") (rise nil) (fall nil) (macroType nil) (voltage nil) (spice nil) (LEFDEFPinName nil) (LEFDEFPinType nil) (mappingTag nil))) (LowClampTerm ((cutoffVoltage "0.7 V") (voltage "0 V") (maxDelay "0.1 ns"))) (CurrentProbe nil) (IbisOutputPkg ((temperature "27") (bufferModel "CDSDefaultOutput_2p5v") (stimuli nil) (offsets nil) (state "tristate") (cycle "1") (termMap nil) (setup "2.0e-09") (hold "1.0e-09") (rise nil) (fall nil) (macroType nil) (voltage nil) (spice nil) (LEFDEFPinName nil) (LEFDEFPinType nil) (mappingTag nil))) (IbisIOPkg ((temperature "27") (bufferModel "CDSDefaultIO_2p5v") (stimuli nil) (offsets nil) (state "tristate") (cycle "1") (termMap nil) (setup "2.0e-09") (hold "1.0e-09") (rise nil) (fall nil) (macroType nil) (voltage nil) (spice nil) (LEFDEFPinName nil) (LEFDEFPinType nil) (mappingTag nil))) (SeriesTerm ((resistance "22 ohm") (maxDelay "0.1 ns"))) (IbisIO_OpenPullDown ((temperature "27") (bufferModel "CDSDefaultIO_2p5v") (stimuli nil) (offsets nil) (state "tristate") (cycle "1") (termMap nil) (setup "2.0e-09") (hold "1.0e-09") (rise nil) (fall nil) (macroType nil) (voltage nil) (spice nil) (LEFDEFPinName nil) (LEFDEFPinType nil) (mappingTag nil))) (clocked ((clockRise "1e-09") (clockFall "1e-09") (clockFreq "100e6") (clockInitState "0") (clockDutyCycle "0.5") (clockJitter "0"))) (CPWSL ((d1Thickness "10 mil") (d1Constant "4.5") (d1LossTangent "0.035") (d2Thickness "0.72 mil") (d2Constant "4.5") (d2LossTangent "0.035") (d3Thickness "10 mil") (d3Constant "4.5") (d3LossTangent "0.035") length("1000 mil") (spacing "5 mil") (spacing2 "5 mil") (spacing3 "5 mil") (spacing4 "5 mil") (spacing5 "5 mil") (traceConductivity "595900 mho/cm") (traceGeometry "cpwms") (traceLayerName "") (traceThickness "0.72 mil") (traceType "single") (traceWidth "5.0 mil") (traceWidth2 "5.0 mil") (traceWidth3 "5.0 mil") (traceWidth4 "5.0 mil") (traceWidth5 "5.0 mil") (traceWidth6 "5.0 mil") (offset "0 mil") (traceCount "1") (impedance nil))) (CPWMS ((d1Thickness "10 mil") (d1Constant "4.5") (d1LossTangent "0.035") (d2Thickness "0.72 mil") (d2Constant "4.5") (d2LossTangent "0.035") (d3Thickness "0.0") (d3Constant "1") (d3LossTangent "0") length("1000 mil") (spacing "5 mil") (spacing2 "5 mil") (spacing3 "5 mil") (spacing4 "5 mil") (spacing5 "5 mil") (traceConductivity "595900 mho/cm") (traceGeometry "cpwms") (traceLayerName "") (traceThickness "0.72 mil") (traceType "single") (traceWidth "5.0 mil") (traceWidth2 "5.0 mil") (traceWidth3 "5.0 mil") (traceWidth4 "5.0 mil") (traceWidth5 "5.0 mil") (traceWidth6 "5.0 mil") (offset "0 mil") (traceCount "1") (impedance nil))) (CPW ((d1Thickness "10 mil") (d1Constant "4.5") (d1LossTangent "0.035") (d2Thickness "0.72 mil") (d2Constant "1") (d2LossTangent "0") (d3Thickness "0.0") (d3Constant "1") (d3LossTangent "0") length("1000 mil") (spacing "5 mil") (spacing2 "5 mil") (spacing3 "5 mil") (spacing4 "5 mil") (spacing5 "5 mil") (traceConductivity "595900 mho/cm") (traceGeometry "cpwms") (traceLayerName "") (traceThickness "0.72 mil") (traceType "single") (traceWidth "5.0 mil") (traceWidth2 "5.0 mil") (traceWidth3 "5.0 mil") (traceWidth4 "5.0 mil") (traceWidth5 "5.0 mil") (traceWidth6 "5.0 mil") (offset "0 mil") (traceCount "1") (impedance nil))) (periodic ((periodicFreq "100e6") (periodicPattern "10") (periodicJitter "0"))) (Diode ((cutoffVoltage "0.7 V"))) (Trace ((d1Thickness "10 mil") (d1Constant "4.5") (d1LossTangent "0.035") (d2Thickness "10 mil") (d2Constant "4.5") (d2LossTangent "0.035") (d3Thickness "0.0") (d3Constant "1.0") (d3LossTangent "0") length("1000 mil") (spacing "5 mil") (spacing2 "5 mil") (spacing3 "5 mil") (spacing4 "5 mil") (spacing5 "5 mil") (traceConductivity "595900 mho/cm") (traceGeometry "microstrip") (traceLayerName "") (traceThickness "0.72 mil") (traceType "single") (traceWidth "5.0 mil") (traceWidth2 "5.0 mil") (traceWidth3 "5.0 mil") (traceWidth4 "5.0 mil") (traceWidth5 "5.0 mil") (traceWidth6 "5.0 mil") (offset "0 mil") (traceCount "1") (impedance nil))) (Cable (length("1 m"))) (Via ((model "Unknown") (viaOutputFormat "Unknown") (viaPadstack nil) (viaTopLayer nil) (viaBottomLayer nil) (viaIsPower nil) (viaIsGround nil))) (async ((asyncTimePoints "") (asyncInitState "1"))) (Resistor ((resistance "50 ohm") (orientation "0"))) (DiffOutputPkg ((temperature "27") (bufferModelNonInverting "CDSDefaultOutput_2p5v") (bufferModelInverting "CDSDefaultOutput_2p5v") (stimuli nil) (offsets nil) (state "tristate") (cycle "1") (termMap nil) (setup "0.9e-09") (hold "0.4e-09") (rise nil) (fall nil) (threshOutputHighMin "2.375  V") (threshOutputHighTyp "2.5  V") (threshOutputHighMax "2.625  V") (threshOutputLowMin "1.275  V") (threshOutputLowTyp "1.7  V") (threshOutputLowMax "1.985  V") (mappingTagNonInverting nil) (mappingTagInverting nil) (spice nil))) (DiffOutput ((temperature "27") (bufferModelNonInverting "CDSDefaultOutput_2p5v") (bufferModelInverting "CDSDefaultOutput_2p5v") (stimuli nil) (offsets nil) (state "tristate") (cycle "1") (termMap nil) (setup "0.9e-09") (hold "0.4e-09") (rise nil) (fall nil) (threshOutputHighMin "2.375  V") (threshOutputHighTyp "2.5  V") (threshOutputHighMax "2.625  V") (threshOutputLowMin "1.275  V") (threshOutputLowTyp "1.7  V") (threshOutputLowMax "1.985  V") (mappingTagNonInverting nil) (mappingTagInverting nil) (spice nil))) (IbisOutput ((temperature "27") (bufferModel "CDSDefaultOutput_2p5v") (stimuli nil) (offsets nil) (state "tristate") (cycle "1") (termMap nil) (setup "2.0e-09") (hold "1.0e-09") (rise nil) (fall nil) (macroType nil) (voltage nil) (spice nil) (LEFDEFPinName nil) (LEFDEFPinType nil) (mappingTag nil))) (Inductor ((inductance "5 nH") (orientation "0"))) (Capacitor ((capacitance "10 pF") (orientation "0"))) (DiffIOPkg ((temperature "27") (bufferModelNonInverting "CDSDefaultIO_2p5v") (bufferModelInverting "CDSDefaultIO_2p5v") (stimuli nil) (offsets nil) (state "tristate") (cycle "1") (termMap nil) (setup "0.9e-09") (hold "0.4e-09") (rise nil) (fall nil) (threshInputHighMin "1.7 V") (threshInputHighTyp "1.7  V") (threshInputHighMax "1.7  V") (threshInputLowMin "0.7  V") (threshInputLowTyp "0.7  V") (threshInputLowMax "0.7 ") (threshOutputHighMin "2.365  V") (threshOutputHighTyp "2.5  V") (threshOutputHighMax "2.625  V") (threshOutputLowMin "1.275  V") (threshOutputLowTyp "1.7  V") (threshOutputLowMax "1.985  V") (mappingTagNonInverting nil) (mappingTagInverting nil) (spice nil))) (IbisIO ((temperature "27") (bufferModel "CDSDefaultIO_2p5v") (stimuli nil) (offsets nil) (state "tristate") (cycle "1") (termMap nil) (setup "2.0e-09") (hold "1.0e-09") (rise nil) (fall nil) (macroType nil) (voltage nil) (spice nil) (LEFDEFPinName nil) (LEFDEFPinType nil) (mappingTag nil))) (Source ((voltage "5 V"))) (DiffIO ((temperature "27") (bufferModelNonInverting "CDSDefaultIO_2p5v") (bufferModelInverting "CDSDefaultIO_2p5v") (stimuli nil) (offsets nil) (state "tristate") (cycle "1") (termMap nil) (setup "0.9e-09") (hold "0.4e-09") (rise nil) (fall nil) (threshInputHighMin "1.7 V") (threshInputHighTyp "1.7  V") (threshInputHighMax "1.7  V") (threshInputLowMin "0.7  V") (threshInputLowTyp "0.7  V") (threshInputLowMax "0.7 ") (threshOutputHighMin "2.365  V") (threshOutputHighTyp "2.5  V") (threshOutputHighMax "2.625  V") (threshOutputLowMin "1.275  V") (threshOutputLowTyp "1.7  V") (threshOutputLowMax "1.985  V") (mappingTagNonInverting nil) (mappingTagInverting nil) (spice nil))) (RLGC (length("1000 mil"))) (IbisInput ((temperature "27") (bufferModel "CDSDefaultInput_2p5v") (cycle "1") (LEFDEFPinName nil) (LEFDEFPinType nil) (mappingTag nil))) (DiffInput ((temperature "27") (bufferModelNonInverting "CDSDefaultInput_2p5v") (bufferModelInverting "CDSDefaultInput_2p5v") (threshInputHighMin "1.7 V") (threshInputHighTyp "1.7  V") (threshInputHighMax "1.7  V") (threshInputLowMin "0.7  V") (threshInputLowTyp "0.7  V") (threshInputLowMax "0.7  V") (mappingTagNonInverting nil) (mappingTagInverting nil) (cycle "1"))) (ESpiceDevice nil) (sync ((syncFreq "100e6") (syncInitState "1") (syncPattern "10") (syncEdgeSwitch "rise"))) (TLine ((diffImpedance "100ohm") (diffVelocity "1.4142e+08M/s") (impedance "60ohm") length("2800 mil") (propDelay "0.5 ns") (velocity "5600 mil/ns") (traceCount "1") (traceGeometry "Microstrip") (impedanceMin nil) (impedanceMax nil) (lengthMin nil) (lengthMax nil) (propDelayMin nil) (propDelayMax nil) (impedanceSweepCount nil) (propDelaySweepCount nil) (velocitySweepCount nil) (lengthSweepCount nil) (matchSetName nil))) (Connector nil) (ShuntTerm ((resistance "50 ohm") (voltage "5 V") (maxDelay "0.1 ns"))) (TheveninTerm ((resistanceUp "180 ohm") (resistanceDown "270 ohm") (voltageUp "5 V") (voltageDown "0 V") (maxDelay "0.1 ns"))) (IbisIO_OpenPullUp ((temperature "27") (bufferModel "CDSDefaultIO_2p5v") (stimuli nil) (offsets nil) (state "tristate") (cycle "1") (termMap nil) (setup "2.0e-09") (hold "1.0e-09") (rise nil) (fall nil) (macroType nil) (voltage nil) (spice nil) (LEFDEFPinName nil) (LEFDEFPinType nil) (mappingTag nil))) (DiffInputPkg ((temperature "27") (bufferModelNonInverting "CDSDefaultInput_2p5v") (bufferModelInverting "CDSDefaultInput_2p5v") (threshInputHighMin "1.7 V") (threshInputHighTyp "1.7  V") (threshInputHighMax "1.7  V") (threshInputLowMin "0.7  V") (threshInputLowTyp "0.7  V") (threshInputLowMax "0.7  V") (mappingTagNonInverting nil) (mappingTagInverting nil) (cycle "1"))) (IbisOutput_OpenPullUp ((temperature "27") (bufferModel "CDSDefaultOutput_2p5v") (stimuli nil) (offsets nil) (state "tristate") (cycle "1") (termMap nil) (setup "2.0e-09") (hold "1.0e-09") (rise nil) (fall nil) (macroType nil) (voltage nil) (spice nil) (LEFDEFPinName nil) (LEFDEFPinType nil) (mappingTag nil))) (idlCircuit ((allDrivers "active") (ftsMode '("Typ")) (rcvrSelect "all") (simMode "Reflection") (tlineDelayMode "time") (userRevision "1.0") (autoSolve "On")))))
				)
				( objectStatus "DDR_J_CMD_DLL1-13" )
			)
			( electricalCSet "@crescent_city_bb_fab1_lib.crescent_city_bb_fab1(sch_1):\DDR_H_CMD_DLL1-13\"
				( groupRef "DDR_H_CMD_DLL1-13:MG_DDR_CMD_NEAR_DIMM" )
				( groupRef "DDR_H_CMD_DLL1-13:MG_DDR_FAR_DIMM-CLK0" )
				( groupRef "DDR_H_CMD_DLL1-13:MG_DDR_FAR_DIMM_CMD" )
				( groupRef "DDR_H_CMD_DLL1-13:MG_DDR_NEAR_DIMM-CLK1" )
				( pinPairRef "DDR_H_CMD_DLL1-13:U2D1.F51:J9U1.228" )
				( pinPairRef "DDR_H_CMD_DLL1-13:U2D1.F51:J1G2.228" )
				( attribute "TOPOLOGY_TEMPLATE_REVISION" "1.0"
					( Origin gBackEnd )
				)
				( topologyData 23957
(SKIDL (Circuits ("MAIN" (Parts ("CRESCENT_CITY_083_20140724_A.@@J1.228" IbisIOPkg (xy (5548 4240)) (refDes "J1G2") (model "Unknown") (Props (_SXDesignName "CRESCENT_CITY_083_20140724_A") (brdx "10643.7 MIL") (brdy "788.33 MIL") (bufferModel "CDSDefaultIO_2p5v") (cycle "1") (hold "1.0e-09") (mappingTag "") (offsets ("4" "0") ("5" "0")) (setup "2.0e-09") (state "tristate") (stimuli ("4" "local0") ("5" "local1")) (temperature "27") (termMap ("4" "Data") ("5" "Enable"))) (Terms ("CRESCENT_CITY_083_20140724_A.X1064370Y78833L2LRATS" "228"))) ("CRESCENT_CITY_083_20140724_A.@@J2.228" IbisIOPkg (xy (5528 4240)) (refDes "J9U1") (model "Unknown") (Props (_SXDesignName "CRESCENT_CITY_083_20140724_A") (brdx "10643.7 MIL") (brdy "796.23 MIL") (bufferModel "CDSDefaultIO_2p5v") (cycle "1") (hold "1.0e-09") (mappingTag "") (offsets ("4" "0") ("5" "0")) (setup "2.0e-09") (state "tristate") (stimuli ("4" "local2") ("5" "local15")) (temperature "27") (termMap ("4" "Data") ("5" "Enable"))) (Terms ("CRESCENT_CITY_083_20140724_A.X1064370Y79623L28LRATS" "228"))) ("CRESCENT_CITY_083_20140724_A.@@U36.F51" IbisIOPkg (xy (5502 4240)) (refDes "U2D1") (model "Unknown") (Props (_SXDesignName "CRESCENT_CITY_083_20140724_A") (brdx "10346.35 MIL") (brdy "2052.1 MIL") (bufferModel "CDSDefaultIO_2p5v") (cycle "1") (hold "1.0e-09") (mappingTag "") (offsets ("4" "0") ("5" "0")) (setup "2.0e-09") (state "tristate") (stimuli ("4" "local16") ("5" "local17")) (temperature "27") (termMap ("4" "Data") ("5" "Enable"))) (Terms ("CRESCENT_CITY_083_20140724_A.X1034635Y205210L2LRATS" "F51"))) ("CRESCENT_CITY_083_20140724_A.T@@RATS@@J2.228@@U36.F51" TLine (xy (5513 4235)) (mirror x) (refDes "TL1") (Props (_SXDesignName "CRESCENT_CITY_083_20140724_A") (impedance "53.474 ohm") length("1553.22 MIL") (propDelay "0.27897 ns") (traceCount "1") (traceGeometry "Microstrip") (velocity "5567.68 mil/ns")) (Terms ("CRESCENT_CITY_083_20140724_A.X1064370Y79623L28LRATS" "1") ("CRESCENT_CITY_083_20140724_A.X1034635Y205210L2LRATS" "2"))) ("CRESCENT_CITY_083_20140724_A.T@@RATS@@J2.228@@J1.228" TLine (xy (5539 4235)) (refDes "TL2") (Props (_SXDesignName "CRESCENT_CITY_083_20140724_A") (impedance "39.682 ohm") length("7.90 MIL") (propDelay "0.00142 ns") (traceCount "1") (traceGeometry "Microstrip") (velocity "5563.39 mil/ns")) (Terms ("CRESCENT_CITY_083_20140724_A.X1064370Y79623L28LRATS" "1") ("CRESCENT_CITY_083_20140724_A.X1064370Y78833L2LRATS" "2")))) (Nodes ("CRESCENT_CITY_083_20140724_A.X1034635Y205210L2LRATS" (terms "CRESCENT_CITY_083_20140724_A.T@@RATS@@J2.228@@U36.F51.2" "CRESCENT_CITY_083_20140724_A.@@U36.F51.1")) ("CRESCENT_CITY_083_20140724_A.X1064370Y78833L2LRATS" (terms "CRESCENT_CITY_083_20140724_A.T@@RATS@@J2.228@@J1.228.2" "CRESCENT_CITY_083_20140724_A.@@J1.228.1")) ("CRESCENT_CITY_083_20140724_A.X1064370Y79623L28LRATS" (terms "CRESCENT_CITY_083_20140724_A.T@@RATS@@J2.228@@J1.228.1" "CRESCENT_CITY_083_20140724_A.T@@RATS@@J2.228@@U36.F51.1" "CRESCENT_CITY_083_20140724_A.@@J2.228.1"))) (Ports) (Stimuli ("local2" (scope local) (stimType periodic) (Props (periodicFreq "5e+007") (periodicJitter "0") (periodicPattern "1"))) ("local15" (scope local) (stimType periodic) (Props (periodicFreq "5e+007") (periodicJitter "0") (periodicPattern "1"))) ("local0" (scope local) (stimType periodic) (Props (periodicFreq "5e+007") (periodicJitter "0") (periodicPattern "1"))) ("local16" (scope local) (stimType periodic) (Props (periodicFreq "5e+007") (periodicJitter "0") (periodicPattern "1"))) ("local1" (scope local) (stimType periodic) (Props (periodicFreq "5e+007") (periodicJitter "0") (periodicPattern "1"))) ("local17" (scope local) (stimType periodic) (Props (periodicFreq "5e+007") (periodicJitter "0") (periodicPattern "1")))) (Notes) (Constraints ("RELATIVE_PROPAGATION_DELAY" ("MG_DDR_CMD_NEAR_DIMM" "CRESCENT_CITY_083_20140724_A U100.F51" "CRESCENT_CITY_083_20140724_A J16.228" "NET GROUP" "LENGTH" "0.000635" "LENGTH" "0") ("MG_DDR_FAR_DIMM-CLK0" "CRESCENT_CITY_083_20140724_A U100.F51" "CRESCENT_CITY_083_20140724_A J15.228" "CLASS" "LENGTH" "0.01778" "LENGTH" "0") ("MG_DDR_FAR_DIMM_CMD" "CRESCENT_CITY_083_20140724_A U100.F51" "CRESCENT_CITY_083_20140724_A J15.228" "NET GROUP" "LENGTH" "0.000635" "LENGTH" "0") ("MG_DDR_NEAR_DIMM-CLK1" "CRESCENT_CITY_083_20140724_A U100.F51" "CRESCENT_CITY_083_20140724_A J16.228" "CLASS" "LENGTH" "0.01778" "LENGTH" "0"))) (MeasurementSets ("EMI" ("EMIStatus" status("on")) ("PeakEmission" status("on")) ("PeakFrequency" status("on")) ("PulseFreq" status("on")) ("RiseTime" status("on")) ("VoltageSwing" status("on"))) ("Reflection" ("BufferDelayFall" status("off")) ("BufferDelayRise" status("off")) ("EyeHeight" status("off")) ("EyeJitter" status("off")) ("EyeWidth" status("off")) ("FirstIncidentFall" status("off")) ("FirstIncidentRise" status("off")) ("Glitch" status("on")) ("GlitchFall" status("off")) ("GlitchRise" status("off")) ("Monotonic" status("on")) ("MonotonicFall" status("off")) ("MonotonicRise" status("off")) ("NoiseMargin" status("on")) ("NoiseMarginHigh" status("off")) ("NoiseMarginLow" status("off")) ("OvershootHigh" status("on")) ("OvershootLow" status("on")) ("PropDelay" status("on")) ("SettleDelay" status("on")) ("SettleDelayFall" status("off")) ("SettleDelayRise" status("off")) ("SwitchDelay" status("on")) ("SwitchDelayFall" status("off")) ("SwitchDelayRise" status("off"))) ("Crosstalk" ("Crosstalk" status("on"))) ("Custom")) (VectorSets) (Props (XnetName "M_A_MA<14>") (allDrivers "active") (autoSolve "Off") (customSimType "Reflection") (ftsMode ("Typ")) (rcvrSelect "all") (tlineDelayMode "time") (userRevision "1.0")))) (Subckts) (CrossSections ("CRESCENT_CITY_083_20140724_A" (Props (SXDesignName "CRESCENT_CITY_083_20140724_A")) (Layers ("" (layerType "SURFACE") (material "AIR") (thickness "0 mil") (dielectricConstant "1.000000") (lossTangent "0") (etchFactor "0.000000") (elecCondVal "0 mho/cm") (thermCondVal "0 w/cm-degC")) ("" (layerType "DIELECTRIC") (material "CONFORMAL_COAT") (thickness "0.5 mil") (dielectricConstant "3.800000") (lossTangent "0.035") (etchFactor "0.000000") (elecCondVal "0 mho/cm") (thermCondVal "0.012 w/cm-degC")) ("TOP" (layerType "CONDUCTOR") (material "COPPER") (thickness "  1.800000 mil") (width "4.00 MIL") (dielectricConstant "4.500000") (lossTangent "0") (etchFactor "70.000000") (elecCondVal "595900.000000 mho/cm") (thermCondVal "0 w/cm-degC") (signalDieConstant "3.800000") (signalLossTangent "0.035")) ("" (layerType "DIELECTRIC") (material "FR-4") (thickness "  2.700000 mil") (dielectricConstant "4.000000") (lossTangent "0.035") (etchFactor "0.000000") (elecCondVal "0 mho/cm") (thermCondVal "0.012 w/cm-degC")) ("L2_GND1" (layerType "PLANE") (material "COPPER") (isShield t) (thickness "  1.200000 mil") (dielectricConstant "4.500000") (lossTangent "0.035") (etchFactor "90.000000") (elecCondVal "595900.000000 mho/cm") (thermCondVal "0.012 w/cm-degC")) ("" (layerType "DIELECTRIC") (material "FR-4") (thickness "  9.900000 mil") (dielectricConstant "4.100000") (lossTangent "0.035") (etchFactor "0.000000") (elecCondVal "0 mho/cm") (thermCondVal "0.012 w/cm-degC")) ("L3_SIG1" (layerType "CONDUCTOR") (material "COPPER") (thickness "  1.200000 mil") (width "4.00 MIL") (dielectricConstant "4.500000") (lossTangent "0.035") (etchFactor "90.000000") (elecCondVal "595900.000000 mho/cm") (thermCondVal "0.012 w/cm-degC") (signalDieConstant "4.100000") (signalLossTangent "0.035")) ("" (layerType "DIELECTRIC") (material "FR-4") (thickness "  3.300000 mil") (dielectricConstant "4.500000") (lossTangent "0.035") (etchFactor "0.000000") (elecCondVal "0 mho/cm") (thermCondVal "0 w/cm-degC")) ("L4_GND2" (layerType "PLANE") (material "COPPER") (isShield t) (thickness "  1.200000 mil") (dielectricConstant "4.500000") (lossTangent "0.035") (etchFactor "90.000000") (elecCondVal "595900.000000 mho/cm") (thermCondVal "0 w/cm-degC")) ("" (layerType "DIELECTRIC") (material "FR-4") (thickness "  3.300000 mil") (dielectricConstant "4.000000") (lossTangent "0.035") (etchFactor "0.000000") (elecCondVal "0 mho/cm") (thermCondVal "0.012 w/cm-degC")) ("L5_SIG2" (layerType "CONDUCTOR") (material "COPPER") (thickness "  1.200000 mil") (width "4.00 MIL") (dielectricConstant "4.500000") (lossTangent "0.035") (etchFactor "90.000000") (elecCondVal "595900.000000 mho/cm") (thermCondVal "0.012 w/cm-degC") (signalDieConstant "4.000000") (signalLossTangent "0.035")) ("" (layerType "DIELECTRIC") (material "FR-4") (thickness "  9.900000 mil") (dielectricConstant "4.500000") (lossTangent "0.035") (etchFactor "0.000000") (elecCondVal "0 mho/cm") (thermCondVal "0 w/cm-degC")) ("L6_GND3" (layerType "PLANE") (material "COPPER") (isShield t) (thickness "  1.200000 mil") (dielectricConstant "4.500000") (lossTangent "0.035") (etchFactor "90.000000") (elecCondVal "595900.000000 mho/cm") (thermCondVal "0 w/cm-degC")) ("" (layerType "DIELECTRIC") (material "FR-4") (thickness "  3.300000 mil") (dielectricConstant "4.100000") (lossTangent "0.035") (etchFactor "0.000000") (elecCondVal "0 mho/cm") (thermCondVal "0.012 w/cm-degC")) ("L7_PWR1-SIG" (layerType "PLANE") (material "COPPER") (isShield t) (thickness "  1.200000 mil") (dielectricConstant "4.500000") (lossTangent "0.035") (etchFactor "90.000000") (elecCondVal "595900.000000 mho/cm") (thermCondVal "0.012 w/cm-degC")) ("" (layerType "DIELECTRIC") (material "FR-4") (thickness "  9.900000 mil") (dielectricConstant "4.000000") (lossTangent "0.035") (etchFactor "0.000000") (elecCondVal "0 mho/cm") (thermCondVal "0.012 w/cm-degC")) ("L8_PWR2-SIG" (layerType "PLANE") (material "COPPER") (isShield t) (thickness "  1.200000 mil") (dielectricConstant "4.500000") (lossTangent "0.035") (etchFactor "90.000000") (elecCondVal "595900.000000 mho/cm") (thermCondVal "0.012 w/cm-degC")) ("" (layerType "DIELECTRIC") (material "FR-4") (thickness "  3.300000 mil") (dielectricConstant "4.500000") (lossTangent "0.035") (etchFactor "0.000000") (elecCondVal "0 mho/cm") (thermCondVal "0 w/cm-degC")) ("L9_GND4" (layerType "PLANE") (material "COPPER") (isShield t) (thickness "  1.200000 mil") (dielectricConstant "4.500000") (lossTangent "0.035") (etchFactor "90.000000") (elecCondVal "595900.000000 mho/cm") (thermCondVal "0 w/cm-degC")) ("" (layerType "DIELECTRIC") (material "FR-4") (thickness "  9.900000 mil") (dielectricConstant "4.100000") (lossTangent "0.035") (etchFactor "0.000000") (elecCondVal "0 mho/cm") (thermCondVal "0.012 w/cm-degC")) ("L10_SIG3" (layerType "CONDUCTOR") (material "COPPER") (thickness "  1.200000 mil") (width "4.00 MIL") (dielectricConstant "4.500000") (lossTangent "0.035") (etchFactor "90.000000") (elecCondVal "595900.000000 mho/cm") (thermCondVal "0.012 w/cm-degC") (signalDieConstant "4.100000") (signalLossTangent "0.035")) ("" (layerType "DIELECTRIC") (material "FR-4") (thickness "  3.300000 mil") (dielectricConstant "4.500000") (lossTangent "0.035") (etchFactor "0.000000") (elecCondVal "0 mho/cm") (thermCondVal "0 w/cm-degC")) ("L11_GND5" (layerType "PLANE") (material "COPPER") (isShield t) (thickness "  1.200000 mil") (dielectricConstant "4.500000") (lossTangent "0.035") (etchFactor "90.000000") (elecCondVal "595900.000000 mho/cm") (thermCondVal "0 w/cm-degC")) ("" (layerType "DIELECTRIC") (material "FR-4") (thickness "  9.900000 mil") (dielectricConstant "4.500000") (lossTangent "0.035") (etchFactor "0.000000") (elecCondVal "0 mho/cm") (thermCondVal "0.012 w/cm-degC")) ("L12_SIG4" (layerType "CONDUCTOR") (material "COPPER") (thickness "  1.200000 mil") (width "4.00 MIL") (dielectricConstant "4.500000") (lossTangent "0.035") (etchFactor "90.000000") (elecCondVal "595900.000000 mho/cm") (thermCondVal "0.012 w/cm-degC") (signalDieConstant "4.500000") (signalLossTangent "0.035")) ("" (layerType "DIELECTRIC") (material "FR-4") (thickness "  3.300000 mil") (dielectricConstant "4.500000") (lossTangent "0.035") (etchFactor "0.000000") (elecCondVal "0 mho/cm") (thermCondVal "0 w/cm-degC")) ("L13_GND6" (layerType "PLANE") (material "COPPER") (isShield t) (thickness "  1.200000 mil") (dielectricConstant "4.500000") (lossTangent "0.035") (etchFactor "90.000000") (elecCondVal "595900.000000 mho/cm") (thermCondVal "0.012 w/cm-degC")) ("" (layerType "DIELECTRIC") (material "FR-4") (thickness "  2.700000 mil") (dielectricConstant "4.500000") (lossTangent "0.035") (etchFactor "0.000000") (elecCondVal "0 mho/cm") (thermCondVal "0.012 w/cm-degC")) ("BOTTOM" (layerType "CONDUCTOR") (material "COPPER") (thickness "  1.800000 mil") (width "4.00 MIL") (dielectricConstant "4.500000") (lossTangent "0") (etchFactor "70.000000") (elecCondVal "595900.000000 mho/cm") (thermCondVal "0 w/cm-degC") (signalDieConstant "3.800000") (signalLossTangent "0.035")) ("" (layerType "DIELECTRIC") (material "CONFORMAL_COAT") (thickness "0.5 mil") (dielectricConstant "3.800000") (lossTangent "0.035") (etchFactor "0.000000") (elecCondVal "0 mho/cm") (thermCondVal "0.012 w/cm-degC")) ("" (layerType "SURFACE") (material "AIR") (thickness "0 mil") (dielectricConstant "1.000000") (lossTangent "0") (etchFactor "0.000000") (elecCondVal "0 mho/cm") (thermCondVal "0 w/cm-degC"))))) (Props (DesUnits "mils 2") (LayerStack ("DIELECTRIC" "DIELECTRIC" "BOTTOM" "DIELECTRIC" "L13_GND6" "DIELECTRIC" "L12_SIG4" "DIELECTRIC" "L11_GND5" "DIELECTRIC" "L10_SIG3" "DIELECTRIC" "L9_GND4" "DIELECTRIC" "L8_PWR2-SIG" "DIELECTRIC" "L7_PWR1-SIG" "DIELECTRIC" "L6_GND3" "DIELECTRIC" "L5_SIG2" "DIELECTRIC" "L4_GND2" "DIELECTRIC" "L3_SIG1" "DIELECTRIC" "L2_GND1" "DIELECTRIC" "TOP" "DIELECTRIC" "DIELECTRIC")) (Revision "16.600")) (Params (DualClampTerm ((cutoffVoltageUp "0.7 V") (cutoffVoltageDown "0.7 V") (voltageUp "5 V") (voltageDown "0 V") (maxDelay "0.1 ns"))) (HiClampTerm ((cutoffVoltage "0.7 V") (voltage "5 V") (maxDelay "0.1 ns"))) (IbisInputPkg ((temperature "27") (bufferModel "CDSDefaultInput_2p5v") (cycle "1") (LEFDEFPinName nil) (LEFDEFPinType nil) (mappingTag nil))) (RCTerm ((resistance "50 ohm") (capacitance "20 pF") (voltage "5 V") (maxDelay "0.1 ns"))) (IbisIOMacro ((temperature "27") (bufferModel "CDSDefaultIO_2p5v") (stimuli nil) (offsets nil) (state "tristate") (cycle "1") (termMap nil) (setup "2.0e-09") (hold "1.0e-09") (rise nil) (fall nil) (macroType nil) (voltage nil) (spice nil) (LEFDEFPinName nil) (LEFDEFPinType nil) (mappingTag nil))) (LowClampTerm ((cutoffVoltage "0.7 V") (voltage "0 V") (maxDelay "0.1 ns"))) (CurrentProbe nil) (IbisOutputPkg ((temperature "27") (bufferModel "CDSDefaultOutput_2p5v") (stimuli nil) (offsets nil) (state "tristate") (cycle "1") (termMap nil) (setup "2.0e-09") (hold "1.0e-09") (rise nil) (fall nil) (macroType nil) (voltage nil) (spice nil) (LEFDEFPinName nil) (LEFDEFPinType nil) (mappingTag nil))) (IbisIOPkg ((temperature "27") (bufferModel "CDSDefaultIO_2p5v") (stimuli nil) (offsets nil) (state "tristate") (cycle "1") (termMap nil) (setup "2.0e-09") (hold "1.0e-09") (rise nil) (fall nil) (macroType nil) (voltage nil) (spice nil) (LEFDEFPinName nil) (LEFDEFPinType nil) (mappingTag nil))) (SeriesTerm ((resistance "22 ohm") (maxDelay "0.1 ns"))) (IbisIO_OpenPullDown ((temperature "27") (bufferModel "CDSDefaultIO_2p5v") (stimuli nil) (offsets nil) (state "tristate") (cycle "1") (termMap nil) (setup "2.0e-09") (hold "1.0e-09") (rise nil) (fall nil) (macroType nil) (voltage nil) (spice nil) (LEFDEFPinName nil) (LEFDEFPinType nil) (mappingTag nil))) (clocked ((clockRise "1e-09") (clockFall "1e-09") (clockFreq "100e6") (clockInitState "0") (clockDutyCycle "0.5") (clockJitter "0"))) (CPWSL ((d1Thickness "10 mil") (d1Constant "4.5") (d1LossTangent "0.035") (d2Thickness "0.72 mil") (d2Constant "4.5") (d2LossTangent "0.035") (d3Thickness "10 mil") (d3Constant "4.5") (d3LossTangent "0.035") length("1000 mil") (spacing "5 mil") (spacing2 "5 mil") (spacing3 "5 mil") (spacing4 "5 mil") (spacing5 "5 mil") (traceConductivity "595900 mho/cm") (traceGeometry "cpwms") (traceLayerName "") (traceThickness "0.72 mil") (traceType "single") (traceWidth "5.0 mil") (traceWidth2 "5.0 mil") (traceWidth3 "5.0 mil") (traceWidth4 "5.0 mil") (traceWidth5 "5.0 mil") (traceWidth6 "5.0 mil") (offset "0 mil") (traceCount "1") (impedance nil))) (CPWMS ((d1Thickness "10 mil") (d1Constant "4.5") (d1LossTangent "0.035") (d2Thickness "0.72 mil") (d2Constant "4.5") (d2LossTangent "0.035") (d3Thickness "0.0") (d3Constant "1") (d3LossTangent "0") length("1000 mil") (spacing "5 mil") (spacing2 "5 mil") (spacing3 "5 mil") (spacing4 "5 mil") (spacing5 "5 mil") (traceConductivity "595900 mho/cm") (traceGeometry "cpwms") (traceLayerName "") (traceThickness "0.72 mil") (traceType "single") (traceWidth "5.0 mil") (traceWidth2 "5.0 mil") (traceWidth3 "5.0 mil") (traceWidth4 "5.0 mil") (traceWidth5 "5.0 mil") (traceWidth6 "5.0 mil") (offset "0 mil") (traceCount "1") (impedance nil))) (CPW ((d1Thickness "10 mil") (d1Constant "4.5") (d1LossTangent "0.035") (d2Thickness "0.72 mil") (d2Constant "1") (d2LossTangent "0") (d3Thickness "0.0") (d3Constant "1") (d3LossTangent "0") length("1000 mil") (spacing "5 mil") (spacing2 "5 mil") (spacing3 "5 mil") (spacing4 "5 mil") (spacing5 "5 mil") (traceConductivity "595900 mho/cm") (traceGeometry "cpwms") (traceLayerName "") (traceThickness "0.72 mil") (traceType "single") (traceWidth "5.0 mil") (traceWidth2 "5.0 mil") (traceWidth3 "5.0 mil") (traceWidth4 "5.0 mil") (traceWidth5 "5.0 mil") (traceWidth6 "5.0 mil") (offset "0 mil") (traceCount "1") (impedance nil))) (periodic ((periodicFreq "100e6") (periodicPattern "10") (periodicJitter "0"))) (Diode ((cutoffVoltage "0.7 V"))) (Trace ((d1Thickness "10 mil") (d1Constant "4.5") (d1LossTangent "0.035") (d2Thickness "10 mil") (d2Constant "4.5") (d2LossTangent "0.035") (d3Thickness "0.0") (d3Constant "1.0") (d3LossTangent "0") length("1000 mil") (spacing "5 mil") (spacing2 "5 mil") (spacing3 "5 mil") (spacing4 "5 mil") (spacing5 "5 mil") (traceConductivity "595900 mho/cm") (traceGeometry "microstrip") (traceLayerName "") (traceThickness "0.72 mil") (traceType "single") (traceWidth "5.0 mil") (traceWidth2 "5.0 mil") (traceWidth3 "5.0 mil") (traceWidth4 "5.0 mil") (traceWidth5 "5.0 mil") (traceWidth6 "5.0 mil") (offset "0 mil") (traceCount "1") (impedance nil))) (Cable (length("1 m"))) (Via ((model "Unknown") (viaOutputFormat "Unknown") (viaPadstack nil) (viaTopLayer nil) (viaBottomLayer nil) (viaIsPower nil) (viaIsGround nil))) (async ((asyncTimePoints "") (asyncInitState "1"))) (Resistor ((resistance "50 ohm") (orientation "0"))) (DiffOutputPkg ((temperature "27") (bufferModelNonInverting "CDSDefaultOutput_2p5v") (bufferModelInverting "CDSDefaultOutput_2p5v") (stimuli nil) (offsets nil) (state "tristate") (cycle "1") (termMap nil) (setup "0.9e-09") (hold "0.4e-09") (rise nil) (fall nil) (threshOutputHighMin "2.375  V") (threshOutputHighTyp "2.5  V") (threshOutputHighMax "2.625  V") (threshOutputLowMin "1.275  V") (threshOutputLowTyp "1.7  V") (threshOutputLowMax "1.985  V") (mappingTagNonInverting nil) (mappingTagInverting nil) (spice nil))) (DiffOutput ((temperature "27") (bufferModelNonInverting "CDSDefaultOutput_2p5v") (bufferModelInverting "CDSDefaultOutput_2p5v") (stimuli nil) (offsets nil) (state "tristate") (cycle "1") (termMap nil) (setup "0.9e-09") (hold "0.4e-09") (rise nil) (fall nil) (threshOutputHighMin "2.375  V") (threshOutputHighTyp "2.5  V") (threshOutputHighMax "2.625  V") (threshOutputLowMin "1.275  V") (threshOutputLowTyp "1.7  V") (threshOutputLowMax "1.985  V") (mappingTagNonInverting nil) (mappingTagInverting nil) (spice nil))) (IbisOutput ((temperature "27") (bufferModel "CDSDefaultOutput_2p5v") (stimuli nil) (offsets nil) (state "tristate") (cycle "1") (termMap nil) (setup "2.0e-09") (hold "1.0e-09") (rise nil) (fall nil) (macroType nil) (voltage nil) (spice nil) (LEFDEFPinName nil) (LEFDEFPinType nil) (mappingTag nil))) (Inductor ((inductance "5 nH") (orientation "0"))) (Capacitor ((capacitance "10 pF") (orientation "0"))) (DiffIOPkg ((temperature "27") (bufferModelNonInverting "CDSDefaultIO_2p5v") (bufferModelInverting "CDSDefaultIO_2p5v") (stimuli nil) (offsets nil) (state "tristate") (cycle "1") (termMap nil) (setup "0.9e-09") (hold "0.4e-09") (rise nil) (fall nil) (threshInputHighMin "1.7 V") (threshInputHighTyp "1.7  V") (threshInputHighMax "1.7  V") (threshInputLowMin "0.7  V") (threshInputLowTyp "0.7  V") (threshInputLowMax "0.7 ") (threshOutputHighMin "2.365  V") (threshOutputHighTyp "2.5  V") (threshOutputHighMax "2.625  V") (threshOutputLowMin "1.275  V") (threshOutputLowTyp "1.7  V") (threshOutputLowMax "1.985  V") (mappingTagNonInverting nil) (mappingTagInverting nil) (spice nil))) (IbisIO ((temperature "27") (bufferModel "CDSDefaultIO_2p5v") (stimuli nil) (offsets nil) (state "tristate") (cycle "1") (termMap nil) (setup "2.0e-09") (hold "1.0e-09") (rise nil) (fall nil) (macroType nil) (voltage nil) (spice nil) (LEFDEFPinName nil) (LEFDEFPinType nil) (mappingTag nil))) (Source ((voltage "5 V"))) (DiffIO ((temperature "27") (bufferModelNonInverting "CDSDefaultIO_2p5v") (bufferModelInverting "CDSDefaultIO_2p5v") (stimuli nil) (offsets nil) (state "tristate") (cycle "1") (termMap nil) (setup "0.9e-09") (hold "0.4e-09") (rise nil) (fall nil) (threshInputHighMin "1.7 V") (threshInputHighTyp "1.7  V") (threshInputHighMax "1.7  V") (threshInputLowMin "0.7  V") (threshInputLowTyp "0.7  V") (threshInputLowMax "0.7 ") (threshOutputHighMin "2.365  V") (threshOutputHighTyp "2.5  V") (threshOutputHighMax "2.625  V") (threshOutputLowMin "1.275  V") (threshOutputLowTyp "1.7  V") (threshOutputLowMax "1.985  V") (mappingTagNonInverting nil) (mappingTagInverting nil) (spice nil))) (RLGC (length("1000 mil"))) (IbisInput ((temperature "27") (bufferModel "CDSDefaultInput_2p5v") (cycle "1") (LEFDEFPinName nil) (LEFDEFPinType nil) (mappingTag nil))) (DiffInput ((temperature "27") (bufferModelNonInverting "CDSDefaultInput_2p5v") (bufferModelInverting "CDSDefaultInput_2p5v") (threshInputHighMin "1.7 V") (threshInputHighTyp "1.7  V") (threshInputHighMax "1.7  V") (threshInputLowMin "0.7  V") (threshInputLowTyp "0.7  V") (threshInputLowMax "0.7  V") (mappingTagNonInverting nil) (mappingTagInverting nil) (cycle "1"))) (ESpiceDevice nil) (sync ((syncFreq "100e6") (syncInitState "1") (syncPattern "10") (syncEdgeSwitch "rise"))) (TLine ((diffImpedance "100ohm") (diffVelocity "1.4142e+08M/s") (impedance "60ohm") length("2800 mil") (propDelay "0.5 ns") (velocity "5600 mil/ns") (traceCount "1") (traceGeometry "Microstrip") (impedanceMin nil) (impedanceMax nil) (lengthMin nil) (lengthMax nil) (propDelayMin nil) (propDelayMax nil) (impedanceSweepCount nil) (propDelaySweepCount nil) (velocitySweepCount nil) (lengthSweepCount nil) (matchSetName nil))) (Connector nil) (ShuntTerm ((resistance "50 ohm") (voltage "5 V") (maxDelay "0.1 ns"))) (TheveninTerm ((resistanceUp "180 ohm") (resistanceDown "270 ohm") (voltageUp "5 V") (voltageDown "0 V") (maxDelay "0.1 ns"))) (IbisIO_OpenPullUp ((temperature "27") (bufferModel "CDSDefaultIO_2p5v") (stimuli nil) (offsets nil) (state "tristate") (cycle "1") (termMap nil) (setup "2.0e-09") (hold "1.0e-09") (rise nil) (fall nil) (macroType nil) (voltage nil) (spice nil) (LEFDEFPinName nil) (LEFDEFPinType nil) (mappingTag nil))) (DiffInputPkg ((temperature "27") (bufferModelNonInverting "CDSDefaultInput_2p5v") (bufferModelInverting "CDSDefaultInput_2p5v") (threshInputHighMin "1.7 V") (threshInputHighTyp "1.7  V") (threshInputHighMax "1.7  V") (threshInputLowMin "0.7  V") (threshInputLowTyp "0.7  V") (threshInputLowMax "0.7  V") (mappingTagNonInverting nil) (mappingTagInverting nil) (cycle "1"))) (IbisOutput_OpenPullUp ((temperature "27") (bufferModel "CDSDefaultOutput_2p5v") (stimuli nil) (offsets nil) (state "tristate") (cycle "1") (termMap nil) (setup "2.0e-09") (hold "1.0e-09") (rise nil) (fall nil) (macroType nil) (voltage nil) (spice nil) (LEFDEFPinName nil) (LEFDEFPinType nil) (mappingTag nil))) (idlCircuit ((allDrivers "active") (ftsMode '("Typ")) (rcvrSelect "all") (simMode "Reflection") (tlineDelayMode "time") (userRevision "1.0") (autoSolve "On")))))
				)
				( objectStatus "DDR_H_CMD_DLL1-13" )
			)
			( electricalCSet "@crescent_city_bb_fab1_lib.crescent_city_bb_fab1(sch_1):\DDR_G_CMD_DLL1-13\"
				( groupRef "DDR_G_CMD_DLL1-13:MG_DDR_NEAR_DIMM-CLK1" )
				( groupRef "DDR_G_CMD_DLL1-13:MG_DDR_FAR_DIMM_CMD" )
				( groupRef "DDR_G_CMD_DLL1-13:MG_DDR_FAR_DIMM-CLK0" )
				( groupRef "DDR_G_CMD_DLL1-13:MG_DDR_CMD_NEAR_DIMM" )
				( pinPairRef "DDR_G_CMD_DLL1-13:U2D1.F51:J9T1.228" )
				( pinPairRef "DDR_G_CMD_DLL1-13:U2D1.F51:J1G1.228" )
				( attribute "TOPOLOGY_TEMPLATE_REVISION" "1.0"
					( Origin gBackEnd )
				)
				( topologyData 23957
(SKIDL (Circuits ("MAIN" (Parts ("CRESCENT_CITY_083_20140724_A.@@J1.228" IbisIOPkg (xy (5548 4240)) (refDes "J1G1") (model "Unknown") (Props (_SXDesignName "CRESCENT_CITY_083_20140724_A") (brdx "10643.7 MIL") (brdy "788.33 MIL") (bufferModel "CDSDefaultIO_2p5v") (cycle "1") (hold "1.0e-09") (mappingTag "") (offsets ("4" "0") ("5" "0")) (setup "2.0e-09") (state "tristate") (stimuli ("4" "local0") ("5" "local1")) (temperature "27") (termMap ("4" "Data") ("5" "Enable"))) (Terms ("CRESCENT_CITY_083_20140724_A.X1064370Y78833L2LRATS" "228"))) ("CRESCENT_CITY_083_20140724_A.@@J2.228" IbisIOPkg (xy (5528 4240)) (refDes "J9T1") (model "Unknown") (Props (_SXDesignName "CRESCENT_CITY_083_20140724_A") (brdx "10643.7 MIL") (brdy "796.23 MIL") (bufferModel "CDSDefaultIO_2p5v") (cycle "1") (hold "1.0e-09") (mappingTag "") (offsets ("4" "0") ("5" "0")) (setup "2.0e-09") (state "tristate") (stimuli ("4" "local2") ("5" "local15")) (temperature "27") (termMap ("4" "Data") ("5" "Enable"))) (Terms ("CRESCENT_CITY_083_20140724_A.X1064370Y79623L28LRATS" "228"))) ("CRESCENT_CITY_083_20140724_A.@@U36.F51" IbisIOPkg (xy (5502 4240)) (refDes "U2D1") (model "Unknown") (Props (_SXDesignName "CRESCENT_CITY_083_20140724_A") (brdx "10346.35 MIL") (brdy "2052.1 MIL") (bufferModel "CDSDefaultIO_2p5v") (cycle "1") (hold "1.0e-09") (mappingTag "") (offsets ("4" "0") ("5" "0")) (setup "2.0e-09") (state "tristate") (stimuli ("4" "local16") ("5" "local17")) (temperature "27") (termMap ("4" "Data") ("5" "Enable"))) (Terms ("CRESCENT_CITY_083_20140724_A.X1034635Y205210L2LRATS" "F51"))) ("CRESCENT_CITY_083_20140724_A.T@@RATS@@J2.228@@U36.F51" TLine (xy (5513 4235)) (mirror x) (refDes "TL1") (Props (_SXDesignName "CRESCENT_CITY_083_20140724_A") (impedance "53.474 ohm") length("1553.22 MIL") (propDelay "0.27897 ns") (traceCount "1") (traceGeometry "Microstrip") (velocity "5567.68 mil/ns")) (Terms ("CRESCENT_CITY_083_20140724_A.X1064370Y79623L28LRATS" "1") ("CRESCENT_CITY_083_20140724_A.X1034635Y205210L2LRATS" "2"))) ("CRESCENT_CITY_083_20140724_A.T@@RATS@@J2.228@@J1.228" TLine (xy (5539 4235)) (refDes "TL2") (Props (_SXDesignName "CRESCENT_CITY_083_20140724_A") (impedance "39.682 ohm") length("7.90 MIL") (propDelay "0.00142 ns") (traceCount "1") (traceGeometry "Microstrip") (velocity "5563.39 mil/ns")) (Terms ("CRESCENT_CITY_083_20140724_A.X1064370Y79623L28LRATS" "1") ("CRESCENT_CITY_083_20140724_A.X1064370Y78833L2LRATS" "2")))) (Nodes ("CRESCENT_CITY_083_20140724_A.X1034635Y205210L2LRATS" (terms "CRESCENT_CITY_083_20140724_A.T@@RATS@@J2.228@@U36.F51.2" "CRESCENT_CITY_083_20140724_A.@@U36.F51.1")) ("CRESCENT_CITY_083_20140724_A.X1064370Y78833L2LRATS" (terms "CRESCENT_CITY_083_20140724_A.T@@RATS@@J2.228@@J1.228.2" "CRESCENT_CITY_083_20140724_A.@@J1.228.1")) ("CRESCENT_CITY_083_20140724_A.X1064370Y79623L28LRATS" (terms "CRESCENT_CITY_083_20140724_A.T@@RATS@@J2.228@@J1.228.1" "CRESCENT_CITY_083_20140724_A.T@@RATS@@J2.228@@U36.F51.1" "CRESCENT_CITY_083_20140724_A.@@J2.228.1"))) (Ports) (Stimuli ("local2" (scope local) (stimType periodic) (Props (periodicFreq "5e+007") (periodicJitter "0") (periodicPattern "1"))) ("local15" (scope local) (stimType periodic) (Props (periodicFreq "5e+007") (periodicJitter "0") (periodicPattern "1"))) ("local0" (scope local) (stimType periodic) (Props (periodicFreq "5e+007") (periodicJitter "0") (periodicPattern "1"))) ("local16" (scope local) (stimType periodic) (Props (periodicFreq "5e+007") (periodicJitter "0") (periodicPattern "1"))) ("local1" (scope local) (stimType periodic) (Props (periodicFreq "5e+007") (periodicJitter "0") (periodicPattern "1"))) ("local17" (scope local) (stimType periodic) (Props (periodicFreq "5e+007") (periodicJitter "0") (periodicPattern "1")))) (Notes) (Constraints ("RELATIVE_PROPAGATION_DELAY" ("MG_DDR_NEAR_DIMM-CLK1" "CRESCENT_CITY_083_20140724_A U100.F51" "CRESCENT_CITY_083_20140724_A J14.228" "CLASS" "LENGTH" "0.01778" "LENGTH" "0") ("MG_DDR_FAR_DIMM_CMD" "CRESCENT_CITY_083_20140724_A U100.F51" "CRESCENT_CITY_083_20140724_A J13.228" "NET GROUP" "LENGTH" "0.000635" "LENGTH" "0") ("MG_DDR_FAR_DIMM-CLK0" "CRESCENT_CITY_083_20140724_A U100.F51" "CRESCENT_CITY_083_20140724_A J13.228" "CLASS" "LENGTH" "0.01778" "LENGTH" "0") ("MG_DDR_CMD_NEAR_DIMM" "CRESCENT_CITY_083_20140724_A U100.F51" "CRESCENT_CITY_083_20140724_A J14.228" "NET GROUP" "LENGTH" "0.000635" "LENGTH" "0"))) (MeasurementSets ("EMI" ("EMIStatus" status("on")) ("PeakEmission" status("on")) ("PeakFrequency" status("on")) ("PulseFreq" status("on")) ("RiseTime" status("on")) ("VoltageSwing" status("on"))) ("Reflection" ("BufferDelayFall" status("off")) ("BufferDelayRise" status("off")) ("EyeHeight" status("off")) ("EyeJitter" status("off")) ("EyeWidth" status("off")) ("FirstIncidentFall" status("off")) ("FirstIncidentRise" status("off")) ("Glitch" status("on")) ("GlitchFall" status("off")) ("GlitchRise" status("off")) ("Monotonic" status("on")) ("MonotonicFall" status("off")) ("MonotonicRise" status("off")) ("NoiseMargin" status("on")) ("NoiseMarginHigh" status("off")) ("NoiseMarginLow" status("off")) ("OvershootHigh" status("on")) ("OvershootLow" status("on")) ("PropDelay" status("on")) ("SettleDelay" status("on")) ("SettleDelayFall" status("off")) ("SettleDelayRise" status("off")) ("SwitchDelay" status("on")) ("SwitchDelayFall" status("off")) ("SwitchDelayRise" status("off"))) ("Crosstalk" ("Crosstalk" status("on"))) ("Custom")) (VectorSets) (Props (XnetName "M_A_MA<14>") (allDrivers "active") (autoSolve "Off") (customSimType "Reflection") (ftsMode ("Typ")) (rcvrSelect "all") (tlineDelayMode "time") (userRevision "1.0")))) (Subckts) (CrossSections ("CRESCENT_CITY_083_20140724_A" (Props (SXDesignName "CRESCENT_CITY_083_20140724_A")) (Layers ("" (layerType "SURFACE") (material "AIR") (thickness "0 mil") (dielectricConstant "1.000000") (lossTangent "0") (etchFactor "0.000000") (elecCondVal "0 mho/cm") (thermCondVal "0 w/cm-degC")) ("" (layerType "DIELECTRIC") (material "CONFORMAL_COAT") (thickness "0.5 mil") (dielectricConstant "3.800000") (lossTangent "0.035") (etchFactor "0.000000") (elecCondVal "0 mho/cm") (thermCondVal "0.012 w/cm-degC")) ("TOP" (layerType "CONDUCTOR") (material "COPPER") (thickness "  1.800000 mil") (width "4.00 MIL") (dielectricConstant "4.500000") (lossTangent "0") (etchFactor "70.000000") (elecCondVal "595900.000000 mho/cm") (thermCondVal "0 w/cm-degC") (signalDieConstant "3.800000") (signalLossTangent "0.035")) ("" (layerType "DIELECTRIC") (material "FR-4") (thickness "  2.700000 mil") (dielectricConstant "4.000000") (lossTangent "0.035") (etchFactor "0.000000") (elecCondVal "0 mho/cm") (thermCondVal "0.012 w/cm-degC")) ("L2_GND1" (layerType "PLANE") (material "COPPER") (isShield t) (thickness "  1.200000 mil") (dielectricConstant "4.500000") (lossTangent "0.035") (etchFactor "90.000000") (elecCondVal "595900.000000 mho/cm") (thermCondVal "0.012 w/cm-degC")) ("" (layerType "DIELECTRIC") (material "FR-4") (thickness "  9.900000 mil") (dielectricConstant "4.100000") (lossTangent "0.035") (etchFactor "0.000000") (elecCondVal "0 mho/cm") (thermCondVal "0.012 w/cm-degC")) ("L3_SIG1" (layerType "CONDUCTOR") (material "COPPER") (thickness "  1.200000 mil") (width "4.00 MIL") (dielectricConstant "4.500000") (lossTangent "0.035") (etchFactor "90.000000") (elecCondVal "595900.000000 mho/cm") (thermCondVal "0.012 w/cm-degC") (signalDieConstant "4.100000") (signalLossTangent "0.035")) ("" (layerType "DIELECTRIC") (material "FR-4") (thickness "  3.300000 mil") (dielectricConstant "4.500000") (lossTangent "0.035") (etchFactor "0.000000") (elecCondVal "0 mho/cm") (thermCondVal "0 w/cm-degC")) ("L4_GND2" (layerType "PLANE") (material "COPPER") (isShield t) (thickness "  1.200000 mil") (dielectricConstant "4.500000") (lossTangent "0.035") (etchFactor "90.000000") (elecCondVal "595900.000000 mho/cm") (thermCondVal "0 w/cm-degC")) ("" (layerType "DIELECTRIC") (material "FR-4") (thickness "  3.300000 mil") (dielectricConstant "4.000000") (lossTangent "0.035") (etchFactor "0.000000") (elecCondVal "0 mho/cm") (thermCondVal "0.012 w/cm-degC")) ("L5_SIG2" (layerType "CONDUCTOR") (material "COPPER") (thickness "  1.200000 mil") (width "4.00 MIL") (dielectricConstant "4.500000") (lossTangent "0.035") (etchFactor "90.000000") (elecCondVal "595900.000000 mho/cm") (thermCondVal "0.012 w/cm-degC") (signalDieConstant "4.000000") (signalLossTangent "0.035")) ("" (layerType "DIELECTRIC") (material "FR-4") (thickness "  9.900000 mil") (dielectricConstant "4.500000") (lossTangent "0.035") (etchFactor "0.000000") (elecCondVal "0 mho/cm") (thermCondVal "0 w/cm-degC")) ("L6_GND3" (layerType "PLANE") (material "COPPER") (isShield t) (thickness "  1.200000 mil") (dielectricConstant "4.500000") (lossTangent "0.035") (etchFactor "90.000000") (elecCondVal "595900.000000 mho/cm") (thermCondVal "0 w/cm-degC")) ("" (layerType "DIELECTRIC") (material "FR-4") (thickness "  3.300000 mil") (dielectricConstant "4.100000") (lossTangent "0.035") (etchFactor "0.000000") (elecCondVal "0 mho/cm") (thermCondVal "0.012 w/cm-degC")) ("L7_PWR1-SIG" (layerType "PLANE") (material "COPPER") (isShield t) (thickness "  1.200000 mil") (dielectricConstant "4.500000") (lossTangent "0.035") (etchFactor "90.000000") (elecCondVal "595900.000000 mho/cm") (thermCondVal "0.012 w/cm-degC")) ("" (layerType "DIELECTRIC") (material "FR-4") (thickness "  9.900000 mil") (dielectricConstant "4.000000") (lossTangent "0.035") (etchFactor "0.000000") (elecCondVal "0 mho/cm") (thermCondVal "0.012 w/cm-degC")) ("L8_PWR2-SIG" (layerType "PLANE") (material "COPPER") (isShield t) (thickness "  1.200000 mil") (dielectricConstant "4.500000") (lossTangent "0.035") (etchFactor "90.000000") (elecCondVal "595900.000000 mho/cm") (thermCondVal "0.012 w/cm-degC")) ("" (layerType "DIELECTRIC") (material "FR-4") (thickness "  3.300000 mil") (dielectricConstant "4.500000") (lossTangent "0.035") (etchFactor "0.000000") (elecCondVal "0 mho/cm") (thermCondVal "0 w/cm-degC")) ("L9_GND4" (layerType "PLANE") (material "COPPER") (isShield t) (thickness "  1.200000 mil") (dielectricConstant "4.500000") (lossTangent "0.035") (etchFactor "90.000000") (elecCondVal "595900.000000 mho/cm") (thermCondVal "0 w/cm-degC")) ("" (layerType "DIELECTRIC") (material "FR-4") (thickness "  9.900000 mil") (dielectricConstant "4.100000") (lossTangent "0.035") (etchFactor "0.000000") (elecCondVal "0 mho/cm") (thermCondVal "0.012 w/cm-degC")) ("L10_SIG3" (layerType "CONDUCTOR") (material "COPPER") (thickness "  1.200000 mil") (width "4.00 MIL") (dielectricConstant "4.500000") (lossTangent "0.035") (etchFactor "90.000000") (elecCondVal "595900.000000 mho/cm") (thermCondVal "0.012 w/cm-degC") (signalDieConstant "4.100000") (signalLossTangent "0.035")) ("" (layerType "DIELECTRIC") (material "FR-4") (thickness "  3.300000 mil") (dielectricConstant "4.500000") (lossTangent "0.035") (etchFactor "0.000000") (elecCondVal "0 mho/cm") (thermCondVal "0 w/cm-degC")) ("L11_GND5" (layerType "PLANE") (material "COPPER") (isShield t) (thickness "  1.200000 mil") (dielectricConstant "4.500000") (lossTangent "0.035") (etchFactor "90.000000") (elecCondVal "595900.000000 mho/cm") (thermCondVal "0 w/cm-degC")) ("" (layerType "DIELECTRIC") (material "FR-4") (thickness "  9.900000 mil") (dielectricConstant "4.500000") (lossTangent "0.035") (etchFactor "0.000000") (elecCondVal "0 mho/cm") (thermCondVal "0.012 w/cm-degC")) ("L12_SIG4" (layerType "CONDUCTOR") (material "COPPER") (thickness "  1.200000 mil") (width "4.00 MIL") (dielectricConstant "4.500000") (lossTangent "0.035") (etchFactor "90.000000") (elecCondVal "595900.000000 mho/cm") (thermCondVal "0.012 w/cm-degC") (signalDieConstant "4.500000") (signalLossTangent "0.035")) ("" (layerType "DIELECTRIC") (material "FR-4") (thickness "  3.300000 mil") (dielectricConstant "4.500000") (lossTangent "0.035") (etchFactor "0.000000") (elecCondVal "0 mho/cm") (thermCondVal "0 w/cm-degC")) ("L13_GND6" (layerType "PLANE") (material "COPPER") (isShield t) (thickness "  1.200000 mil") (dielectricConstant "4.500000") (lossTangent "0.035") (etchFactor "90.000000") (elecCondVal "595900.000000 mho/cm") (thermCondVal "0.012 w/cm-degC")) ("" (layerType "DIELECTRIC") (material "FR-4") (thickness "  2.700000 mil") (dielectricConstant "4.500000") (lossTangent "0.035") (etchFactor "0.000000") (elecCondVal "0 mho/cm") (thermCondVal "0.012 w/cm-degC")) ("BOTTOM" (layerType "CONDUCTOR") (material "COPPER") (thickness "  1.800000 mil") (width "4.00 MIL") (dielectricConstant "4.500000") (lossTangent "0") (etchFactor "70.000000") (elecCondVal "595900.000000 mho/cm") (thermCondVal "0 w/cm-degC") (signalDieConstant "3.800000") (signalLossTangent "0.035")) ("" (layerType "DIELECTRIC") (material "CONFORMAL_COAT") (thickness "0.5 mil") (dielectricConstant "3.800000") (lossTangent "0.035") (etchFactor "0.000000") (elecCondVal "0 mho/cm") (thermCondVal "0.012 w/cm-degC")) ("" (layerType "SURFACE") (material "AIR") (thickness "0 mil") (dielectricConstant "1.000000") (lossTangent "0") (etchFactor "0.000000") (elecCondVal "0 mho/cm") (thermCondVal "0 w/cm-degC"))))) (Props (DesUnits "mils 2") (LayerStack ("DIELECTRIC" "DIELECTRIC" "BOTTOM" "DIELECTRIC" "L13_GND6" "DIELECTRIC" "L12_SIG4" "DIELECTRIC" "L11_GND5" "DIELECTRIC" "L10_SIG3" "DIELECTRIC" "L9_GND4" "DIELECTRIC" "L8_PWR2-SIG" "DIELECTRIC" "L7_PWR1-SIG" "DIELECTRIC" "L6_GND3" "DIELECTRIC" "L5_SIG2" "DIELECTRIC" "L4_GND2" "DIELECTRIC" "L3_SIG1" "DIELECTRIC" "L2_GND1" "DIELECTRIC" "TOP" "DIELECTRIC" "DIELECTRIC")) (Revision "16.600")) (Params (DualClampTerm ((cutoffVoltageUp "0.7 V") (cutoffVoltageDown "0.7 V") (voltageUp "5 V") (voltageDown "0 V") (maxDelay "0.1 ns"))) (HiClampTerm ((cutoffVoltage "0.7 V") (voltage "5 V") (maxDelay "0.1 ns"))) (IbisInputPkg ((temperature "27") (bufferModel "CDSDefaultInput_2p5v") (cycle "1") (LEFDEFPinName nil) (LEFDEFPinType nil) (mappingTag nil))) (RCTerm ((resistance "50 ohm") (capacitance "20 pF") (voltage "5 V") (maxDelay "0.1 ns"))) (IbisIOMacro ((temperature "27") (bufferModel "CDSDefaultIO_2p5v") (stimuli nil) (offsets nil) (state "tristate") (cycle "1") (termMap nil) (setup "2.0e-09") (hold "1.0e-09") (rise nil) (fall nil) (macroType nil) (voltage nil) (spice nil) (LEFDEFPinName nil) (LEFDEFPinType nil) (mappingTag nil))) (LowClampTerm ((cutoffVoltage "0.7 V") (voltage "0 V") (maxDelay "0.1 ns"))) (CurrentProbe nil) (IbisOutputPkg ((temperature "27") (bufferModel "CDSDefaultOutput_2p5v") (stimuli nil) (offsets nil) (state "tristate") (cycle "1") (termMap nil) (setup "2.0e-09") (hold "1.0e-09") (rise nil) (fall nil) (macroType nil) (voltage nil) (spice nil) (LEFDEFPinName nil) (LEFDEFPinType nil) (mappingTag nil))) (IbisIOPkg ((temperature "27") (bufferModel "CDSDefaultIO_2p5v") (stimuli nil) (offsets nil) (state "tristate") (cycle "1") (termMap nil) (setup "2.0e-09") (hold "1.0e-09") (rise nil) (fall nil) (macroType nil) (voltage nil) (spice nil) (LEFDEFPinName nil) (LEFDEFPinType nil) (mappingTag nil))) (SeriesTerm ((resistance "22 ohm") (maxDelay "0.1 ns"))) (IbisIO_OpenPullDown ((temperature "27") (bufferModel "CDSDefaultIO_2p5v") (stimuli nil) (offsets nil) (state "tristate") (cycle "1") (termMap nil) (setup "2.0e-09") (hold "1.0e-09") (rise nil) (fall nil) (macroType nil) (voltage nil) (spice nil) (LEFDEFPinName nil) (LEFDEFPinType nil) (mappingTag nil))) (clocked ((clockRise "1e-09") (clockFall "1e-09") (clockFreq "100e6") (clockInitState "0") (clockDutyCycle "0.5") (clockJitter "0"))) (CPWSL ((d1Thickness "10 mil") (d1Constant "4.5") (d1LossTangent "0.035") (d2Thickness "0.72 mil") (d2Constant "4.5") (d2LossTangent "0.035") (d3Thickness "10 mil") (d3Constant "4.5") (d3LossTangent "0.035") length("1000 mil") (spacing "5 mil") (spacing2 "5 mil") (spacing3 "5 mil") (spacing4 "5 mil") (spacing5 "5 mil") (traceConductivity "595900 mho/cm") (traceGeometry "cpwms") (traceLayerName "") (traceThickness "0.72 mil") (traceType "single") (traceWidth "5.0 mil") (traceWidth2 "5.0 mil") (traceWidth3 "5.0 mil") (traceWidth4 "5.0 mil") (traceWidth5 "5.0 mil") (traceWidth6 "5.0 mil") (offset "0 mil") (traceCount "1") (impedance nil))) (CPWMS ((d1Thickness "10 mil") (d1Constant "4.5") (d1LossTangent "0.035") (d2Thickness "0.72 mil") (d2Constant "4.5") (d2LossTangent "0.035") (d3Thickness "0.0") (d3Constant "1") (d3LossTangent "0") length("1000 mil") (spacing "5 mil") (spacing2 "5 mil") (spacing3 "5 mil") (spacing4 "5 mil") (spacing5 "5 mil") (traceConductivity "595900 mho/cm") (traceGeometry "cpwms") (traceLayerName "") (traceThickness "0.72 mil") (traceType "single") (traceWidth "5.0 mil") (traceWidth2 "5.0 mil") (traceWidth3 "5.0 mil") (traceWidth4 "5.0 mil") (traceWidth5 "5.0 mil") (traceWidth6 "5.0 mil") (offset "0 mil") (traceCount "1") (impedance nil))) (CPW ((d1Thickness "10 mil") (d1Constant "4.5") (d1LossTangent "0.035") (d2Thickness "0.72 mil") (d2Constant "1") (d2LossTangent "0") (d3Thickness "0.0") (d3Constant "1") (d3LossTangent "0") length("1000 mil") (spacing "5 mil") (spacing2 "5 mil") (spacing3 "5 mil") (spacing4 "5 mil") (spacing5 "5 mil") (traceConductivity "595900 mho/cm") (traceGeometry "cpwms") (traceLayerName "") (traceThickness "0.72 mil") (traceType "single") (traceWidth "5.0 mil") (traceWidth2 "5.0 mil") (traceWidth3 "5.0 mil") (traceWidth4 "5.0 mil") (traceWidth5 "5.0 mil") (traceWidth6 "5.0 mil") (offset "0 mil") (traceCount "1") (impedance nil))) (periodic ((periodicFreq "100e6") (periodicPattern "10") (periodicJitter "0"))) (Diode ((cutoffVoltage "0.7 V"))) (Trace ((d1Thickness "10 mil") (d1Constant "4.5") (d1LossTangent "0.035") (d2Thickness "10 mil") (d2Constant "4.5") (d2LossTangent "0.035") (d3Thickness "0.0") (d3Constant "1.0") (d3LossTangent "0") length("1000 mil") (spacing "5 mil") (spacing2 "5 mil") (spacing3 "5 mil") (spacing4 "5 mil") (spacing5 "5 mil") (traceConductivity "595900 mho/cm") (traceGeometry "microstrip") (traceLayerName "") (traceThickness "0.72 mil") (traceType "single") (traceWidth "5.0 mil") (traceWidth2 "5.0 mil") (traceWidth3 "5.0 mil") (traceWidth4 "5.0 mil") (traceWidth5 "5.0 mil") (traceWidth6 "5.0 mil") (offset "0 mil") (traceCount "1") (impedance nil))) (Cable (length("1 m"))) (Via ((model "Unknown") (viaOutputFormat "Unknown") (viaPadstack nil) (viaTopLayer nil) (viaBottomLayer nil) (viaIsPower nil) (viaIsGround nil))) (async ((asyncTimePoints "") (asyncInitState "1"))) (Resistor ((resistance "50 ohm") (orientation "0"))) (DiffOutputPkg ((temperature "27") (bufferModelNonInverting "CDSDefaultOutput_2p5v") (bufferModelInverting "CDSDefaultOutput_2p5v") (stimuli nil) (offsets nil) (state "tristate") (cycle "1") (termMap nil) (setup "0.9e-09") (hold "0.4e-09") (rise nil) (fall nil) (threshOutputHighMin "2.375  V") (threshOutputHighTyp "2.5  V") (threshOutputHighMax "2.625  V") (threshOutputLowMin "1.275  V") (threshOutputLowTyp "1.7  V") (threshOutputLowMax "1.985  V") (mappingTagNonInverting nil) (mappingTagInverting nil) (spice nil))) (DiffOutput ((temperature "27") (bufferModelNonInverting "CDSDefaultOutput_2p5v") (bufferModelInverting "CDSDefaultOutput_2p5v") (stimuli nil) (offsets nil) (state "tristate") (cycle "1") (termMap nil) (setup "0.9e-09") (hold "0.4e-09") (rise nil) (fall nil) (threshOutputHighMin "2.375  V") (threshOutputHighTyp "2.5  V") (threshOutputHighMax "2.625  V") (threshOutputLowMin "1.275  V") (threshOutputLowTyp "1.7  V") (threshOutputLowMax "1.985  V") (mappingTagNonInverting nil) (mappingTagInverting nil) (spice nil))) (IbisOutput ((temperature "27") (bufferModel "CDSDefaultOutput_2p5v") (stimuli nil) (offsets nil) (state "tristate") (cycle "1") (termMap nil) (setup "2.0e-09") (hold "1.0e-09") (rise nil) (fall nil) (macroType nil) (voltage nil) (spice nil) (LEFDEFPinName nil) (LEFDEFPinType nil) (mappingTag nil))) (Inductor ((inductance "5 nH") (orientation "0"))) (Capacitor ((capacitance "10 pF") (orientation "0"))) (DiffIOPkg ((temperature "27") (bufferModelNonInverting "CDSDefaultIO_2p5v") (bufferModelInverting "CDSDefaultIO_2p5v") (stimuli nil) (offsets nil) (state "tristate") (cycle "1") (termMap nil) (setup "0.9e-09") (hold "0.4e-09") (rise nil) (fall nil) (threshInputHighMin "1.7 V") (threshInputHighTyp "1.7  V") (threshInputHighMax "1.7  V") (threshInputLowMin "0.7  V") (threshInputLowTyp "0.7  V") (threshInputLowMax "0.7 ") (threshOutputHighMin "2.365  V") (threshOutputHighTyp "2.5  V") (threshOutputHighMax "2.625  V") (threshOutputLowMin "1.275  V") (threshOutputLowTyp "1.7  V") (threshOutputLowMax "1.985  V") (mappingTagNonInverting nil) (mappingTagInverting nil) (spice nil))) (IbisIO ((temperature "27") (bufferModel "CDSDefaultIO_2p5v") (stimuli nil) (offsets nil) (state "tristate") (cycle "1") (termMap nil) (setup "2.0e-09") (hold "1.0e-09") (rise nil) (fall nil) (macroType nil) (voltage nil) (spice nil) (LEFDEFPinName nil) (LEFDEFPinType nil) (mappingTag nil))) (Source ((voltage "5 V"))) (DiffIO ((temperature "27") (bufferModelNonInverting "CDSDefaultIO_2p5v") (bufferModelInverting "CDSDefaultIO_2p5v") (stimuli nil) (offsets nil) (state "tristate") (cycle "1") (termMap nil) (setup "0.9e-09") (hold "0.4e-09") (rise nil) (fall nil) (threshInputHighMin "1.7 V") (threshInputHighTyp "1.7  V") (threshInputHighMax "1.7  V") (threshInputLowMin "0.7  V") (threshInputLowTyp "0.7  V") (threshInputLowMax "0.7 ") (threshOutputHighMin "2.365  V") (threshOutputHighTyp "2.5  V") (threshOutputHighMax "2.625  V") (threshOutputLowMin "1.275  V") (threshOutputLowTyp "1.7  V") (threshOutputLowMax "1.985  V") (mappingTagNonInverting nil) (mappingTagInverting nil) (spice nil))) (RLGC (length("1000 mil"))) (IbisInput ((temperature "27") (bufferModel "CDSDefaultInput_2p5v") (cycle "1") (LEFDEFPinName nil) (LEFDEFPinType nil) (mappingTag nil))) (DiffInput ((temperature "27") (bufferModelNonInverting "CDSDefaultInput_2p5v") (bufferModelInverting "CDSDefaultInput_2p5v") (threshInputHighMin "1.7 V") (threshInputHighTyp "1.7  V") (threshInputHighMax "1.7  V") (threshInputLowMin "0.7  V") (threshInputLowTyp "0.7  V") (threshInputLowMax "0.7  V") (mappingTagNonInverting nil) (mappingTagInverting nil) (cycle "1"))) (ESpiceDevice nil) (sync ((syncFreq "100e6") (syncInitState "1") (syncPattern "10") (syncEdgeSwitch "rise"))) (TLine ((diffImpedance "100ohm") (diffVelocity "1.4142e+08M/s") (impedance "60ohm") length("2800 mil") (propDelay "0.5 ns") (velocity "5600 mil/ns") (traceCount "1") (traceGeometry "Microstrip") (impedanceMin nil) (impedanceMax nil) (lengthMin nil) (lengthMax nil) (propDelayMin nil) (propDelayMax nil) (impedanceSweepCount nil) (propDelaySweepCount nil) (velocitySweepCount nil) (lengthSweepCount nil) (matchSetName nil))) (Connector nil) (ShuntTerm ((resistance "50 ohm") (voltage "5 V") (maxDelay "0.1 ns"))) (TheveninTerm ((resistanceUp "180 ohm") (resistanceDown "270 ohm") (voltageUp "5 V") (voltageDown "0 V") (maxDelay "0.1 ns"))) (IbisIO_OpenPullUp ((temperature "27") (bufferModel "CDSDefaultIO_2p5v") (stimuli nil) (offsets nil) (state "tristate") (cycle "1") (termMap nil) (setup "2.0e-09") (hold "1.0e-09") (rise nil) (fall nil) (macroType nil) (voltage nil) (spice nil) (LEFDEFPinName nil) (LEFDEFPinType nil) (mappingTag nil))) (DiffInputPkg ((temperature "27") (bufferModelNonInverting "CDSDefaultInput_2p5v") (bufferModelInverting "CDSDefaultInput_2p5v") (threshInputHighMin "1.7 V") (threshInputHighTyp "1.7  V") (threshInputHighMax "1.7  V") (threshInputLowMin "0.7  V") (threshInputLowTyp "0.7  V") (threshInputLowMax "0.7  V") (mappingTagNonInverting nil) (mappingTagInverting nil) (cycle "1"))) (IbisOutput_OpenPullUp ((temperature "27") (bufferModel "CDSDefaultOutput_2p5v") (stimuli nil) (offsets nil) (state "tristate") (cycle "1") (termMap nil) (setup "2.0e-09") (hold "1.0e-09") (rise nil) (fall nil) (macroType nil) (voltage nil) (spice nil) (LEFDEFPinName nil) (LEFDEFPinType nil) (mappingTag nil))) (idlCircuit ((allDrivers "active") (ftsMode '("Typ")) (rcvrSelect "all") (simMode "Reflection") (tlineDelayMode "time") (userRevision "1.0") (autoSolve "On")))))
				)
				( objectStatus "DDR_G_CMD_DLL1-13" )
			)
			( electricalCSet "@crescent_city_bb_fab1_lib.crescent_city_bb_fab1(sch_1):\DDR_K_CMD_DLL1-13\"
				( groupRef "DDR_K_CMD_DLL1-13:MG_DDR_CMD_NEAR_DIMM" )
				( groupRef "DDR_K_CMD_DLL1-13:MG_DDR_FAR_DIMM-CLK0" )
				( groupRef "DDR_K_CMD_DLL1-13:MG_DDR_FAR_DIMM_CMD" )
				( groupRef "DDR_K_CMD_DLL1-13:MG_DDR_NEAR_DIMM-CLK1" )
				( pinPairRef "DDR_K_CMD_DLL1-13:U2D1.F51:J9M1.228" )
				( pinPairRef "DDR_K_CMD_DLL1-13:U2D1.F51:J1B1.228" )
				( attribute "TOPOLOGY_TEMPLATE_REVISION" "1.0"
					( Origin gBackEnd )
				)
				( topologyData 23957
(SKIDL (Circuits ("MAIN" (Parts ("CRESCENT_CITY_083_20140724_A.@@J1.228" IbisIOPkg (xy (5548 4240)) (refDes "J1B1") (model "Unknown") (Props (_SXDesignName "CRESCENT_CITY_083_20140724_A") (brdx "10643.7 MIL") (brdy "788.33 MIL") (bufferModel "CDSDefaultIO_2p5v") (cycle "1") (hold "1.0e-09") (mappingTag "") (offsets ("4" "0") ("5" "0")) (setup "2.0e-09") (state "tristate") (stimuli ("4" "local0") ("5" "local1")) (temperature "27") (termMap ("4" "Data") ("5" "Enable"))) (Terms ("CRESCENT_CITY_083_20140724_A.X1064370Y78833L2LRATS" "228"))) ("CRESCENT_CITY_083_20140724_A.@@J2.228" IbisIOPkg (xy (5528 4240)) (refDes "J9M1") (model "Unknown") (Props (_SXDesignName "CRESCENT_CITY_083_20140724_A") (brdx "10643.7 MIL") (brdy "796.23 MIL") (bufferModel "CDSDefaultIO_2p5v") (cycle "1") (hold "1.0e-09") (mappingTag "") (offsets ("4" "0") ("5" "0")) (setup "2.0e-09") (state "tristate") (stimuli ("4" "local2") ("5" "local15")) (temperature "27") (termMap ("4" "Data") ("5" "Enable"))) (Terms ("CRESCENT_CITY_083_20140724_A.X1064370Y79623L28LRATS" "228"))) ("CRESCENT_CITY_083_20140724_A.@@U36.F51" IbisIOPkg (xy (5502 4240)) (refDes "U2D1") (model "Unknown") (Props (_SXDesignName "CRESCENT_CITY_083_20140724_A") (brdx "10346.35 MIL") (brdy "2052.1 MIL") (bufferModel "CDSDefaultIO_2p5v") (cycle "1") (hold "1.0e-09") (mappingTag "") (offsets ("4" "0") ("5" "0")) (setup "2.0e-09") (state "tristate") (stimuli ("4" "local16") ("5" "local17")) (temperature "27") (termMap ("4" "Data") ("5" "Enable"))) (Terms ("CRESCENT_CITY_083_20140724_A.X1034635Y205210L2LRATS" "F51"))) ("CRESCENT_CITY_083_20140724_A.T@@RATS@@J2.228@@U36.F51" TLine (xy (5513 4235)) (mirror x) (refDes "TL1") (Props (_SXDesignName "CRESCENT_CITY_083_20140724_A") (impedance "53.474 ohm") length("1553.22 MIL") (propDelay "0.27897 ns") (traceCount "1") (traceGeometry "Microstrip") (velocity "5567.68 mil/ns")) (Terms ("CRESCENT_CITY_083_20140724_A.X1064370Y79623L28LRATS" "1") ("CRESCENT_CITY_083_20140724_A.X1034635Y205210L2LRATS" "2"))) ("CRESCENT_CITY_083_20140724_A.T@@RATS@@J2.228@@J1.228" TLine (xy (5539 4235)) (refDes "TL2") (Props (_SXDesignName "CRESCENT_CITY_083_20140724_A") (impedance "39.682 ohm") length("7.90 MIL") (propDelay "0.00142 ns") (traceCount "1") (traceGeometry "Microstrip") (velocity "5563.39 mil/ns")) (Terms ("CRESCENT_CITY_083_20140724_A.X1064370Y79623L28LRATS" "1") ("CRESCENT_CITY_083_20140724_A.X1064370Y78833L2LRATS" "2")))) (Nodes ("CRESCENT_CITY_083_20140724_A.X1034635Y205210L2LRATS" (terms "CRESCENT_CITY_083_20140724_A.T@@RATS@@J2.228@@U36.F51.2" "CRESCENT_CITY_083_20140724_A.@@U36.F51.1")) ("CRESCENT_CITY_083_20140724_A.X1064370Y78833L2LRATS" (terms "CRESCENT_CITY_083_20140724_A.T@@RATS@@J2.228@@J1.228.2" "CRESCENT_CITY_083_20140724_A.@@J1.228.1")) ("CRESCENT_CITY_083_20140724_A.X1064370Y79623L28LRATS" (terms "CRESCENT_CITY_083_20140724_A.T@@RATS@@J2.228@@J1.228.1" "CRESCENT_CITY_083_20140724_A.T@@RATS@@J2.228@@U36.F51.1" "CRESCENT_CITY_083_20140724_A.@@J2.228.1"))) (Ports) (Stimuli ("local2" (scope local) (stimType periodic) (Props (periodicFreq "5e+007") (periodicJitter "0") (periodicPattern "1"))) ("local15" (scope local) (stimType periodic) (Props (periodicFreq "5e+007") (periodicJitter "0") (periodicPattern "1"))) ("local0" (scope local) (stimType periodic) (Props (periodicFreq "5e+007") (periodicJitter "0") (periodicPattern "1"))) ("local16" (scope local) (stimType periodic) (Props (periodicFreq "5e+007") (periodicJitter "0") (periodicPattern "1"))) ("local1" (scope local) (stimType periodic) (Props (periodicFreq "5e+007") (periodicJitter "0") (periodicPattern "1"))) ("local17" (scope local) (stimType periodic) (Props (periodicFreq "5e+007") (periodicJitter "0") (periodicPattern "1")))) (Notes) (Constraints ("RELATIVE_PROPAGATION_DELAY" ("MG_DDR_CMD_NEAR_DIMM" "CRESCENT_CITY_083_20140724_A U100.F51" "CRESCENT_CITY_083_20140724_A J20.228" "NET GROUP" "LENGTH" "0.000635" "LENGTH" "0") ("MG_DDR_FAR_DIMM-CLK0" "CRESCENT_CITY_083_20140724_A U100.F51" "CRESCENT_CITY_083_20140724_A J19.228" "CLASS" "LENGTH" "0.01778" "LENGTH" "0") ("MG_DDR_FAR_DIMM_CMD" "CRESCENT_CITY_083_20140724_A U100.F51" "CRESCENT_CITY_083_20140724_A J19.228" "NET GROUP" "LENGTH" "0.000635" "LENGTH" "0") ("MG_DDR_NEAR_DIMM-CLK1" "CRESCENT_CITY_083_20140724_A U100.F51" "CRESCENT_CITY_083_20140724_A J20.228" "CLASS" "LENGTH" "0.01778" "LENGTH" "0"))) (MeasurementSets ("EMI" ("EMIStatus" status("on")) ("PeakEmission" status("on")) ("PeakFrequency" status("on")) ("PulseFreq" status("on")) ("RiseTime" status("on")) ("VoltageSwing" status("on"))) ("Reflection" ("BufferDelayFall" status("off")) ("BufferDelayRise" status("off")) ("EyeHeight" status("off")) ("EyeJitter" status("off")) ("EyeWidth" status("off")) ("FirstIncidentFall" status("off")) ("FirstIncidentRise" status("off")) ("Glitch" status("on")) ("GlitchFall" status("off")) ("GlitchRise" status("off")) ("Monotonic" status("on")) ("MonotonicFall" status("off")) ("MonotonicRise" status("off")) ("NoiseMargin" status("on")) ("NoiseMarginHigh" status("off")) ("NoiseMarginLow" status("off")) ("OvershootHigh" status("on")) ("OvershootLow" status("on")) ("PropDelay" status("on")) ("SettleDelay" status("on")) ("SettleDelayFall" status("off")) ("SettleDelayRise" status("off")) ("SwitchDelay" status("on")) ("SwitchDelayFall" status("off")) ("SwitchDelayRise" status("off"))) ("Crosstalk" ("Crosstalk" status("on"))) ("Custom")) (VectorSets) (Props (XnetName "M_A_MA<14>") (allDrivers "active") (autoSolve "Off") (customSimType "Reflection") (ftsMode ("Typ")) (rcvrSelect "all") (tlineDelayMode "time") (userRevision "1.0")))) (Subckts) (CrossSections ("CRESCENT_CITY_083_20140724_A" (Props (SXDesignName "CRESCENT_CITY_083_20140724_A")) (Layers ("" (layerType "SURFACE") (material "AIR") (thickness "0 mil") (dielectricConstant "1.000000") (lossTangent "0") (etchFactor "0.000000") (elecCondVal "0 mho/cm") (thermCondVal "0 w/cm-degC")) ("" (layerType "DIELECTRIC") (material "CONFORMAL_COAT") (thickness "0.5 mil") (dielectricConstant "3.800000") (lossTangent "0.035") (etchFactor "0.000000") (elecCondVal "0 mho/cm") (thermCondVal "0.012 w/cm-degC")) ("TOP" (layerType "CONDUCTOR") (material "COPPER") (thickness "  1.800000 mil") (width "4.00 MIL") (dielectricConstant "4.500000") (lossTangent "0") (etchFactor "70.000000") (elecCondVal "595900.000000 mho/cm") (thermCondVal "0 w/cm-degC") (signalDieConstant "3.800000") (signalLossTangent "0.035")) ("" (layerType "DIELECTRIC") (material "FR-4") (thickness "  2.700000 mil") (dielectricConstant "4.000000") (lossTangent "0.035") (etchFactor "0.000000") (elecCondVal "0 mho/cm") (thermCondVal "0.012 w/cm-degC")) ("L2_GND1" (layerType "PLANE") (material "COPPER") (isShield t) (thickness "  1.200000 mil") (dielectricConstant "4.500000") (lossTangent "0.035") (etchFactor "90.000000") (elecCondVal "595900.000000 mho/cm") (thermCondVal "0.012 w/cm-degC")) ("" (layerType "DIELECTRIC") (material "FR-4") (thickness "  9.900000 mil") (dielectricConstant "4.100000") (lossTangent "0.035") (etchFactor "0.000000") (elecCondVal "0 mho/cm") (thermCondVal "0.012 w/cm-degC")) ("L3_SIG1" (layerType "CONDUCTOR") (material "COPPER") (thickness "  1.200000 mil") (width "4.00 MIL") (dielectricConstant "4.500000") (lossTangent "0.035") (etchFactor "90.000000") (elecCondVal "595900.000000 mho/cm") (thermCondVal "0.012 w/cm-degC") (signalDieConstant "4.100000") (signalLossTangent "0.035")) ("" (layerType "DIELECTRIC") (material "FR-4") (thickness "  3.300000 mil") (dielectricConstant "4.500000") (lossTangent "0.035") (etchFactor "0.000000") (elecCondVal "0 mho/cm") (thermCondVal "0 w/cm-degC")) ("L4_GND2" (layerType "PLANE") (material "COPPER") (isShield t) (thickness "  1.200000 mil") (dielectricConstant "4.500000") (lossTangent "0.035") (etchFactor "90.000000") (elecCondVal "595900.000000 mho/cm") (thermCondVal "0 w/cm-degC")) ("" (layerType "DIELECTRIC") (material "FR-4") (thickness "  3.300000 mil") (dielectricConstant "4.000000") (lossTangent "0.035") (etchFactor "0.000000") (elecCondVal "0 mho/cm") (thermCondVal "0.012 w/cm-degC")) ("L5_SIG2" (layerType "CONDUCTOR") (material "COPPER") (thickness "  1.200000 mil") (width "4.00 MIL") (dielectricConstant "4.500000") (lossTangent "0.035") (etchFactor "90.000000") (elecCondVal "595900.000000 mho/cm") (thermCondVal "0.012 w/cm-degC") (signalDieConstant "4.000000") (signalLossTangent "0.035")) ("" (layerType "DIELECTRIC") (material "FR-4") (thickness "  9.900000 mil") (dielectricConstant "4.500000") (lossTangent "0.035") (etchFactor "0.000000") (elecCondVal "0 mho/cm") (thermCondVal "0 w/cm-degC")) ("L6_GND3" (layerType "PLANE") (material "COPPER") (isShield t) (thickness "  1.200000 mil") (dielectricConstant "4.500000") (lossTangent "0.035") (etchFactor "90.000000") (elecCondVal "595900.000000 mho/cm") (thermCondVal "0 w/cm-degC")) ("" (layerType "DIELECTRIC") (material "FR-4") (thickness "  3.300000 mil") (dielectricConstant "4.100000") (lossTangent "0.035") (etchFactor "0.000000") (elecCondVal "0 mho/cm") (thermCondVal "0.012 w/cm-degC")) ("L7_PWR1-SIG" (layerType "PLANE") (material "COPPER") (isShield t) (thickness "  1.200000 mil") (dielectricConstant "4.500000") (lossTangent "0.035") (etchFactor "90.000000") (elecCondVal "595900.000000 mho/cm") (thermCondVal "0.012 w/cm-degC")) ("" (layerType "DIELECTRIC") (material "FR-4") (thickness "  9.900000 mil") (dielectricConstant "4.000000") (lossTangent "0.035") (etchFactor "0.000000") (elecCondVal "0 mho/cm") (thermCondVal "0.012 w/cm-degC")) ("L8_PWR2-SIG" (layerType "PLANE") (material "COPPER") (isShield t) (thickness "  1.200000 mil") (dielectricConstant "4.500000") (lossTangent "0.035") (etchFactor "90.000000") (elecCondVal "595900.000000 mho/cm") (thermCondVal "0.012 w/cm-degC")) ("" (layerType "DIELECTRIC") (material "FR-4") (thickness "  3.300000 mil") (dielectricConstant "4.500000") (lossTangent "0.035") (etchFactor "0.000000") (elecCondVal "0 mho/cm") (thermCondVal "0 w/cm-degC")) ("L9_GND4" (layerType "PLANE") (material "COPPER") (isShield t) (thickness "  1.200000 mil") (dielectricConstant "4.500000") (lossTangent "0.035") (etchFactor "90.000000") (elecCondVal "595900.000000 mho/cm") (thermCondVal "0 w/cm-degC")) ("" (layerType "DIELECTRIC") (material "FR-4") (thickness "  9.900000 mil") (dielectricConstant "4.100000") (lossTangent "0.035") (etchFactor "0.000000") (elecCondVal "0 mho/cm") (thermCondVal "0.012 w/cm-degC")) ("L10_SIG3" (layerType "CONDUCTOR") (material "COPPER") (thickness "  1.200000 mil") (width "4.00 MIL") (dielectricConstant "4.500000") (lossTangent "0.035") (etchFactor "90.000000") (elecCondVal "595900.000000 mho/cm") (thermCondVal "0.012 w/cm-degC") (signalDieConstant "4.100000") (signalLossTangent "0.035")) ("" (layerType "DIELECTRIC") (material "FR-4") (thickness "  3.300000 mil") (dielectricConstant "4.500000") (lossTangent "0.035") (etchFactor "0.000000") (elecCondVal "0 mho/cm") (thermCondVal "0 w/cm-degC")) ("L11_GND5" (layerType "PLANE") (material "COPPER") (isShield t) (thickness "  1.200000 mil") (dielectricConstant "4.500000") (lossTangent "0.035") (etchFactor "90.000000") (elecCondVal "595900.000000 mho/cm") (thermCondVal "0 w/cm-degC")) ("" (layerType "DIELECTRIC") (material "FR-4") (thickness "  9.900000 mil") (dielectricConstant "4.500000") (lossTangent "0.035") (etchFactor "0.000000") (elecCondVal "0 mho/cm") (thermCondVal "0.012 w/cm-degC")) ("L12_SIG4" (layerType "CONDUCTOR") (material "COPPER") (thickness "  1.200000 mil") (width "4.00 MIL") (dielectricConstant "4.500000") (lossTangent "0.035") (etchFactor "90.000000") (elecCondVal "595900.000000 mho/cm") (thermCondVal "0.012 w/cm-degC") (signalDieConstant "4.500000") (signalLossTangent "0.035")) ("" (layerType "DIELECTRIC") (material "FR-4") (thickness "  3.300000 mil") (dielectricConstant "4.500000") (lossTangent "0.035") (etchFactor "0.000000") (elecCondVal "0 mho/cm") (thermCondVal "0 w/cm-degC")) ("L13_GND6" (layerType "PLANE") (material "COPPER") (isShield t) (thickness "  1.200000 mil") (dielectricConstant "4.500000") (lossTangent "0.035") (etchFactor "90.000000") (elecCondVal "595900.000000 mho/cm") (thermCondVal "0.012 w/cm-degC")) ("" (layerType "DIELECTRIC") (material "FR-4") (thickness "  2.700000 mil") (dielectricConstant "4.500000") (lossTangent "0.035") (etchFactor "0.000000") (elecCondVal "0 mho/cm") (thermCondVal "0.012 w/cm-degC")) ("BOTTOM" (layerType "CONDUCTOR") (material "COPPER") (thickness "  1.800000 mil") (width "4.00 MIL") (dielectricConstant "4.500000") (lossTangent "0") (etchFactor "70.000000") (elecCondVal "595900.000000 mho/cm") (thermCondVal "0 w/cm-degC") (signalDieConstant "3.800000") (signalLossTangent "0.035")) ("" (layerType "DIELECTRIC") (material "CONFORMAL_COAT") (thickness "0.5 mil") (dielectricConstant "3.800000") (lossTangent "0.035") (etchFactor "0.000000") (elecCondVal "0 mho/cm") (thermCondVal "0.012 w/cm-degC")) ("" (layerType "SURFACE") (material "AIR") (thickness "0 mil") (dielectricConstant "1.000000") (lossTangent "0") (etchFactor "0.000000") (elecCondVal "0 mho/cm") (thermCondVal "0 w/cm-degC"))))) (Props (DesUnits "mils 2") (LayerStack ("DIELECTRIC" "DIELECTRIC" "BOTTOM" "DIELECTRIC" "L13_GND6" "DIELECTRIC" "L12_SIG4" "DIELECTRIC" "L11_GND5" "DIELECTRIC" "L10_SIG3" "DIELECTRIC" "L9_GND4" "DIELECTRIC" "L8_PWR2-SIG" "DIELECTRIC" "L7_PWR1-SIG" "DIELECTRIC" "L6_GND3" "DIELECTRIC" "L5_SIG2" "DIELECTRIC" "L4_GND2" "DIELECTRIC" "L3_SIG1" "DIELECTRIC" "L2_GND1" "DIELECTRIC" "TOP" "DIELECTRIC" "DIELECTRIC")) (Revision "16.600")) (Params (DualClampTerm ((cutoffVoltageUp "0.7 V") (cutoffVoltageDown "0.7 V") (voltageUp "5 V") (voltageDown "0 V") (maxDelay "0.1 ns"))) (HiClampTerm ((cutoffVoltage "0.7 V") (voltage "5 V") (maxDelay "0.1 ns"))) (IbisInputPkg ((temperature "27") (bufferModel "CDSDefaultInput_2p5v") (cycle "1") (LEFDEFPinName nil) (LEFDEFPinType nil) (mappingTag nil))) (RCTerm ((resistance "50 ohm") (capacitance "20 pF") (voltage "5 V") (maxDelay "0.1 ns"))) (IbisIOMacro ((temperature "27") (bufferModel "CDSDefaultIO_2p5v") (stimuli nil) (offsets nil) (state "tristate") (cycle "1") (termMap nil) (setup "2.0e-09") (hold "1.0e-09") (rise nil) (fall nil) (macroType nil) (voltage nil) (spice nil) (LEFDEFPinName nil) (LEFDEFPinType nil) (mappingTag nil))) (LowClampTerm ((cutoffVoltage "0.7 V") (voltage "0 V") (maxDelay "0.1 ns"))) (CurrentProbe nil) (IbisOutputPkg ((temperature "27") (bufferModel "CDSDefaultOutput_2p5v") (stimuli nil) (offsets nil) (state "tristate") (cycle "1") (termMap nil) (setup "2.0e-09") (hold "1.0e-09") (rise nil) (fall nil) (macroType nil) (voltage nil) (spice nil) (LEFDEFPinName nil) (LEFDEFPinType nil) (mappingTag nil))) (IbisIOPkg ((temperature "27") (bufferModel "CDSDefaultIO_2p5v") (stimuli nil) (offsets nil) (state "tristate") (cycle "1") (termMap nil) (setup "2.0e-09") (hold "1.0e-09") (rise nil) (fall nil) (macroType nil) (voltage nil) (spice nil) (LEFDEFPinName nil) (LEFDEFPinType nil) (mappingTag nil))) (SeriesTerm ((resistance "22 ohm") (maxDelay "0.1 ns"))) (IbisIO_OpenPullDown ((temperature "27") (bufferModel "CDSDefaultIO_2p5v") (stimuli nil) (offsets nil) (state "tristate") (cycle "1") (termMap nil) (setup "2.0e-09") (hold "1.0e-09") (rise nil) (fall nil) (macroType nil) (voltage nil) (spice nil) (LEFDEFPinName nil) (LEFDEFPinType nil) (mappingTag nil))) (clocked ((clockRise "1e-09") (clockFall "1e-09") (clockFreq "100e6") (clockInitState "0") (clockDutyCycle "0.5") (clockJitter "0"))) (CPWSL ((d1Thickness "10 mil") (d1Constant "4.5") (d1LossTangent "0.035") (d2Thickness "0.72 mil") (d2Constant "4.5") (d2LossTangent "0.035") (d3Thickness "10 mil") (d3Constant "4.5") (d3LossTangent "0.035") length("1000 mil") (spacing "5 mil") (spacing2 "5 mil") (spacing3 "5 mil") (spacing4 "5 mil") (spacing5 "5 mil") (traceConductivity "595900 mho/cm") (traceGeometry "cpwms") (traceLayerName "") (traceThickness "0.72 mil") (traceType "single") (traceWidth "5.0 mil") (traceWidth2 "5.0 mil") (traceWidth3 "5.0 mil") (traceWidth4 "5.0 mil") (traceWidth5 "5.0 mil") (traceWidth6 "5.0 mil") (offset "0 mil") (traceCount "1") (impedance nil))) (CPWMS ((d1Thickness "10 mil") (d1Constant "4.5") (d1LossTangent "0.035") (d2Thickness "0.72 mil") (d2Constant "4.5") (d2LossTangent "0.035") (d3Thickness "0.0") (d3Constant "1") (d3LossTangent "0") length("1000 mil") (spacing "5 mil") (spacing2 "5 mil") (spacing3 "5 mil") (spacing4 "5 mil") (spacing5 "5 mil") (traceConductivity "595900 mho/cm") (traceGeometry "cpwms") (traceLayerName "") (traceThickness "0.72 mil") (traceType "single") (traceWidth "5.0 mil") (traceWidth2 "5.0 mil") (traceWidth3 "5.0 mil") (traceWidth4 "5.0 mil") (traceWidth5 "5.0 mil") (traceWidth6 "5.0 mil") (offset "0 mil") (traceCount "1") (impedance nil))) (CPW ((d1Thickness "10 mil") (d1Constant "4.5") (d1LossTangent "0.035") (d2Thickness "0.72 mil") (d2Constant "1") (d2LossTangent "0") (d3Thickness "0.0") (d3Constant "1") (d3LossTangent "0") length("1000 mil") (spacing "5 mil") (spacing2 "5 mil") (spacing3 "5 mil") (spacing4 "5 mil") (spacing5 "5 mil") (traceConductivity "595900 mho/cm") (traceGeometry "cpwms") (traceLayerName "") (traceThickness "0.72 mil") (traceType "single") (traceWidth "5.0 mil") (traceWidth2 "5.0 mil") (traceWidth3 "5.0 mil") (traceWidth4 "5.0 mil") (traceWidth5 "5.0 mil") (traceWidth6 "5.0 mil") (offset "0 mil") (traceCount "1") (impedance nil))) (periodic ((periodicFreq "100e6") (periodicPattern "10") (periodicJitter "0"))) (Diode ((cutoffVoltage "0.7 V"))) (Trace ((d1Thickness "10 mil") (d1Constant "4.5") (d1LossTangent "0.035") (d2Thickness "10 mil") (d2Constant "4.5") (d2LossTangent "0.035") (d3Thickness "0.0") (d3Constant "1.0") (d3LossTangent "0") length("1000 mil") (spacing "5 mil") (spacing2 "5 mil") (spacing3 "5 mil") (spacing4 "5 mil") (spacing5 "5 mil") (traceConductivity "595900 mho/cm") (traceGeometry "microstrip") (traceLayerName "") (traceThickness "0.72 mil") (traceType "single") (traceWidth "5.0 mil") (traceWidth2 "5.0 mil") (traceWidth3 "5.0 mil") (traceWidth4 "5.0 mil") (traceWidth5 "5.0 mil") (traceWidth6 "5.0 mil") (offset "0 mil") (traceCount "1") (impedance nil))) (Cable (length("1 m"))) (Via ((model "Unknown") (viaOutputFormat "Unknown") (viaPadstack nil) (viaTopLayer nil) (viaBottomLayer nil) (viaIsPower nil) (viaIsGround nil))) (async ((asyncTimePoints "") (asyncInitState "1"))) (Resistor ((resistance "50 ohm") (orientation "0"))) (DiffOutputPkg ((temperature "27") (bufferModelNonInverting "CDSDefaultOutput_2p5v") (bufferModelInverting "CDSDefaultOutput_2p5v") (stimuli nil) (offsets nil) (state "tristate") (cycle "1") (termMap nil) (setup "0.9e-09") (hold "0.4e-09") (rise nil) (fall nil) (threshOutputHighMin "2.375  V") (threshOutputHighTyp "2.5  V") (threshOutputHighMax "2.625  V") (threshOutputLowMin "1.275  V") (threshOutputLowTyp "1.7  V") (threshOutputLowMax "1.985  V") (mappingTagNonInverting nil) (mappingTagInverting nil) (spice nil))) (DiffOutput ((temperature "27") (bufferModelNonInverting "CDSDefaultOutput_2p5v") (bufferModelInverting "CDSDefaultOutput_2p5v") (stimuli nil) (offsets nil) (state "tristate") (cycle "1") (termMap nil) (setup "0.9e-09") (hold "0.4e-09") (rise nil) (fall nil) (threshOutputHighMin "2.375  V") (threshOutputHighTyp "2.5  V") (threshOutputHighMax "2.625  V") (threshOutputLowMin "1.275  V") (threshOutputLowTyp "1.7  V") (threshOutputLowMax "1.985  V") (mappingTagNonInverting nil) (mappingTagInverting nil) (spice nil))) (IbisOutput ((temperature "27") (bufferModel "CDSDefaultOutput_2p5v") (stimuli nil) (offsets nil) (state "tristate") (cycle "1") (termMap nil) (setup "2.0e-09") (hold "1.0e-09") (rise nil) (fall nil) (macroType nil) (voltage nil) (spice nil) (LEFDEFPinName nil) (LEFDEFPinType nil) (mappingTag nil))) (Inductor ((inductance "5 nH") (orientation "0"))) (Capacitor ((capacitance "10 pF") (orientation "0"))) (DiffIOPkg ((temperature "27") (bufferModelNonInverting "CDSDefaultIO_2p5v") (bufferModelInverting "CDSDefaultIO_2p5v") (stimuli nil) (offsets nil) (state "tristate") (cycle "1") (termMap nil) (setup "0.9e-09") (hold "0.4e-09") (rise nil) (fall nil) (threshInputHighMin "1.7 V") (threshInputHighTyp "1.7  V") (threshInputHighMax "1.7  V") (threshInputLowMin "0.7  V") (threshInputLowTyp "0.7  V") (threshInputLowMax "0.7 ") (threshOutputHighMin "2.365  V") (threshOutputHighTyp "2.5  V") (threshOutputHighMax "2.625  V") (threshOutputLowMin "1.275  V") (threshOutputLowTyp "1.7  V") (threshOutputLowMax "1.985  V") (mappingTagNonInverting nil) (mappingTagInverting nil) (spice nil))) (IbisIO ((temperature "27") (bufferModel "CDSDefaultIO_2p5v") (stimuli nil) (offsets nil) (state "tristate") (cycle "1") (termMap nil) (setup "2.0e-09") (hold "1.0e-09") (rise nil) (fall nil) (macroType nil) (voltage nil) (spice nil) (LEFDEFPinName nil) (LEFDEFPinType nil) (mappingTag nil))) (Source ((voltage "5 V"))) (DiffIO ((temperature "27") (bufferModelNonInverting "CDSDefaultIO_2p5v") (bufferModelInverting "CDSDefaultIO_2p5v") (stimuli nil) (offsets nil) (state "tristate") (cycle "1") (termMap nil) (setup "0.9e-09") (hold "0.4e-09") (rise nil) (fall nil) (threshInputHighMin "1.7 V") (threshInputHighTyp "1.7  V") (threshInputHighMax "1.7  V") (threshInputLowMin "0.7  V") (threshInputLowTyp "0.7  V") (threshInputLowMax "0.7 ") (threshOutputHighMin "2.365  V") (threshOutputHighTyp "2.5  V") (threshOutputHighMax "2.625  V") (threshOutputLowMin "1.275  V") (threshOutputLowTyp "1.7  V") (threshOutputLowMax "1.985  V") (mappingTagNonInverting nil) (mappingTagInverting nil) (spice nil))) (RLGC (length("1000 mil"))) (IbisInput ((temperature "27") (bufferModel "CDSDefaultInput_2p5v") (cycle "1") (LEFDEFPinName nil) (LEFDEFPinType nil) (mappingTag nil))) (DiffInput ((temperature "27") (bufferModelNonInverting "CDSDefaultInput_2p5v") (bufferModelInverting "CDSDefaultInput_2p5v") (threshInputHighMin "1.7 V") (threshInputHighTyp "1.7  V") (threshInputHighMax "1.7  V") (threshInputLowMin "0.7  V") (threshInputLowTyp "0.7  V") (threshInputLowMax "0.7  V") (mappingTagNonInverting nil) (mappingTagInverting nil) (cycle "1"))) (ESpiceDevice nil) (sync ((syncFreq "100e6") (syncInitState "1") (syncPattern "10") (syncEdgeSwitch "rise"))) (TLine ((diffImpedance "100ohm") (diffVelocity "1.4142e+08M/s") (impedance "60ohm") length("2800 mil") (propDelay "0.5 ns") (velocity "5600 mil/ns") (traceCount "1") (traceGeometry "Microstrip") (impedanceMin nil) (impedanceMax nil) (lengthMin nil) (lengthMax nil) (propDelayMin nil) (propDelayMax nil) (impedanceSweepCount nil) (propDelaySweepCount nil) (velocitySweepCount nil) (lengthSweepCount nil) (matchSetName nil))) (Connector nil) (ShuntTerm ((resistance "50 ohm") (voltage "5 V") (maxDelay "0.1 ns"))) (TheveninTerm ((resistanceUp "180 ohm") (resistanceDown "270 ohm") (voltageUp "5 V") (voltageDown "0 V") (maxDelay "0.1 ns"))) (IbisIO_OpenPullUp ((temperature "27") (bufferModel "CDSDefaultIO_2p5v") (stimuli nil) (offsets nil) (state "tristate") (cycle "1") (termMap nil) (setup "2.0e-09") (hold "1.0e-09") (rise nil) (fall nil) (macroType nil) (voltage nil) (spice nil) (LEFDEFPinName nil) (LEFDEFPinType nil) (mappingTag nil))) (DiffInputPkg ((temperature "27") (bufferModelNonInverting "CDSDefaultInput_2p5v") (bufferModelInverting "CDSDefaultInput_2p5v") (threshInputHighMin "1.7 V") (threshInputHighTyp "1.7  V") (threshInputHighMax "1.7  V") (threshInputLowMin "0.7  V") (threshInputLowTyp "0.7  V") (threshInputLowMax "0.7  V") (mappingTagNonInverting nil) (mappingTagInverting nil) (cycle "1"))) (IbisOutput_OpenPullUp ((temperature "27") (bufferModel "CDSDefaultOutput_2p5v") (stimuli nil) (offsets nil) (state "tristate") (cycle "1") (termMap nil) (setup "2.0e-09") (hold "1.0e-09") (rise nil) (fall nil) (macroType nil) (voltage nil) (spice nil) (LEFDEFPinName nil) (LEFDEFPinType nil) (mappingTag nil))) (idlCircuit ((allDrivers "active") (ftsMode '("Typ")) (rcvrSelect "all") (simMode "Reflection") (tlineDelayMode "time") (userRevision "1.0") (autoSolve "On")))))
				)
				( objectStatus "DDR_K_CMD_DLL1-13" )
			)
			( electricalCSet "@crescent_city_bb_fab1_lib.crescent_city_bb_fab1(sch_1):\DDR_L_CMD_DLL1-13\"
				( groupRef "DDR_L_CMD_DLL1-13:MG_DDR_CMD_NEAR_DIMM" )
				( groupRef "DDR_L_CMD_DLL1-13:MG_DDR_FAR_DIMM-CLK0" )
				( groupRef "DDR_L_CMD_DLL1-13:MG_DDR_FAR_DIMM_CMD" )
				( groupRef "DDR_L_CMD_DLL1-13:MG_DDR_NEAR_DIMM-CLK1" )
				( pinPairRef "DDR_L_CMD_DLL1-13:U2D1.F51:J9L2.228" )
				( pinPairRef "DDR_L_CMD_DLL1-13:U2D1.F51:J1A2.228" )
				( attribute "TOPOLOGY_TEMPLATE_REVISION" "1.0"
					( Origin gBackEnd )
				)
				( topologyData 23957
(SKIDL (Circuits ("MAIN" (Parts ("CRESCENT_CITY_083_20140724_A.@@J1.228" IbisIOPkg (xy (5548 4240)) (refDes "J1A2") (model "Unknown") (Props (_SXDesignName "CRESCENT_CITY_083_20140724_A") (brdx "10643.7 MIL") (brdy "788.33 MIL") (bufferModel "CDSDefaultIO_2p5v") (cycle "1") (hold "1.0e-09") (mappingTag "") (offsets ("4" "0") ("5" "0")) (setup "2.0e-09") (state "tristate") (stimuli ("4" "local0") ("5" "local1")) (temperature "27") (termMap ("4" "Data") ("5" "Enable"))) (Terms ("CRESCENT_CITY_083_20140724_A.X1064370Y78833L2LRATS" "228"))) ("CRESCENT_CITY_083_20140724_A.@@J2.228" IbisIOPkg (xy (5528 4240)) (refDes "J9L2") (model "Unknown") (Props (_SXDesignName "CRESCENT_CITY_083_20140724_A") (brdx "10643.7 MIL") (brdy "796.23 MIL") (bufferModel "CDSDefaultIO_2p5v") (cycle "1") (hold "1.0e-09") (mappingTag "") (offsets ("4" "0") ("5" "0")) (setup "2.0e-09") (state "tristate") (stimuli ("4" "local2") ("5" "local15")) (temperature "27") (termMap ("4" "Data") ("5" "Enable"))) (Terms ("CRESCENT_CITY_083_20140724_A.X1064370Y79623L28LRATS" "228"))) ("CRESCENT_CITY_083_20140724_A.@@U36.F51" IbisIOPkg (xy (5502 4240)) (refDes "U2D1") (model "Unknown") (Props (_SXDesignName "CRESCENT_CITY_083_20140724_A") (brdx "10346.35 MIL") (brdy "2052.1 MIL") (bufferModel "CDSDefaultIO_2p5v") (cycle "1") (hold "1.0e-09") (mappingTag "") (offsets ("4" "0") ("5" "0")) (setup "2.0e-09") (state "tristate") (stimuli ("4" "local16") ("5" "local17")) (temperature "27") (termMap ("4" "Data") ("5" "Enable"))) (Terms ("CRESCENT_CITY_083_20140724_A.X1034635Y205210L2LRATS" "F51"))) ("CRESCENT_CITY_083_20140724_A.T@@RATS@@J2.228@@U36.F51" TLine (xy (5513 4235)) (mirror x) (refDes "TL1") (Props (_SXDesignName "CRESCENT_CITY_083_20140724_A") (impedance "53.474 ohm") length("1553.22 MIL") (propDelay "0.27897 ns") (traceCount "1") (traceGeometry "Microstrip") (velocity "5567.68 mil/ns")) (Terms ("CRESCENT_CITY_083_20140724_A.X1064370Y79623L28LRATS" "1") ("CRESCENT_CITY_083_20140724_A.X1034635Y205210L2LRATS" "2"))) ("CRESCENT_CITY_083_20140724_A.T@@RATS@@J2.228@@J1.228" TLine (xy (5539 4235)) (refDes "TL2") (Props (_SXDesignName "CRESCENT_CITY_083_20140724_A") (impedance "39.682 ohm") length("7.90 MIL") (propDelay "0.00142 ns") (traceCount "1") (traceGeometry "Microstrip") (velocity "5563.39 mil/ns")) (Terms ("CRESCENT_CITY_083_20140724_A.X1064370Y79623L28LRATS" "1") ("CRESCENT_CITY_083_20140724_A.X1064370Y78833L2LRATS" "2")))) (Nodes ("CRESCENT_CITY_083_20140724_A.X1034635Y205210L2LRATS" (terms "CRESCENT_CITY_083_20140724_A.T@@RATS@@J2.228@@U36.F51.2" "CRESCENT_CITY_083_20140724_A.@@U36.F51.1")) ("CRESCENT_CITY_083_20140724_A.X1064370Y78833L2LRATS" (terms "CRESCENT_CITY_083_20140724_A.T@@RATS@@J2.228@@J1.228.2" "CRESCENT_CITY_083_20140724_A.@@J1.228.1")) ("CRESCENT_CITY_083_20140724_A.X1064370Y79623L28LRATS" (terms "CRESCENT_CITY_083_20140724_A.T@@RATS@@J2.228@@J1.228.1" "CRESCENT_CITY_083_20140724_A.T@@RATS@@J2.228@@U36.F51.1" "CRESCENT_CITY_083_20140724_A.@@J2.228.1"))) (Ports) (Stimuli ("local2" (scope local) (stimType periodic) (Props (periodicFreq "5e+007") (periodicJitter "0") (periodicPattern "1"))) ("local15" (scope local) (stimType periodic) (Props (periodicFreq "5e+007") (periodicJitter "0") (periodicPattern "1"))) ("local0" (scope local) (stimType periodic) (Props (periodicFreq "5e+007") (periodicJitter "0") (periodicPattern "1"))) ("local16" (scope local) (stimType periodic) (Props (periodicFreq "5e+007") (periodicJitter "0") (periodicPattern "1"))) ("local1" (scope local) (stimType periodic) (Props (periodicFreq "5e+007") (periodicJitter "0") (periodicPattern "1"))) ("local17" (scope local) (stimType periodic) (Props (periodicFreq "5e+007") (periodicJitter "0") (periodicPattern "1")))) (Notes) (Constraints ("RELATIVE_PROPAGATION_DELAY" ("MG_DDR_CMD_NEAR_DIMM" "CRESCENT_CITY_083_20140724_A U100.F51" "CRESCENT_CITY_083_20140724_A J22.228" "NET GROUP" "LENGTH" "0.000635" "LENGTH" "0") ("MG_DDR_FAR_DIMM-CLK0" "CRESCENT_CITY_083_20140724_A U100.F51" "CRESCENT_CITY_083_20140724_A J21.228" "CLASS" "LENGTH" "0.01778" "LENGTH" "0") ("MG_DDR_FAR_DIMM_CMD" "CRESCENT_CITY_083_20140724_A U100.F51" "CRESCENT_CITY_083_20140724_A J21.228" "NET GROUP" "LENGTH" "0.000635" "LENGTH" "0") ("MG_DDR_NEAR_DIMM-CLK1" "CRESCENT_CITY_083_20140724_A U100.F51" "CRESCENT_CITY_083_20140724_A J22.228" "CLASS" "LENGTH" "0.01778" "LENGTH" "0"))) (MeasurementSets ("EMI" ("EMIStatus" status("on")) ("PeakEmission" status("on")) ("PeakFrequency" status("on")) ("PulseFreq" status("on")) ("RiseTime" status("on")) ("VoltageSwing" status("on"))) ("Reflection" ("BufferDelayFall" status("off")) ("BufferDelayRise" status("off")) ("EyeHeight" status("off")) ("EyeJitter" status("off")) ("EyeWidth" status("off")) ("FirstIncidentFall" status("off")) ("FirstIncidentRise" status("off")) ("Glitch" status("on")) ("GlitchFall" status("off")) ("GlitchRise" status("off")) ("Monotonic" status("on")) ("MonotonicFall" status("off")) ("MonotonicRise" status("off")) ("NoiseMargin" status("on")) ("NoiseMarginHigh" status("off")) ("NoiseMarginLow" status("off")) ("OvershootHigh" status("on")) ("OvershootLow" status("on")) ("PropDelay" status("on")) ("SettleDelay" status("on")) ("SettleDelayFall" status("off")) ("SettleDelayRise" status("off")) ("SwitchDelay" status("on")) ("SwitchDelayFall" status("off")) ("SwitchDelayRise" status("off"))) ("Crosstalk" ("Crosstalk" status("on"))) ("Custom")) (VectorSets) (Props (XnetName "M_A_MA<14>") (allDrivers "active") (autoSolve "Off") (customSimType "Reflection") (ftsMode ("Typ")) (rcvrSelect "all") (tlineDelayMode "time") (userRevision "1.0")))) (Subckts) (CrossSections ("CRESCENT_CITY_083_20140724_A" (Props (SXDesignName "CRESCENT_CITY_083_20140724_A")) (Layers ("" (layerType "SURFACE") (material "AIR") (thickness "0 mil") (dielectricConstant "1.000000") (lossTangent "0") (etchFactor "0.000000") (elecCondVal "0 mho/cm") (thermCondVal "0 w/cm-degC")) ("" (layerType "DIELECTRIC") (material "CONFORMAL_COAT") (thickness "0.5 mil") (dielectricConstant "3.800000") (lossTangent "0.035") (etchFactor "0.000000") (elecCondVal "0 mho/cm") (thermCondVal "0.012 w/cm-degC")) ("TOP" (layerType "CONDUCTOR") (material "COPPER") (thickness "  1.800000 mil") (width "4.00 MIL") (dielectricConstant "4.500000") (lossTangent "0") (etchFactor "70.000000") (elecCondVal "595900.000000 mho/cm") (thermCondVal "0 w/cm-degC") (signalDieConstant "3.800000") (signalLossTangent "0.035")) ("" (layerType "DIELECTRIC") (material "FR-4") (thickness "  2.700000 mil") (dielectricConstant "4.000000") (lossTangent "0.035") (etchFactor "0.000000") (elecCondVal "0 mho/cm") (thermCondVal "0.012 w/cm-degC")) ("L2_GND1" (layerType "PLANE") (material "COPPER") (isShield t) (thickness "  1.200000 mil") (dielectricConstant "4.500000") (lossTangent "0.035") (etchFactor "90.000000") (elecCondVal "595900.000000 mho/cm") (thermCondVal "0.012 w/cm-degC")) ("" (layerType "DIELECTRIC") (material "FR-4") (thickness "  9.900000 mil") (dielectricConstant "4.100000") (lossTangent "0.035") (etchFactor "0.000000") (elecCondVal "0 mho/cm") (thermCondVal "0.012 w/cm-degC")) ("L3_SIG1" (layerType "CONDUCTOR") (material "COPPER") (thickness "  1.200000 mil") (width "4.00 MIL") (dielectricConstant "4.500000") (lossTangent "0.035") (etchFactor "90.000000") (elecCondVal "595900.000000 mho/cm") (thermCondVal "0.012 w/cm-degC") (signalDieConstant "4.100000") (signalLossTangent "0.035")) ("" (layerType "DIELECTRIC") (material "FR-4") (thickness "  3.300000 mil") (dielectricConstant "4.500000") (lossTangent "0.035") (etchFactor "0.000000") (elecCondVal "0 mho/cm") (thermCondVal "0 w/cm-degC")) ("L4_GND2" (layerType "PLANE") (material "COPPER") (isShield t) (thickness "  1.200000 mil") (dielectricConstant "4.500000") (lossTangent "0.035") (etchFactor "90.000000") (elecCondVal "595900.000000 mho/cm") (thermCondVal "0 w/cm-degC")) ("" (layerType "DIELECTRIC") (material "FR-4") (thickness "  3.300000 mil") (dielectricConstant "4.000000") (lossTangent "0.035") (etchFactor "0.000000") (elecCondVal "0 mho/cm") (thermCondVal "0.012 w/cm-degC")) ("L5_SIG2" (layerType "CONDUCTOR") (material "COPPER") (thickness "  1.200000 mil") (width "4.00 MIL") (dielectricConstant "4.500000") (lossTangent "0.035") (etchFactor "90.000000") (elecCondVal "595900.000000 mho/cm") (thermCondVal "0.012 w/cm-degC") (signalDieConstant "4.000000") (signalLossTangent "0.035")) ("" (layerType "DIELECTRIC") (material "FR-4") (thickness "  9.900000 mil") (dielectricConstant "4.500000") (lossTangent "0.035") (etchFactor "0.000000") (elecCondVal "0 mho/cm") (thermCondVal "0 w/cm-degC")) ("L6_GND3" (layerType "PLANE") (material "COPPER") (isShield t) (thickness "  1.200000 mil") (dielectricConstant "4.500000") (lossTangent "0.035") (etchFactor "90.000000") (elecCondVal "595900.000000 mho/cm") (thermCondVal "0 w/cm-degC")) ("" (layerType "DIELECTRIC") (material "FR-4") (thickness "  3.300000 mil") (dielectricConstant "4.100000") (lossTangent "0.035") (etchFactor "0.000000") (elecCondVal "0 mho/cm") (thermCondVal "0.012 w/cm-degC")) ("L7_PWR1-SIG" (layerType "PLANE") (material "COPPER") (isShield t) (thickness "  1.200000 mil") (dielectricConstant "4.500000") (lossTangent "0.035") (etchFactor "90.000000") (elecCondVal "595900.000000 mho/cm") (thermCondVal "0.012 w/cm-degC")) ("" (layerType "DIELECTRIC") (material "FR-4") (thickness "  9.900000 mil") (dielectricConstant "4.000000") (lossTangent "0.035") (etchFactor "0.000000") (elecCondVal "0 mho/cm") (thermCondVal "0.012 w/cm-degC")) ("L8_PWR2-SIG" (layerType "PLANE") (material "COPPER") (isShield t) (thickness "  1.200000 mil") (dielectricConstant "4.500000") (lossTangent "0.035") (etchFactor "90.000000") (elecCondVal "595900.000000 mho/cm") (thermCondVal "0.012 w/cm-degC")) ("" (layerType "DIELECTRIC") (material "FR-4") (thickness "  3.300000 mil") (dielectricConstant "4.500000") (lossTangent "0.035") (etchFactor "0.000000") (elecCondVal "0 mho/cm") (thermCondVal "0 w/cm-degC")) ("L9_GND4" (layerType "PLANE") (material "COPPER") (isShield t) (thickness "  1.200000 mil") (dielectricConstant "4.500000") (lossTangent "0.035") (etchFactor "90.000000") (elecCondVal "595900.000000 mho/cm") (thermCondVal "0 w/cm-degC")) ("" (layerType "DIELECTRIC") (material "FR-4") (thickness "  9.900000 mil") (dielectricConstant "4.100000") (lossTangent "0.035") (etchFactor "0.000000") (elecCondVal "0 mho/cm") (thermCondVal "0.012 w/cm-degC")) ("L10_SIG3" (layerType "CONDUCTOR") (material "COPPER") (thickness "  1.200000 mil") (width "4.00 MIL") (dielectricConstant "4.500000") (lossTangent "0.035") (etchFactor "90.000000") (elecCondVal "595900.000000 mho/cm") (thermCondVal "0.012 w/cm-degC") (signalDieConstant "4.100000") (signalLossTangent "0.035")) ("" (layerType "DIELECTRIC") (material "FR-4") (thickness "  3.300000 mil") (dielectricConstant "4.500000") (lossTangent "0.035") (etchFactor "0.000000") (elecCondVal "0 mho/cm") (thermCondVal "0 w/cm-degC")) ("L11_GND5" (layerType "PLANE") (material "COPPER") (isShield t) (thickness "  1.200000 mil") (dielectricConstant "4.500000") (lossTangent "0.035") (etchFactor "90.000000") (elecCondVal "595900.000000 mho/cm") (thermCondVal "0 w/cm-degC")) ("" (layerType "DIELECTRIC") (material "FR-4") (thickness "  9.900000 mil") (dielectricConstant "4.500000") (lossTangent "0.035") (etchFactor "0.000000") (elecCondVal "0 mho/cm") (thermCondVal "0.012 w/cm-degC")) ("L12_SIG4" (layerType "CONDUCTOR") (material "COPPER") (thickness "  1.200000 mil") (width "4.00 MIL") (dielectricConstant "4.500000") (lossTangent "0.035") (etchFactor "90.000000") (elecCondVal "595900.000000 mho/cm") (thermCondVal "0.012 w/cm-degC") (signalDieConstant "4.500000") (signalLossTangent "0.035")) ("" (layerType "DIELECTRIC") (material "FR-4") (thickness "  3.300000 mil") (dielectricConstant "4.500000") (lossTangent "0.035") (etchFactor "0.000000") (elecCondVal "0 mho/cm") (thermCondVal "0 w/cm-degC")) ("L13_GND6" (layerType "PLANE") (material "COPPER") (isShield t) (thickness "  1.200000 mil") (dielectricConstant "4.500000") (lossTangent "0.035") (etchFactor "90.000000") (elecCondVal "595900.000000 mho/cm") (thermCondVal "0.012 w/cm-degC")) ("" (layerType "DIELECTRIC") (material "FR-4") (thickness "  2.700000 mil") (dielectricConstant "4.500000") (lossTangent "0.035") (etchFactor "0.000000") (elecCondVal "0 mho/cm") (thermCondVal "0.012 w/cm-degC")) ("BOTTOM" (layerType "CONDUCTOR") (material "COPPER") (thickness "  1.800000 mil") (width "4.00 MIL") (dielectricConstant "4.500000") (lossTangent "0") (etchFactor "70.000000") (elecCondVal "595900.000000 mho/cm") (thermCondVal "0 w/cm-degC") (signalDieConstant "3.800000") (signalLossTangent "0.035")) ("" (layerType "DIELECTRIC") (material "CONFORMAL_COAT") (thickness "0.5 mil") (dielectricConstant "3.800000") (lossTangent "0.035") (etchFactor "0.000000") (elecCondVal "0 mho/cm") (thermCondVal "0.012 w/cm-degC")) ("" (layerType "SURFACE") (material "AIR") (thickness "0 mil") (dielectricConstant "1.000000") (lossTangent "0") (etchFactor "0.000000") (elecCondVal "0 mho/cm") (thermCondVal "0 w/cm-degC"))))) (Props (DesUnits "mils 2") (LayerStack ("DIELECTRIC" "DIELECTRIC" "BOTTOM" "DIELECTRIC" "L13_GND6" "DIELECTRIC" "L12_SIG4" "DIELECTRIC" "L11_GND5" "DIELECTRIC" "L10_SIG3" "DIELECTRIC" "L9_GND4" "DIELECTRIC" "L8_PWR2-SIG" "DIELECTRIC" "L7_PWR1-SIG" "DIELECTRIC" "L6_GND3" "DIELECTRIC" "L5_SIG2" "DIELECTRIC" "L4_GND2" "DIELECTRIC" "L3_SIG1" "DIELECTRIC" "L2_GND1" "DIELECTRIC" "TOP" "DIELECTRIC" "DIELECTRIC")) (Revision "16.600")) (Params (DualClampTerm ((cutoffVoltageUp "0.7 V") (cutoffVoltageDown "0.7 V") (voltageUp "5 V") (voltageDown "0 V") (maxDelay "0.1 ns"))) (HiClampTerm ((cutoffVoltage "0.7 V") (voltage "5 V") (maxDelay "0.1 ns"))) (IbisInputPkg ((temperature "27") (bufferModel "CDSDefaultInput_2p5v") (cycle "1") (LEFDEFPinName nil) (LEFDEFPinType nil) (mappingTag nil))) (RCTerm ((resistance "50 ohm") (capacitance "20 pF") (voltage "5 V") (maxDelay "0.1 ns"))) (IbisIOMacro ((temperature "27") (bufferModel "CDSDefaultIO_2p5v") (stimuli nil) (offsets nil) (state "tristate") (cycle "1") (termMap nil) (setup "2.0e-09") (hold "1.0e-09") (rise nil) (fall nil) (macroType nil) (voltage nil) (spice nil) (LEFDEFPinName nil) (LEFDEFPinType nil) (mappingTag nil))) (LowClampTerm ((cutoffVoltage "0.7 V") (voltage "0 V") (maxDelay "0.1 ns"))) (CurrentProbe nil) (IbisOutputPkg ((temperature "27") (bufferModel "CDSDefaultOutput_2p5v") (stimuli nil) (offsets nil) (state "tristate") (cycle "1") (termMap nil) (setup "2.0e-09") (hold "1.0e-09") (rise nil) (fall nil) (macroType nil) (voltage nil) (spice nil) (LEFDEFPinName nil) (LEFDEFPinType nil) (mappingTag nil))) (IbisIOPkg ((temperature "27") (bufferModel "CDSDefaultIO_2p5v") (stimuli nil) (offsets nil) (state "tristate") (cycle "1") (termMap nil) (setup "2.0e-09") (hold "1.0e-09") (rise nil) (fall nil) (macroType nil) (voltage nil) (spice nil) (LEFDEFPinName nil) (LEFDEFPinType nil) (mappingTag nil))) (SeriesTerm ((resistance "22 ohm") (maxDelay "0.1 ns"))) (IbisIO_OpenPullDown ((temperature "27") (bufferModel "CDSDefaultIO_2p5v") (stimuli nil) (offsets nil) (state "tristate") (cycle "1") (termMap nil) (setup "2.0e-09") (hold "1.0e-09") (rise nil) (fall nil) (macroType nil) (voltage nil) (spice nil) (LEFDEFPinName nil) (LEFDEFPinType nil) (mappingTag nil))) (clocked ((clockRise "1e-09") (clockFall "1e-09") (clockFreq "100e6") (clockInitState "0") (clockDutyCycle "0.5") (clockJitter "0"))) (CPWSL ((d1Thickness "10 mil") (d1Constant "4.5") (d1LossTangent "0.035") (d2Thickness "0.72 mil") (d2Constant "4.5") (d2LossTangent "0.035") (d3Thickness "10 mil") (d3Constant "4.5") (d3LossTangent "0.035") length("1000 mil") (spacing "5 mil") (spacing2 "5 mil") (spacing3 "5 mil") (spacing4 "5 mil") (spacing5 "5 mil") (traceConductivity "595900 mho/cm") (traceGeometry "cpwms") (traceLayerName "") (traceThickness "0.72 mil") (traceType "single") (traceWidth "5.0 mil") (traceWidth2 "5.0 mil") (traceWidth3 "5.0 mil") (traceWidth4 "5.0 mil") (traceWidth5 "5.0 mil") (traceWidth6 "5.0 mil") (offset "0 mil") (traceCount "1") (impedance nil))) (CPWMS ((d1Thickness "10 mil") (d1Constant "4.5") (d1LossTangent "0.035") (d2Thickness "0.72 mil") (d2Constant "4.5") (d2LossTangent "0.035") (d3Thickness "0.0") (d3Constant "1") (d3LossTangent "0") length("1000 mil") (spacing "5 mil") (spacing2 "5 mil") (spacing3 "5 mil") (spacing4 "5 mil") (spacing5 "5 mil") (traceConductivity "595900 mho/cm") (traceGeometry "cpwms") (traceLayerName "") (traceThickness "0.72 mil") (traceType "single") (traceWidth "5.0 mil") (traceWidth2 "5.0 mil") (traceWidth3 "5.0 mil") (traceWidth4 "5.0 mil") (traceWidth5 "5.0 mil") (traceWidth6 "5.0 mil") (offset "0 mil") (traceCount "1") (impedance nil))) (CPW ((d1Thickness "10 mil") (d1Constant "4.5") (d1LossTangent "0.035") (d2Thickness "0.72 mil") (d2Constant "1") (d2LossTangent "0") (d3Thickness "0.0") (d3Constant "1") (d3LossTangent "0") length("1000 mil") (spacing "5 mil") (spacing2 "5 mil") (spacing3 "5 mil") (spacing4 "5 mil") (spacing5 "5 mil") (traceConductivity "595900 mho/cm") (traceGeometry "cpwms") (traceLayerName "") (traceThickness "0.72 mil") (traceType "single") (traceWidth "5.0 mil") (traceWidth2 "5.0 mil") (traceWidth3 "5.0 mil") (traceWidth4 "5.0 mil") (traceWidth5 "5.0 mil") (traceWidth6 "5.0 mil") (offset "0 mil") (traceCount "1") (impedance nil))) (periodic ((periodicFreq "100e6") (periodicPattern "10") (periodicJitter "0"))) (Diode ((cutoffVoltage "0.7 V"))) (Trace ((d1Thickness "10 mil") (d1Constant "4.5") (d1LossTangent "0.035") (d2Thickness "10 mil") (d2Constant "4.5") (d2LossTangent "0.035") (d3Thickness "0.0") (d3Constant "1.0") (d3LossTangent "0") length("1000 mil") (spacing "5 mil") (spacing2 "5 mil") (spacing3 "5 mil") (spacing4 "5 mil") (spacing5 "5 mil") (traceConductivity "595900 mho/cm") (traceGeometry "microstrip") (traceLayerName "") (traceThickness "0.72 mil") (traceType "single") (traceWidth "5.0 mil") (traceWidth2 "5.0 mil") (traceWidth3 "5.0 mil") (traceWidth4 "5.0 mil") (traceWidth5 "5.0 mil") (traceWidth6 "5.0 mil") (offset "0 mil") (traceCount "1") (impedance nil))) (Cable (length("1 m"))) (Via ((model "Unknown") (viaOutputFormat "Unknown") (viaPadstack nil) (viaTopLayer nil) (viaBottomLayer nil) (viaIsPower nil) (viaIsGround nil))) (async ((asyncTimePoints "") (asyncInitState "1"))) (Resistor ((resistance "50 ohm") (orientation "0"))) (DiffOutputPkg ((temperature "27") (bufferModelNonInverting "CDSDefaultOutput_2p5v") (bufferModelInverting "CDSDefaultOutput_2p5v") (stimuli nil) (offsets nil) (state "tristate") (cycle "1") (termMap nil) (setup "0.9e-09") (hold "0.4e-09") (rise nil) (fall nil) (threshOutputHighMin "2.375  V") (threshOutputHighTyp "2.5  V") (threshOutputHighMax "2.625  V") (threshOutputLowMin "1.275  V") (threshOutputLowTyp "1.7  V") (threshOutputLowMax "1.985  V") (mappingTagNonInverting nil) (mappingTagInverting nil) (spice nil))) (DiffOutput ((temperature "27") (bufferModelNonInverting "CDSDefaultOutput_2p5v") (bufferModelInverting "CDSDefaultOutput_2p5v") (stimuli nil) (offsets nil) (state "tristate") (cycle "1") (termMap nil) (setup "0.9e-09") (hold "0.4e-09") (rise nil) (fall nil) (threshOutputHighMin "2.375  V") (threshOutputHighTyp "2.5  V") (threshOutputHighMax "2.625  V") (threshOutputLowMin "1.275  V") (threshOutputLowTyp "1.7  V") (threshOutputLowMax "1.985  V") (mappingTagNonInverting nil) (mappingTagInverting nil) (spice nil))) (IbisOutput ((temperature "27") (bufferModel "CDSDefaultOutput_2p5v") (stimuli nil) (offsets nil) (state "tristate") (cycle "1") (termMap nil) (setup "2.0e-09") (hold "1.0e-09") (rise nil) (fall nil) (macroType nil) (voltage nil) (spice nil) (LEFDEFPinName nil) (LEFDEFPinType nil) (mappingTag nil))) (Inductor ((inductance "5 nH") (orientation "0"))) (Capacitor ((capacitance "10 pF") (orientation "0"))) (DiffIOPkg ((temperature "27") (bufferModelNonInverting "CDSDefaultIO_2p5v") (bufferModelInverting "CDSDefaultIO_2p5v") (stimuli nil) (offsets nil) (state "tristate") (cycle "1") (termMap nil) (setup "0.9e-09") (hold "0.4e-09") (rise nil) (fall nil) (threshInputHighMin "1.7 V") (threshInputHighTyp "1.7  V") (threshInputHighMax "1.7  V") (threshInputLowMin "0.7  V") (threshInputLowTyp "0.7  V") (threshInputLowMax "0.7 ") (threshOutputHighMin "2.365  V") (threshOutputHighTyp "2.5  V") (threshOutputHighMax "2.625  V") (threshOutputLowMin "1.275  V") (threshOutputLowTyp "1.7  V") (threshOutputLowMax "1.985  V") (mappingTagNonInverting nil) (mappingTagInverting nil) (spice nil))) (IbisIO ((temperature "27") (bufferModel "CDSDefaultIO_2p5v") (stimuli nil) (offsets nil) (state "tristate") (cycle "1") (termMap nil) (setup "2.0e-09") (hold "1.0e-09") (rise nil) (fall nil) (macroType nil) (voltage nil) (spice nil) (LEFDEFPinName nil) (LEFDEFPinType nil) (mappingTag nil))) (Source ((voltage "5 V"))) (DiffIO ((temperature "27") (bufferModelNonInverting "CDSDefaultIO_2p5v") (bufferModelInverting "CDSDefaultIO_2p5v") (stimuli nil) (offsets nil) (state "tristate") (cycle "1") (termMap nil) (setup "0.9e-09") (hold "0.4e-09") (rise nil) (fall nil) (threshInputHighMin "1.7 V") (threshInputHighTyp "1.7  V") (threshInputHighMax "1.7  V") (threshInputLowMin "0.7  V") (threshInputLowTyp "0.7  V") (threshInputLowMax "0.7 ") (threshOutputHighMin "2.365  V") (threshOutputHighTyp "2.5  V") (threshOutputHighMax "2.625  V") (threshOutputLowMin "1.275  V") (threshOutputLowTyp "1.7  V") (threshOutputLowMax "1.985  V") (mappingTagNonInverting nil) (mappingTagInverting nil) (spice nil))) (RLGC (length("1000 mil"))) (IbisInput ((temperature "27") (bufferModel "CDSDefaultInput_2p5v") (cycle "1") (LEFDEFPinName nil) (LEFDEFPinType nil) (mappingTag nil))) (DiffInput ((temperature "27") (bufferModelNonInverting "CDSDefaultInput_2p5v") (bufferModelInverting "CDSDefaultInput_2p5v") (threshInputHighMin "1.7 V") (threshInputHighTyp "1.7  V") (threshInputHighMax "1.7  V") (threshInputLowMin "0.7  V") (threshInputLowTyp "0.7  V") (threshInputLowMax "0.7  V") (mappingTagNonInverting nil) (mappingTagInverting nil) (cycle "1"))) (ESpiceDevice nil) (sync ((syncFreq "100e6") (syncInitState "1") (syncPattern "10") (syncEdgeSwitch "rise"))) (TLine ((diffImpedance "100ohm") (diffVelocity "1.4142e+08M/s") (impedance "60ohm") length("2800 mil") (propDelay "0.5 ns") (velocity "5600 mil/ns") (traceCount "1") (traceGeometry "Microstrip") (impedanceMin nil) (impedanceMax nil) (lengthMin nil) (lengthMax nil) (propDelayMin nil) (propDelayMax nil) (impedanceSweepCount nil) (propDelaySweepCount nil) (velocitySweepCount nil) (lengthSweepCount nil) (matchSetName nil))) (Connector nil) (ShuntTerm ((resistance "50 ohm") (voltage "5 V") (maxDelay "0.1 ns"))) (TheveninTerm ((resistanceUp "180 ohm") (resistanceDown "270 ohm") (voltageUp "5 V") (voltageDown "0 V") (maxDelay "0.1 ns"))) (IbisIO_OpenPullUp ((temperature "27") (bufferModel "CDSDefaultIO_2p5v") (stimuli nil) (offsets nil) (state "tristate") (cycle "1") (termMap nil) (setup "2.0e-09") (hold "1.0e-09") (rise nil) (fall nil) (macroType nil) (voltage nil) (spice nil) (LEFDEFPinName nil) (LEFDEFPinType nil) (mappingTag nil))) (DiffInputPkg ((temperature "27") (bufferModelNonInverting "CDSDefaultInput_2p5v") (bufferModelInverting "CDSDefaultInput_2p5v") (threshInputHighMin "1.7 V") (threshInputHighTyp "1.7  V") (threshInputHighMax "1.7  V") (threshInputLowMin "0.7  V") (threshInputLowTyp "0.7  V") (threshInputLowMax "0.7  V") (mappingTagNonInverting nil) (mappingTagInverting nil) (cycle "1"))) (IbisOutput_OpenPullUp ((temperature "27") (bufferModel "CDSDefaultOutput_2p5v") (stimuli nil) (offsets nil) (state "tristate") (cycle "1") (termMap nil) (setup "2.0e-09") (hold "1.0e-09") (rise nil) (fall nil) (macroType nil) (voltage nil) (spice nil) (LEFDEFPinName nil) (LEFDEFPinType nil) (mappingTag nil))) (idlCircuit ((allDrivers "active") (ftsMode '("Typ")) (rcvrSelect "all") (simMode "Reflection") (tlineDelayMode "time") (userRevision "1.0") (autoSolve "On")))))
				)
				( objectStatus "DDR_L_CMD_DLL1-13" )
			)
			( electricalCSet "@crescent_city_bb_fab1_lib.crescent_city_bb_fab1(sch_1):\DDR_M_CMD_DLL1-13\"
				( groupRef "DDR_M_CMD_DLL1-13:MG_DDR_CMD_NEAR_DIMM" )
				( groupRef "DDR_M_CMD_DLL1-13:MG_DDR_FAR_DIMM-CLK0" )
				( groupRef "DDR_M_CMD_DLL1-13:MG_DDR_FAR_DIMM_CMD" )
				( groupRef "DDR_M_CMD_DLL1-13:MG_DDR_NEAR_DIMM-CLK1" )
				( pinPairRef "DDR_M_CMD_DLL1-13:U2D1.F51:J9L1.228" )
				( pinPairRef "DDR_M_CMD_DLL1-13:U2D1.F51:J1A1.228" )
				( attribute "TOPOLOGY_TEMPLATE_REVISION" "1.0"
					( Origin gBackEnd )
				)
				( topologyData 23957
(SKIDL (Circuits ("MAIN" (Parts ("CRESCENT_CITY_083_20140724_A.@@J1.228" IbisIOPkg (xy (5548 4240)) (refDes "J1A1") (model "Unknown") (Props (_SXDesignName "CRESCENT_CITY_083_20140724_A") (brdx "10643.7 MIL") (brdy "788.33 MIL") (bufferModel "CDSDefaultIO_2p5v") (cycle "1") (hold "1.0e-09") (mappingTag "") (offsets ("4" "0") ("5" "0")) (setup "2.0e-09") (state "tristate") (stimuli ("4" "local0") ("5" "local1")) (temperature "27") (termMap ("4" "Data") ("5" "Enable"))) (Terms ("CRESCENT_CITY_083_20140724_A.X1064370Y78833L2LRATS" "228"))) ("CRESCENT_CITY_083_20140724_A.@@J2.228" IbisIOPkg (xy (5528 4240)) (refDes "J9L1") (model "Unknown") (Props (_SXDesignName "CRESCENT_CITY_083_20140724_A") (brdx "10643.7 MIL") (brdy "796.23 MIL") (bufferModel "CDSDefaultIO_2p5v") (cycle "1") (hold "1.0e-09") (mappingTag "") (offsets ("4" "0") ("5" "0")) (setup "2.0e-09") (state "tristate") (stimuli ("4" "local2") ("5" "local15")) (temperature "27") (termMap ("4" "Data") ("5" "Enable"))) (Terms ("CRESCENT_CITY_083_20140724_A.X1064370Y79623L28LRATS" "228"))) ("CRESCENT_CITY_083_20140724_A.@@U36.F51" IbisIOPkg (xy (5502 4240)) (refDes "U2D1") (model "Unknown") (Props (_SXDesignName "CRESCENT_CITY_083_20140724_A") (brdx "10346.35 MIL") (brdy "2052.1 MIL") (bufferModel "CDSDefaultIO_2p5v") (cycle "1") (hold "1.0e-09") (mappingTag "") (offsets ("4" "0") ("5" "0")) (setup "2.0e-09") (state "tristate") (stimuli ("4" "local16") ("5" "local17")) (temperature "27") (termMap ("4" "Data") ("5" "Enable"))) (Terms ("CRESCENT_CITY_083_20140724_A.X1034635Y205210L2LRATS" "F51"))) ("CRESCENT_CITY_083_20140724_A.T@@RATS@@J2.228@@U36.F51" TLine (xy (5513 4235)) (mirror x) (refDes "TL1") (Props (_SXDesignName "CRESCENT_CITY_083_20140724_A") (impedance "53.474 ohm") length("1553.22 MIL") (propDelay "0.27897 ns") (traceCount "1") (traceGeometry "Microstrip") (velocity "5567.68 mil/ns")) (Terms ("CRESCENT_CITY_083_20140724_A.X1064370Y79623L28LRATS" "1") ("CRESCENT_CITY_083_20140724_A.X1034635Y205210L2LRATS" "2"))) ("CRESCENT_CITY_083_20140724_A.T@@RATS@@J2.228@@J1.228" TLine (xy (5539 4235)) (refDes "TL2") (Props (_SXDesignName "CRESCENT_CITY_083_20140724_A") (impedance "39.682 ohm") length("7.90 MIL") (propDelay "0.00142 ns") (traceCount "1") (traceGeometry "Microstrip") (velocity "5563.39 mil/ns")) (Terms ("CRESCENT_CITY_083_20140724_A.X1064370Y79623L28LRATS" "1") ("CRESCENT_CITY_083_20140724_A.X1064370Y78833L2LRATS" "2")))) (Nodes ("CRESCENT_CITY_083_20140724_A.X1034635Y205210L2LRATS" (terms "CRESCENT_CITY_083_20140724_A.T@@RATS@@J2.228@@U36.F51.2" "CRESCENT_CITY_083_20140724_A.@@U36.F51.1")) ("CRESCENT_CITY_083_20140724_A.X1064370Y78833L2LRATS" (terms "CRESCENT_CITY_083_20140724_A.T@@RATS@@J2.228@@J1.228.2" "CRESCENT_CITY_083_20140724_A.@@J1.228.1")) ("CRESCENT_CITY_083_20140724_A.X1064370Y79623L28LRATS" (terms "CRESCENT_CITY_083_20140724_A.T@@RATS@@J2.228@@J1.228.1" "CRESCENT_CITY_083_20140724_A.T@@RATS@@J2.228@@U36.F51.1" "CRESCENT_CITY_083_20140724_A.@@J2.228.1"))) (Ports) (Stimuli ("local2" (scope local) (stimType periodic) (Props (periodicFreq "5e+007") (periodicJitter "0") (periodicPattern "1"))) ("local15" (scope local) (stimType periodic) (Props (periodicFreq "5e+007") (periodicJitter "0") (periodicPattern "1"))) ("local0" (scope local) (stimType periodic) (Props (periodicFreq "5e+007") (periodicJitter "0") (periodicPattern "1"))) ("local16" (scope local) (stimType periodic) (Props (periodicFreq "5e+007") (periodicJitter "0") (periodicPattern "1"))) ("local1" (scope local) (stimType periodic) (Props (periodicFreq "5e+007") (periodicJitter "0") (periodicPattern "1"))) ("local17" (scope local) (stimType periodic) (Props (periodicFreq "5e+007") (periodicJitter "0") (periodicPattern "1")))) (Notes) (Constraints ("RELATIVE_PROPAGATION_DELAY" ("MG_DDR_CMD_NEAR_DIMM" "CRESCENT_CITY_083_20140724_A U100.F51" "CRESCENT_CITY_083_20140724_A J24.228" "NET GROUP" "LENGTH" "0.000635" "LENGTH" "0") ("MG_DDR_FAR_DIMM-CLK0" "CRESCENT_CITY_083_20140724_A U100.F51" "CRESCENT_CITY_083_20140724_A J23.228" "CLASS" "LENGTH" "0.01778" "LENGTH" "0") ("MG_DDR_FAR_DIMM_CMD" "CRESCENT_CITY_083_20140724_A U100.F51" "CRESCENT_CITY_083_20140724_A J23.228" "NET GROUP" "LENGTH" "0.000635" "LENGTH" "0") ("MG_DDR_NEAR_DIMM-CLK1" "CRESCENT_CITY_083_20140724_A U100.F51" "CRESCENT_CITY_083_20140724_A J24.228" "CLASS" "LENGTH" "0.01778" "LENGTH" "0"))) (MeasurementSets ("EMI" ("EMIStatus" status("on")) ("PeakEmission" status("on")) ("PeakFrequency" status("on")) ("PulseFreq" status("on")) ("RiseTime" status("on")) ("VoltageSwing" status("on"))) ("Reflection" ("BufferDelayFall" status("off")) ("BufferDelayRise" status("off")) ("EyeHeight" status("off")) ("EyeJitter" status("off")) ("EyeWidth" status("off")) ("FirstIncidentFall" status("off")) ("FirstIncidentRise" status("off")) ("Glitch" status("on")) ("GlitchFall" status("off")) ("GlitchRise" status("off")) ("Monotonic" status("on")) ("MonotonicFall" status("off")) ("MonotonicRise" status("off")) ("NoiseMargin" status("on")) ("NoiseMarginHigh" status("off")) ("NoiseMarginLow" status("off")) ("OvershootHigh" status("on")) ("OvershootLow" status("on")) ("PropDelay" status("on")) ("SettleDelay" status("on")) ("SettleDelayFall" status("off")) ("SettleDelayRise" status("off")) ("SwitchDelay" status("on")) ("SwitchDelayFall" status("off")) ("SwitchDelayRise" status("off"))) ("Crosstalk" ("Crosstalk" status("on"))) ("Custom")) (VectorSets) (Props (XnetName "M_A_MA<14>") (allDrivers "active") (autoSolve "Off") (customSimType "Reflection") (ftsMode ("Typ")) (rcvrSelect "all") (tlineDelayMode "time") (userRevision "1.0")))) (Subckts) (CrossSections ("CRESCENT_CITY_083_20140724_A" (Props (SXDesignName "CRESCENT_CITY_083_20140724_A")) (Layers ("" (layerType "SURFACE") (material "AIR") (thickness "0 mil") (dielectricConstant "1.000000") (lossTangent "0") (etchFactor "0.000000") (elecCondVal "0 mho/cm") (thermCondVal "0 w/cm-degC")) ("" (layerType "DIELECTRIC") (material "CONFORMAL_COAT") (thickness "0.5 mil") (dielectricConstant "3.800000") (lossTangent "0.035") (etchFactor "0.000000") (elecCondVal "0 mho/cm") (thermCondVal "0.012 w/cm-degC")) ("TOP" (layerType "CONDUCTOR") (material "COPPER") (thickness "  1.800000 mil") (width "4.00 MIL") (dielectricConstant "4.500000") (lossTangent "0") (etchFactor "70.000000") (elecCondVal "595900.000000 mho/cm") (thermCondVal "0 w/cm-degC") (signalDieConstant "3.800000") (signalLossTangent "0.035")) ("" (layerType "DIELECTRIC") (material "FR-4") (thickness "  2.700000 mil") (dielectricConstant "4.000000") (lossTangent "0.035") (etchFactor "0.000000") (elecCondVal "0 mho/cm") (thermCondVal "0.012 w/cm-degC")) ("L2_GND1" (layerType "PLANE") (material "COPPER") (isShield t) (thickness "  1.200000 mil") (dielectricConstant "4.500000") (lossTangent "0.035") (etchFactor "90.000000") (elecCondVal "595900.000000 mho/cm") (thermCondVal "0.012 w/cm-degC")) ("" (layerType "DIELECTRIC") (material "FR-4") (thickness "  9.900000 mil") (dielectricConstant "4.100000") (lossTangent "0.035") (etchFactor "0.000000") (elecCondVal "0 mho/cm") (thermCondVal "0.012 w/cm-degC")) ("L3_SIG1" (layerType "CONDUCTOR") (material "COPPER") (thickness "  1.200000 mil") (width "4.00 MIL") (dielectricConstant "4.500000") (lossTangent "0.035") (etchFactor "90.000000") (elecCondVal "595900.000000 mho/cm") (thermCondVal "0.012 w/cm-degC") (signalDieConstant "4.100000") (signalLossTangent "0.035")) ("" (layerType "DIELECTRIC") (material "FR-4") (thickness "  3.300000 mil") (dielectricConstant "4.500000") (lossTangent "0.035") (etchFactor "0.000000") (elecCondVal "0 mho/cm") (thermCondVal "0 w/cm-degC")) ("L4_GND2" (layerType "PLANE") (material "COPPER") (isShield t) (thickness "  1.200000 mil") (dielectricConstant "4.500000") (lossTangent "0.035") (etchFactor "90.000000") (elecCondVal "595900.000000 mho/cm") (thermCondVal "0 w/cm-degC")) ("" (layerType "DIELECTRIC") (material "FR-4") (thickness "  3.300000 mil") (dielectricConstant "4.000000") (lossTangent "0.035") (etchFactor "0.000000") (elecCondVal "0 mho/cm") (thermCondVal "0.012 w/cm-degC")) ("L5_SIG2" (layerType "CONDUCTOR") (material "COPPER") (thickness "  1.200000 mil") (width "4.00 MIL") (dielectricConstant "4.500000") (lossTangent "0.035") (etchFactor "90.000000") (elecCondVal "595900.000000 mho/cm") (thermCondVal "0.012 w/cm-degC") (signalDieConstant "4.000000") (signalLossTangent "0.035")) ("" (layerType "DIELECTRIC") (material "FR-4") (thickness "  9.900000 mil") (dielectricConstant "4.500000") (lossTangent "0.035") (etchFactor "0.000000") (elecCondVal "0 mho/cm") (thermCondVal "0 w/cm-degC")) ("L6_GND3" (layerType "PLANE") (material "COPPER") (isShield t) (thickness "  1.200000 mil") (dielectricConstant "4.500000") (lossTangent "0.035") (etchFactor "90.000000") (elecCondVal "595900.000000 mho/cm") (thermCondVal "0 w/cm-degC")) ("" (layerType "DIELECTRIC") (material "FR-4") (thickness "  3.300000 mil") (dielectricConstant "4.100000") (lossTangent "0.035") (etchFactor "0.000000") (elecCondVal "0 mho/cm") (thermCondVal "0.012 w/cm-degC")) ("L7_PWR1-SIG" (layerType "PLANE") (material "COPPER") (isShield t) (thickness "  1.200000 mil") (dielectricConstant "4.500000") (lossTangent "0.035") (etchFactor "90.000000") (elecCondVal "595900.000000 mho/cm") (thermCondVal "0.012 w/cm-degC")) ("" (layerType "DIELECTRIC") (material "FR-4") (thickness "  9.900000 mil") (dielectricConstant "4.000000") (lossTangent "0.035") (etchFactor "0.000000") (elecCondVal "0 mho/cm") (thermCondVal "0.012 w/cm-degC")) ("L8_PWR2-SIG" (layerType "PLANE") (material "COPPER") (isShield t) (thickness "  1.200000 mil") (dielectricConstant "4.500000") (lossTangent "0.035") (etchFactor "90.000000") (elecCondVal "595900.000000 mho/cm") (thermCondVal "0.012 w/cm-degC")) ("" (layerType "DIELECTRIC") (material "FR-4") (thickness "  3.300000 mil") (dielectricConstant "4.500000") (lossTangent "0.035") (etchFactor "0.000000") (elecCondVal "0 mho/cm") (thermCondVal "0 w/cm-degC")) ("L9_GND4" (layerType "PLANE") (material "COPPER") (isShield t) (thickness "  1.200000 mil") (dielectricConstant "4.500000") (lossTangent "0.035") (etchFactor "90.000000") (elecCondVal "595900.000000 mho/cm") (thermCondVal "0 w/cm-degC")) ("" (layerType "DIELECTRIC") (material "FR-4") (thickness "  9.900000 mil") (dielectricConstant "4.100000") (lossTangent "0.035") (etchFactor "0.000000") (elecCondVal "0 mho/cm") (thermCondVal "0.012 w/cm-degC")) ("L10_SIG3" (layerType "CONDUCTOR") (material "COPPER") (thickness "  1.200000 mil") (width "4.00 MIL") (dielectricConstant "4.500000") (lossTangent "0.035") (etchFactor "90.000000") (elecCondVal "595900.000000 mho/cm") (thermCondVal "0.012 w/cm-degC") (signalDieConstant "4.100000") (signalLossTangent "0.035")) ("" (layerType "DIELECTRIC") (material "FR-4") (thickness "  3.300000 mil") (dielectricConstant "4.500000") (lossTangent "0.035") (etchFactor "0.000000") (elecCondVal "0 mho/cm") (thermCondVal "0 w/cm-degC")) ("L11_GND5" (layerType "PLANE") (material "COPPER") (isShield t) (thickness "  1.200000 mil") (dielectricConstant "4.500000") (lossTangent "0.035") (etchFactor "90.000000") (elecCondVal "595900.000000 mho/cm") (thermCondVal "0 w/cm-degC")) ("" (layerType "DIELECTRIC") (material "FR-4") (thickness "  9.900000 mil") (dielectricConstant "4.500000") (lossTangent "0.035") (etchFactor "0.000000") (elecCondVal "0 mho/cm") (thermCondVal "0.012 w/cm-degC")) ("L12_SIG4" (layerType "CONDUCTOR") (material "COPPER") (thickness "  1.200000 mil") (width "4.00 MIL") (dielectricConstant "4.500000") (lossTangent "0.035") (etchFactor "90.000000") (elecCondVal "595900.000000 mho/cm") (thermCondVal "0.012 w/cm-degC") (signalDieConstant "4.500000") (signalLossTangent "0.035")) ("" (layerType "DIELECTRIC") (material "FR-4") (thickness "  3.300000 mil") (dielectricConstant "4.500000") (lossTangent "0.035") (etchFactor "0.000000") (elecCondVal "0 mho/cm") (thermCondVal "0 w/cm-degC")) ("L13_GND6" (layerType "PLANE") (material "COPPER") (isShield t) (thickness "  1.200000 mil") (dielectricConstant "4.500000") (lossTangent "0.035") (etchFactor "90.000000") (elecCondVal "595900.000000 mho/cm") (thermCondVal "0.012 w/cm-degC")) ("" (layerType "DIELECTRIC") (material "FR-4") (thickness "  2.700000 mil") (dielectricConstant "4.500000") (lossTangent "0.035") (etchFactor "0.000000") (elecCondVal "0 mho/cm") (thermCondVal "0.012 w/cm-degC")) ("BOTTOM" (layerType "CONDUCTOR") (material "COPPER") (thickness "  1.800000 mil") (width "4.00 MIL") (dielectricConstant "4.500000") (lossTangent "0") (etchFactor "70.000000") (elecCondVal "595900.000000 mho/cm") (thermCondVal "0 w/cm-degC") (signalDieConstant "3.800000") (signalLossTangent "0.035")) ("" (layerType "DIELECTRIC") (material "CONFORMAL_COAT") (thickness "0.5 mil") (dielectricConstant "3.800000") (lossTangent "0.035") (etchFactor "0.000000") (elecCondVal "0 mho/cm") (thermCondVal "0.012 w/cm-degC")) ("" (layerType "SURFACE") (material "AIR") (thickness "0 mil") (dielectricConstant "1.000000") (lossTangent "0") (etchFactor "0.000000") (elecCondVal "0 mho/cm") (thermCondVal "0 w/cm-degC"))))) (Props (DesUnits "mils 2") (LayerStack ("DIELECTRIC" "DIELECTRIC" "BOTTOM" "DIELECTRIC" "L13_GND6" "DIELECTRIC" "L12_SIG4" "DIELECTRIC" "L11_GND5" "DIELECTRIC" "L10_SIG3" "DIELECTRIC" "L9_GND4" "DIELECTRIC" "L8_PWR2-SIG" "DIELECTRIC" "L7_PWR1-SIG" "DIELECTRIC" "L6_GND3" "DIELECTRIC" "L5_SIG2" "DIELECTRIC" "L4_GND2" "DIELECTRIC" "L3_SIG1" "DIELECTRIC" "L2_GND1" "DIELECTRIC" "TOP" "DIELECTRIC" "DIELECTRIC")) (Revision "16.600")) (Params (DualClampTerm ((cutoffVoltageUp "0.7 V") (cutoffVoltageDown "0.7 V") (voltageUp "5 V") (voltageDown "0 V") (maxDelay "0.1 ns"))) (HiClampTerm ((cutoffVoltage "0.7 V") (voltage "5 V") (maxDelay "0.1 ns"))) (IbisInputPkg ((temperature "27") (bufferModel "CDSDefaultInput_2p5v") (cycle "1") (LEFDEFPinName nil) (LEFDEFPinType nil) (mappingTag nil))) (RCTerm ((resistance "50 ohm") (capacitance "20 pF") (voltage "5 V") (maxDelay "0.1 ns"))) (IbisIOMacro ((temperature "27") (bufferModel "CDSDefaultIO_2p5v") (stimuli nil) (offsets nil) (state "tristate") (cycle "1") (termMap nil) (setup "2.0e-09") (hold "1.0e-09") (rise nil) (fall nil) (macroType nil) (voltage nil) (spice nil) (LEFDEFPinName nil) (LEFDEFPinType nil) (mappingTag nil))) (LowClampTerm ((cutoffVoltage "0.7 V") (voltage "0 V") (maxDelay "0.1 ns"))) (CurrentProbe nil) (IbisOutputPkg ((temperature "27") (bufferModel "CDSDefaultOutput_2p5v") (stimuli nil) (offsets nil) (state "tristate") (cycle "1") (termMap nil) (setup "2.0e-09") (hold "1.0e-09") (rise nil) (fall nil) (macroType nil) (voltage nil) (spice nil) (LEFDEFPinName nil) (LEFDEFPinType nil) (mappingTag nil))) (IbisIOPkg ((temperature "27") (bufferModel "CDSDefaultIO_2p5v") (stimuli nil) (offsets nil) (state "tristate") (cycle "1") (termMap nil) (setup "2.0e-09") (hold "1.0e-09") (rise nil) (fall nil) (macroType nil) (voltage nil) (spice nil) (LEFDEFPinName nil) (LEFDEFPinType nil) (mappingTag nil))) (SeriesTerm ((resistance "22 ohm") (maxDelay "0.1 ns"))) (IbisIO_OpenPullDown ((temperature "27") (bufferModel "CDSDefaultIO_2p5v") (stimuli nil) (offsets nil) (state "tristate") (cycle "1") (termMap nil) (setup "2.0e-09") (hold "1.0e-09") (rise nil) (fall nil) (macroType nil) (voltage nil) (spice nil) (LEFDEFPinName nil) (LEFDEFPinType nil) (mappingTag nil))) (clocked ((clockRise "1e-09") (clockFall "1e-09") (clockFreq "100e6") (clockInitState "0") (clockDutyCycle "0.5") (clockJitter "0"))) (CPWSL ((d1Thickness "10 mil") (d1Constant "4.5") (d1LossTangent "0.035") (d2Thickness "0.72 mil") (d2Constant "4.5") (d2LossTangent "0.035") (d3Thickness "10 mil") (d3Constant "4.5") (d3LossTangent "0.035") length("1000 mil") (spacing "5 mil") (spacing2 "5 mil") (spacing3 "5 mil") (spacing4 "5 mil") (spacing5 "5 mil") (traceConductivity "595900 mho/cm") (traceGeometry "cpwms") (traceLayerName "") (traceThickness "0.72 mil") (traceType "single") (traceWidth "5.0 mil") (traceWidth2 "5.0 mil") (traceWidth3 "5.0 mil") (traceWidth4 "5.0 mil") (traceWidth5 "5.0 mil") (traceWidth6 "5.0 mil") (offset "0 mil") (traceCount "1") (impedance nil))) (CPWMS ((d1Thickness "10 mil") (d1Constant "4.5") (d1LossTangent "0.035") (d2Thickness "0.72 mil") (d2Constant "4.5") (d2LossTangent "0.035") (d3Thickness "0.0") (d3Constant "1") (d3LossTangent "0") length("1000 mil") (spacing "5 mil") (spacing2 "5 mil") (spacing3 "5 mil") (spacing4 "5 mil") (spacing5 "5 mil") (traceConductivity "595900 mho/cm") (traceGeometry "cpwms") (traceLayerName "") (traceThickness "0.72 mil") (traceType "single") (traceWidth "5.0 mil") (traceWidth2 "5.0 mil") (traceWidth3 "5.0 mil") (traceWidth4 "5.0 mil") (traceWidth5 "5.0 mil") (traceWidth6 "5.0 mil") (offset "0 mil") (traceCount "1") (impedance nil))) (CPW ((d1Thickness "10 mil") (d1Constant "4.5") (d1LossTangent "0.035") (d2Thickness "0.72 mil") (d2Constant "1") (d2LossTangent "0") (d3Thickness "0.0") (d3Constant "1") (d3LossTangent "0") length("1000 mil") (spacing "5 mil") (spacing2 "5 mil") (spacing3 "5 mil") (spacing4 "5 mil") (spacing5 "5 mil") (traceConductivity "595900 mho/cm") (traceGeometry "cpwms") (traceLayerName "") (traceThickness "0.72 mil") (traceType "single") (traceWidth "5.0 mil") (traceWidth2 "5.0 mil") (traceWidth3 "5.0 mil") (traceWidth4 "5.0 mil") (traceWidth5 "5.0 mil") (traceWidth6 "5.0 mil") (offset "0 mil") (traceCount "1") (impedance nil))) (periodic ((periodicFreq "100e6") (periodicPattern "10") (periodicJitter "0"))) (Diode ((cutoffVoltage "0.7 V"))) (Trace ((d1Thickness "10 mil") (d1Constant "4.5") (d1LossTangent "0.035") (d2Thickness "10 mil") (d2Constant "4.5") (d2LossTangent "0.035") (d3Thickness "0.0") (d3Constant "1.0") (d3LossTangent "0") length("1000 mil") (spacing "5 mil") (spacing2 "5 mil") (spacing3 "5 mil") (spacing4 "5 mil") (spacing5 "5 mil") (traceConductivity "595900 mho/cm") (traceGeometry "microstrip") (traceLayerName "") (traceThickness "0.72 mil") (traceType "single") (traceWidth "5.0 mil") (traceWidth2 "5.0 mil") (traceWidth3 "5.0 mil") (traceWidth4 "5.0 mil") (traceWidth5 "5.0 mil") (traceWidth6 "5.0 mil") (offset "0 mil") (traceCount "1") (impedance nil))) (Cable (length("1 m"))) (Via ((model "Unknown") (viaOutputFormat "Unknown") (viaPadstack nil) (viaTopLayer nil) (viaBottomLayer nil) (viaIsPower nil) (viaIsGround nil))) (async ((asyncTimePoints "") (asyncInitState "1"))) (Resistor ((resistance "50 ohm") (orientation "0"))) (DiffOutputPkg ((temperature "27") (bufferModelNonInverting "CDSDefaultOutput_2p5v") (bufferModelInverting "CDSDefaultOutput_2p5v") (stimuli nil) (offsets nil) (state "tristate") (cycle "1") (termMap nil) (setup "0.9e-09") (hold "0.4e-09") (rise nil) (fall nil) (threshOutputHighMin "2.375  V") (threshOutputHighTyp "2.5  V") (threshOutputHighMax "2.625  V") (threshOutputLowMin "1.275  V") (threshOutputLowTyp "1.7  V") (threshOutputLowMax "1.985  V") (mappingTagNonInverting nil) (mappingTagInverting nil) (spice nil))) (DiffOutput ((temperature "27") (bufferModelNonInverting "CDSDefaultOutput_2p5v") (bufferModelInverting "CDSDefaultOutput_2p5v") (stimuli nil) (offsets nil) (state "tristate") (cycle "1") (termMap nil) (setup "0.9e-09") (hold "0.4e-09") (rise nil) (fall nil) (threshOutputHighMin "2.375  V") (threshOutputHighTyp "2.5  V") (threshOutputHighMax "2.625  V") (threshOutputLowMin "1.275  V") (threshOutputLowTyp "1.7  V") (threshOutputLowMax "1.985  V") (mappingTagNonInverting nil) (mappingTagInverting nil) (spice nil))) (IbisOutput ((temperature "27") (bufferModel "CDSDefaultOutput_2p5v") (stimuli nil) (offsets nil) (state "tristate") (cycle "1") (termMap nil) (setup "2.0e-09") (hold "1.0e-09") (rise nil) (fall nil) (macroType nil) (voltage nil) (spice nil) (LEFDEFPinName nil) (LEFDEFPinType nil) (mappingTag nil))) (Inductor ((inductance "5 nH") (orientation "0"))) (Capacitor ((capacitance "10 pF") (orientation "0"))) (DiffIOPkg ((temperature "27") (bufferModelNonInverting "CDSDefaultIO_2p5v") (bufferModelInverting "CDSDefaultIO_2p5v") (stimuli nil) (offsets nil) (state "tristate") (cycle "1") (termMap nil) (setup "0.9e-09") (hold "0.4e-09") (rise nil) (fall nil) (threshInputHighMin "1.7 V") (threshInputHighTyp "1.7  V") (threshInputHighMax "1.7  V") (threshInputLowMin "0.7  V") (threshInputLowTyp "0.7  V") (threshInputLowMax "0.7 ") (threshOutputHighMin "2.365  V") (threshOutputHighTyp "2.5  V") (threshOutputHighMax "2.625  V") (threshOutputLowMin "1.275  V") (threshOutputLowTyp "1.7  V") (threshOutputLowMax "1.985  V") (mappingTagNonInverting nil) (mappingTagInverting nil) (spice nil))) (IbisIO ((temperature "27") (bufferModel "CDSDefaultIO_2p5v") (stimuli nil) (offsets nil) (state "tristate") (cycle "1") (termMap nil) (setup "2.0e-09") (hold "1.0e-09") (rise nil) (fall nil) (macroType nil) (voltage nil) (spice nil) (LEFDEFPinName nil) (LEFDEFPinType nil) (mappingTag nil))) (Source ((voltage "5 V"))) (DiffIO ((temperature "27") (bufferModelNonInverting "CDSDefaultIO_2p5v") (bufferModelInverting "CDSDefaultIO_2p5v") (stimuli nil) (offsets nil) (state "tristate") (cycle "1") (termMap nil) (setup "0.9e-09") (hold "0.4e-09") (rise nil) (fall nil) (threshInputHighMin "1.7 V") (threshInputHighTyp "1.7  V") (threshInputHighMax "1.7  V") (threshInputLowMin "0.7  V") (threshInputLowTyp "0.7  V") (threshInputLowMax "0.7 ") (threshOutputHighMin "2.365  V") (threshOutputHighTyp "2.5  V") (threshOutputHighMax "2.625  V") (threshOutputLowMin "1.275  V") (threshOutputLowTyp "1.7  V") (threshOutputLowMax "1.985  V") (mappingTagNonInverting nil) (mappingTagInverting nil) (spice nil))) (RLGC (length("1000 mil"))) (IbisInput ((temperature "27") (bufferModel "CDSDefaultInput_2p5v") (cycle "1") (LEFDEFPinName nil) (LEFDEFPinType nil) (mappingTag nil))) (DiffInput ((temperature "27") (bufferModelNonInverting "CDSDefaultInput_2p5v") (bufferModelInverting "CDSDefaultInput_2p5v") (threshInputHighMin "1.7 V") (threshInputHighTyp "1.7  V") (threshInputHighMax "1.7  V") (threshInputLowMin "0.7  V") (threshInputLowTyp "0.7  V") (threshInputLowMax "0.7  V") (mappingTagNonInverting nil) (mappingTagInverting nil) (cycle "1"))) (ESpiceDevice nil) (sync ((syncFreq "100e6") (syncInitState "1") (syncPattern "10") (syncEdgeSwitch "rise"))) (TLine ((diffImpedance "100ohm") (diffVelocity "1.4142e+08M/s") (impedance "60ohm") length("2800 mil") (propDelay "0.5 ns") (velocity "5600 mil/ns") (traceCount "1") (traceGeometry "Microstrip") (impedanceMin nil) (impedanceMax nil) (lengthMin nil) (lengthMax nil) (propDelayMin nil) (propDelayMax nil) (impedanceSweepCount nil) (propDelaySweepCount nil) (velocitySweepCount nil) (lengthSweepCount nil) (matchSetName nil))) (Connector nil) (ShuntTerm ((resistance "50 ohm") (voltage "5 V") (maxDelay "0.1 ns"))) (TheveninTerm ((resistanceUp "180 ohm") (resistanceDown "270 ohm") (voltageUp "5 V") (voltageDown "0 V") (maxDelay "0.1 ns"))) (IbisIO_OpenPullUp ((temperature "27") (bufferModel "CDSDefaultIO_2p5v") (stimuli nil) (offsets nil) (state "tristate") (cycle "1") (termMap nil) (setup "2.0e-09") (hold "1.0e-09") (rise nil) (fall nil) (macroType nil) (voltage nil) (spice nil) (LEFDEFPinName nil) (LEFDEFPinType nil) (mappingTag nil))) (DiffInputPkg ((temperature "27") (bufferModelNonInverting "CDSDefaultInput_2p5v") (bufferModelInverting "CDSDefaultInput_2p5v") (threshInputHighMin "1.7 V") (threshInputHighTyp "1.7  V") (threshInputHighMax "1.7  V") (threshInputLowMin "0.7  V") (threshInputLowTyp "0.7  V") (threshInputLowMax "0.7  V") (mappingTagNonInverting nil) (mappingTagInverting nil) (cycle "1"))) (IbisOutput_OpenPullUp ((temperature "27") (bufferModel "CDSDefaultOutput_2p5v") (stimuli nil) (offsets nil) (state "tristate") (cycle "1") (termMap nil) (setup "2.0e-09") (hold "1.0e-09") (rise nil) (fall nil) (macroType nil) (voltage nil) (spice nil) (LEFDEFPinName nil) (LEFDEFPinType nil) (mappingTag nil))) (idlCircuit ((allDrivers "active") (ftsMode '("Typ")) (rcvrSelect "all") (simMode "Reflection") (tlineDelayMode "time") (userRevision "1.0") (autoSolve "On")))))
				)
				( objectStatus "DDR_M_CMD_DLL1-13" )
			)
			( electricalCSet "@crescent_city_bb_fab1_lib.crescent_city_bb_fab1(sch_1):\NIC_MDI_MNG\"
				( attribute "DIFFP_GATHER_CONTROL" "IGNORE"
					( Origin gBackEnd )
				)
				( attribute "DIFFP_UNCOUPLED_LENGTH" "25.00"
					( Origin gBackEnd )
				)
				( attribute "DIFFP_COUPLED_PLUS" "10.00"
					( Origin gBackEnd )
				)
				( attribute "DIFFP_COUPLED_MINUS" "0.10"
					( Origin gBackEnd )
				)
				( attribute "DIFFP_PHASE_TOL" "30 mil"
					( Units "uPhaseTol" "ns" 1.000000)
					( Origin gBackEnd )
				)
				( attribute "DIFFP_PHASE_MAX_LENGTH" "600.00"
					( Origin gBackEnd )
				)
				( attribute "DIFFP_PHASE_TOL_DYNAMIC" "45 mil"
					( Units "uPhaseTol" "mil" 1.000000)
					( Origin gBackEnd )
				)
				( attribute "TOPOLOGY_TEMPLATE_REVISION" "1.0"
					( Origin gBackEnd )
				)
				( topologyData 21599
(SKIDL (Circuits ("MAIN" (Parts ("CRESCENT_CITY_181_20150105_A.@@J44.E5" IbisIOPkg (xy (5502 4240)) (refDes "J1F1") (model "Unknown") (Props (_SXDesignName "CRESCENT_CITY_181_20150105_A") (brdx "66.93 MIL") (brdy "1248.43 MIL") (bufferModel "CDSDefaultIO_2p5v") (cycle "1") (hold "1.0e-09") (mappingTag "") (offsets ("4" "0") ("5" "0")) (setup "2.0e-09") (state "tristate") (stimuli ("4" "local36") ("5" "local37")) (temperature "27") (termMap ("4" "Data") ("5" "Enable"))) (Terms ("CRESCENT_CITY_181_20150105_A.X6693Y124843L2LRATS" "E5"))) ("CRESCENT_CITY_181_20150105_A.T@@RATS@@C9.2@@J44.E5" TLine (xy (5497 4229)) (refDes "TL5") (Props (_SXDesignName "CRESCENT_CITY_181_20150105_A") (impedance "49.675 ohm") length("19666.50 MIL") (propDelay "3.53224 ns") (traceCount "1") (traceGeometry "Microstrip") (velocity "5567.72 mil/ns")) (Terms ("CRESCENT_CITY_181_20150105_A.X1879500Y31000L2LRATS" "1") ("CRESCENT_CITY_181_20150105_A.X6693Y124843L2LRATS" "2"))) ("CRESCENT_CITY_181_20150105_A.@@C9.2.1" Resistor (xy (5488 4229)) (mirror x) (refDes "C9G12") (value "4700 Ohm") (Props (_SXDesignName "CRESCENT_CITY_181_20150105_A")) (Terms ("CRESCENT_CITY_181_20150105_A.X1879500Y31000L2LRATS" "2") ("0" "1")))) (Nodes ("CRESCENT_CITY_181_20150105_A.X1879500Y31000L2LRATS" (terms "CRESCENT_CITY_181_20150105_A.@@C9.2.1.1" "CRESCENT_CITY_181_20150105_A.T@@RATS@@C9.2@@J44.E5.1")) ("CRESCENT_CITY_181_20150105_A.X6693Y124843L2LRATS" (terms "CRESCENT_CITY_181_20150105_A.T@@RATS@@C9.2@@J44.E5.2" "CRESCENT_CITY_181_20150105_A.@@J44.E5.1"))) (Ports) (Stimuli ("local36" (scope local) (stimType periodic) (Props (periodicFreq "5e+007") (periodicJitter "0") (periodicPattern "1"))) ("local37" (scope local) (stimType periodic) (Props (periodicFreq "5e+007") (periodicJitter "0") (periodicPattern "1")))) (Notes) (Constraints ("DP_GATHER_CONTROL" "IGNORE") ("DP_MAX_UNCOUPLED_LENGTH" "0.000254") ("DP_PHASE_MAX_LENGTH" "0.01524") ("DP_PHASE_TOLERANCE" ("LENGTH" "0.000762")) ("DP_PHASE_TOLERANCE_DYNAMIC" ("LENGTH" "0.000762"))) (MeasurementSets ("EMI" ("EMIStatus" status("on")) ("PeakEmission" status("on")) ("PeakFrequency" status("on")) ("PulseFreq" status("on")) ("RiseTime" status("on")) ("VoltageSwing" status("on"))) ("Reflection" ("BufferDelayFall" status("off")) ("BufferDelayRise" status("off")) ("EyeHeight" status("off")) ("EyeJitter" status("off")) ("EyeWidth" status("off")) ("FirstIncidentFall" status("off")) ("FirstIncidentRise" status("off")) ("Glitch" status("on")) ("GlitchFall" status("off")) ("GlitchRise" status("off")) ("Monotonic" status("on")) ("MonotonicFall" status("off")) ("MonotonicRise" status("off")) ("NoiseMargin" status("on")) ("NoiseMarginHigh" status("off")) ("NoiseMarginLow" status("off")) ("OvershootHigh" status("on")) ("OvershootLow" status("on")) ("PropDelay" status("on")) ("SettleDelay" status("on")) ("SettleDelayFall" status("off")) ("SettleDelayRise" status("off")) ("SwitchDelay" status("on")) ("SwitchDelayFall" status("off")) ("SwitchDelayRise" status("off"))) ("Crosstalk" ("Crosstalk" status("on"))) ("Custom")) (VectorSets) (Props (XnetName "NIC_MDI_MNG_RX_DN") (allDrivers "active") (customSimType "Reflection") (ftsMode ("Typ")) (rcvrSelect "all") (tlineDelayMode "time") (userRevision "1.0")))) (Subckts) (CrossSections ("CRESCENT_CITY_181_20150105_A" (Props (SXDesignName "CRESCENT_CITY_181_20150105_A")) (Layers ("" (layerType "SURFACE") (material "AIR") (thickness "0 mil") (dielectricConstant "1.000000") (lossTangent "0") (etchFactor "0.000000") (elecCondVal "0 mho/cm") (thermCondVal "0 w/cm-degC")) ("" (layerType "DIELECTRIC") (material "CONFORMAL_COAT") (thickness "0.5 mil") (dielectricConstant "3.800000") (lossTangent "0.035") (etchFactor "0.000000") (elecCondVal "0 mho/cm") (thermCondVal "0.012 w/cm-degC")) ("TOP" (layerType "CONDUCTOR") (material "COPPER") (thickness "  2.100000 mil") (width "4.00 MIL") (dielectricConstant "4.500000") (lossTangent "0") (etchFactor "70.000000") (elecCondVal "595900.000000 mho/cm") (thermCondVal "0 w/cm-degC") (signalDieConstant "3.800000") (signalLossTangent "0.035")) ("" (layerType "DIELECTRIC") (material "FR-4") (thickness "  2.670000 mil") (dielectricConstant "4.000000") (lossTangent "0.035") (etchFactor "0.000000") (elecCondVal "0 mho/cm") (thermCondVal "0.012 w/cm-degC")) ("L2_GND1" (layerType "PLANE") (material "COPPER") (isShield t) (thickness "  1.250000 mil") (dielectricConstant "4.500000") (lossTangent "0.035") (etchFactor "90.000000") (elecCondVal "595900.000000 mho/cm") (thermCondVal "0.012 w/cm-degC")) ("" (layerType "DIELECTRIC") (material "FR-4") (thickness "  9.000000 mil") (dielectricConstant "4.100000") (lossTangent "0.035") (etchFactor "0.000000") (elecCondVal "0 mho/cm") (thermCondVal "0.012 w/cm-degC")) ("L3_SIG1" (layerType "CONDUCTOR") (material "COPPER") (thickness "  1.250000 mil") (width "4.00 MIL") (dielectricConstant "4.500000") (lossTangent "0.035") (etchFactor "90.000000") (elecCondVal "595900.000000 mho/cm") (thermCondVal "0.012 w/cm-degC") (signalDieConstant "4.100000") (signalLossTangent "0.035")) ("" (layerType "DIELECTRIC") (material "FR-4") (thickness "  3.000000 mil") (dielectricConstant "4.500000") (lossTangent "0.035") (etchFactor "0.000000") (elecCondVal "0 mho/cm") (thermCondVal "0 w/cm-degC")) ("L4_GND2" (layerType "PLANE") (material "COPPER") (isShield t) (thickness "  1.250000 mil") (dielectricConstant "4.500000") (lossTangent "0.035") (etchFactor "90.000000") (elecCondVal "595900.000000 mho/cm") (thermCondVal "0 w/cm-degC")) ("" (layerType "DIELECTRIC") (material "FR-4") (thickness "  9.000000 mil") (dielectricConstant "4.000000") (lossTangent "0.035") (etchFactor "0.000000") (elecCondVal "0 mho/cm") (thermCondVal "0.012 w/cm-degC")) ("L5_SIG2" (layerType "CONDUCTOR") (material "COPPER") (thickness "  1.250000 mil") (width "4.00 MIL") (dielectricConstant "4.500000") (lossTangent "0.035") (etchFactor "90.000000") (elecCondVal "595900.000000 mho/cm") (thermCondVal "0.012 w/cm-degC") (signalDieConstant "4.000000") (signalLossTangent "0.035")) ("" (layerType "DIELECTRIC") (material "FR-4") (thickness "  3.000000 mil") (dielectricConstant "4.500000") (lossTangent "0.035") (etchFactor "0.000000") (elecCondVal "0 mho/cm") (thermCondVal "0 w/cm-degC")) ("L6_GND3" (layerType "PLANE") (material "COPPER") (isShield t) (thickness "  1.250000 mil") (dielectricConstant "4.500000") (lossTangent "0.035") (etchFactor "90.000000") (elecCondVal "595900.000000 mho/cm") (thermCondVal "0 w/cm-degC")) ("" (layerType "DIELECTRIC") (material "FR-4") (thickness "  4.500000 mil") (dielectricConstant "4.100000") (lossTangent "0.035") (etchFactor "0.000000") (elecCondVal "0 mho/cm") (thermCondVal "0.012 w/cm-degC")) ("L7_PWR1-SIG" (layerType "PLANE") (material "COPPER") (isShield t) (thickness "  2.400000 mil") (dielectricConstant "4.500000") (lossTangent "0.035") (etchFactor "90.000000") (elecCondVal "595900.000000 mho/cm") (thermCondVal "0.012 w/cm-degC")) ("" (layerType "DIELECTRIC") (material "FR-4") (thickness "  4.600000 mil") (dielectricConstant "4.000000") (lossTangent "0.035") (etchFactor "0.000000") (elecCondVal "0 mho/cm") (thermCondVal "0.012 w/cm-degC")) ("L8_PWR2-SIG" (layerType "PLANE") (material "COPPER") (isShield t) (thickness "  2.400000 mil") (dielectricConstant "4.500000") (lossTangent "0.035") (etchFactor "90.000000") (elecCondVal "595900.000000 mho/cm") (thermCondVal "0.012 w/cm-degC")) ("" (layerType "DIELECTRIC") (material "FR-4") (thickness "  4.500000 mil") (dielectricConstant "4.500000") (lossTangent "0.035") (etchFactor "0.000000") (elecCondVal "0 mho/cm") (thermCondVal "0 w/cm-degC")) ("L9_GND4" (layerType "PLANE") (material "COPPER") (isShield t) (thickness "  1.250000 mil") (dielectricConstant "4.500000") (lossTangent "0.035") (etchFactor "90.000000") (elecCondVal "595900.000000 mho/cm") (thermCondVal "0 w/cm-degC")) ("" (layerType "DIELECTRIC") (material "FR-4") (thickness "  3.000000 mil") (dielectricConstant "4.100000") (lossTangent "0.035") (etchFactor "0.000000") (elecCondVal "0 mho/cm") (thermCondVal "0.012 w/cm-degC")) ("L10_SIG3" (layerType "CONDUCTOR") (material "COPPER") (thickness "  1.250000 mil") (width "4.00 MIL") (dielectricConstant "4.500000") (lossTangent "0.035") (etchFactor "90.000000") (elecCondVal "595900.000000 mho/cm") (thermCondVal "0.012 w/cm-degC") (signalDieConstant "4.100000") (signalLossTangent "0.035")) ("" (layerType "DIELECTRIC") (material "FR-4") (thickness "  9.000000 mil") (dielectricConstant "4.500000") (lossTangent "0.035") (etchFactor "0.000000") (elecCondVal "0 mho/cm") (thermCondVal "0 w/cm-degC")) ("L11_GND5" (layerType "PLANE") (material "COPPER") (isShield t) (thickness "  1.250000 mil") (dielectricConstant "4.500000") (lossTangent "0.035") (etchFactor "90.000000") (elecCondVal "595900.000000 mho/cm") (thermCondVal "0 w/cm-degC")) ("" (layerType "DIELECTRIC") (material "FR-4") (thickness "  3.000000 mil") (dielectricConstant "4.500000") (lossTangent "0.035") (etchFactor "0.000000") (elecCondVal "0 mho/cm") (thermCondVal "0.012 w/cm-degC")) ("L12_SIG4" (layerType "CONDUCTOR") (material "COPPER") (thickness "  1.250000 mil") (width "4.00 MIL") (dielectricConstant "4.500000") (lossTangent "0.035") (etchFactor "90.000000") (elecCondVal "595900.000000 mho/cm") (thermCondVal "0.012 w/cm-degC") (signalDieConstant "4.500000") (signalLossTangent "0.035")) ("" (layerType "DIELECTRIC") (material "FR-4") (thickness "  9.000000 mil") (dielectricConstant "4.500000") (lossTangent "0.035") (etchFactor "0.000000") (elecCondVal "0 mho/cm") (thermCondVal "0 w/cm-degC")) ("L13_GND6" (layerType "PLANE") (material "COPPER") (isShield t) (thickness "  1.250000 mil") (dielectricConstant "4.500000") (lossTangent "0.035") (etchFactor "90.000000") (elecCondVal "595900.000000 mho/cm") (thermCondVal "0.012 w/cm-degC")) ("" (layerType "DIELECTRIC") (material "FR-4") (thickness "  2.670000 mil") (dielectricConstant "4.500000") (lossTangent "0.035") (etchFactor "0.000000") (elecCondVal "0 mho/cm") (thermCondVal "0.012 w/cm-degC")) ("BOTTOM" (layerType "CONDUCTOR") (material "COPPER") (thickness "  2.100000 mil") (width "4.00 MIL") (dielectricConstant "4.500000") (lossTangent "0") (etchFactor "70.000000") (elecCondVal "595900.000000 mho/cm") (thermCondVal "0 w/cm-degC") (signalDieConstant "3.800000") (signalLossTangent "0.035")) ("" (layerType "DIELECTRIC") (material "CONFORMAL_COAT") (thickness "0.5 mil") (dielectricConstant "3.800000") (lossTangent "0.035") (etchFactor "0.000000") (elecCondVal "0 mho/cm") (thermCondVal "0.012 w/cm-degC")) ("" (layerType "SURFACE") (material "AIR") (thickness "0 mil") (dielectricConstant "1.000000") (lossTangent "0") (etchFactor "0.000000") (elecCondVal "0 mho/cm") (thermCondVal "0 w/cm-degC"))))) (Props (DesUnits "mils 2") (LayerStack ("DIELECTRIC" "DIELECTRIC" "BOTTOM" "DIELECTRIC" "L13_GND6" "DIELECTRIC" "L12_SIG4" "DIELECTRIC" "L11_GND5" "DIELECTRIC" "L10_SIG3" "DIELECTRIC" "L9_GND4" "DIELECTRIC" "L8_PWR2-SIG" "DIELECTRIC" "L7_PWR1-SIG" "DIELECTRIC" "L6_GND3" "DIELECTRIC" "L5_SIG2" "DIELECTRIC" "L4_GND2" "DIELECTRIC" "L3_SIG1" "DIELECTRIC" "L2_GND1" "DIELECTRIC" "TOP" "DIELECTRIC" "DIELECTRIC")) (Revision "16.600")) (Params (LowClampTerm ((cutoffVoltage "0.7 V") (voltage "0 V") (maxDelay "0.1 ns"))) (IbisInputPkg ((temperature "27") (bufferModel "CDSDefaultInput_2p5v") (cycle "1") (LEFDEFPinName nil) (LEFDEFPinType nil) (mappingTag nil))) (SeriesTerm ((resistance "22 ohm") (maxDelay "0.1 ns"))) (RCTerm ((resistance "50 ohm") (capacitance "20 pF") (voltage "5 V") (maxDelay "0.1 ns"))) (TheveninTerm ((resistanceUp "180 ohm") (resistanceDown "270 ohm") (voltageUp "5 V") (voltageDown "0 V") (maxDelay "0.1 ns"))) (CurrentProbe nil) (IbisIOPkg ((temperature "27") (bufferModel "CDSDefaultIO_2p5v") (stimuli nil) (offsets nil) (state "tristate") (cycle "1") (termMap nil) (setup "2.0e-09") (hold "1.0e-09") (rise nil) (fall nil) (macroType nil) (voltage nil) (spice nil) (LEFDEFPinName nil) (LEFDEFPinType nil) (mappingTag nil))) (ShuntTerm ((resistance "50 ohm") (voltage "5 V") (maxDelay "0.1 ns"))) (IbisOutputPkg ((temperature "27") (bufferModel "CDSDefaultOutput_2p5v") (stimuli nil) (offsets nil) (state "tristate") (cycle "1") (termMap nil) (setup "2.0e-09") (hold "1.0e-09") (rise nil) (fall nil) (macroType nil) (voltage nil) (spice nil) (LEFDEFPinName nil) (LEFDEFPinType nil) (mappingTag nil))) (clocked ((clockRise "1e-09") (clockFall "1e-09") (clockFreq "100e6") (clockInitState "0") (clockDutyCycle "0.5") (clockJitter "0"))) (Diode ((cutoffVoltage "0.7 V"))) (IbisOutput_OpenPullUp ((temperature "27") (bufferModel "CDSDefaultOutput_2p5v") (stimuli nil) (offsets nil) (state "tristate") (cycle "1") (termMap nil) (setup "2.0e-09") (hold "1.0e-09") (rise nil) (fall nil) (macroType nil) (voltage nil) (spice nil) (LEFDEFPinName nil) (LEFDEFPinType nil) (mappingTag nil))) (Trace ((d1Thickness "10 mil") (d1Constant "4.5") (d1LossTangent "0.035") (d2Thickness "10 mil") (d2Constant "4.5") (d2LossTangent "0.035") (d3Thickness "0.0") (d3Constant "1.0") (d3LossTangent "0") length("1000 mil") (spacing "5 mil") (spacing2 "5 mil") (spacing3 "5 mil") (spacing4 "5 mil") (spacing5 "5 mil") (traceConductivity "595900 mho/cm") (traceGeometry "microstrip") (traceLayerName "") (traceThickness "0.72 mil") (traceType "single") (traceWidth "5.0 mil") (traceWidth2 "5.0 mil") (traceWidth3 "5.0 mil") (traceWidth4 "5.0 mil") (traceWidth5 "5.0 mil") (traceWidth6 "5.0 mil") (offset "0 mil") (traceCount "1") (impedance nil))) (DualClampTerm ((cutoffVoltageUp "0.7 V") (cutoffVoltageDown "0.7 V") (voltageUp "5 V") (voltageDown "0 V") (maxDelay "0.1 ns"))) (Via ((model "Unknown") (viaOutputFormat "Unknown") (viaPadstack nil) (viaTopLayer nil) (viaBottomLayer nil) (viaIsPower nil) (viaIsGround nil))) (periodic ((periodicFreq "100e6") (periodicPattern "10") (periodicJitter "0"))) (IbisIO_OpenPullDown ((temperature "27") (bufferModel "CDSDefaultIO_2p5v") (stimuli nil) (offsets nil) (state "tristate") (cycle "1") (termMap nil) (setup "2.0e-09") (hold "1.0e-09") (rise nil) (fall nil) (macroType nil) (voltage nil) (spice nil) (LEFDEFPinName nil) (LEFDEFPinType nil) (mappingTag nil))) (IbisIO_OpenPullUp ((temperature "27") (bufferModel "CDSDefaultIO_2p5v") (stimuli nil) (offsets nil) (state "tristate") (cycle "1") (termMap nil) (setup "2.0e-09") (hold "1.0e-09") (rise nil) (fall nil) (macroType nil) (voltage nil) (spice nil) (LEFDEFPinName nil) (LEFDEFPinType nil) (mappingTag nil))) (HiClampTerm ((cutoffVoltage "0.7 V") (voltage "5 V") (maxDelay "0.1 ns"))) (CPWMS ((d1Thickness "10 mil") (d1Constant "4.5") (d1LossTangent "0.035") (d2Thickness "0.72 mil") (d2Constant "4.5") (d2LossTangent "0.035") (d3Thickness "0.0") (d3Constant "1") (d3LossTangent "0") length("1000 mil") (spacing "5 mil") (spacing2 "5 mil") (spacing3 "5 mil") (spacing4 "5 mil") (spacing5 "5 mil") (traceConductivity "595900 mho/cm") (traceGeometry "cpwms") (traceLayerName "") (traceThickness "0.72 mil") (traceType "single") (traceWidth "5.0 mil") (traceWidth2 "5.0 mil") (traceWidth3 "5.0 mil") (traceWidth4 "5.0 mil") (traceWidth5 "5.0 mil") (traceWidth6 "5.0 mil") (offset "0 mil") (traceCount "1") (impedance nil))) (Cable (length("1 m"))) (ESpiceDevice nil) (CPW ((d1Thickness "10 mil") (d1Constant "4.5") (d1LossTangent "0.035") (d2Thickness "0.72 mil") (d2Constant "1") (d2LossTangent "0") (d3Thickness "0.0") (d3Constant "1") (d3LossTangent "0") length("1000 mil") (spacing "5 mil") (spacing2 "5 mil") (spacing3 "5 mil") (spacing4 "5 mil") (spacing5 "5 mil") (traceConductivity "595900 mho/cm") (traceGeometry "cpwms") (traceLayerName "") (traceThickness "0.72 mil") (traceType "single") (traceWidth "5.0 mil") (traceWidth2 "5.0 mil") (traceWidth3 "5.0 mil") (traceWidth4 "5.0 mil") (traceWidth5 "5.0 mil") (traceWidth6 "5.0 mil") (offset "0 mil") (traceCount "1") (impedance nil))) (IbisInput ((temperature "27") (bufferModel "CDSDefaultInput_2p5v") (cycle "1") (LEFDEFPinName nil) (LEFDEFPinType nil) (mappingTag nil))) (Inductor ((inductance "5 nH") (orientation "0"))) (DiffOutput ((temperature "27") (bufferModelNonInverting "CDSDefaultOutput_2p5v") (bufferModelInverting "CDSDefaultOutput_2p5v") (stimuli nil) (offsets nil) (state "tristate") (cycle "1") (termMap nil) (setup "0.9e-09") (hold "0.4e-09") (rise nil) (fall nil) (threshOutputHighMin "2.375  V") (threshOutputHighTyp "2.5  V") (threshOutputHighMax "2.625  V") (threshOutputLowMin "1.275  V") (threshOutputLowTyp "1.7  V") (threshOutputLowMax "1.985  V") (mappingTagNonInverting nil) (mappingTagInverting nil) (spice nil))) (Capacitor ((capacitance "10 pF") (orientation "0"))) (DiffOutputPkg ((temperature "27") (bufferModelNonInverting "CDSDefaultOutput_2p5v") (bufferModelInverting "CDSDefaultOutput_2p5v") (stimuli nil) (offsets nil) (state "tristate") (cycle "1") (termMap nil) (setup "0.9e-09") (hold "0.4e-09") (rise nil) (fall nil) (threshOutputHighMin "2.375  V") (threshOutputHighTyp "2.5  V") (threshOutputHighMax "2.625  V") (threshOutputLowMin "1.275  V") (threshOutputLowTyp "1.7  V") (threshOutputLowMax "1.985  V") (mappingTagNonInverting nil) (mappingTagInverting nil) (spice nil))) (RLGC (length("1000 mil"))) (DiffIO ((temperature "27") (bufferModelNonInverting "CDSDefaultIO_2p5v") (bufferModelInverting "CDSDefaultIO_2p5v") (stimuli nil) (offsets nil) (state "tristate") (cycle "1") (termMap nil) (setup "0.9e-09") (hold "0.4e-09") (rise nil) (fall nil) (threshInputHighMin "1.7 V") (threshInputHighTyp "1.7  V") (threshInputHighMax "1.7  V") (threshInputLowMin "0.7  V") (threshInputLowTyp "0.7  V") (threshInputLowMax "0.7 ") (threshOutputHighMin "2.365  V") (threshOutputHighTyp "2.5  V") (threshOutputHighMax "2.625  V") (threshOutputLowMin "1.275  V") (threshOutputLowTyp "1.7  V") (threshOutputLowMax "1.985  V") (mappingTagNonInverting nil) (mappingTagInverting nil) (spice nil))) (IbisOutput ((temperature "27") (bufferModel "CDSDefaultOutput_2p5v") (stimuli nil) (offsets nil) (state "tristate") (cycle "1") (termMap nil) (setup "2.0e-09") (hold "1.0e-09") (rise nil) (fall nil) (macroType nil) (voltage nil) (spice nil) (LEFDEFPinName nil) (LEFDEFPinType nil) (mappingTag nil))) (IbisIO ((temperature "27") (bufferModel "CDSDefaultIO_2p5v") (stimuli nil) (offsets nil) (state "tristate") (cycle "1") (termMap nil) (setup "2.0e-09") (hold "1.0e-09") (rise nil) (fall nil) (macroType nil) (voltage nil) (spice nil) (LEFDEFPinName nil) (LEFDEFPinType nil) (mappingTag nil))) (Source ((voltage "5 V"))) (DiffIOPkg ((temperature "27") (bufferModelNonInverting "CDSDefaultIO_2p5v") (bufferModelInverting "CDSDefaultIO_2p5v") (stimuli nil) (offsets nil) (state "tristate") (cycle "1") (termMap nil) (setup "0.9e-09") (hold "0.4e-09") (rise nil) (fall nil) (threshInputHighMin "1.7 V") (threshInputHighTyp "1.7  V") (threshInputHighMax "1.7  V") (threshInputLowMin "0.7  V") (threshInputLowTyp "0.7  V") (threshInputLowMax "0.7 ") (threshOutputHighMin "2.365  V") (threshOutputHighTyp "2.5  V") (threshOutputHighMax "2.625  V") (threshOutputLowMin "1.275  V") (threshOutputLowTyp "1.7  V") (threshOutputLowMax "1.985  V") (mappingTagNonInverting nil) (mappingTagInverting nil) (spice nil))) (Connector nil) (Resistor ((resistance "50 ohm") (orientation "0"))) (DiffInput ((temperature "27") (bufferModelNonInverting "CDSDefaultInput_2p5v") (bufferModelInverting "CDSDefaultInput_2p5v") (threshInputHighMin "1.7 V") (threshInputHighTyp "1.7  V") (threshInputHighMax "1.7  V") (threshInputLowMin "0.7  V") (threshInputLowTyp "0.7  V") (threshInputLowMax "0.7  V") (mappingTagNonInverting nil) (mappingTagInverting nil) (cycle "1"))) (CPWSL ((d1Thickness "10 mil") (d1Constant "4.5") (d1LossTangent "0.035") (d2Thickness "0.72 mil") (d2Constant "4.5") (d2LossTangent "0.035") (d3Thickness "10 mil") (d3Constant "4.5") (d3LossTangent "0.035") length("1000 mil") (spacing "5 mil") (spacing2 "5 mil") (spacing3 "5 mil") (spacing4 "5 mil") (spacing5 "5 mil") (traceConductivity "595900 mho/cm") (traceGeometry "cpwms") (traceLayerName "") (traceThickness "0.72 mil") (traceType "single") (traceWidth "5.0 mil") (traceWidth2 "5.0 mil") (traceWidth3 "5.0 mil") (traceWidth4 "5.0 mil") (traceWidth5 "5.0 mil") (traceWidth6 "5.0 mil") (offset "0 mil") (traceCount "1") (impedance nil))) (TLine ((diffImpedance "100ohm") (diffVelocity "1.4142e+08M/s") (impedance "60ohm") length("2800 mil") (propDelay "0.5 ns") (velocity "5600 mil/ns") (traceCount "1") (traceGeometry "Microstrip") (impedanceMin nil) (impedanceMax nil) (lengthMin nil) (lengthMax nil) (propDelayMin nil) (propDelayMax nil) (impedanceSweepCount nil) (propDelaySweepCount nil) (velocitySweepCount nil) (lengthSweepCount nil) (matchSetName nil))) (DiffInputPkg ((temperature "27") (bufferModelNonInverting "CDSDefaultInput_2p5v") (bufferModelInverting "CDSDefaultInput_2p5v") (threshInputHighMin "1.7 V") (threshInputHighTyp "1.7  V") (threshInputHighMax "1.7  V") (threshInputLowMin "0.7  V") (threshInputLowTyp "0.7  V") (threshInputLowMax "0.7  V") (mappingTagNonInverting nil) (mappingTagInverting nil) (cycle "1"))) (IbisIOMacro ((temperature "27") (bufferModel "CDSDefaultIO_2p5v") (stimuli nil) (offsets nil) (state "tristate") (cycle "1") (termMap nil) (setup "2.0e-09") (hold "1.0e-09") (rise nil) (fall nil) (macroType nil) (voltage nil) (spice nil) (LEFDEFPinName nil) (LEFDEFPinType nil) (mappingTag nil))) (async ((asyncTimePoints "") (asyncInitState "1"))) (sync ((syncFreq "100e6") (syncInitState "1") (syncPattern "10") (syncEdgeSwitch "rise"))) (idlCircuit ((allDrivers "active") (ftsMode '("Typ")) (rcvrSelect "all") (simMode "Reflection") (tlineDelayMode "time") (userRevision "1.0") (autoSolve "On")))))
				)
				( objectStatus "NIC_MDI_MNG" )
			)
			( electricalCSet "@crescent_city_bb_fab1_lib.crescent_city_bb_fab1(sch_1):\TDT_85_OHMS_L1_DN\"
				( attribute "MAX_VIA_COUNT" "2"
					( Origin gBackEnd )
				)
				( attribute "PROPAGATION_DELAY_PATH_TYPE" "AD:AR"
					( Origin gBackEnd )
				)
				( attribute "PROPAGATION_DELAY_MIN" "8000.00 MIL"
					( Units "uMaxMinProp" "ns" 1.000000)
					( Origin gBackEnd )
				)
				( attribute "DIFFP_GATHER_CONTROL" "IGNORE"
					( Origin gBackEnd )
				)
				( attribute "DIFFP_UNCOUPLED_LENGTH" "50.00"
					( Origin gBackEnd )
				)
				( attribute "DIFFP_COUPLED_PLUS" "0.10"
					( Origin gBackEnd )
				)
				( attribute "DIFFP_COUPLED_MINUS" "0.10"
					( Origin gBackEnd )
				)
				( attribute "DIFFP_PHASE_TOL" "10 mil"
					( Units "uPhaseTol" "ns" 1.000000)
					( Origin gBackEnd )
				)
				( attribute "TOPOLOGY_TEMPLATE_REVISION" "1.0"
					( Origin gBackEnd )
				)
				( topologyData 24259
(SKIDL (Circuits ("MAIN" (Parts ("CRESCENT_CITY_634_20150410_E.@@DB1.2" IbisIOPkg (xy (5522 4240)) (refDes "DB1") (model "Unknown") (Props (_SXDesignName "CRESCENT_CITY_634_20150410_E") (brdx "30600 MIL") (brdy "10539.37 MIL") (bufferModel "CDSDefaultIO_2p5v") (cycle "1") (hold "1.0e-09") (mappingTag "") (offsets ("4" "0") ("5" "0")) (setup "2.0e-09") (state "tristate") (stimuli ("4" "local19") ("5" "local20")) (temperature "27") (termMap ("4" "Data") ("5" "Enable"))) (Terms ("CRESCENT_CITY_634_20150410_E.X3060000Y1053937L2LRATS" "2"))) ("CRESCENT_CITY_634_20150410_E.@@DB11.2" IbisIOPkg (xy (5502 4240)) (refDes "DB11") (model "Unknown") (Props (_SXDesignName "CRESCENT_CITY_634_20150410_E") (brdx "22500 MIL") (brdy "10539.37 MIL") (bufferModel "CDSDefaultIO_2p5v") (cycle "1") (hold "1.0e-09") (mappingTag "") (offsets ("4" "0") ("5" "0")) (setup "2.0e-09") (state "tristate") (stimuli ("4" "local21") ("5" "local22")) (temperature "27") (termMap ("4" "Data") ("5" "Enable"))) (Terms ("CRESCENT_CITY_634_20150410_E.X2250000Y1053937L2LRATS" "2"))) ("CRESCENT_CITY_634_20150410_E.T@@RATS@@DB11.2@@DB1.2" TLine (xy (5513 4235)) (refDes "TL1") (Props (_SXDesignName "CRESCENT_CITY_634_20150410_E") (impedance "47.169 ohm") length("8100.00 MIL") (propDelay "1.45482 ns") (traceCount "1") (traceGeometry "Microstrip") (velocity "5567.72 mil/ns")) (Terms ("CRESCENT_CITY_634_20150410_E.X2250000Y1053937L2LRATS" "1") ("CRESCENT_CITY_634_20150410_E.X3060000Y1053937L2LRATS" "2")))) (Nodes ("CRESCENT_CITY_634_20150410_E.X3060000Y1053937L2LRATS" (terms "CRESCENT_CITY_634_20150410_E.T@@RATS@@DB11.2@@DB1.2.2" "CRESCENT_CITY_634_20150410_E.@@DB1.2.1")) ("CRESCENT_CITY_634_20150410_E.X2250000Y1053937L2LRATS" (terms "CRESCENT_CITY_634_20150410_E.T@@RATS@@DB11.2@@DB1.2.1" "CRESCENT_CITY_634_20150410_E.@@DB11.2.1"))) (Ports) (Stimuli ("local22" (scope local) (stimType periodic) (Props (periodicFreq "5e+007") (periodicJitter "0") (periodicPattern "1"))) ("local20" (scope local) (stimType periodic) (Props (periodicFreq "5e+007") (periodicJitter "0") (periodicPattern "1"))) ("local21" (scope local) (stimType periodic) (Props (periodicFreq "5e+007") (periodicJitter "0") (periodicPattern "1"))) ("local19" (scope local) (stimType periodic) (Props (periodicFreq "5e+007") (periodicJitter "0") (periodicPattern "1")))) (Notes) (Constraints ("DELAY_RULE" ("ALL DRVRS" "ALL RCVRS" "LENGTH" "0.2032" "LENGTH" "")) ("DP_GATHER_CONTROL" "IGNORE") ("DP_MAX_UNCOUPLED_LENGTH" "0.00127") ("DP_NEGATIVE_COUPLED_TOLERANCE" "2.54e-006") ("DP_PHASE_TOLERANCE" ("LENGTH" "0.000254")) ("DP_POSITIVE_COUPLED_TOLERANCE" "2.54e-006")) (MeasurementSets ("EMI" ("EMIStatus" status("on")) ("PeakEmission" status("on")) ("PeakFrequency" status("on")) ("PulseFreq" status("on")) ("RiseTime" status("on")) ("VoltageSwing" status("on"))) ("Reflection" ("BufferDelayFall" status("off")) ("BufferDelayRise" status("off")) ("EyeHeight" status("off")) ("EyeJitter" status("off")) ("EyeWidth" status("off")) ("FirstIncidentFall" status("off")) ("FirstIncidentRise" status("off")) ("Glitch" status("on")) ("GlitchFall" status("off")) ("GlitchRise" status("off")) ("Monotonic" status("on")) ("MonotonicFall" status("off")) ("MonotonicRise" status("off")) ("NoiseMargin" status("on")) ("NoiseMarginHigh" status("off")) ("NoiseMarginLow" status("off")) ("OvershootHigh" status("on")) ("OvershootLow" status("on")) ("PropDelay" status("on")) ("SettleDelay" status("on")) ("SettleDelayFall" status("off")) ("SettleDelayRise" status("off")) ("SwitchDelay" status("on")) ("SwitchDelayFall" status("off")) ("SwitchDelayRise" status("off"))) ("Crosstalk" ("Crosstalk" status("on"))) ("Custom")) (VectorSets) (Props (XnetName "TDT_85_OHMS_L1_DN") (allDrivers "active") (customSimType "Reflection") (ftsMode ("Typ")) (rcvrSelect "all") (tlineDelayMode "time") (userRevision "1.0")))) (Subckts) (CrossSections ("CRESCENT_CITY_634_20150410_E" (Props (SXDesignName "CRESCENT_CITY_634_20150410_E")) (Layers ("" (layerType "SURFACE") (material "AIR") (thickness "0 mil") (dielectricConstant "1.000000") (lossTangent "0") (etchFactor "0.000000") (elecCondVal "0 mho/cm") (thermCondVal "0 w/cm-degC")) ("" (layerType "DIELECTRIC") (material "CONFORMAL_COAT") (thickness "0.5 mil") (dielectricConstant "3.800000") (lossTangent "0.035") (etchFactor "0.000000") (elecCondVal "0 mho/cm") (thermCondVal "0.012 w/cm-degC")) ("TOP" (layerType "CONDUCTOR") (material "COPPER") (thickness "  2.100000 mil") (width "4.00 MIL") (dielectricConstant "4.500000") (lossTangent "0") (etchFactor "70.000000") (elecCondVal "595900.000000 mho/cm") (thermCondVal "0 w/cm-degC") (signalDieConstant "3.800000") (signalLossTangent "0.035")) ("" (layerType "DIELECTRIC") (material "FR-4") (thickness "  2.670000 mil") (dielectricConstant "4.000000") (lossTangent "0.035") (etchFactor "0.000000") (elecCondVal "0 mho/cm") (thermCondVal "0.012 w/cm-degC")) ("L2_GND1" (layerType "PLANE") (material "COPPER") (isShield t) (thickness "  1.250000 mil") (dielectricConstant "4.500000") (lossTangent "0.035") (etchFactor "90.000000") (elecCondVal "595900.000000 mho/cm") (thermCondVal "0.012 w/cm-degC")) ("" (layerType "DIELECTRIC") (material "FR-4") (thickness "  9.000000 mil") (dielectricConstant "4.100000") (lossTangent "0.035") (etchFactor "0.000000") (elecCondVal "0 mho/cm") (thermCondVal "0.012 w/cm-degC")) ("L3_SIG1" (layerType "CONDUCTOR") (material "COPPER") (thickness "  1.250000 mil") (width "4.00 MIL") (dielectricConstant "4.500000") (lossTangent "0.035") (etchFactor "90.000000") (elecCondVal "595900.000000 mho/cm") (thermCondVal "0.012 w/cm-degC") (signalDieConstant "4.100000") (signalLossTangent "0.035")) ("" (layerType "DIELECTRIC") (material "FR-4") (thickness "  3.000000 mil") (dielectricConstant "4.500000") (lossTangent "0.035") (etchFactor "0.000000") (elecCondVal "0 mho/cm") (thermCondVal "0 w/cm-degC")) ("L4_GND2" (layerType "PLANE") (material "COPPER") (isShield t) (thickness "  1.250000 mil") (dielectricConstant "4.500000") (lossTangent "0.035") (etchFactor "90.000000") (elecCondVal "595900.000000 mho/cm") (thermCondVal "0 w/cm-degC")) ("" (layerType "DIELECTRIC") (material "FR-4") (thickness "  9.000000 mil") (dielectricConstant "4.000000") (lossTangent "0.035") (etchFactor "0.000000") (elecCondVal "0 mho/cm") (thermCondVal "0.012 w/cm-degC")) ("L5_SIG2" (layerType "CONDUCTOR") (material "COPPER") (thickness "  1.250000 mil") (width "4.00 MIL") (dielectricConstant "4.500000") (lossTangent "0.035") (etchFactor "90.000000") (elecCondVal "595900.000000 mho/cm") (thermCondVal "0.012 w/cm-degC") (signalDieConstant "4.000000") (signalLossTangent "0.035")) ("" (layerType "DIELECTRIC") (material "FR-4") (thickness "  3.000000 mil") (dielectricConstant "4.500000") (lossTangent "0.035") (etchFactor "0.000000") (elecCondVal "0 mho/cm") (thermCondVal "0 w/cm-degC")) ("L6_GND3" (layerType "PLANE") (material "COPPER") (isShield t) (thickness "  1.250000 mil") (dielectricConstant "4.500000") (lossTangent "0.035") (etchFactor "90.000000") (elecCondVal "595900.000000 mho/cm") (thermCondVal "0 w/cm-degC")) ("" (layerType "DIELECTRIC") (material "FR-4") (thickness "  4.500000 mil") (dielectricConstant "4.100000") (lossTangent "0.035") (etchFactor "0.000000") (elecCondVal "0 mho/cm") (thermCondVal "0.012 w/cm-degC")) ("L7_PWR1-SIG" (layerType "PLANE") (material "COPPER") (isShield t) (thickness "  2.610000 mil") (dielectricConstant "4.500000") (lossTangent "0.035") (etchFactor "90.000000") (elecCondVal "595900.000000 mho/cm") (thermCondVal "0.012 w/cm-degC")) ("" (layerType "DIELECTRIC") (material "FR-4") (thickness "  3.100000 mil") (dielectricConstant "4.500000") (lossTangent "0.035") (etchFactor "0.000000") (elecCondVal "0 mho/cm") (thermCondVal "0 w/cm-degC")) ("L8_GND_TEMP" (layerType "PLANE") (material "COPPER") (isShield t) (thickness "  1.250000 mil") (dielectricConstant "4.500000") (lossTangent "0.035") (etchFactor "90.000000") (elecCondVal "595900.000000 mho/cm") (thermCondVal "0 w/cm-degC")) ("" (layerType "DIELECTRIC") (material "FR-4") (thickness "  3.030000 mil") (dielectricConstant "4.500000") (lossTangent "0.035") (etchFactor "0.000000") (elecCondVal "0 mho/cm") (thermCondVal "0 w/cm-degC")) ("L9_SIG_TEMP" (layerType "CONDUCTOR") (material "COPPER") (thickness "  1.250000 mil") (width "3.52 MIL") (dielectricConstant "4.500000") (lossTangent "0.035") (etchFactor "90.000000") (elecCondVal "595900.000000 mho/cm") (thermCondVal "0 w/cm-degC") (signalDieConstant "4.500000") (signalLossTangent "0.035")) ("" (layerType "DIELECTRIC") (material "FR-4") (thickness "  5.000000 mil") (dielectricConstant "4.500000") (lossTangent "0.035") (etchFactor "0.000000") (elecCondVal "0 mho/cm") (thermCondVal "0 w/cm-degC")) ("L10_SIG_TEMP" (layerType "CONDUCTOR") (material "COPPER") (thickness "  1.250000 mil") (width "3.52 MIL") (dielectricConstant "4.500000") (lossTangent "0.035") (etchFactor "90.000000") (elecCondVal "595900.000000 mho/cm") (thermCondVal "0 w/cm-degC") (signalDieConstant "4.500000") (signalLossTangent "0.035")) ("" (layerType "DIELECTRIC") (material "FR-4") (thickness "  3.030000 mil") (dielectricConstant "4.500000") (lossTangent "0.035") (etchFactor "0.000000") (elecCondVal "0 mho/cm") (thermCondVal "0 w/cm-degC")) ("L11_GND_TEMP" (layerType "PLANE") (material "COPPER") (isShield t) (thickness "  1.250000 mil") (dielectricConstant "4.500000") (lossTangent "0.035") (etchFactor "90.000000") (elecCondVal "595900.000000 mho/cm") (thermCondVal "0 w/cm-degC")) ("" (layerType "DIELECTRIC") (material "FR-4") (thickness "  3.100000 mil") (dielectricConstant "4.000000") (lossTangent "0.035") (etchFactor "0.000000") (elecCondVal "0 mho/cm") (thermCondVal "0.012 w/cm-degC")) ("L12_PWR2-SIG" (layerType "PLANE") (material "COPPER") (isShield t) (thickness "  2.610000 mil") (dielectricConstant "4.500000") (lossTangent "0.035") (etchFactor "90.000000") (elecCondVal "595900.000000 mho/cm") (thermCondVal "0.012 w/cm-degC")) ("" (layerType "DIELECTRIC") (material "FR-4") (thickness "  4.500000 mil") (dielectricConstant "4.500000") (lossTangent "0.035") (etchFactor "0.000000") (elecCondVal "0 mho/cm") (thermCondVal "0 w/cm-degC")) ("L13_GND4" (layerType "PLANE") (material "COPPER") (isShield t) (thickness "  1.250000 mil") (dielectricConstant "4.500000") (lossTangent "0.035") (etchFactor "90.000000") (elecCondVal "595900.000000 mho/cm") (thermCondVal "0 w/cm-degC")) ("" (layerType "DIELECTRIC") (material "FR-4") (thickness "  3.000000 mil") (dielectricConstant "4.100000") (lossTangent "0.035") (etchFactor "0.000000") (elecCondVal "0 mho/cm") (thermCondVal "0.012 w/cm-degC")) ("L14_SIG3" (layerType "CONDUCTOR") (material "COPPER") (thickness "  1.250000 mil") (width "4.00 MIL") (dielectricConstant "4.500000") (lossTangent "0.035") (etchFactor "90.000000") (elecCondVal "595900.000000 mho/cm") (thermCondVal "0.012 w/cm-degC") (signalDieConstant "4.100000") (signalLossTangent "0.035")) ("" (layerType "DIELECTRIC") (material "FR-4") (thickness "  9.000000 mil") (dielectricConstant "4.500000") (lossTangent "0.035") (etchFactor "0.000000") (elecCondVal "0 mho/cm") (thermCondVal "0 w/cm-degC")) ("L15_GND5" (layerType "PLANE") (material "COPPER") (isShield t) (thickness "  1.250000 mil") (dielectricConstant "4.500000") (lossTangent "0.035") (etchFactor "90.000000") (elecCondVal "595900.000000 mho/cm") (thermCondVal "0 w/cm-degC")) ("" (layerType "DIELECTRIC") (material "FR-4") (thickness "  3.000000 mil") (dielectricConstant "4.500000") (lossTangent "0.035") (etchFactor "0.000000") (elecCondVal "0 mho/cm") (thermCondVal "0.012 w/cm-degC")) ("L16_SIG4" (layerType "CONDUCTOR") (material "COPPER") (thickness "  1.250000 mil") (width "4.00 MIL") (dielectricConstant "4.500000") (lossTangent "0.035") (etchFactor "90.000000") (elecCondVal "595900.000000 mho/cm") (thermCondVal "0.012 w/cm-degC") (signalDieConstant "4.500000") (signalLossTangent "0.035")) ("" (layerType "DIELECTRIC") (material "FR-4") (thickness "  9.000000 mil") (dielectricConstant "4.500000") (lossTangent "0.035") (etchFactor "0.000000") (elecCondVal "0 mho/cm") (thermCondVal "0 w/cm-degC")) ("L17_GND6" (layerType "PLANE") (material "COPPER") (isShield t) (thickness "  1.250000 mil") (dielectricConstant "4.500000") (lossTangent "0.035") (etchFactor "90.000000") (elecCondVal "595900.000000 mho/cm") (thermCondVal "0.012 w/cm-degC")) ("" (layerType "DIELECTRIC") (material "FR-4") (thickness "  2.670000 mil") (dielectricConstant "4.500000") (lossTangent "0.035") (etchFactor "0.000000") (elecCondVal "0 mho/cm") (thermCondVal "0.012 w/cm-degC")) ("BOTTOM" (layerType "CONDUCTOR") (material "COPPER") (thickness "  2.100000 mil") (width "4.00 MIL") (dielectricConstant "4.500000") (lossTangent "0") (etchFactor "70.000000") (elecCondVal "595900.000000 mho/cm") (thermCondVal "0 w/cm-degC") (signalDieConstant "3.800000") (signalLossTangent "0.035")) ("" (layerType "DIELECTRIC") (material "CONFORMAL_COAT") (thickness "0.5 mil") (dielectricConstant "3.800000") (lossTangent "0.035") (etchFactor "0.000000") (elecCondVal "0 mho/cm") (thermCondVal "0.012 w/cm-degC")) ("" (layerType "SURFACE") (material "AIR") (thickness "0 mil") (dielectricConstant "1.000000") (lossTangent "0") (etchFactor "0.000000") (elecCondVal "0 mho/cm") (thermCondVal "0 w/cm-degC"))))) (Props (DesUnits "mils 2") (LayerStack ("DIELECTRIC" "DIELECTRIC" "BOTTOM" "DIELECTRIC" "L17_GND6" "DIELECTRIC" "L16_SIG4" "DIELECTRIC" "L15_GND5" "DIELECTRIC" "L14_SIG3" "DIELECTRIC" "L13_GND4" "DIELECTRIC" "L12_PWR2-SIG" "DIELECTRIC" "L11_GND_TEMP" "DIELECTRIC" "L10_SIG_TEMP" "DIELECTRIC" "L9_SIG_TEMP" "DIELECTRIC" "L8_GND_TEMP" "DIELECTRIC" "L7_PWR1-SIG" "DIELECTRIC" "L6_GND3" "DIELECTRIC" "L5_SIG2" "DIELECTRIC" "L4_GND2" "DIELECTRIC" "L3_SIG1" "DIELECTRIC" "L2_GND1" "DIELECTRIC" "TOP" "DIELECTRIC" "DIELECTRIC")) (Revision "16.600")) (Params (DiffInputPkg ((temperature "27") (bufferModelNonInverting "CDSDefaultInput_2p5v") (bufferModelInverting "CDSDefaultInput_2p5v") (threshInputHighMin "1.7 V") (threshInputHighTyp "1.7  V") (threshInputHighMax "1.7  V") (threshInputLowMin "0.7  V") (threshInputLowTyp "0.7  V") (threshInputLowMax "0.7  V") (mappingTagNonInverting nil) (mappingTagInverting nil) (cycle "1"))) (Diode ((cutoffVoltage "0.7 V"))) (IbisIOMacro ((temperature "27") (bufferModel "CDSDefaultIO_2p5v") (stimuli nil) (offsets nil) (state "tristate") (cycle "1") (termMap nil) (setup "2.0e-09") (hold "1.0e-09") (rise nil) (fall nil) (macroType nil) (voltage nil) (spice nil) (LEFDEFPinName nil) (LEFDEFPinType nil) (mappingTag nil))) (DualClampTerm ((cutoffVoltageUp "0.7 V") (cutoffVoltageDown "0.7 V") (voltageUp "5 V") (voltageDown "0 V") (maxDelay "0.1 ns"))) (HiClampTerm ((cutoffVoltage "0.7 V") (voltage "5 V") (maxDelay "0.1 ns"))) (idlCircuit ((allDrivers "active") (ftsMode '("Typ")) (rcvrSelect "all") (simMode "Reflection") (tlineDelayMode "time") (userRevision "1.0") (autoSolve "On"))) (TLine ((diffImpedance "100ohm") (diffVelocity "1.4142e+08M/s") (impedance "60ohm") length("2800 mil") (propDelay "0.5 ns") (velocity "5600 mil/ns") (traceCount "1") (traceGeometry "Microstrip") (impedanceMin nil) (impedanceMax nil) (lengthMin nil) (lengthMax nil) (propDelayMin nil) (propDelayMax nil) (impedanceSweepCount nil) (propDelaySweepCount nil) (velocitySweepCount nil) (lengthSweepCount nil) (matchSetName nil))) (LowClampTerm ((cutoffVoltage "0.7 V") (voltage "0 V") (maxDelay "0.1 ns"))) (sync ((syncFreq "100e6") (syncInitState "1") (syncPattern "10") (syncEdgeSwitch "rise"))) (SeriesTerm ((resistance "22 ohm") (maxDelay "0.1 ns"))) (RCTerm ((resistance "50 ohm") (capacitance "20 pF") (voltage "5 V") (maxDelay "0.1 ns"))) (TheveninTerm ((resistanceUp "180 ohm") (resistanceDown "270 ohm") (voltageUp "5 V") (voltageDown "0 V") (maxDelay "0.1 ns"))) (ShuntTerm ((resistance "50 ohm") (voltage "5 V") (maxDelay "0.1 ns"))) (Connector nil) (IbisIO_OpenPullDown ((temperature "27") (bufferModel "CDSDefaultIO_2p5v") (stimuli nil) (offsets nil) (state "tristate") (cycle "1") (termMap nil) (setup "2.0e-09") (hold "1.0e-09") (rise nil) (fall nil) (macroType nil) (voltage nil) (spice nil) (LEFDEFPinName nil) (LEFDEFPinType nil) (mappingTag nil))) (IbisIO_OpenPullUp ((temperature "27") (bufferModel "CDSDefaultIO_2p5v") (stimuli nil) (offsets nil) (state "tristate") (cycle "1") (termMap nil) (setup "2.0e-09") (hold "1.0e-09") (rise nil) (fall nil) (macroType nil) (voltage nil) (spice nil) (LEFDEFPinName nil) (LEFDEFPinType nil) (mappingTag nil))) (Resistor ((resistance "50 ohm") (orientation "0"))) (DiffInput ((temperature "27") (bufferModelNonInverting "CDSDefaultInput_2p5v") (bufferModelInverting "CDSDefaultInput_2p5v") (threshInputHighMin "1.7 V") (threshInputHighTyp "1.7  V") (threshInputHighMax "1.7  V") (threshInputLowMin "0.7  V") (threshInputLowTyp "0.7  V") (threshInputLowMax "0.7  V") (mappingTagNonInverting nil) (mappingTagInverting nil) (cycle "1"))) (Capacitor ((capacitance "10 pF") (orientation "0"))) (DiffOutputPkg ((temperature "27") (bufferModelNonInverting "CDSDefaultOutput_2p5v") (bufferModelInverting "CDSDefaultOutput_2p5v") (stimuli nil) (offsets nil) (state "tristate") (cycle "1") (termMap nil) (setup "0.9e-09") (hold "0.4e-09") (rise nil) (fall nil) (threshOutputHighMin "2.375  V") (threshOutputHighTyp "2.5  V") (threshOutputHighMax "2.625  V") (threshOutputLowMin "1.275  V") (threshOutputLowTyp "1.7  V") (threshOutputLowMax "1.985  V") (mappingTagNonInverting nil) (mappingTagInverting nil) (spice nil))) (ESpiceDevice nil) (IbisInput ((temperature "27") (bufferModel "CDSDefaultInput_2p5v") (cycle "1") (LEFDEFPinName nil) (LEFDEFPinType nil) (mappingTag nil))) (Inductor ((inductance "5 nH") (orientation "0"))) (DiffOutput ((temperature "27") (bufferModelNonInverting "CDSDefaultOutput_2p5v") (bufferModelInverting "CDSDefaultOutput_2p5v") (stimuli nil) (offsets nil) (state "tristate") (cycle "1") (termMap nil) (setup "0.9e-09") (hold "0.4e-09") (rise nil) (fall nil) (threshOutputHighMin "2.375  V") (threshOutputHighTyp "2.5  V") (threshOutputHighMax "2.625  V") (threshOutputLowMin "1.275  V") (threshOutputLowTyp "1.7  V") (threshOutputLowMax "1.985  V") (mappingTagNonInverting nil) (mappingTagInverting nil) (spice nil))) (Source ((voltage "5 V"))) (DiffIOPkg ((temperature "27") (bufferModelNonInverting "CDSDefaultIO_2p5v") (bufferModelInverting "CDSDefaultIO_2p5v") (stimuli nil) (offsets nil) (state "tristate") (cycle "1") (termMap nil) (setup "0.9e-09") (hold "0.4e-09") (rise nil) (fall nil) (threshInputHighMin "1.7 V") (threshInputHighTyp "1.7  V") (threshInputHighMax "1.7  V") (threshInputLowMin "0.7  V") (threshInputLowTyp "0.7  V") (threshInputLowMax "0.7 ") (threshOutputHighMin "2.365  V") (threshOutputHighTyp "2.5  V") (threshOutputHighMax "2.625  V") (threshOutputLowMin "1.275  V") (threshOutputLowTyp "1.7  V") (threshOutputLowMax "1.985  V") (mappingTagNonInverting nil) (mappingTagInverting nil) (spice nil))) (RLGC (length("1000 mil"))) (DiffIO ((temperature "27") (bufferModelNonInverting "CDSDefaultIO_2p5v") (bufferModelInverting "CDSDefaultIO_2p5v") (stimuli nil) (offsets nil) (state "tristate") (cycle "1") (termMap nil) (setup "0.9e-09") (hold "0.4e-09") (rise nil) (fall nil) (threshInputHighMin "1.7 V") (threshInputHighTyp "1.7  V") (threshInputHighMax "1.7  V") (threshInputLowMin "0.7  V") (threshInputLowTyp "0.7  V") (threshInputLowMax "0.7 ") (threshOutputHighMin "2.365  V") (threshOutputHighTyp "2.5  V") (threshOutputHighMax "2.625  V") (threshOutputLowMin "1.275  V") (threshOutputLowTyp "1.7  V") (threshOutputLowMax "1.985  V") (mappingTagNonInverting nil) (mappingTagInverting nil) (spice nil))) (IbisOutput ((temperature "27") (bufferModel "CDSDefaultOutput_2p5v") (stimuli nil) (offsets nil) (state "tristate") (cycle "1") (termMap nil) (setup "2.0e-09") (hold "1.0e-09") (rise nil) (fall nil) (macroType nil) (voltage nil) (spice nil) (LEFDEFPinName nil) (LEFDEFPinType nil) (mappingTag nil))) (IbisIO ((temperature "27") (bufferModel "CDSDefaultIO_2p5v") (stimuli nil) (offsets nil) (state "tristate") (cycle "1") (termMap nil) (setup "2.0e-09") (hold "1.0e-09") (rise nil) (fall nil) (macroType nil) (voltage nil) (spice nil) (LEFDEFPinName nil) (LEFDEFPinType nil) (mappingTag nil))) (CPWSL ((d1Thickness "10 mil") (d1Constant "4.5") (d1LossTangent "0.035") (d2Thickness "0.72 mil") (d2Constant "4.5") (d2LossTangent "0.035") (d3Thickness "10 mil") (d3Constant "4.5") (d3LossTangent "0.035") length("1000 mil") (spacing "5 mil") (spacing2 "5 mil") (spacing3 "5 mil") (spacing4 "5 mil") (spacing5 "5 mil") (traceConductivity "595900 mho/cm") (traceGeometry "cpwms") (traceLayerName "") (traceThickness "0.72 mil") (traceType "single") (traceWidth "5.0 mil") (traceWidth2 "5.0 mil") (traceWidth3 "5.0 mil") (traceWidth4 "5.0 mil") (traceWidth5 "5.0 mil") (traceWidth6 "5.0 mil") (offset "0 mil") (traceCount "1") (impedance nil))) (Cable (length("1 m"))) (Trace ((d1Thickness "10 mil") (d1Constant "4.5") (d1LossTangent "0.035") (d2Thickness "10 mil") (d2Constant "4.5") (d2LossTangent "0.035") (d3Thickness "0.0") (d3Constant "1.0") (d3LossTangent "0") length("1000 mil") (spacing "5 mil") (spacing2 "5 mil") (spacing3 "5 mil") (spacing4 "5 mil") (spacing5 "5 mil") (traceConductivity "595900 mho/cm") (traceGeometry "microstrip") (traceLayerName "") (traceThickness "0.72 mil") (traceType "single") (traceWidth "5.0 mil") (traceWidth2 "5.0 mil") (traceWidth3 "5.0 mil") (traceWidth4 "5.0 mil") (traceWidth5 "5.0 mil") (traceWidth6 "5.0 mil") (offset "0 mil") (traceCount "1") (impedance nil))) (CPWMS ((d1Thickness "10 mil") (d1Constant "4.5") (d1LossTangent "0.035") (d2Thickness "0.72 mil") (d2Constant "4.5") (d2LossTangent "0.035") (d3Thickness "0.0") (d3Constant "1") (d3LossTangent "0") length("1000 mil") (spacing "5 mil") (spacing2 "5 mil") (spacing3 "5 mil") (spacing4 "5 mil") (spacing5 "5 mil") (traceConductivity "595900 mho/cm") (traceGeometry "cpwms") (traceLayerName "") (traceThickness "0.72 mil") (traceType "single") (traceWidth "5.0 mil") (traceWidth2 "5.0 mil") (traceWidth3 "5.0 mil") (traceWidth4 "5.0 mil") (traceWidth5 "5.0 mil") (traceWidth6 "5.0 mil") (offset "0 mil") (traceCount "1") (impedance nil))) (CPW ((d1Thickness "10 mil") (d1Constant "4.5") (d1LossTangent "0.035") (d2Thickness "0.72 mil") (d2Constant "1") (d2LossTangent "0") (d3Thickness "0.0") (d3Constant "1") (d3LossTangent "0") length("1000 mil") (spacing "5 mil") (spacing2 "5 mil") (spacing3 "5 mil") (spacing4 "5 mil") (spacing5 "5 mil") (traceConductivity "595900 mho/cm") (traceGeometry "cpwms") (traceLayerName "") (traceThickness "0.72 mil") (traceType "single") (traceWidth "5.0 mil") (traceWidth2 "5.0 mil") (traceWidth3 "5.0 mil") (traceWidth4 "5.0 mil") (traceWidth5 "5.0 mil") (traceWidth6 "5.0 mil") (offset "0 mil") (traceCount "1") (impedance nil))) (async ((asyncTimePoints "") (asyncInitState "1"))) (IbisOutput_OpenPullUp ((temperature "27") (bufferModel "CDSDefaultOutput_2p5v") (stimuli nil) (offsets nil) (state "tristate") (cycle "1") (termMap nil) (setup "2.0e-09") (hold "1.0e-09") (rise nil) (fall nil) (macroType nil) (voltage nil) (spice nil) (LEFDEFPinName nil) (LEFDEFPinType nil) (mappingTag nil))) (clocked ((clockRise "1e-09") (clockFall "1e-09") (clockFreq "100e6") (clockInitState "0") (clockDutyCycle "0.5") (clockJitter "0"))) (Via ((model "Unknown") (viaOutputFormat "Unknown") (viaPadstack nil) (viaTopLayer nil) (viaBottomLayer nil) (viaIsPower nil) (viaIsGround nil))) (periodic ((periodicFreq "100e6") (periodicPattern "10") (periodicJitter "0"))) (IbisInputPkg ((temperature "27") (bufferModel "CDSDefaultInput_2p5v") (cycle "1") (LEFDEFPinName nil) (LEFDEFPinType nil) (mappingTag nil))) (IbisIOPkg ((temperature "27") (bufferModel "CDSDefaultIO_2p5v") (stimuli nil) (offsets nil) (state "tristate") (cycle "1") (termMap nil) (setup "2.0e-09") (hold "1.0e-09") (rise nil) (fall nil) (macroType nil) (voltage nil) (spice nil) (LEFDEFPinName nil) (LEFDEFPinType nil) (mappingTag nil))) (CurrentProbe nil) (IbisOutputPkg ((temperature "27") (bufferModel "CDSDefaultOutput_2p5v") (stimuli nil) (offsets nil) (state "tristate") (cycle "1") (termMap nil) (setup "2.0e-09") (hold "1.0e-09") (rise nil) (fall nil) (macroType nil) (voltage nil) (spice nil) (LEFDEFPinName nil) (LEFDEFPinType nil) (mappingTag nil)))))
				)
				( objectStatus "TDT_85_OHMS" )
			)
			( physicalCSet "@baseboard_fab2_lib.baseboard_fab2(sch_1):\100_OHM_DIFF_FAB2\"
				( attribute "DIFFP_PRIMARY_GAP" "13.38,0.00,12.52,0.00,12.52,0.00,0.00,0.00,0.00,12.52,0.00,12.52,0.00,13.38"
					( Origin gBackEnd )
				)
				( attribute "DIFFP_COUPLED_PLUS" "0.10,0.10,0.10,0.10,0.10,0.10,0.10,0.10,0.10,0.10,0.10,0.10,0.10,0.10"
					( Origin gBackEnd )
				)
				( attribute "DIFFP_COUPLED_MINUS" "0.00,0.00,0.00,0.00,0.00,0.00,0.00,0.00,0.00,0.00,0.00,0.00,0.00,0.00"
					( Origin gBackEnd )
				)
				( attribute "DIFFP_MIN_SPACE" "4.00,4.00,4.00,4.00,4.00,4.00,4.00,4.00,4.00,4.00,4.00,4.00,4.00,4.00"
					( Origin gBackEnd )
				)
				( attribute "MIN_LINE_WIDTH" "4.62,3.99,3.99,3.99,3.99,3.99,3.99,3.99,3.99,3.99,3.99,3.99,3.99,4.62"
					( Origin gBackEnd )
				)
				( attribute "MAX_LINE_WIDTH" "4.62,3.99,3.99,3.99,3.99,3.99,3.99,3.99,3.99,3.99,3.99,3.99,3.99,4.62"
					( Origin gBackEnd )
				)
				( attribute "DIFFP_NECK_GAP" "4.00,4.00,4.00,4.00,4.00,4.00,4.00,4.00,4.00,4.00,4.00,4.00,4.00,4.00"
					( Origin gBackEnd )
				)
				( attribute "MIN_NECK_WIDTH" "3.51,3.51,3.51,3.51,3.51,3.51,3.51,3.51,3.51,3.51,3.51,3.51,3.51,3.51"
					( Origin gBackEnd )
				)
				( attribute "MAXIMUM_NECK_LENGTH" "1000.00,1000.00,1000.00,1000.00,1000.00,1000.00,1000.00,1000.00,1000.00,1000.00,1000.00,1000.00,1000.00,1000.00"
					( Origin gBackEnd )
				)
				( attribute "VIA_LIST" "V_C20P10AP28,V_C20P10C26AP28_TP,V_C20P10AP28_TP,TP_C26B,TP_C30T,R20X5R20X7D16S,R20X5R20X7D16SB"
					( Origin gBackEnd )
				)
				( attribute "ALLOW_ON_ETCH_SUBCLASS" "TRUE,TRUE,TRUE,TRUE,TRUE,TRUE,TRUE,TRUE,TRUE,TRUE,TRUE,TRUE,TRUE,TRUE"
					( Origin gBackEnd )
				)
				( attribute "TS_ALLOWED" "ANYWHERE,ANYWHERE,ANYWHERE,ANYWHERE,ANYWHERE,ANYWHERE,ANYWHERE,ANYWHERE,ANYWHERE,ANYWHERE,ANYWHERE,ANYWHERE,ANYWHERE,ANYWHERE"
					( Origin gBackEnd )
				)
				( attribute "MIN_BVIA_STAGGER" "5.00,5.00,5.00,5.00,5.00,5.00,5.00,5.00,5.00,5.00,5.00,5.00,5.00,5.00"
					( Origin gBackEnd )
				)
				( attribute "MAX_BVIA_STAGGER" "0.00,0.00,0.00,0.00,0.00,0.00,0.00,0.00,0.00,0.00,0.00,0.00,0.00,0.00"
					( Origin gBackEnd )
				)
				( attribute "PAD_PAD_DIRECT_CONNECT" "ALL_ALLOWED,ALL_ALLOWED,ALL_ALLOWED,ALL_ALLOWED,ALL_ALLOWED,ALL_ALLOWED,ALL_ALLOWED,ALL_ALLOWED,ALL_ALLOWED,ALL_ALLOWED,ALL_ALLOWED,ALL_ALLOWED,ALL_ALLOWED,ALL_ALLOWED"
					( Origin gBackEnd )
				)
				( objectStatus "100_OHM_DIFF_OPTION2" )
			)
			( physicalCSet "@baseboard_fab2_lib.baseboard_fab2(sch_1):\5-5-5_DIFF\"
				( attribute "DIFFP_PRIMARY_GAP" "5.00,5.00,5.00,5.00,5.00,5.00,5.00,5.00,5.00,5.00,5.00,5.00,5.00,5.00"
					( Origin gBackEnd )
				)
				( attribute "DIFFP_COUPLED_PLUS" "0.10,0.10,0.10,0.10,0.10,0.10,0.10,0.10,0.10,0.10,0.10,0.10,0.10,0.10"
					( Origin gBackEnd )
				)
				( attribute "DIFFP_COUPLED_MINUS" "0.10,0.10,0.10,0.10,0.10,0.10,0.10,0.10,0.10,0.10,0.10,0.10,0.10,0.10"
					( Origin gBackEnd )
				)
				( attribute "DIFFP_MIN_SPACE" "4.00,4.00,4.00,4.00,4.00,4.00,4.00,4.00,4.00,4.00,4.00,4.00,4.00,4.00"
					( Origin gBackEnd )
				)
				( attribute "MIN_LINE_WIDTH" "5.00,5.00,5.00,5.00,5.00,5.00,5.00,5.00,5.00,5.00,5.00,5.00,5.00,5.00"
					( Origin gBackEnd )
				)
				( attribute "MAX_LINE_WIDTH" "5.00,5.00,5.00,5.00,5.00,5.00,5.00,5.00,5.00,5.00,5.00,5.00,5.00,5.00"
					( Origin gBackEnd )
				)
				( attribute "DIFFP_NECK_GAP" "5.00,5.00,5.00,5.00,5.00,5.00,5.00,5.00,5.00,5.00,5.00,5.00,5.00,5.00"
					( Origin gBackEnd )
				)
				( attribute "MIN_NECK_WIDTH" "5.00,5.00,5.00,5.00,5.00,5.00,5.00,5.00,5.00,5.00,5.00,5.00,5.00,5.00"
					( Origin gBackEnd )
				)
				( attribute "MAXIMUM_NECK_LENGTH" "250.00,250.00,250.00,250.00,250.00,250.00,250.00,250.00,250.00,250.00,250.00,250.00,250.00,250.00"
					( Origin gBackEnd )
				)
				( attribute "VIA_LIST" "V_C20P10AP28,V_C20P10C26AP28_TP,V_C20P10AP28_TP,TP_C26B,TP_C30T,R20X5R20X7D16S,R20X5R20X7D16SB"
					( Origin gBackEnd )
				)
				( attribute "ALLOW_ON_ETCH_SUBCLASS" "TRUE,TRUE,TRUE,TRUE,TRUE,TRUE,TRUE,TRUE,TRUE,TRUE,TRUE,TRUE,TRUE,TRUE"
					( Origin gBackEnd )
				)
				( attribute "TS_ALLOWED" "ANYWHERE,ANYWHERE,ANYWHERE,ANYWHERE,ANYWHERE,ANYWHERE,ANYWHERE,ANYWHERE,ANYWHERE,ANYWHERE,ANYWHERE,ANYWHERE,ANYWHERE,ANYWHERE"
					( Origin gBackEnd )
				)
				( attribute "MIN_BVIA_STAGGER" "5.00,5.00,5.00,5.00,5.00,5.00,5.00,5.00,5.00,5.00,5.00,5.00,5.00,5.00"
					( Origin gBackEnd )
				)
				( attribute "MAX_BVIA_STAGGER" "0.00,0.00,0.00,0.00,0.00,0.00,0.00,0.00,0.00,0.00,0.00,0.00,0.00,0.00"
					( Origin gBackEnd )
				)
				( attribute "PAD_PAD_DIRECT_CONNECT" "ALL_ALLOWED,ALL_ALLOWED,ALL_ALLOWED,ALL_ALLOWED,ALL_ALLOWED,ALL_ALLOWED,ALL_ALLOWED,ALL_ALLOWED,ALL_ALLOWED,ALL_ALLOWED,ALL_ALLOWED,ALL_ALLOWED,ALL_ALLOWED,ALL_ALLOWED"
					( Origin gBackEnd )
				)
				( objectStatus "5-5-5_DIFF" )
			)
			( physicalCSet "@crescent_city_bb_fab1_lib.crescent_city_bb_fab1(sch_1):\85_OHM_DIFF_CLK\"
				( attribute "DIFFP_PRIMARY_GAP" "7.00,7.00,7.00,7.00,7.00,7.00,7.00,7.00,7.00,7.00,7.00,7.00,7.00,7.00"
					( Origin gBackEnd )
				)
				( attribute "DIFFP_COUPLED_PLUS" "0.10,0.10,0.10,0.10,0.10,0.10,0.10,0.10,0.10,0.10,0.10,0.10,0.10,0.10"
					( Origin gBackEnd )
				)
				( attribute "DIFFP_COUPLED_MINUS" "0.01,0.01,0.01,0.01,0.01,0.01,0.01,0.01,0.01,0.01,0.01,0.01,0.01,0.01"
					( Origin gBackEnd )
				)
				( attribute "DIFFP_MIN_SPACE" "3.90,3.90,3.90,3.90,3.90,3.90,3.90,3.90,3.90,3.90,3.90,3.90,3.90,3.90"
					( Origin gBackEnd )
				)
				( attribute "MIN_LINE_WIDTH" "5.00,4.50,4.50,4.50,4.50,4.50,4.50,4.50,4.50,4.50,4.50,4.50,4.50,5.00"
					( Origin gBackEnd )
				)
				( attribute "MAX_LINE_WIDTH" "5.00,4.50,4.50,4.50,4.50,4.50,4.50,4.50,4.50,4.50,4.50,4.50,4.50,5.00"
					( Origin gBackEnd )
				)
				( attribute "DIFFP_NECK_GAP" "4.00,4.00,4.00,4.00,4.00,4.00,4.00,4.00,4.00,4.00,4.00,4.00,4.00,4.00"
					( Origin gBackEnd )
				)
				( attribute "MIN_NECK_WIDTH" "3.50,3.50,3.50,3.50,3.50,3.50,3.50,3.50,3.50,3.50,3.50,3.50,3.50,3.50"
					( Origin gBackEnd )
				)
				( attribute "MAXIMUM_NECK_LENGTH" "1200.00,1200.00,1200.00,1200.00,1200.00,1200.00,1200.00,1200.00,1200.00,1200.00,1200.00,1200.00,1200.00,1200.00"
					( Origin gBackEnd )
				)
				( attribute "VIA_LIST" "V_C20P10AP28,V_C20P10C26AP28_TP,V_C20P10AP28_TP,TP_C26B,TP_C30T,R20X5R20X7D16S,R20X5R20X7D16SB"
					( Origin gBackEnd )
				)
				( attribute "ALLOW_ON_ETCH_SUBCLASS" "TRUE,FALSE,TRUE,FALSE,TRUE,FALSE,FALSE,FALSE,FALSE,TRUE,FALSE,TRUE,FALSE,TRUE"
					( Origin gBackEnd )
				)
				( attribute "TS_ALLOWED" "ANYWHERE,ANYWHERE,ANYWHERE,ANYWHERE,ANYWHERE,ANYWHERE,ANYWHERE,ANYWHERE,ANYWHERE,ANYWHERE,ANYWHERE,ANYWHERE,ANYWHERE,ANYWHERE"
					( Origin gBackEnd )
				)
				( attribute "MIN_BVIA_STAGGER" "5.00,5.00,5.00,5.00,5.00,5.00,5.00,5.00,5.00,5.00,5.00,5.00,5.00,5.00"
					( Origin gBackEnd )
				)
				( attribute "MAX_BVIA_STAGGER" "0.00,0.00,0.00,0.00,0.00,0.00,0.00,0.00,0.00,0.00,0.00,0.00,0.00,0.00"
					( Origin gBackEnd )
				)
				( attribute "PAD_PAD_DIRECT_CONNECT" "ALL_ALLOWED,ALL_ALLOWED,ALL_ALLOWED,ALL_ALLOWED,ALL_ALLOWED,ALL_ALLOWED,ALL_ALLOWED,ALL_ALLOWED,ALL_ALLOWED,ALL_ALLOWED,ALL_ALLOWED,ALL_ALLOWED,ALL_ALLOWED,ALL_ALLOWED"
					( Origin gBackEnd )
				)
				( objectStatus "85_OHM_DIFF_CLK" )
			)
			( physicalCSet "@crescent_city_bb_fab1_lib.crescent_city_bb_fab1(sch_1):\85_OHM_DIFF_WBG\"
				( attribute "DIFFP_PRIMARY_GAP" "5.00,7.00,7.00,7.00,7.00,7.00,7.00,7.00,7.00,7.00,7.00,7.00,7.00,5.00"
					( Origin gBackEnd )
				)
				( attribute "DIFFP_COUPLED_PLUS" "0.10,0.10,0.10,0.10,0.10,0.10,0.10,0.10,0.10,0.10,0.10,0.10,0.10,0.10"
					( Origin gBackEnd )
				)
				( attribute "DIFFP_COUPLED_MINUS" "0.01,0.01,0.01,0.01,0.01,0.01,0.01,0.01,0.01,0.01,0.01,0.01,0.01,0.01"
					( Origin gBackEnd )
				)
				( attribute "DIFFP_MIN_SPACE" "3.90,3.90,3.90,3.90,3.90,3.90,3.90,3.90,3.90,3.90,3.90,3.90,3.90,3.90"
					( Origin gBackEnd )
				)
				( attribute "MIN_LINE_WIDTH" "4.50,4.50,4.50,4.50,4.50,4.50,4.50,4.50,4.50,4.50,4.50,4.50,4.50,4.50"
					( Origin gBackEnd )
				)
				( attribute "MAX_LINE_WIDTH" "4.50,4.50,4.50,4.50,4.50,4.50,4.50,4.50,4.50,4.50,4.50,4.50,4.50,4.50"
					( Origin gBackEnd )
				)
				( attribute "DIFFP_NECK_GAP" "4.00,4.00,4.00,4.00,4.00,4.00,4.00,4.00,4.00,4.00,4.00,4.00,4.00,4.00"
					( Origin gBackEnd )
				)
				( attribute "MIN_NECK_WIDTH" "3.50,3.50,3.50,3.50,3.50,3.50,3.50,3.50,3.50,3.50,3.50,3.50,3.50,3.50"
					( Origin gBackEnd )
				)
				( attribute "MAXIMUM_NECK_LENGTH" "1200.00,1200.00,1200.00,1200.00,1200.00,1200.00,1200.00,1200.00,1200.00,1200.00,1200.00,1200.00,1200.00,1200.00"
					( Origin gBackEnd )
				)
				( attribute "VIA_LIST" "V_C20P10AP28,V_C20P10C26AP28_TP,V_C20P10AP28_TP,TP_C26B,TP_C30T,R20X5R20X7D16S,R20X5R20X7D16SB"
					( Origin gBackEnd )
				)
				( attribute "ALLOW_ON_ETCH_SUBCLASS" "TRUE,FALSE,TRUE,FALSE,TRUE,FALSE,FALSE,FALSE,FALSE,TRUE,FALSE,TRUE,FALSE,TRUE"
					( Origin gBackEnd )
				)
				( attribute "TS_ALLOWED" "ANYWHERE,ANYWHERE,ANYWHERE,ANYWHERE,ANYWHERE,ANYWHERE,ANYWHERE,ANYWHERE,ANYWHERE,ANYWHERE,ANYWHERE,ANYWHERE,ANYWHERE,ANYWHERE"
					( Origin gBackEnd )
				)
				( attribute "MIN_BVIA_STAGGER" "5.00,5.00,5.00,5.00,5.00,5.00,5.00,5.00,5.00,5.00,5.00,5.00,5.00,5.00"
					( Origin gBackEnd )
				)
				( attribute "MAX_BVIA_STAGGER" "0.00,0.00,0.00,0.00,0.00,0.00,0.00,0.00,0.00,0.00,0.00,0.00,0.00,0.00"
					( Origin gBackEnd )
				)
				( attribute "PAD_PAD_DIRECT_CONNECT" "ALL_ALLOWED,ALL_ALLOWED,ALL_ALLOWED,ALL_ALLOWED,ALL_ALLOWED,ALL_ALLOWED,ALL_ALLOWED,ALL_ALLOWED,ALL_ALLOWED,ALL_ALLOWED,ALL_ALLOWED,ALL_ALLOWED,ALL_ALLOWED,ALL_ALLOWED"
					( Origin gBackEnd )
				)
				( objectStatus "85_OHM_DIFF_WBG" )
			)
			( physicalCSet "@crescent_city_bb_fab1_lib.crescent_city_bb_fab1(sch_1):\85_OHM_DIFF_EV_CLOCKS\"
				( attribute "DIFFP_PRIMARY_GAP" "5.00,7.00,7.00,7.00,7.00,7.00,7.00,7.00,7.00,7.00,7.00,7.00,7.00,5.00"
					( Origin gBackEnd )
				)
				( attribute "DIFFP_COUPLED_PLUS" "0.10,0.10,0.10,0.10,0.10,0.10,0.10,0.10,0.10,0.10,0.10,0.10,0.10,0.10"
					( Origin gBackEnd )
				)
				( attribute "DIFFP_COUPLED_MINUS" "0.01,0.01,0.01,0.01,0.01,0.01,0.01,0.01,0.01,0.01,0.01,0.01,0.01,0.01"
					( Origin gBackEnd )
				)
				( attribute "DIFFP_MIN_SPACE" "3.90,3.90,3.90,3.90,3.90,3.90,3.90,3.90,3.90,3.90,3.90,3.90,3.90,3.90"
					( Origin gBackEnd )
				)
				( attribute "MIN_LINE_WIDTH" "4.50,4.50,4.50,4.50,4.50,4.50,4.50,4.50,4.50,4.50,4.50,4.50,4.50,4.50"
					( Origin gBackEnd )
				)
				( attribute "MAX_LINE_WIDTH" "4.50,4.50,4.50,4.50,4.50,4.50,4.50,4.50,4.50,4.50,4.50,4.50,4.50,4.50"
					( Origin gBackEnd )
				)
				( attribute "DIFFP_NECK_GAP" "4.00,4.00,4.00,4.00,4.00,4.00,4.00,4.00,4.00,4.00,4.00,4.00,4.00,4.00"
					( Origin gBackEnd )
				)
				( attribute "MIN_NECK_WIDTH" "3.50,3.50,3.50,3.50,3.50,3.50,3.50,3.50,3.50,3.50,3.50,3.50,3.50,3.50"
					( Origin gBackEnd )
				)
				( attribute "MAXIMUM_NECK_LENGTH" "1200.00,1200.00,1200.00,1200.00,1200.00,1200.00,1200.00,1200.00,1200.00,1200.00,1200.00,1200.00,1200.00,1200.00"
					( Origin gBackEnd )
				)
				( attribute "VIA_LIST" "V_C20P10AP28,V_C20P10C26AP28_TP,V_C20P10AP28_TP,TP_C26B,TP_C30T,R20X5R20X7D16S,R20X5R20X7D16SB"
					( Origin gBackEnd )
				)
				( attribute "ALLOW_ON_ETCH_SUBCLASS" "TRUE,FALSE,TRUE,FALSE,TRUE,FALSE,FALSE,FALSE,FALSE,TRUE,FALSE,TRUE,FALSE,TRUE"
					( Origin gBackEnd )
				)
				( attribute "TS_ALLOWED" "ANYWHERE,ANYWHERE,ANYWHERE,ANYWHERE,ANYWHERE,ANYWHERE,ANYWHERE,ANYWHERE,ANYWHERE,ANYWHERE,ANYWHERE,ANYWHERE,ANYWHERE,ANYWHERE"
					( Origin gBackEnd )
				)
				( attribute "MIN_BVIA_STAGGER" "5.00,5.00,5.00,5.00,5.00,5.00,5.00,5.00,5.00,5.00,5.00,5.00,5.00,5.00"
					( Origin gBackEnd )
				)
				( attribute "MAX_BVIA_STAGGER" "0.00,0.00,0.00,0.00,0.00,0.00,0.00,0.00,0.00,0.00,0.00,0.00,0.00,0.00"
					( Origin gBackEnd )
				)
				( attribute "PAD_PAD_DIRECT_CONNECT" "ALL_ALLOWED,ALL_ALLOWED,ALL_ALLOWED,ALL_ALLOWED,ALL_ALLOWED,ALL_ALLOWED,ALL_ALLOWED,ALL_ALLOWED,ALL_ALLOWED,ALL_ALLOWED,ALL_ALLOWED,ALL_ALLOWED,ALL_ALLOWED,ALL_ALLOWED"
					( Origin gBackEnd )
				)
				( objectStatus "85_OHM_DIFF_EV_CLOCKS" )
			)
			( physicalCSet "@crescent_city_bb_fab1_lib.crescent_city_bb_fab1(sch_1):\VR_MISC_SIG\"
				( attribute "DIFFP_PRIMARY_GAP" "0.00,0.00,0.00,0.00,0.00,0.00,0.00,0.00,0.00,0.00,0.00,0.00,0.00,0.00"
					( Origin gBackEnd )
				)
				( attribute "DIFFP_COUPLED_PLUS" "0.00,0.00,0.00,0.00,0.00,0.00,0.00,0.00,0.00,0.00,0.00,0.00,0.00,0.00"
					( Origin gBackEnd )
				)
				( attribute "DIFFP_COUPLED_MINUS" "0.00,0.00,0.00,0.00,0.00,0.00,0.00,0.00,0.00,0.00,0.00,0.00,0.00,0.00"
					( Origin gBackEnd )
				)
				( attribute "DIFFP_MIN_SPACE" "0.00,0.00,0.00,0.00,0.00,0.00,0.00,0.00,0.00,0.00,0.00,0.00,0.00,0.00"
					( Origin gBackEnd )
				)
				( attribute "MIN_LINE_WIDTH" "4.00,5.00,4.50,5.00,4.50,5.00,5.00,5.00,5.00,4.50,5.00,4.50,5.00,4.50"
					( Origin gBackEnd )
				)
				( attribute "MAX_LINE_WIDTH" "30.00,30.00,30.00,30.00,30.00,30.00,30.00,30.00,30.00,30.00,30.00,30.00,30.00,30.00"
					( Origin gBackEnd )
				)
				( attribute "DIFFP_NECK_GAP" "0.00,0.00,0.00,0.00,0.00,0.00,0.00,0.00,0.00,0.00,0.00,0.00,0.00,0.00"
					( Origin gBackEnd )
				)
				( attribute "MIN_NECK_WIDTH" "4.00,5.00,4.50,5.00,4.50,5.00,5.00,5.00,5.00,4.50,5.00,4.50,5.00,4.50"
					( Origin gBackEnd )
				)
				( attribute "MAXIMUM_NECK_LENGTH" "0.00,0.00,0.00,0.00,0.00,0.00,0.00,0.00,0.00,0.00,0.00,0.00,0.00,0.00"
					( Origin gBackEnd )
				)
				( attribute "VIA_LIST" "V_C20P10AP28,V_C20P10C26AP28_TP,V_C20P10AP28_TP,TP_C26B,TP_C30T,R20X5R20X7D16S,R20X5R20X7D16SB"
					( Origin gBackEnd )
				)
				( attribute "ALLOW_ON_ETCH_SUBCLASS" "TRUE,TRUE,TRUE,TRUE,TRUE,TRUE,TRUE,TRUE,TRUE,TRUE,TRUE,TRUE,TRUE,TRUE"
					( Origin gBackEnd )
				)
				( attribute "TS_ALLOWED" "ANYWHERE,ANYWHERE,ANYWHERE,ANYWHERE,ANYWHERE,ANYWHERE,ANYWHERE,ANYWHERE,ANYWHERE,ANYWHERE,ANYWHERE,ANYWHERE,ANYWHERE,ANYWHERE"
					( Origin gBackEnd )
				)
				( attribute "MIN_BVIA_STAGGER" "5.00,5.00,5.00,5.00,5.00,5.00,5.00,5.00,5.00,5.00,5.00,5.00,5.00,5.00"
					( Origin gBackEnd )
				)
				( attribute "MAX_BVIA_STAGGER" "0.00,0.00,0.00,0.00,0.00,0.00,0.00,0.00,0.00,0.00,0.00,0.00,0.00,0.00"
					( Origin gBackEnd )
				)
				( attribute "PAD_PAD_DIRECT_CONNECT" "ALL_ALLOWED,ALL_ALLOWED,ALL_ALLOWED,ALL_ALLOWED,ALL_ALLOWED,ALL_ALLOWED,ALL_ALLOWED,ALL_ALLOWED,ALL_ALLOWED,ALL_ALLOWED,ALL_ALLOWED,ALL_ALLOWED,ALL_ALLOWED,ALL_ALLOWED"
					( Origin gBackEnd )
				)
				( objectStatus "VR_MISC_SIG" )
			)
			( physicalCSet "@crescent_city_bb_fab1_lib.crescent_city_bb_fab1(sch_1):\4_MIL\"
				( attribute "DIFFP_PRIMARY_GAP" "0.00,0.00,0.00,0.00,0.00,0.00,0.00,0.00,0.00,0.00,0.00,0.00,0.00,0.00"
					( Origin gBackEnd )
				)
				( attribute "DIFFP_COUPLED_PLUS" "0.00,0.00,0.00,0.00,0.00,0.00,0.00,0.00,0.00,0.00,0.00,0.00,0.00,0.00"
					( Origin gBackEnd )
				)
				( attribute "DIFFP_COUPLED_MINUS" "0.00,0.00,0.00,0.00,0.00,0.00,0.00,0.00,0.00,0.00,0.00,0.00,0.00,0.00"
					( Origin gBackEnd )
				)
				( attribute "DIFFP_MIN_SPACE" "0.00,0.00,0.00,0.00,0.00,0.00,0.00,0.00,0.00,0.00,0.00,0.00,0.00,0.00"
					( Origin gBackEnd )
				)
				( attribute "MIN_LINE_WIDTH" "4.00,4.00,4.00,4.00,4.00,4.00,4.00,4.00,4.00,4.00,4.00,4.00,4.00,4.00"
					( Origin gBackEnd )
				)
				( attribute "MAX_LINE_WIDTH" "25.00,25.00,25.00,25.00,25.00,25.00,25.00,25.00,25.00,25.00,25.00,25.00,25.00,25.00"
					( Origin gBackEnd )
				)
				( attribute "DIFFP_NECK_GAP" "0.00,0.00,0.00,0.00,0.00,0.00,0.00,0.00,0.00,0.00,0.00,0.00,0.00,0.00"
					( Origin gBackEnd )
				)
				( attribute "MIN_NECK_WIDTH" "3.50,3.50,3.50,3.50,3.50,3.50,3.50,3.50,3.50,3.50,3.50,3.50,3.50,3.50"
					( Origin gBackEnd )
				)
				( attribute "MAXIMUM_NECK_LENGTH" "800.00,800.00,800.00,800.00,800.00,800.00,800.00,800.00,800.00,800.00,800.00,800.00,800.00,800.00"
					( Origin gBackEnd )
				)
				( attribute "VIA_LIST" "V_C20P10AP28,V_C20P10C26AP28_TP,V_C20P10AP28_TP,TP_C26B,TP_C30T,R20X5R20X7D16S,R20X5R20X7D16SB"
					( Origin gBackEnd )
				)
				( attribute "ALLOW_ON_ETCH_SUBCLASS" "TRUE,TRUE,TRUE,TRUE,TRUE,TRUE,TRUE,TRUE,TRUE,TRUE,TRUE,TRUE,TRUE,TRUE"
					( Origin gBackEnd )
				)
				( attribute "TS_ALLOWED" "ANYWHERE,ANYWHERE,ANYWHERE,ANYWHERE,ANYWHERE,ANYWHERE,ANYWHERE,ANYWHERE,ANYWHERE,ANYWHERE,ANYWHERE,ANYWHERE,ANYWHERE,ANYWHERE"
					( Origin gBackEnd )
				)
				( attribute "MIN_BVIA_STAGGER" "5.00,5.00,5.00,5.00,5.00,5.00,5.00,5.00,5.00,5.00,5.00,5.00,5.00,5.00"
					( Origin gBackEnd )
				)
				( attribute "MAX_BVIA_STAGGER" "0.00,0.00,0.00,0.00,0.00,0.00,0.00,0.00,0.00,0.00,0.00,0.00,0.00,0.00"
					( Origin gBackEnd )
				)
				( attribute "PAD_PAD_DIRECT_CONNECT" "ALL_ALLOWED,ALL_ALLOWED,ALL_ALLOWED,ALL_ALLOWED,ALL_ALLOWED,ALL_ALLOWED,ALL_ALLOWED,ALL_ALLOWED,ALL_ALLOWED,ALL_ALLOWED,ALL_ALLOWED,ALL_ALLOWED,ALL_ALLOWED,ALL_ALLOWED"
					( Origin gBackEnd )
				)
				( objectStatus "4_MIL" )
			)
			( physicalCSet "@crescent_city_bb_fab1_lib.crescent_city_bb_fab1(sch_1):\4_MIL_W\"
				( attribute "DIFFP_PRIMARY_GAP" "0.00,0.00,0.00,0.00,0.00,0.00,0.00,0.00,0.00,0.00,0.00,0.00,0.00,0.00"
					( Origin gBackEnd )
				)
				( attribute "DIFFP_COUPLED_PLUS" "0.00,0.00,0.00,0.00,0.00,0.00,0.00,0.00,0.00,0.00,0.00,0.00,0.00,0.00"
					( Origin gBackEnd )
				)
				( attribute "DIFFP_COUPLED_MINUS" "0.00,0.00,0.00,0.00,0.00,0.00,0.00,0.00,0.00,0.00,0.00,0.00,0.00,0.00"
					( Origin gBackEnd )
				)
				( attribute "DIFFP_MIN_SPACE" "0.00,0.00,0.00,0.00,0.00,0.00,0.00,0.00,0.00,0.00,0.00,0.00,0.00,0.00"
					( Origin gBackEnd )
				)
				( attribute "MIN_LINE_WIDTH" "4.25,3.52,3.52,3.52,3.52,3.52,3.52,3.52,3.52,3.52,3.52,3.52,3.52,4.25"
					( Origin gBackEnd )
				)
				( attribute "MAX_LINE_WIDTH" "25.00,25.00,25.00,25.00,25.00,25.00,25.00,25.00,25.00,25.00,25.00,25.00,25.00,25.00"
					( Origin gBackEnd )
				)
				( attribute "DIFFP_NECK_GAP" "0.00,0.00,0.00,0.00,0.00,0.00,0.00,0.00,0.00,0.00,0.00,0.00,0.00,0.00"
					( Origin gBackEnd )
				)
				( attribute "MIN_NECK_WIDTH" "3.50,3.50,3.50,3.50,3.50,3.50,3.50,3.50,3.50,3.50,3.50,3.50,3.50,3.50"
					( Origin gBackEnd )
				)
				( attribute "MAXIMUM_NECK_LENGTH" "800.00,800.00,800.00,800.00,800.00,800.00,800.00,800.00,800.00,800.00,800.00,800.00,800.00,800.00"
					( Origin gBackEnd )
				)
				( attribute "VIA_LIST" "V_C20P10AP28,V_C20P10C26AP28_TP,V_C20P10AP28_TP,TP_C26B,TP_C30T,R20X5R20X7D16S,R20X5R20X7D16SB"
					( Origin gBackEnd )
				)
				( attribute "ALLOW_ON_ETCH_SUBCLASS" "TRUE,TRUE,TRUE,TRUE,TRUE,TRUE,TRUE,TRUE,TRUE,TRUE,TRUE,TRUE,TRUE,TRUE"
					( Origin gBackEnd )
				)
				( attribute "TS_ALLOWED" "ANYWHERE,ANYWHERE,ANYWHERE,ANYWHERE,ANYWHERE,ANYWHERE,ANYWHERE,ANYWHERE,ANYWHERE,ANYWHERE,ANYWHERE,ANYWHERE,ANYWHERE,ANYWHERE"
					( Origin gBackEnd )
				)
				( attribute "MIN_BVIA_STAGGER" "5.00,5.00,5.00,5.00,5.00,5.00,5.00,5.00,5.00,5.00,5.00,5.00,5.00,5.00"
					( Origin gBackEnd )
				)
				( attribute "MAX_BVIA_STAGGER" "0.00,0.00,0.00,0.00,0.00,0.00,0.00,0.00,0.00,0.00,0.00,0.00,0.00,0.00"
					( Origin gBackEnd )
				)
				( attribute "PAD_PAD_DIRECT_CONNECT" "ALL_ALLOWED,ALL_ALLOWED,ALL_ALLOWED,ALL_ALLOWED,ALL_ALLOWED,ALL_ALLOWED,ALL_ALLOWED,ALL_ALLOWED,ALL_ALLOWED,ALL_ALLOWED,ALL_ALLOWED,ALL_ALLOWED,ALL_ALLOWED,ALL_ALLOWED"
					( Origin gBackEnd )
				)
				( objectStatus "4_MIL_W" )
			)
			( physicalCSet "@crescent_city_bb_fab1_lib.crescent_city_bb_fab1(sch_1):\20MIL_W\"
				( attribute "DIFFP_PRIMARY_GAP" "500.00,500.00,500.00,500.00,500.00,500.00,500.00,500.00,500.00,500.00,500.00,500.00,500.00,500.00"
					( Origin gBackEnd )
				)
				( attribute "DIFFP_COUPLED_PLUS" "500.00,500.00,500.00,500.00,500.00,500.00,500.00,500.00,500.00,500.00,500.00,500.00,500.00,500.00"
					( Origin gBackEnd )
				)
				( attribute "DIFFP_COUPLED_MINUS" "500.00,500.00,500.00,500.00,500.00,500.00,500.00,500.00,500.00,500.00,500.00,500.00,500.00,500.00"
					( Origin gBackEnd )
				)
				( attribute "DIFFP_MIN_SPACE" "500.00,500.00,500.00,500.00,500.00,500.00,500.00,500.00,500.00,500.00,500.00,500.00,500.00,500.00"
					( Origin gBackEnd )
				)
				( attribute "MIN_LINE_WIDTH" "500.00,500.00,500.00,500.00,500.00,500.00,500.00,500.00,500.00,500.00,500.00,500.00,500.00,500.00"
					( Origin gBackEnd )
				)
				( attribute "MAX_LINE_WIDTH" "500.00,500.00,500.00,500.00,500.00,500.00,500.00,500.00,500.00,500.00,500.00,500.00,500.00,500.00"
					( Origin gBackEnd )
				)
				( attribute "DIFFP_NECK_GAP" "500.00,500.00,500.00,500.00,500.00,500.00,500.00,500.00,500.00,500.00,500.00,500.00,500.00,500.00"
					( Origin gBackEnd )
				)
				( attribute "MIN_NECK_WIDTH" "500.00,500.00,500.00,500.00,500.00,500.00,500.00,500.00,500.00,500.00,500.00,500.00,500.00,500.00"
					( Origin gBackEnd )
				)
				( attribute "MAXIMUM_NECK_LENGTH" "500.00,500.00,500.00,500.00,500.00,500.00,500.00,500.00,500.00,500.00,500.00,500.00,500.00,500.00"
					( Origin gBackEnd )
				)
				( attribute "VIA_LIST" "V_C20P10AP28,V_C20P10C26AP28_TP,V_C20P10AP28_TP,TP_C26B,TP_C30T,R20X5R20X7D16S,R20X5R20X7D16SB"
					( Origin gBackEnd )
				)
				( attribute "ALLOW_ON_ETCH_SUBCLASS" "TRUE,TRUE,TRUE,TRUE,TRUE,TRUE,TRUE,TRUE,TRUE,TRUE,TRUE,TRUE,TRUE,TRUE"
					( Origin gBackEnd )
				)
				( attribute "TS_ALLOWED" "ANYWHERE,ANYWHERE,ANYWHERE,ANYWHERE,ANYWHERE,ANYWHERE,ANYWHERE,ANYWHERE,ANYWHERE,ANYWHERE,ANYWHERE,ANYWHERE,ANYWHERE,ANYWHERE"
					( Origin gBackEnd )
				)
				( attribute "MIN_BVIA_STAGGER" "5.00,5.00,5.00,5.00,5.00,5.00,5.00,5.00,5.00,5.00,5.00,5.00,5.00,5.00"
					( Origin gBackEnd )
				)
				( attribute "MAX_BVIA_STAGGER" "5.00,5.00,5.00,5.00,5.00,5.00,5.00,5.00,5.00,5.00,5.00,5.00,5.00,5.00"
					( Origin gBackEnd )
				)
				( attribute "PAD_PAD_DIRECT_CONNECT" "ALL_ALLOWED,ALL_ALLOWED,ALL_ALLOWED,ALL_ALLOWED,ALL_ALLOWED,ALL_ALLOWED,ALL_ALLOWED,ALL_ALLOWED,ALL_ALLOWED,ALL_ALLOWED,ALL_ALLOWED,ALL_ALLOWED,ALL_ALLOWED,ALL_ALLOWED"
					( Origin gBackEnd )
				)
				( objectStatus "20MIL_W" )
			)
			( physicalCSet "@crescent_city_bb_fab1_lib.crescent_city_bb_fab1(sch_1):\BGA_BO_DIFF_83_MS_&_85_SL\"
				( attribute "DIFFP_PRIMARY_GAP" "4.10,4.10,4.10,4.10,4.10,4.10,4.10,4.10,4.10,4.10,4.10,4.10,4.10,4.10"
					( Origin gBackEnd )
				)
				( attribute "DIFFP_COUPLED_PLUS" "0.01,0.01,0.01,0.01,0.01,0.01,0.01,0.01,0.01,0.01,0.01,0.01,0.01,0.01"
					( Origin gBackEnd )
				)
				( attribute "DIFFP_COUPLED_MINUS" "0.01,0.01,0.01,0.01,0.01,0.01,0.01,0.01,0.01,0.01,0.01,0.01,0.01,0.01"
					( Origin gBackEnd )
				)
				( attribute "DIFFP_MIN_SPACE" "3.90,3.90,3.90,3.90,3.90,3.90,3.90,3.90,3.90,3.90,3.90,3.90,3.90,3.90"
					( Origin gBackEnd )
				)
				( attribute "MIN_LINE_WIDTH" "3.90,3.90,3.90,3.90,3.90,3.90,3.90,3.90,3.90,3.90,3.90,3.90,3.90,3.90"
					( Origin gBackEnd )
				)
				( attribute "MAX_LINE_WIDTH" "5.00,5.00,5.00,5.00,5.00,5.00,5.00,5.00,5.00,5.00,5.00,5.00,5.00,5.00"
					( Origin gBackEnd )
				)
				( attribute "DIFFP_NECK_GAP" "4.00,4.00,4.00,4.00,4.00,4.00,4.00,4.00,4.00,4.00,4.00,4.00,4.00,4.00"
					( Origin gBackEnd )
				)
				( attribute "MIN_NECK_WIDTH" "3.50,3.50,3.50,3.50,3.50,3.50,3.50,3.50,3.50,3.50,3.50,3.50,3.50,3.50"
					( Origin gBackEnd )
				)
				( attribute "MAXIMUM_NECK_LENGTH" "1200.00,1200.00,1200.00,1200.00,1200.00,1200.00,1200.00,1200.00,1200.00,1200.00,1200.00,1200.00,1200.00,1200.00"
					( Origin gBackEnd )
				)
				( attribute "VIA_LIST" "V_C20P10AP28,V_C20P10C26AP28_TP,V_C20P10AP28_TP,TP_C26B,TP_C30T"
					( Origin gBackEnd )
				)
				( attribute "ALLOW_ON_ETCH_SUBCLASS" "TRUE,FALSE,TRUE,FALSE,TRUE,FALSE,FALSE,FALSE,FALSE,TRUE,FALSE,TRUE,FALSE,TRUE"
					( Origin gBackEnd )
				)
				( attribute "TS_ALLOWED" "ANYWHERE,ANYWHERE,ANYWHERE,ANYWHERE,ANYWHERE,ANYWHERE,ANYWHERE,ANYWHERE,ANYWHERE,ANYWHERE,ANYWHERE,ANYWHERE,ANYWHERE,ANYWHERE"
					( Origin gBackEnd )
				)
				( attribute "MIN_BVIA_STAGGER" "5.00,5.00,5.00,5.00,5.00,5.00,5.00,5.00,5.00,5.00,5.00,5.00,5.00,5.00"
					( Origin gBackEnd )
				)
				( attribute "MAX_BVIA_STAGGER" "0.00,0.00,0.00,0.00,0.00,0.00,0.00,0.00,0.00,0.00,0.00,0.00,0.00,0.00"
					( Origin gBackEnd )
				)
				( attribute "PAD_PAD_DIRECT_CONNECT" "ALL_ALLOWED,ALL_ALLOWED,ALL_ALLOWED,ALL_ALLOWED,ALL_ALLOWED,ALL_ALLOWED,ALL_ALLOWED,ALL_ALLOWED,ALL_ALLOWED,ALL_ALLOWED,ALL_ALLOWED,ALL_ALLOWED,ALL_ALLOWED,ALL_ALLOWED"
					( Origin gBackEnd )
				)
				( objectStatus "BGA_BO_DIFF_83_MS_&_85_SL" )
			)
			( physicalCSet "@sapphirecity_baseboard_lib.sapphirecity_baseboard(sch_1):\10_MILS-SE-DEBUG\"
				( attribute "DIFFP_PRIMARY_GAP" "0.00,0.00,0.00,0.00,0.00,0.00,0.00,0.00,0.00,0.00,0.00,0.00,0.00,0.00"
					( Origin gBackEnd )
				)
				( attribute "DIFFP_COUPLED_PLUS" "0.00,0.00,0.00,0.00,0.00,0.00,0.00,0.00,0.00,0.00,0.00,0.00,0.00,0.00"
					( Origin gBackEnd )
				)
				( attribute "DIFFP_COUPLED_MINUS" "0.00,0.00,0.00,0.00,0.00,0.00,0.00,0.00,0.00,0.00,0.00,0.00,0.00,0.00"
					( Origin gBackEnd )
				)
				( attribute "DIFFP_MIN_SPACE" "0.00,0.00,0.00,0.00,0.00,0.00,0.00,0.00,0.00,0.00,0.00,0.00,0.00,0.00"
					( Origin gBackEnd )
				)
				( attribute "MIN_LINE_WIDTH" "10.00,10.00,10.00,10.00,10.00,10.00,10.00,10.00,10.00,10.00,10.00,10.00,10.00,10.00"
					( Origin gBackEnd )
				)
				( attribute "MAX_LINE_WIDTH" "30.00,30.00,30.00,30.00,30.00,30.00,30.00,30.00,30.00,30.00,30.00,30.00,30.00,30.00"
					( Origin gBackEnd )
				)
				( attribute "DIFFP_NECK_GAP" "0.00,0.00,0.00,0.00,0.00,0.00,0.00,0.00,0.00,0.00,0.00,0.00,0.00,0.00"
					( Origin gBackEnd )
				)
				( attribute "MIN_NECK_WIDTH" "4.00,4.00,4.00,4.00,4.00,4.00,4.00,4.00,4.00,4.00,4.00,4.00,4.00,4.00"
					( Origin gBackEnd )
				)
				( attribute "MAXIMUM_NECK_LENGTH" "250.00,250.00,250.00,250.00,250.00,250.00,250.00,250.00,250.00,250.00,250.00,250.00,250.00,250.00"
					( Origin gBackEnd )
				)
				( attribute "VIA_LIST" "V_C20P10AP28,V_C20P10C26AP28_TP,V_C20P10AP28_TP,TP_C26B,TP_C30T,R20X5R20X7D16S,R20X5R20X7D16SB"
					( Origin gBackEnd )
				)
				( attribute "ALLOW_ON_ETCH_SUBCLASS" "TRUE,FALSE,TRUE,FALSE,TRUE,FALSE,FALSE,FALSE,FALSE,TRUE,FALSE,TRUE,FALSE,TRUE"
					( Origin gBackEnd )
				)
				( attribute "TS_ALLOWED" "ANYWHERE,ANYWHERE,ANYWHERE,ANYWHERE,ANYWHERE,ANYWHERE,ANYWHERE,ANYWHERE,ANYWHERE,ANYWHERE,ANYWHERE,ANYWHERE,ANYWHERE,ANYWHERE"
					( Origin gBackEnd )
				)
				( attribute "MIN_BVIA_STAGGER" "5.00,5.00,5.00,5.00,5.00,5.00,5.00,5.00,5.00,5.00,5.00,5.00,5.00,5.00"
					( Origin gBackEnd )
				)
				( attribute "MAX_BVIA_STAGGER" "0.00,0.00,0.00,0.00,0.00,0.00,0.00,0.00,0.00,0.00,0.00,0.00,0.00,0.00"
					( Origin gBackEnd )
				)
				( attribute "PAD_PAD_DIRECT_CONNECT" "ALL_ALLOWED,ALL_ALLOWED,ALL_ALLOWED,ALL_ALLOWED,ALL_ALLOWED,ALL_ALLOWED,ALL_ALLOWED,ALL_ALLOWED,ALL_ALLOWED,ALL_ALLOWED,ALL_ALLOWED,ALL_ALLOWED,ALL_ALLOWED,ALL_ALLOWED"
					( Origin gBackEnd )
				)
				( objectStatus "10_MILS-SE-DEBUG" )
			)
			( physicalCSet "@sapphirecity_baseboard_lib.sapphirecity_baseboard(sch_1):\40_OHM_US_AND_38_OHM_SL\"
				( attribute "DIFFP_PRIMARY_GAP" "5.00,5.00,5.00,5.00,5.00,5.00,5.00,5.00,5.00,5.00,5.00,5.00,5.00,5.00"
					( Origin gBackEnd )
				)
				( attribute "DIFFP_COUPLED_PLUS" "0.00,0.00,0.00,0.00,0.00,0.00,0.00,0.00,0.00,0.00,0.00,0.00,0.00,0.00"
					( Origin gBackEnd )
				)
				( attribute "DIFFP_COUPLED_MINUS" "0.00,0.00,0.00,0.00,0.00,0.00,0.00,0.00,0.00,0.00,0.00,0.00,0.00,0.00"
					( Origin gBackEnd )
				)
				( attribute "DIFFP_MIN_SPACE" "4.00,4.00,4.00,4.00,4.00,4.00,4.00,4.00,4.00,4.00,4.00,4.00,4.00,4.00"
					( Origin gBackEnd )
				)
				( attribute "MIN_LINE_WIDTH" "6.50,5.60,5.60,5.60,5.60,5.60,5.60,5.60,5.60,5.60,5.60,5.60,5.60,6.50"
					( Origin gBackEnd )
				)
				( attribute "MAX_LINE_WIDTH" "6.50,5.60,5.60,5.60,5.60,5.60,5.60,5.60,5.60,5.60,5.60,5.60,5.60,6.50"
					( Origin gBackEnd )
				)
				( attribute "DIFFP_NECK_GAP" "0.00,0.00,0.00,0.00,0.00,0.00,0.00,0.00,0.00,0.00,0.00,0.00,0.00,0.00"
					( Origin gBackEnd )
				)
				( attribute "MIN_NECK_WIDTH" "3.50,3.50,3.50,3.50,3.50,3.50,3.50,3.50,3.50,3.50,3.50,3.50,3.50,3.50"
					( Origin gBackEnd )
				)
				( attribute "MAXIMUM_NECK_LENGTH" "2000.00,2000.00,2000.00,2000.00,2000.00,2000.00,2000.00,2000.00,2000.00,2000.00,2000.00,2000.00,2000.00,2000.00"
					( Origin gBackEnd )
				)
				( attribute "VIA_LIST" "V_C20P10AP28,V_C20P10C26AP28_TP,V_C20P10AP28_TP,TP_C26B,TP_C30T,R20X5R20X7D16S,R20X5R20X7D16SB"
					( Origin gBackEnd )
				)
				( attribute "ALLOW_ON_ETCH_SUBCLASS" "TRUE,TRUE,TRUE,TRUE,TRUE,TRUE,TRUE,TRUE,TRUE,TRUE,TRUE,TRUE,TRUE,TRUE"
					( Origin gBackEnd )
				)
				( attribute "TS_ALLOWED" "ANYWHERE,ANYWHERE,ANYWHERE,ANYWHERE,ANYWHERE,ANYWHERE,ANYWHERE,ANYWHERE,ANYWHERE,ANYWHERE,ANYWHERE,ANYWHERE,ANYWHERE,ANYWHERE"
					( Origin gBackEnd )
				)
				( attribute "MIN_BVIA_STAGGER" "5.00,5.00,5.00,5.00,5.00,5.00,5.00,5.00,5.00,5.00,5.00,5.00,5.00,5.00"
					( Origin gBackEnd )
				)
				( attribute "MAX_BVIA_STAGGER" "0.00,0.00,0.00,0.00,0.00,0.00,0.00,0.00,0.00,0.00,0.00,0.00,0.00,0.00"
					( Origin gBackEnd )
				)
				( attribute "PAD_PAD_DIRECT_CONNECT" "ALL_ALLOWED,ALL_ALLOWED,ALL_ALLOWED,ALL_ALLOWED,ALL_ALLOWED,ALL_ALLOWED,ALL_ALLOWED,ALL_ALLOWED,ALL_ALLOWED,ALL_ALLOWED,ALL_ALLOWED,ALL_ALLOWED,ALL_ALLOWED,ALL_ALLOWED"
					( Origin gBackEnd )
				)
				( objectStatus "40-OHM_US_&_38-OHM_SL_SE" )
			)
			( physicalCSet "@sapphirecity_baseboard_lib.sapphirecity_baseboard(sch_1):\DDR4_DQ_CAC_STB_CMP\"
				( attribute "DIFFP_PRIMARY_GAP" "5.00,4.50,4.50,4.50,4.50,4.50,4.50,4.50,4.50,4.50,4.50,4.50,4.50,5.00"
					( Origin gBackEnd )
				)
				( attribute "DIFFP_COUPLED_PLUS" "0.00,0.00,0.00,0.00,0.00,0.00,0.00,0.00,0.00,0.00,0.00,0.00,0.00,0.00"
					( Origin gBackEnd )
				)
				( attribute "DIFFP_COUPLED_MINUS" "0.00,0.00,0.00,0.00,0.00,0.00,0.00,0.00,0.00,0.00,0.00,0.00,0.00,0.00"
					( Origin gBackEnd )
				)
				( attribute "DIFFP_MIN_SPACE" "3.99,3.99,3.99,3.99,3.99,3.99,3.99,3.99,3.99,3.99,3.99,3.99,3.99,3.99"
					( Origin gBackEnd )
				)
				( attribute "MIN_LINE_WIDTH" "4.50,8.00,8.00,8.00,8.00,8.00,8.00,8.00,8.00,8.00,8.00,8.00,8.00,4.50"
					( Origin gBackEnd )
				)
				( attribute "MAX_LINE_WIDTH" "4.50,8.00,8.00,8.00,8.00,8.00,8.00,8.00,8.00,8.00,8.00,8.00,8.00,4.50"
					( Origin gBackEnd )
				)
				( attribute "DIFFP_NECK_GAP" "4.00,4.00,4.00,4.00,4.00,4.00,4.00,4.00,4.00,4.00,4.00,4.00,4.00,4.00"
					( Origin gBackEnd )
				)
				( attribute "MIN_NECK_WIDTH" "4.00,3.50,3.50,3.50,3.50,3.50,3.50,3.50,3.50,3.50,3.50,3.50,3.50,3.50"
					( Origin gBackEnd )
				)
				( attribute "MAXIMUM_NECK_LENGTH" "1000.00,1000.00,1000.00,1000.00,1000.00,1000.00,1000.00,1000.00,1000.00,1000.00,1000.00,1000.00,1000.00,1000.00"
					( Origin gBackEnd )
				)
				( attribute "VIA_LIST" "V_C20P10AP28,V_C20P10C26AP28_TP,V_C20P10AP28_TP,TP_C26B,TP_C30T"
					( Origin gBackEnd )
				)
				( attribute "ALLOW_ON_ETCH_SUBCLASS" "TRUE,TRUE,TRUE,TRUE,TRUE,TRUE,TRUE,TRUE,TRUE,TRUE,TRUE,TRUE,TRUE,TRUE"
					( Origin gBackEnd )
				)
				( attribute "TS_ALLOWED" "ANYWHERE,ANYWHERE,ANYWHERE,ANYWHERE,ANYWHERE,ANYWHERE,ANYWHERE,ANYWHERE,ANYWHERE,ANYWHERE,ANYWHERE,ANYWHERE,ANYWHERE,ANYWHERE"
					( Origin gBackEnd )
				)
				( attribute "MIN_BVIA_STAGGER" "5.00,5.00,5.00,5.00,5.00,5.00,5.00,5.00,5.00,5.00,5.00,5.00,5.00,5.00"
					( Origin gBackEnd )
				)
				( attribute "MAX_BVIA_STAGGER" "0.00,0.00,0.00,0.00,0.00,0.00,0.00,0.00,0.00,0.00,0.00,0.00,0.00,0.00"
					( Origin gBackEnd )
				)
				( attribute "PAD_PAD_DIRECT_CONNECT" "ALL_ALLOWED,ALL_ALLOWED,ALL_ALLOWED,ALL_ALLOWED,ALL_ALLOWED,ALL_ALLOWED,ALL_ALLOWED,ALL_ALLOWED,ALL_ALLOWED,ALL_ALLOWED,ALL_ALLOWED,ALL_ALLOWED,ALL_ALLOWED,ALL_ALLOWED"
					( Origin gBackEnd )
				)
				( objectStatus "DDR4_DQ_CAC_STB_CMP" )
			)
			( physicalCSet "@sapphirecity_baseboard_lib.sapphirecity_baseboard(sch_1):\DDR4_DQS_CLK_DIFF_STB_CMP\"
				( attribute "DIFFP_PRIMARY_GAP" "5.00,4.50,4.50,4.50,4.50,4.50,4.50,4.50,4.50,4.50,4.50,4.50,4.50,5.00"
					( Origin gBackEnd )
				)
				( attribute "DIFFP_COUPLED_PLUS" "0.00,0.00,0.00,0.00,0.00,0.00,0.00,0.00,0.00,0.00,0.00,0.00,0.00,0.00"
					( Origin gBackEnd )
				)
				( attribute "DIFFP_COUPLED_MINUS" "0.00,0.00,0.00,0.00,0.00,0.00,0.00,0.00,0.00,0.00,0.00,0.00,0.00,0.00"
					( Origin gBackEnd )
				)
				( attribute "DIFFP_MIN_SPACE" "3.99,3.99,3.99,3.99,3.99,3.99,3.99,3.99,3.99,3.99,3.99,3.99,3.99,3.99"
					( Origin gBackEnd )
				)
				( attribute "MIN_LINE_WIDTH" "4.50,8.00,8.00,8.00,8.00,8.00,8.00,8.00,8.00,8.00,8.00,8.00,8.00,4.50"
					( Origin gBackEnd )
				)
				( attribute "MAX_LINE_WIDTH" "4.50,8.00,8.00,8.00,8.00,8.00,8.00,8.00,8.00,8.00,8.00,8.00,8.00,4.50"
					( Origin gBackEnd )
				)
				( attribute "DIFFP_NECK_GAP" "4.00,4.00,4.00,4.00,4.00,4.00,4.00,4.00,4.00,4.00,4.00,4.00,4.00,4.00"
					( Origin gBackEnd )
				)
				( attribute "MIN_NECK_WIDTH" "4.00,3.50,3.50,3.50,3.50,3.50,3.50,3.50,3.50,3.50,3.50,3.50,3.50,3.50"
					( Origin gBackEnd )
				)
				( attribute "MAXIMUM_NECK_LENGTH" "1000.00,1000.00,1000.00,1000.00,1000.00,1000.00,1000.00,1000.00,1000.00,1000.00,1000.00,1000.00,1000.00,1000.00"
					( Origin gBackEnd )
				)
				( attribute "VIA_LIST" "V_C20P10AP28,V_C20P10C26AP28_TP,V_C20P10AP28_TP,TP_C26B,TP_C30T"
					( Origin gBackEnd )
				)
				( attribute "ALLOW_ON_ETCH_SUBCLASS" "TRUE,TRUE,TRUE,TRUE,TRUE,TRUE,TRUE,TRUE,TRUE,TRUE,TRUE,TRUE,TRUE,TRUE"
					( Origin gBackEnd )
				)
				( attribute "TS_ALLOWED" "ANYWHERE,ANYWHERE,ANYWHERE,ANYWHERE,ANYWHERE,ANYWHERE,ANYWHERE,ANYWHERE,ANYWHERE,ANYWHERE,ANYWHERE,ANYWHERE,ANYWHERE,ANYWHERE"
					( Origin gBackEnd )
				)
				( attribute "MIN_BVIA_STAGGER" "5.00,5.00,5.00,5.00,5.00,5.00,5.00,5.00,5.00,5.00,5.00,5.00,5.00,5.00"
					( Origin gBackEnd )
				)
				( attribute "MAX_BVIA_STAGGER" "0.00,0.00,0.00,0.00,0.00,0.00,0.00,0.00,0.00,0.00,0.00,0.00,0.00,0.00"
					( Origin gBackEnd )
				)
				( attribute "PAD_PAD_DIRECT_CONNECT" "ALL_ALLOWED,ALL_ALLOWED,ALL_ALLOWED,ALL_ALLOWED,ALL_ALLOWED,ALL_ALLOWED,ALL_ALLOWED,ALL_ALLOWED,ALL_ALLOWED,ALL_ALLOWED,ALL_ALLOWED,ALL_ALLOWED,ALL_ALLOWED,ALL_ALLOWED"
					( Origin gBackEnd )
				)
				( objectStatus "DDR4_DQS_CLK_DIFF_STB_CMP" )
			)
			( physicalCSet "@sapphirecity_baseboard_lib.sapphirecity_baseboard(sch_1):\DDR4_STUBBY_TIGHT_MICROSTRIP\"
				( attribute "DIFFP_PRIMARY_GAP" "0.00,0.00,0.00,0.00,0.00,0.00,0.00,0.00,0.00,0.00,0.00,0.00,0.00,0.00"
					( Origin gBackEnd )
				)
				( attribute "DIFFP_COUPLED_PLUS" "0.00,0.00,0.00,0.00,0.00,0.00,0.00,0.00,0.00,0.00,0.00,0.00,0.00,0.00"
					( Origin gBackEnd )
				)
				( attribute "DIFFP_COUPLED_MINUS" "0.00,0.00,0.00,0.00,0.00,0.00,0.00,0.00,0.00,0.00,0.00,0.00,0.00,0.00"
					( Origin gBackEnd )
				)
				( attribute "DIFFP_MIN_SPACE" "0.00,0.00,0.00,0.00,0.00,0.00,0.00,0.00,0.00,0.00,0.00,0.00,0.00,0.00"
					( Origin gBackEnd )
				)
				( attribute "MIN_LINE_WIDTH" "4.00,4.00,4.00,4.00,4.00,4.00,4.00,4.00,4.00,4.00,4.00,4.00,4.00,4.00"
					( Origin gBackEnd )
				)
				( attribute "MAX_LINE_WIDTH" "4.00,4.00,4.00,4.00,4.00,4.00,4.00,4.00,4.00,4.00,4.00,4.00,4.00,4.00"
					( Origin gBackEnd )
				)
				( attribute "DIFFP_NECK_GAP" "0.00,0.00,0.00,0.00,0.00,0.00,0.00,0.00,0.00,0.00,0.00,0.00,0.00,0.00"
					( Origin gBackEnd )
				)
				( attribute "MIN_NECK_WIDTH" "3.50,3.50,3.50,3.50,3.50,3.50,3.50,3.50,3.50,3.50,3.50,3.50,3.50,3.50"
					( Origin gBackEnd )
				)
				( attribute "MAXIMUM_NECK_LENGTH" "1000.00,1000.00,1000.00,1000.00,1000.00,1000.00,1000.00,1000.00,1000.00,1000.00,1000.00,1000.00,1000.00,1000.00"
					( Origin gBackEnd )
				)
				( attribute "VIA_LIST" "V_C20P10AP28,V_C20P10C26AP28_TP,V_C20P10AP28_TP,TP_C26B,TP_C30T"
					( Origin gBackEnd )
				)
				( attribute "ALLOW_ON_ETCH_SUBCLASS" "TRUE,TRUE,TRUE,TRUE,TRUE,TRUE,TRUE,TRUE,TRUE,TRUE,TRUE,TRUE,TRUE,TRUE"
					( Origin gBackEnd )
				)
				( attribute "TS_ALLOWED" "ANYWHERE,ANYWHERE,ANYWHERE,ANYWHERE,ANYWHERE,ANYWHERE,ANYWHERE,ANYWHERE,ANYWHERE,ANYWHERE,ANYWHERE,ANYWHERE,ANYWHERE,ANYWHERE"
					( Origin gBackEnd )
				)
				( attribute "MIN_BVIA_STAGGER" "5.00,5.00,5.00,5.00,5.00,5.00,5.00,5.00,5.00,5.00,5.00,5.00,5.00,5.00"
					( Origin gBackEnd )
				)
				( attribute "MAX_BVIA_STAGGER" "0.00,0.00,0.00,0.00,0.00,0.00,0.00,0.00,0.00,0.00,0.00,0.00,0.00,0.00"
					( Origin gBackEnd )
				)
				( attribute "PAD_PAD_DIRECT_CONNECT" "ALL_ALLOWED,ALL_ALLOWED,ALL_ALLOWED,ALL_ALLOWED,ALL_ALLOWED,ALL_ALLOWED,ALL_ALLOWED,ALL_ALLOWED,ALL_ALLOWED,ALL_ALLOWED,ALL_ALLOWED,ALL_ALLOWED,ALL_ALLOWED,ALL_ALLOWED"
					( Origin gBackEnd )
				)
				( objectStatus "DDR4_STUBBY_TIGHT_MICROSTRIP" )
			)
			( physicalCSet "@sapphirecity_baseboard_lib.sapphirecity_baseboard(sch_1):\PCI\"
				( attribute "DIFFP_PRIMARY_GAP" "7.00,0.00,6.50,0.00,6.50,0.00,0.00,0.00,0.00,6.50,0.00,6.50,0.00,7.00"
					( Origin gBackEnd )
				)
				( attribute "DIFFP_COUPLED_PLUS" "0.05,0.10,0.05,0.10,0.05,0.10,0.10,0.10,0.10,0.05,0.10,0.05,0.10,0.05"
					( Origin gBackEnd )
				)
				( attribute "DIFFP_COUPLED_MINUS" "0.05,0.10,0.05,0.10,0.05,0.10,0.10,0.10,0.10,0.05,0.10,0.05,0.10,0.05"
					( Origin gBackEnd )
				)
				( attribute "DIFFP_MIN_SPACE" "3.90,3.90,3.90,3.90,3.90,3.90,3.90,3.90,3.90,3.90,3.90,3.90,3.90,3.90"
					( Origin gBackEnd )
				)
				( attribute "MIN_LINE_WIDTH" "5.00,5.00,5.00,5.00,5.00,5.00,5.00,5.00,5.00,5.00,5.00,5.00,5.00,5.00"
					( Origin gBackEnd )
				)
				( attribute "MAX_LINE_WIDTH" "5.00,5.00,5.00,5.00,5.00,5.00,5.00,5.00,5.00,5.00,5.00,5.00,5.00,5.00"
					( Origin gBackEnd )
				)
				( attribute "DIFFP_NECK_GAP" "4.00,4.00,4.00,4.00,4.00,4.00,4.00,4.00,4.00,4.00,4.00,4.00,4.00,4.00"
					( Origin gBackEnd )
				)
				( attribute "MIN_NECK_WIDTH" "3.50,3.50,3.50,3.50,3.50,3.50,3.50,3.50,3.50,3.50,3.50,3.50,3.50,3.50"
					( Origin gBackEnd )
				)
				( attribute "MAXIMUM_NECK_LENGTH" "1200.00,1200.00,1200.00,1200.00,1200.00,1200.00,1200.00,1200.00,1200.00,1200.00,1200.00,1200.00,1200.00,1200.00"
					( Origin gBackEnd )
				)
				( attribute "VIA_LIST" "V_C20P10AP28,V_C20P10C26AP28_TP,V_C20P10AP28_TP,TP_C26B,TP_C30T,R20X5R20X7D16S,R20X5R20X7D16SB"
					( Origin gBackEnd )
				)
				( attribute "ALLOW_ON_ETCH_SUBCLASS" "TRUE,FALSE,TRUE,FALSE,TRUE,FALSE,FALSE,FALSE,FALSE,TRUE,FALSE,TRUE,FALSE,TRUE"
					( Origin gBackEnd )
				)
				( attribute "TS_ALLOWED" "ANYWHERE,ANYWHERE,ANYWHERE,ANYWHERE,ANYWHERE,ANYWHERE,ANYWHERE,ANYWHERE,ANYWHERE,ANYWHERE,ANYWHERE,ANYWHERE,ANYWHERE,ANYWHERE"
					( Origin gBackEnd )
				)
				( attribute "MIN_BVIA_STAGGER" "5.00,5.00,5.00,5.00,5.00,5.00,5.00,5.00,5.00,5.00,5.00,5.00,5.00,5.00"
					( Origin gBackEnd )
				)
				( attribute "MAX_BVIA_STAGGER" "0.00,0.00,0.00,0.00,0.00,0.00,0.00,0.00,0.00,0.00,0.00,0.00,0.00,0.00"
					( Origin gBackEnd )
				)
				( attribute "PAD_PAD_DIRECT_CONNECT" "ALL_ALLOWED,ALL_ALLOWED,ALL_ALLOWED,ALL_ALLOWED,ALL_ALLOWED,ALL_ALLOWED,ALL_ALLOWED,ALL_ALLOWED,ALL_ALLOWED,ALL_ALLOWED,ALL_ALLOWED,ALL_ALLOWED,ALL_ALLOWED,ALL_ALLOWED"
					( Origin gBackEnd )
				)
				( objectStatus "KTI" )
			)
			( physicalCSet "@sapphirecity_baseboard_lib.sapphirecity_baseboard(sch_1):\DDR4_STUBBY_MICROSTRIP\"
				( attribute "DIFFP_PRIMARY_GAP" "0.00,0.00,0.00,0.00,0.00,0.00,0.00,0.00,0.00,0.00,0.00,0.00,0.00,0.00"
					( Origin gBackEnd )
				)
				( attribute "DIFFP_COUPLED_PLUS" "0.00,0.00,0.00,0.00,0.00,0.00,0.00,0.00,0.00,0.00,0.00,0.00,0.00,0.00"
					( Origin gBackEnd )
				)
				( attribute "DIFFP_COUPLED_MINUS" "0.00,0.00,0.00,0.00,0.00,0.00,0.00,0.00,0.00,0.00,0.00,0.00,0.00,0.00"
					( Origin gBackEnd )
				)
				( attribute "DIFFP_MIN_SPACE" "0.00,0.00,0.00,0.00,0.00,0.00,0.00,0.00,0.00,0.00,0.00,0.00,0.00,0.00"
					( Origin gBackEnd )
				)
				( attribute "MIN_LINE_WIDTH" "4.50,4.50,4.50,4.50,4.50,4.50,4.50,4.50,4.50,4.50,4.50,4.50,4.50,4.50"
					( Origin gBackEnd )
				)
				( attribute "MAX_LINE_WIDTH" "4.50,4.50,4.50,4.50,4.50,4.50,4.50,4.50,4.50,4.50,4.50,4.50,4.50,4.50"
					( Origin gBackEnd )
				)
				( attribute "DIFFP_NECK_GAP" "0.00,0.00,0.00,0.00,0.00,0.00,0.00,0.00,0.00,0.00,0.00,0.00,0.00,0.00"
					( Origin gBackEnd )
				)
				( attribute "MIN_NECK_WIDTH" "3.50,3.50,3.50,3.50,3.50,3.50,3.50,3.50,3.50,3.50,3.50,3.50,3.50,3.50"
					( Origin gBackEnd )
				)
				( attribute "MAXIMUM_NECK_LENGTH" "1000.00,1000.00,1000.00,1000.00,1000.00,1000.00,1000.00,1000.00,1000.00,1000.00,1000.00,1000.00,1000.00,1000.00"
					( Origin gBackEnd )
				)
				( attribute "VIA_LIST" "V_C20P10AP28,V_C20P10C26AP28_TP,V_C20P10AP28_TP,TP_C26B,TP_C30T"
					( Origin gBackEnd )
				)
				( attribute "ALLOW_ON_ETCH_SUBCLASS" "TRUE,TRUE,TRUE,TRUE,TRUE,TRUE,TRUE,TRUE,TRUE,TRUE,TRUE,TRUE,TRUE,TRUE"
					( Origin gBackEnd )
				)
				( attribute "TS_ALLOWED" "ANYWHERE,ANYWHERE,ANYWHERE,ANYWHERE,ANYWHERE,ANYWHERE,ANYWHERE,ANYWHERE,ANYWHERE,ANYWHERE,ANYWHERE,ANYWHERE,ANYWHERE,ANYWHERE"
					( Origin gBackEnd )
				)
				( attribute "MIN_BVIA_STAGGER" "5.00,5.00,5.00,5.00,5.00,5.00,5.00,5.00,5.00,5.00,5.00,5.00,5.00,5.00"
					( Origin gBackEnd )
				)
				( attribute "MAX_BVIA_STAGGER" "0.00,0.00,0.00,0.00,0.00,0.00,0.00,0.00,0.00,0.00,0.00,0.00,0.00,0.00"
					( Origin gBackEnd )
				)
				( attribute "PAD_PAD_DIRECT_CONNECT" "ALL_ALLOWED,ALL_ALLOWED,ALL_ALLOWED,ALL_ALLOWED,ALL_ALLOWED,ALL_ALLOWED,ALL_ALLOWED,ALL_ALLOWED,ALL_ALLOWED,ALL_ALLOWED,ALL_ALLOWED,ALL_ALLOWED,ALL_ALLOWED,ALL_ALLOWED"
					( Origin gBackEnd )
				)
				( objectStatus "DDR4_STUBBY_MICROSTRIP" )
			)
			( physicalCSet "@sapphirecity_baseboard_lib.sapphirecity_baseboard(sch_1):\DDR4_2SPC_DQ/DQS\"
				( attribute "DIFFP_PRIMARY_GAP" "5.00,5.00,5.00,5.00,5.00,5.00,5.00,5.00,5.00,5.00,5.00,5.00,5.00,5.00"
					( Origin gBackEnd )
				)
				( attribute "DIFFP_COUPLED_PLUS" "0.01,0.01,0.01,0.01,0.01,0.01,0.01,0.01,0.01,0.01,0.01,0.01,0.01,0.01"
					( Origin gBackEnd )
				)
				( attribute "DIFFP_COUPLED_MINUS" "0.02,0.02,0.02,0.02,0.02,0.02,0.02,0.02,0.02,0.02,0.02,0.02,0.02,0.02"
					( Origin gBackEnd )
				)
				( attribute "DIFFP_MIN_SPACE" "3.98,3.98,3.98,3.98,3.98,3.98,3.98,3.98,3.98,3.98,3.98,3.98,3.98,3.98"
					( Origin gBackEnd )
				)
				( attribute "MIN_LINE_WIDTH" "6.50,6.10,5.60,6.10,5.60,6.10,6.10,6.10,6.10,5.60,6.10,5.60,6.10,6.50"
					( Origin gBackEnd )
				)
				( attribute "MAX_LINE_WIDTH" "6.50,6.10,5.60,6.10,5.60,6.10,6.10,6.10,6.10,5.60,6.10,5.60,6.10,6.50"
					( Origin gBackEnd )
				)
				( attribute "DIFFP_NECK_GAP" "4.00,4.00,4.00,4.00,4.00,4.00,4.00,4.00,4.00,4.00,4.00,4.00,4.00,4.00"
					( Origin gBackEnd )
				)
				( attribute "MIN_NECK_WIDTH" "3.50,3.50,3.50,3.50,3.50,3.50,3.50,3.50,3.50,3.50,3.50,3.50,3.50,3.50"
					( Origin gBackEnd )
				)
				( attribute "MAXIMUM_NECK_LENGTH" "2000.00,2000.00,2000.00,2000.00,2000.00,2000.00,2000.00,2000.00,2000.00,2000.00,2000.00,2000.00,2000.00,2000.00"
					( Origin gBackEnd )
				)
				( attribute "VIA_LIST" "V_C20P10AP28,V_C20P10C26AP28_TP,V_C20P10AP28_TP,TP_C26B,TP_C30T,R20X5R20X7D16S,R20X5R20X7D16SB"
					( Origin gBackEnd )
				)
				( attribute "ALLOW_ON_ETCH_SUBCLASS" "TRUE,TRUE,TRUE,TRUE,TRUE,TRUE,TRUE,TRUE,TRUE,TRUE,TRUE,TRUE,TRUE,TRUE"
					( Origin gBackEnd )
				)
				( attribute "TS_ALLOWED" "ANYWHERE,ANYWHERE,ANYWHERE,ANYWHERE,ANYWHERE,ANYWHERE,ANYWHERE,ANYWHERE,ANYWHERE,ANYWHERE,ANYWHERE,ANYWHERE,ANYWHERE,ANYWHERE"
					( Origin gBackEnd )
				)
				( attribute "MIN_BVIA_STAGGER" "5.00,5.00,5.00,5.00,5.00,5.00,5.00,5.00,5.00,5.00,5.00,5.00,5.00,5.00"
					( Origin gBackEnd )
				)
				( attribute "MAX_BVIA_STAGGER" "0.00,0.00,0.00,0.00,0.00,0.00,0.00,0.00,0.00,0.00,0.00,0.00,0.00,0.00"
					( Origin gBackEnd )
				)
				( attribute "PAD_PAD_DIRECT_CONNECT" "ALL_ALLOWED,ALL_ALLOWED,ALL_ALLOWED,ALL_ALLOWED,ALL_ALLOWED,ALL_ALLOWED,ALL_ALLOWED,ALL_ALLOWED,ALL_ALLOWED,ALL_ALLOWED,ALL_ALLOWED,ALL_ALLOWED,ALL_ALLOWED,ALL_ALLOWED"
					( Origin gBackEnd )
				)
				( objectStatus "40-OHM_US_&_38-OHM_SL_DIFF" )
			)
			( physicalCSet "@sapphirecity_baseboard_lib.sapphirecity_baseboard(sch_1):\ISENSE\"
				( attribute "DIFFP_PRIMARY_GAP" "5.00,5.00,5.00,5.00,5.00,5.00,5.00,5.00,5.00,5.00,5.00,5.00,5.00,5.00"
					( Origin gBackEnd )
				)
				( attribute "DIFFP_COUPLED_PLUS" "0.01,0.01,0.01,0.01,0.01,0.01,0.01,0.01,0.01,0.01,0.01,0.01,0.01,0.01"
					( Origin gBackEnd )
				)
				( attribute "DIFFP_COUPLED_MINUS" "0.02,0.02,0.02,0.02,0.02,0.02,0.02,0.02,0.02,0.02,0.02,0.02,0.02,0.02"
					( Origin gBackEnd )
				)
				( attribute "DIFFP_MIN_SPACE" "3.98,3.98,3.98,3.98,3.98,3.98,3.98,3.98,3.98,3.98,3.98,3.98,3.98,3.98"
					( Origin gBackEnd )
				)
				( attribute "MIN_LINE_WIDTH" "10.00,10.00,10.00,10.00,10.00,10.00,10.00,10.00,10.00,10.00,10.00,10.00,10.00,10.00"
					( Origin gBackEnd )
				)
				( attribute "MAX_LINE_WIDTH" "10.00,10.00,10.00,10.00,10.00,10.00,10.00,10.00,10.00,10.00,10.00,10.00,10.00,10.00"
					( Origin gBackEnd )
				)
				( attribute "DIFFP_NECK_GAP" "4.00,4.00,4.00,4.00,4.00,4.00,4.00,4.00,4.00,4.00,4.00,4.00,4.00,4.00"
					( Origin gBackEnd )
				)
				( attribute "MIN_NECK_WIDTH" "3.90,3.90,3.90,3.90,3.90,3.90,3.90,3.90,3.90,3.90,3.90,3.90,3.90,3.90"
					( Origin gBackEnd )
				)
				( attribute "MAXIMUM_NECK_LENGTH" "9999.00,9999.00,9999.00,9999.00,9999.00,9999.00,9999.00,9999.00,9999.00,9999.00,9999.00,9999.00,9999.00,9999.00"
					( Origin gBackEnd )
				)
				( attribute "VIA_LIST" "V_C20P10AP28,V_C20P10C26AP28_TP,V_C20P10AP28_TP,TP_C26B,TP_C30T,R20X5R20X7D16S,R20X5R20X7D16SB"
					( Origin gBackEnd )
				)
				( attribute "ALLOW_ON_ETCH_SUBCLASS" "TRUE,TRUE,TRUE,TRUE,TRUE,TRUE,TRUE,TRUE,TRUE,TRUE,TRUE,TRUE,TRUE,TRUE"
					( Origin gBackEnd )
				)
				( attribute "TS_ALLOWED" "ANYWHERE,ANYWHERE,ANYWHERE,ANYWHERE,ANYWHERE,ANYWHERE,ANYWHERE,ANYWHERE,ANYWHERE,ANYWHERE,ANYWHERE,ANYWHERE,ANYWHERE,ANYWHERE"
					( Origin gBackEnd )
				)
				( attribute "MIN_BVIA_STAGGER" "5.00,5.00,5.00,5.00,5.00,5.00,5.00,5.00,5.00,5.00,5.00,5.00,5.00,5.00"
					( Origin gBackEnd )
				)
				( attribute "MAX_BVIA_STAGGER" "0.00,0.00,0.00,0.00,0.00,0.00,0.00,0.00,0.00,0.00,0.00,0.00,0.00,0.00"
					( Origin gBackEnd )
				)
				( attribute "PAD_PAD_DIRECT_CONNECT" "ALL_ALLOWED,ALL_ALLOWED,ALL_ALLOWED,ALL_ALLOWED,ALL_ALLOWED,ALL_ALLOWED,ALL_ALLOWED,ALL_ALLOWED,ALL_ALLOWED,ALL_ALLOWED,ALL_ALLOWED,ALL_ALLOWED,ALL_ALLOWED,ALL_ALLOWED"
					( Origin gBackEnd )
				)
				( objectStatus "ISENSE_DIFF" )
			)
			( physicalCSet "@sapphirecity_baseboard_lib.sapphirecity_baseboard(sch_1):\100_OHM\"
				( attribute "DIFFP_PRIMARY_GAP" "13.99,13.00,13.00,13.00,13.00,13.00,13.00,13.00,13.00,13.00,13.00,13.00,13.00,13.99"
					( Origin gBackEnd )
				)
				( attribute "DIFFP_COUPLED_PLUS" "0.10,0.10,0.10,0.10,0.10,0.10,0.10,0.10,0.10,0.10,0.10,0.10,0.10,0.10"
					( Origin gBackEnd )
				)
				( attribute "DIFFP_COUPLED_MINUS" "0.00,0.00,0.00,0.00,0.00,0.00,0.00,0.00,0.00,0.00,0.00,0.00,0.00,0.00"
					( Origin gBackEnd )
				)
				( attribute "DIFFP_MIN_SPACE" "4.00,4.00,4.00,4.00,4.00,4.00,4.00,4.00,4.00,4.00,4.00,4.00,4.00,4.00"
					( Origin gBackEnd )
				)
				( attribute "MIN_LINE_WIDTH" "4.01,3.51,3.51,3.51,3.51,3.51,3.51,3.51,3.51,3.51,3.51,3.51,3.51,4.01"
					( Origin gBackEnd )
				)
				( attribute "MAX_LINE_WIDTH" "4.01,3.51,3.51,3.51,3.51,3.51,3.51,3.51,3.51,3.51,3.51,3.51,3.51,4.01"
					( Origin gBackEnd )
				)
				( attribute "DIFFP_NECK_GAP" "4.00,4.00,4.00,4.00,4.00,4.00,4.00,4.00,4.00,4.00,4.00,4.00,4.00,4.00"
					( Origin gBackEnd )
				)
				( attribute "MIN_NECK_WIDTH" "3.51,3.51,3.51,3.51,3.51,3.51,3.51,3.51,3.51,3.51,3.51,3.51,3.51,3.51"
					( Origin gBackEnd )
				)
				( attribute "MAXIMUM_NECK_LENGTH" "1000.00,1000.00,1000.00,1000.00,1000.00,1000.00,1000.00,1000.00,1000.00,1000.00,1000.00,1000.00,1000.00,1000.00"
					( Origin gBackEnd )
				)
				( attribute "VIA_LIST" "V_C20P10AP28,V_C20P10C26AP28_TP,V_C20P10AP28_TP,TP_C26B,TP_C30T,R20X5R20X7D16S,R20X5R20X7D16SB"
					( Origin gBackEnd )
				)
				( attribute "ALLOW_ON_ETCH_SUBCLASS" "TRUE,TRUE,TRUE,TRUE,TRUE,TRUE,TRUE,TRUE,TRUE,TRUE,TRUE,TRUE,TRUE,TRUE"
					( Origin gBackEnd )
				)
				( attribute "TS_ALLOWED" "ANYWHERE,ANYWHERE,ANYWHERE,ANYWHERE,ANYWHERE,ANYWHERE,ANYWHERE,ANYWHERE,ANYWHERE,ANYWHERE,ANYWHERE,ANYWHERE,ANYWHERE,ANYWHERE"
					( Origin gBackEnd )
				)
				( attribute "MIN_BVIA_STAGGER" "5.00,5.00,5.00,5.00,5.00,5.00,5.00,5.00,5.00,5.00,5.00,5.00,5.00,5.00"
					( Origin gBackEnd )
				)
				( attribute "MAX_BVIA_STAGGER" "0.00,0.00,0.00,0.00,0.00,0.00,0.00,0.00,0.00,0.00,0.00,0.00,0.00,0.00"
					( Origin gBackEnd )
				)
				( attribute "PAD_PAD_DIRECT_CONNECT" "ALL_ALLOWED,ALL_ALLOWED,ALL_ALLOWED,ALL_ALLOWED,ALL_ALLOWED,ALL_ALLOWED,ALL_ALLOWED,ALL_ALLOWED,ALL_ALLOWED,ALL_ALLOWED,ALL_ALLOWED,ALL_ALLOWED,ALL_ALLOWED,ALL_ALLOWED"
					( Origin gBackEnd )
				)
				( objectStatus "100_OHM_DIFF_FAB1" )
			)
			( physicalCSet "@sapphirecity_baseboard_lib.sapphirecity_baseboard(sch_1):\VR_SIG-SE\"
				( attribute "DIFFP_PRIMARY_GAP" "0.00,0.00,0.00,0.00,0.00,0.00,0.00,0.00,0.00,0.00,0.00,0.00,0.00,0.00"
					( Origin gBackEnd )
				)
				( attribute "DIFFP_COUPLED_PLUS" "0.00,0.00,0.00,0.00,0.00,0.00,0.00,0.00,0.00,0.00,0.00,0.00,0.00,0.00"
					( Origin gBackEnd )
				)
				( attribute "DIFFP_COUPLED_MINUS" "0.00,0.00,0.00,0.00,0.00,0.00,0.00,0.00,0.00,0.00,0.00,0.00,0.00,0.00"
					( Origin gBackEnd )
				)
				( attribute "DIFFP_MIN_SPACE" "0.00,0.00,0.00,0.00,0.00,0.00,0.00,0.00,0.00,0.00,0.00,0.00,0.00,0.00"
					( Origin gBackEnd )
				)
				( attribute "MIN_LINE_WIDTH" "4.00,5.00,4.50,5.00,4.50,5.00,5.00,5.00,5.00,4.50,5.00,4.50,5.00,4.50"
					( Origin gBackEnd )
				)
				( attribute "MAX_LINE_WIDTH" "30.00,30.00,30.00,30.00,30.00,30.00,30.00,30.00,30.00,30.00,30.00,30.00,30.00,30.00"
					( Origin gBackEnd )
				)
				( attribute "DIFFP_NECK_GAP" "0.00,0.00,0.00,0.00,0.00,0.00,0.00,0.00,0.00,0.00,0.00,0.00,0.00,0.00"
					( Origin gBackEnd )
				)
				( attribute "MIN_NECK_WIDTH" "4.00,5.00,4.50,5.00,4.50,5.00,5.00,5.00,5.00,4.50,5.00,4.50,5.00,4.50"
					( Origin gBackEnd )
				)
				( attribute "MAXIMUM_NECK_LENGTH" "0.00,0.00,0.00,0.00,0.00,0.00,0.00,0.00,0.00,0.00,0.00,0.00,0.00,0.00"
					( Origin gBackEnd )
				)
				( attribute "VIA_LIST" "V_C20P10AP28,V_C20P10C26AP28_TP,V_C20P10AP28_TP,TP_C26B,TP_C30T,R20X5R20X7D16S,R20X5R20X7D16SB"
					( Origin gBackEnd )
				)
				( attribute "ALLOW_ON_ETCH_SUBCLASS" "TRUE,TRUE,TRUE,TRUE,TRUE,TRUE,TRUE,TRUE,TRUE,TRUE,TRUE,TRUE,TRUE,TRUE"
					( Origin gBackEnd )
				)
				( attribute "TS_ALLOWED" "ANYWHERE,ANYWHERE,ANYWHERE,ANYWHERE,ANYWHERE,ANYWHERE,ANYWHERE,ANYWHERE,ANYWHERE,ANYWHERE,ANYWHERE,ANYWHERE,ANYWHERE,ANYWHERE"
					( Origin gBackEnd )
				)
				( attribute "MIN_BVIA_STAGGER" "5.00,5.00,5.00,5.00,5.00,5.00,5.00,5.00,5.00,5.00,5.00,5.00,5.00,5.00"
					( Origin gBackEnd )
				)
				( attribute "MAX_BVIA_STAGGER" "0.00,0.00,0.00,0.00,0.00,0.00,0.00,0.00,0.00,0.00,0.00,0.00,0.00,0.00"
					( Origin gBackEnd )
				)
				( attribute "PAD_PAD_DIRECT_CONNECT" "ALL_ALLOWED,ALL_ALLOWED,ALL_ALLOWED,ALL_ALLOWED,ALL_ALLOWED,ALL_ALLOWED,ALL_ALLOWED,ALL_ALLOWED,ALL_ALLOWED,ALL_ALLOWED,ALL_ALLOWED,ALL_ALLOWED,ALL_ALLOWED,ALL_ALLOWED"
					( Origin gBackEnd )
				)
				( objectStatus "VR_SIG-SE" )
			)
			( physicalCSet "@sapphirecity_baseboard_lib.sapphirecity_baseboard(sch_1):\10-5-10_DIFF\"
				( attribute "DIFFP_PRIMARY_GAP" "5.00,5.00,5.00,5.00,5.00,5.00,5.00,5.00,5.00,5.00,5.00,5.00,5.00,5.00"
					( Origin gBackEnd )
				)
				( attribute "DIFFP_COUPLED_PLUS" "0.10,0.10,0.10,0.10,0.10,0.10,0.10,0.10,0.10,0.10,0.10,0.10,0.10,0.10"
					( Origin gBackEnd )
				)
				( attribute "DIFFP_COUPLED_MINUS" "0.10,0.10,0.10,0.10,0.10,0.10,0.10,0.10,0.10,0.10,0.10,0.10,0.10,0.10"
					( Origin gBackEnd )
				)
				( attribute "DIFFP_MIN_SPACE" "4.00,4.00,4.00,4.00,4.00,4.00,4.00,4.00,4.00,4.00,4.00,4.00,4.00,4.00"
					( Origin gBackEnd )
				)
				( attribute "MIN_LINE_WIDTH" "10.00,10.00,10.00,10.00,10.00,10.00,10.00,10.00,10.00,10.00,10.00,10.00,10.00,10.00"
					( Origin gBackEnd )
				)
				( attribute "MAX_LINE_WIDTH" "10.00,10.00,10.00,10.00,10.00,10.00,10.00,10.00,10.00,10.00,10.00,10.00,10.00,10.00"
					( Origin gBackEnd )
				)
				( attribute "DIFFP_NECK_GAP" "5.00,5.00,5.00,5.00,5.00,5.00,5.00,5.00,5.00,5.00,5.00,5.00,5.00,5.00"
					( Origin gBackEnd )
				)
				( attribute "MIN_NECK_WIDTH" "5.00,5.00,5.00,5.00,5.00,5.00,5.00,5.00,5.00,5.00,5.00,5.00,5.00,5.00"
					( Origin gBackEnd )
				)
				( attribute "MAXIMUM_NECK_LENGTH" "250.00,250.00,250.00,250.00,250.00,250.00,250.00,250.00,250.00,250.00,250.00,250.00,250.00,250.00"
					( Origin gBackEnd )
				)
				( attribute "VIA_LIST" "V_C20P10AP28,V_C20P10C26AP28_TP,V_C20P10AP28_TP,TP_C26B,TP_C30T,R20X5R20X7D16S,R20X5R20X7D16SB"
					( Origin gBackEnd )
				)
				( attribute "ALLOW_ON_ETCH_SUBCLASS" "TRUE,TRUE,TRUE,TRUE,TRUE,TRUE,TRUE,TRUE,TRUE,TRUE,TRUE,TRUE,TRUE,TRUE"
					( Origin gBackEnd )
				)
				( attribute "TS_ALLOWED" "ANYWHERE,ANYWHERE,ANYWHERE,ANYWHERE,ANYWHERE,ANYWHERE,ANYWHERE,ANYWHERE,ANYWHERE,ANYWHERE,ANYWHERE,ANYWHERE,ANYWHERE,ANYWHERE"
					( Origin gBackEnd )
				)
				( attribute "MIN_BVIA_STAGGER" "5.00,5.00,5.00,5.00,5.00,5.00,5.00,5.00,5.00,5.00,5.00,5.00,5.00,5.00"
					( Origin gBackEnd )
				)
				( attribute "MAX_BVIA_STAGGER" "0.00,0.00,0.00,0.00,0.00,0.00,0.00,0.00,0.00,0.00,0.00,0.00,0.00,0.00"
					( Origin gBackEnd )
				)
				( attribute "PAD_PAD_DIRECT_CONNECT" "ALL_ALLOWED,ALL_ALLOWED,ALL_ALLOWED,ALL_ALLOWED,ALL_ALLOWED,ALL_ALLOWED,ALL_ALLOWED,ALL_ALLOWED,ALL_ALLOWED,ALL_ALLOWED,ALL_ALLOWED,ALL_ALLOWED,ALL_ALLOWED,ALL_ALLOWED"
					( Origin gBackEnd )
				)
				( objectStatus "10-5-10_DIFF" )
			)
			( physicalCSet "@sapphirecity_baseboard_lib.sapphirecity_baseboard(sch_1):\95_OHM_DIFF\"
				( attribute "DIFFP_PRIMARY_GAP" "13.50,11.98,11.98,11.98,11.98,11.98,11.98,11.98,11.98,11.98,11.98,11.98,11.98,13.50"
					( Origin gBackEnd )
				)
				( attribute "DIFFP_COUPLED_PLUS" "0.10,0.10,0.10,0.10,0.10,0.10,0.10,0.10,0.10,0.10,0.10,0.10,0.10,0.10"
					( Origin gBackEnd )
				)
				( attribute "DIFFP_COUPLED_MINUS" "0.00,0.00,0.00,0.00,0.00,0.00,0.00,0.00,0.00,0.00,0.00,0.00,0.00,0.00"
					( Origin gBackEnd )
				)
				( attribute "DIFFP_MIN_SPACE" "4.00,0.00,4.00,0.00,4.00,0.00,0.00,0.00,0.00,4.00,0.00,4.00,0.00,4.00"
					( Origin gBackEnd )
				)
				( attribute "MIN_LINE_WIDTH" "4.60,4.02,4.02,4.02,4.02,4.02,4.02,4.02,4.02,4.02,4.02,4.02,4.02,4.60"
					( Origin gBackEnd )
				)
				( attribute "MAX_LINE_WIDTH" "4.60,4.02,4.02,4.02,4.02,4.02,4.02,4.02,4.02,4.02,4.02,4.02,4.02,4.60"
					( Origin gBackEnd )
				)
				( attribute "DIFFP_NECK_GAP" "4.00,4.00,4.00,4.00,4.00,4.00,4.00,4.00,4.00,4.00,4.00,4.00,4.00,4.00"
					( Origin gBackEnd )
				)
				( attribute "MIN_NECK_WIDTH" "3.50,3.50,3.50,3.50,3.50,3.50,3.50,3.50,3.50,3.50,3.50,3.50,3.50,3.50"
					( Origin gBackEnd )
				)
				( attribute "MAXIMUM_NECK_LENGTH" "500.00,500.00,500.00,500.00,500.00,500.00,500.00,500.00,500.00,500.00,500.00,500.00,500.00,500.00"
					( Origin gBackEnd )
				)
				( attribute "VIA_LIST" "V_C20P10AP28,V_C20P10C26AP28_TP,V_C20P10AP28_TP,TP_C26B,TP_C30T,R20X5R20X7D16S,R20X5R20X7D16SB"
					( Origin gBackEnd )
				)
				( attribute "ALLOW_ON_ETCH_SUBCLASS" "TRUE,FALSE,TRUE,FALSE,TRUE,FALSE,FALSE,FALSE,FALSE,TRUE,FALSE,TRUE,FALSE,TRUE"
					( Origin gBackEnd )
				)
				( attribute "TS_ALLOWED" "ANYWHERE,ANYWHERE,ANYWHERE,ANYWHERE,ANYWHERE,ANYWHERE,ANYWHERE,ANYWHERE,ANYWHERE,ANYWHERE,ANYWHERE,ANYWHERE,ANYWHERE,ANYWHERE"
					( Origin gBackEnd )
				)
				( attribute "MIN_BVIA_STAGGER" "5.00,5.00,5.00,5.00,5.00,5.00,5.00,5.00,5.00,5.00,5.00,5.00,5.00,5.00"
					( Origin gBackEnd )
				)
				( attribute "MAX_BVIA_STAGGER" "0.00,0.00,0.00,0.00,0.00,0.00,0.00,0.00,0.00,0.00,0.00,0.00,0.00,0.00"
					( Origin gBackEnd )
				)
				( attribute "PAD_PAD_DIRECT_CONNECT" "ALL_ALLOWED,ALL_ALLOWED,ALL_ALLOWED,ALL_ALLOWED,ALL_ALLOWED,ALL_ALLOWED,ALL_ALLOWED,ALL_ALLOWED,ALL_ALLOWED,ALL_ALLOWED,ALL_ALLOWED,ALL_ALLOWED,ALL_ALLOWED,ALL_ALLOWED"
					( Origin gBackEnd )
				)
				( objectStatus "93_OHM_DIFF" )
			)
			( physicalCSet "@sapphirecity_baseboard_lib.sapphirecity_baseboard(sch_1):\15_MILS-SE\"
				( attribute "DIFFP_PRIMARY_GAP" "0.00,0.00,0.00,0.00,0.00,0.00,0.00,0.00,0.00,0.00,0.00,0.00,0.00,0.00"
					( Origin gBackEnd )
				)
				( attribute "DIFFP_COUPLED_PLUS" "0.00,0.00,0.00,0.00,0.00,0.00,0.00,0.00,0.00,0.00,0.00,0.00,0.00,0.00"
					( Origin gBackEnd )
				)
				( attribute "DIFFP_COUPLED_MINUS" "0.00,0.00,0.00,0.00,0.00,0.00,0.00,0.00,0.00,0.00,0.00,0.00,0.00,0.00"
					( Origin gBackEnd )
				)
				( attribute "DIFFP_MIN_SPACE" "0.00,0.00,0.00,0.00,0.00,0.00,0.00,0.00,0.00,0.00,0.00,0.00,0.00,0.00"
					( Origin gBackEnd )
				)
				( attribute "MIN_LINE_WIDTH" "15.00,15.00,15.00,15.00,15.00,15.00,15.00,15.00,15.00,15.00,15.00,15.00,15.00,15.00"
					( Origin gBackEnd )
				)
				( attribute "MAX_LINE_WIDTH" "50.00,50.00,50.00,50.00,50.00,50.00,50.00,50.00,50.00,50.00,50.00,50.00,50.00,50.00"
					( Origin gBackEnd )
				)
				( attribute "DIFFP_NECK_GAP" "0.00,0.00,0.00,0.00,0.00,0.00,0.00,0.00,0.00,0.00,0.00,0.00,0.00,0.00"
					( Origin gBackEnd )
				)
				( attribute "MIN_NECK_WIDTH" "4.00,4.00,4.00,4.00,4.00,4.00,4.00,4.00,4.00,4.00,4.00,4.00,4.00,4.00"
					( Origin gBackEnd )
				)
				( attribute "MAXIMUM_NECK_LENGTH" "250.00,250.00,250.00,250.00,250.00,250.00,250.00,250.00,250.00,250.00,250.00,250.00,250.00,250.00"
					( Origin gBackEnd )
				)
				( attribute "VIA_LIST" "V_C20P10AP28,V_C20P10C26AP28_TP,V_C20P10AP28_TP,TP_C26B,TP_C30T,R20X5R20X7D16S,R20X5R20X7D16SB"
					( Origin gBackEnd )
				)
				( attribute "ALLOW_ON_ETCH_SUBCLASS" "TRUE,TRUE,TRUE,TRUE,TRUE,TRUE,TRUE,TRUE,TRUE,TRUE,TRUE,TRUE,TRUE,TRUE"
					( Origin gBackEnd )
				)
				( attribute "TS_ALLOWED" "ANYWHERE,ANYWHERE,ANYWHERE,ANYWHERE,ANYWHERE,ANYWHERE,ANYWHERE,ANYWHERE,ANYWHERE,ANYWHERE,ANYWHERE,ANYWHERE,ANYWHERE,ANYWHERE"
					( Origin gBackEnd )
				)
				( attribute "MIN_BVIA_STAGGER" "5.00,5.00,5.00,5.00,5.00,5.00,5.00,5.00,5.00,5.00,5.00,5.00,5.00,5.00"
					( Origin gBackEnd )
				)
				( attribute "MAX_BVIA_STAGGER" "0.00,0.00,0.00,0.00,0.00,0.00,0.00,0.00,0.00,0.00,0.00,0.00,0.00,0.00"
					( Origin gBackEnd )
				)
				( attribute "PAD_PAD_DIRECT_CONNECT" "ALL_ALLOWED,ALL_ALLOWED,ALL_ALLOWED,ALL_ALLOWED,ALL_ALLOWED,ALL_ALLOWED,ALL_ALLOWED,ALL_ALLOWED,ALL_ALLOWED,ALL_ALLOWED,ALL_ALLOWED,ALL_ALLOWED,ALL_ALLOWED,ALL_ALLOWED"
					( Origin gBackEnd )
				)
				( objectStatus "15_MILS_W" )
			)
			( physicalCSet "@sapphirecity_baseboard_lib.sapphirecity_baseboard(sch_1):\10_MILS-SE\"
				( attribute "DIFFP_PRIMARY_GAP" "0.00,0.00,0.00,0.00,0.00,0.00,0.00,0.00,0.00,0.00,0.00,0.00,0.00,0.00"
					( Origin gBackEnd )
				)
				( attribute "DIFFP_COUPLED_PLUS" "0.00,0.00,0.00,0.00,0.00,0.00,0.00,0.00,0.00,0.00,0.00,0.00,0.00,0.00"
					( Origin gBackEnd )
				)
				( attribute "DIFFP_COUPLED_MINUS" "0.00,0.00,0.00,0.00,0.00,0.00,0.00,0.00,0.00,0.00,0.00,0.00,0.00,0.00"
					( Origin gBackEnd )
				)
				( attribute "DIFFP_MIN_SPACE" "0.00,0.00,0.00,0.00,0.00,0.00,0.00,0.00,0.00,0.00,0.00,0.00,0.00,0.00"
					( Origin gBackEnd )
				)
				( attribute "MIN_LINE_WIDTH" "10.00,10.00,10.00,10.00,10.00,10.00,10.00,10.00,10.00,10.00,10.00,10.00,10.00,10.00"
					( Origin gBackEnd )
				)
				( attribute "MAX_LINE_WIDTH" "30.00,30.00,30.00,30.00,30.00,30.00,30.00,30.00,30.00,30.00,30.00,30.00,30.00,30.00"
					( Origin gBackEnd )
				)
				( attribute "DIFFP_NECK_GAP" "0.00,0.00,0.00,0.00,0.00,0.00,0.00,0.00,0.00,0.00,0.00,0.00,0.00,0.00"
					( Origin gBackEnd )
				)
				( attribute "MIN_NECK_WIDTH" "4.00,4.00,4.00,4.00,4.00,4.00,4.00,4.00,4.00,4.00,4.00,4.00,4.00,4.00"
					( Origin gBackEnd )
				)
				( attribute "MAXIMUM_NECK_LENGTH" "1100.00,1100.00,1100.00,1100.00,1100.00,1100.00,1100.00,1100.00,1100.00,1100.00,1100.00,1100.00,1100.00,1100.00"
					( Origin gBackEnd )
				)
				( attribute "VIA_LIST" "V_C20P10AP28,V_C20P10C26AP28_TP,V_C20P10AP28_TP,TP_C26B,TP_C30T,R20X5R20X7D16S,R20X5R20X7D16SB"
					( Origin gBackEnd )
				)
				( attribute "ALLOW_ON_ETCH_SUBCLASS" "TRUE,FALSE,TRUE,FALSE,TRUE,FALSE,FALSE,FALSE,FALSE,TRUE,FALSE,TRUE,FALSE,TRUE"
					( Origin gBackEnd )
				)
				( attribute "TS_ALLOWED" "ANYWHERE,ANYWHERE,ANYWHERE,ANYWHERE,ANYWHERE,ANYWHERE,ANYWHERE,ANYWHERE,ANYWHERE,ANYWHERE,ANYWHERE,ANYWHERE,ANYWHERE,ANYWHERE"
					( Origin gBackEnd )
				)
				( attribute "MIN_BVIA_STAGGER" "5.00,5.00,5.00,5.00,5.00,5.00,5.00,5.00,5.00,5.00,5.00,5.00,5.00,5.00"
					( Origin gBackEnd )
				)
				( attribute "MAX_BVIA_STAGGER" "0.00,0.00,0.00,0.00,0.00,0.00,0.00,0.00,0.00,0.00,0.00,0.00,0.00,0.00"
					( Origin gBackEnd )
				)
				( attribute "PAD_PAD_DIRECT_CONNECT" "ALL_ALLOWED,ALL_ALLOWED,ALL_ALLOWED,ALL_ALLOWED,ALL_ALLOWED,ALL_ALLOWED,ALL_ALLOWED,ALL_ALLOWED,ALL_ALLOWED,ALL_ALLOWED,ALL_ALLOWED,ALL_ALLOWED,ALL_ALLOWED,ALL_ALLOWED"
					( Origin gBackEnd )
				)
				( objectStatus "10_MILS-SE" )
			)
			( physicalCSet "@sapphirecity_baseboard_lib.sapphirecity_baseboard(sch_1):\10-MILS-POWER\"
				( attribute "DIFFP_PRIMARY_GAP" "0.00,0.00,0.00,0.00,0.00,0.00,0.00,0.00,0.00,0.00,0.00,0.00,0.00,0.00"
					( Origin gBackEnd )
				)
				( attribute "DIFFP_COUPLED_PLUS" "0.00,0.00,0.00,0.00,0.00,0.00,0.00,0.00,0.00,0.00,0.00,0.00,0.00,0.00"
					( Origin gBackEnd )
				)
				( attribute "DIFFP_COUPLED_MINUS" "0.00,0.00,0.00,0.00,0.00,0.00,0.00,0.00,0.00,0.00,0.00,0.00,0.00,0.00"
					( Origin gBackEnd )
				)
				( attribute "DIFFP_MIN_SPACE" "0.00,0.00,0.00,0.00,0.00,0.00,0.00,0.00,0.00,0.00,0.00,0.00,0.00,0.00"
					( Origin gBackEnd )
				)
				( attribute "MIN_LINE_WIDTH" "10.00,10.00,10.00,10.00,10.00,10.00,10.00,10.00,10.00,10.00,10.00,10.00,10.00,10.00"
					( Origin gBackEnd )
				)
				( attribute "MAX_LINE_WIDTH" "50.00,50.00,50.00,50.00,50.00,50.00,50.00,50.00,50.00,50.00,50.00,50.00,50.00,50.00"
					( Origin gBackEnd )
				)
				( attribute "DIFFP_NECK_GAP" "0.00,0.00,0.00,0.00,0.00,0.00,0.00,0.00,0.00,0.00,0.00,0.00,0.00,0.00"
					( Origin gBackEnd )
				)
				( attribute "MIN_NECK_WIDTH" "4.00,4.00,4.00,4.00,4.00,4.00,4.00,4.00,4.00,4.00,4.00,4.00,4.00,4.00"
					( Origin gBackEnd )
				)
				( attribute "MAXIMUM_NECK_LENGTH" "1100.00,1100.00,1100.00,1100.00,1100.00,1100.00,1100.00,1100.00,1100.00,1100.00,1100.00,1100.00,1100.00,1100.00"
					( Origin gBackEnd )
				)
				( attribute "VIA_LIST" "V_C20P10AP28,V_C20P10C26AP28_TP,V_C20P10AP28_TP,TP_C26B,TP_C30T,R20X5R20X7D16S,R20X5R20X7D16SB"
					( Origin gBackEnd )
				)
				( attribute "ALLOW_ON_ETCH_SUBCLASS" "TRUE,TRUE,TRUE,TRUE,TRUE,TRUE,TRUE,TRUE,TRUE,TRUE,TRUE,TRUE,TRUE,TRUE"
					( Origin gBackEnd )
				)
				( attribute "TS_ALLOWED" "ANYWHERE,ANYWHERE,ANYWHERE,ANYWHERE,ANYWHERE,ANYWHERE,ANYWHERE,ANYWHERE,ANYWHERE,ANYWHERE,ANYWHERE,ANYWHERE,ANYWHERE,ANYWHERE"
					( Origin gBackEnd )
				)
				( attribute "MIN_BVIA_STAGGER" "5.00,5.00,5.00,5.00,5.00,5.00,5.00,5.00,5.00,5.00,5.00,5.00,5.00,5.00"
					( Origin gBackEnd )
				)
				( attribute "MAX_BVIA_STAGGER" "0.00,0.00,0.00,0.00,0.00,0.00,0.00,0.00,0.00,0.00,0.00,0.00,0.00,0.00"
					( Origin gBackEnd )
				)
				( attribute "PAD_PAD_DIRECT_CONNECT" "ALL_ALLOWED,ALL_ALLOWED,ALL_ALLOWED,ALL_ALLOWED,ALL_ALLOWED,ALL_ALLOWED,ALL_ALLOWED,ALL_ALLOWED,ALL_ALLOWED,ALL_ALLOWED,ALL_ALLOWED,ALL_ALLOWED,ALL_ALLOWED,ALL_ALLOWED"
					( Origin gBackEnd )
				)
				( objectStatus "10-MILS-POWER" )
			)
			( physicalCSet "@sapphirecity_baseboard_lib.sapphirecity_baseboard(sch_1):\50_OHMS-SE\"
				( attribute "DIFFP_PRIMARY_GAP" "0.00,0.00,0.00,0.00,0.00,0.00,0.00,0.00,0.00,0.00,0.00,0.00,0.00,0.00"
					( Origin gBackEnd )
				)
				( attribute "DIFFP_COUPLED_PLUS" "0.00,0.00,0.00,0.00,0.00,0.00,0.00,0.00,0.00,0.00,0.00,0.00,0.00,0.00"
					( Origin gBackEnd )
				)
				( attribute "DIFFP_COUPLED_MINUS" "0.00,0.00,0.00,0.00,0.00,0.00,0.00,0.00,0.00,0.00,0.00,0.00,0.00,0.00"
					( Origin gBackEnd )
				)
				( attribute "DIFFP_MIN_SPACE" "0.00,0.00,0.00,0.00,0.00,0.00,0.00,0.00,0.00,0.00,0.00,0.00,0.00,0.00"
					( Origin gBackEnd )
				)
				( attribute "MIN_LINE_WIDTH" "4.25,3.52,3.52,3.52,3.52,3.52,3.52,3.52,3.52,3.52,3.52,3.52,3.52,4.25"
					( Origin gBackEnd )
				)
				( attribute "MAX_LINE_WIDTH" "4.25,3.52,3.52,3.52,3.52,3.52,3.52,3.52,3.52,3.52,3.52,3.52,3.52,4.25"
					( Origin gBackEnd )
				)
				( attribute "DIFFP_NECK_GAP" "0.00,0.00,0.00,0.00,0.00,0.00,0.00,0.00,0.00,0.00,0.00,0.00,0.00,0.00"
					( Origin gBackEnd )
				)
				( attribute "MIN_NECK_WIDTH" "3.50,3.50,4.00,3.50,4.00,3.50,3.50,3.50,3.50,4.00,3.50,4.00,3.50,4.00"
					( Origin gBackEnd )
				)
				( attribute "MAXIMUM_NECK_LENGTH" "1000.00,1000.00,1000.00,1000.00,1000.00,1000.00,1000.00,1000.00,1000.00,1000.00,1000.00,1000.00,1000.00,1000.00"
					( Origin gBackEnd )
				)
				( attribute "VIA_LIST" "V_C20P10AP28,V_C20P10C26AP28_TP,V_C20P10AP28_TP,TP_C26B,TP_C30T,R20X5R20X7D16S,R20X5R20X7D16SB"
					( Origin gBackEnd )
				)
				( attribute "ALLOW_ON_ETCH_SUBCLASS" "TRUE,FALSE,TRUE,FALSE,TRUE,FALSE,FALSE,FALSE,FALSE,TRUE,FALSE,TRUE,FALSE,TRUE"
					( Origin gBackEnd )
				)
				( attribute "TS_ALLOWED" "ANYWHERE,ANYWHERE,ANYWHERE,ANYWHERE,ANYWHERE,ANYWHERE,ANYWHERE,ANYWHERE,ANYWHERE,ANYWHERE,ANYWHERE,ANYWHERE,ANYWHERE,ANYWHERE"
					( Origin gBackEnd )
				)
				( attribute "MIN_BVIA_STAGGER" "5.00,5.00,5.00,5.00,5.00,5.00,5.00,5.00,5.00,5.00,5.00,5.00,5.00,5.00"
					( Origin gBackEnd )
				)
				( attribute "MAX_BVIA_STAGGER" "0.00,0.00,0.00,0.00,0.00,0.00,0.00,0.00,0.00,0.00,0.00,0.00,0.00,0.00"
					( Origin gBackEnd )
				)
				( attribute "PAD_PAD_DIRECT_CONNECT" "ALL_ALLOWED,ALL_ALLOWED,ALL_ALLOWED,ALL_ALLOWED,ALL_ALLOWED,ALL_ALLOWED,ALL_ALLOWED,ALL_ALLOWED,ALL_ALLOWED,ALL_ALLOWED,ALL_ALLOWED,ALL_ALLOWED,ALL_ALLOWED,ALL_ALLOWED"
					( Origin gBackEnd )
				)
				( objectStatus "50_OHM_SE" )
			)
			( physicalCSet "@sapphirecity_baseboard_lib.sapphirecity_baseboard(sch_1):\DDR4_2SPC_DQ\"
				( attribute "DIFFP_PRIMARY_GAP" "0.00,0.00,0.00,0.00,0.00,0.00,0.00,0.00,0.00,0.00,0.00,0.00,0.00,0.00"
					( Origin gBackEnd )
				)
				( attribute "DIFFP_COUPLED_PLUS" "0.00,0.00,0.00,0.00,0.00,0.00,0.00,0.00,0.00,0.00,0.00,0.00,0.00,0.00"
					( Origin gBackEnd )
				)
				( attribute "DIFFP_COUPLED_MINUS" "0.00,0.00,0.00,0.00,0.00,0.00,0.00,0.00,0.00,0.00,0.00,0.00,0.00,0.00"
					( Origin gBackEnd )
				)
				( attribute "DIFFP_MIN_SPACE" "0.00,0.00,0.00,0.00,0.00,0.00,0.00,0.00,0.00,0.00,0.00,0.00,0.00,0.00"
					( Origin gBackEnd )
				)
				( attribute "MIN_LINE_WIDTH" "6.50,8.00,8.00,8.00,8.00,8.00,8.00,8.00,8.00,8.00,8.00,8.00,8.00,6.50"
					( Origin gBackEnd )
				)
				( attribute "MAX_LINE_WIDTH" "6.50,8.00,8.00,8.00,8.00,8.00,8.00,8.00,8.00,8.00,8.00,8.00,8.00,6.50"
					( Origin gBackEnd )
				)
				( attribute "DIFFP_NECK_GAP" "0.00,0.00,0.00,0.00,0.00,0.00,0.00,0.00,0.00,0.00,0.00,0.00,0.00,0.00"
					( Origin gBackEnd )
				)
				( attribute "MIN_NECK_WIDTH" "3.50,3.50,3.50,3.50,3.50,3.50,3.50,3.50,3.50,3.50,3.50,3.50,3.50,3.50"
					( Origin gBackEnd )
				)
				( attribute "MAXIMUM_NECK_LENGTH" "2000.00,2000.00,2000.00,2000.00,2000.00,2000.00,2000.00,2000.00,2000.00,2000.00,2000.00,2000.00,2000.00,2000.00"
					( Origin gBackEnd )
				)
				( attribute "VIA_LIST" "V_C20P10AP28,V_C20P10C26AP28_TP,V_C20P10AP28_TP,TP_C26B,TP_C30T"
					( Origin gBackEnd )
				)
				( attribute "ALLOW_ON_ETCH_SUBCLASS" "TRUE,TRUE,TRUE,TRUE,TRUE,TRUE,TRUE,TRUE,TRUE,TRUE,TRUE,TRUE,TRUE,TRUE"
					( Origin gBackEnd )
				)
				( attribute "TS_ALLOWED" "ANYWHERE,ANYWHERE,ANYWHERE,ANYWHERE,ANYWHERE,ANYWHERE,ANYWHERE,ANYWHERE,ANYWHERE,ANYWHERE,ANYWHERE,ANYWHERE,ANYWHERE,ANYWHERE"
					( Origin gBackEnd )
				)
				( attribute "MIN_BVIA_STAGGER" "5.00,5.00,5.00,5.00,5.00,5.00,5.00,5.00,5.00,5.00,5.00,5.00,5.00,5.00"
					( Origin gBackEnd )
				)
				( attribute "MAX_BVIA_STAGGER" "0.00,0.00,0.00,0.00,0.00,0.00,0.00,0.00,0.00,0.00,0.00,0.00,0.00,0.00"
					( Origin gBackEnd )
				)
				( attribute "PAD_PAD_DIRECT_CONNECT" "ALL_ALLOWED,ALL_ALLOWED,ALL_ALLOWED,ALL_ALLOWED,ALL_ALLOWED,ALL_ALLOWED,ALL_ALLOWED,ALL_ALLOWED,ALL_ALLOWED,ALL_ALLOWED,ALL_ALLOWED,ALL_ALLOWED,ALL_ALLOWED,ALL_ALLOWED"
					( Origin gBackEnd )
				)
				( objectStatus "DDR4_2SPC_DQ" )
			)
			( physicalCSet "@sapphirecity_baseboard_lib.sapphirecity_baseboard(sch_1):\DDR4_2SPC_CAC\"
				( attribute "DIFFP_PRIMARY_GAP" "0.00,0.00,0.00,0.00,0.00,0.00,0.00,0.00,0.00,0.00,0.00,0.00,0.00,0.00"
					( Origin gBackEnd )
				)
				( attribute "DIFFP_COUPLED_PLUS" "0.00,0.00,0.00,0.00,0.00,0.00,0.00,0.00,0.00,0.00,0.00,0.00,0.00,0.00"
					( Origin gBackEnd )
				)
				( attribute "DIFFP_COUPLED_MINUS" "0.00,0.00,0.00,0.00,0.00,0.00,0.00,0.00,0.00,0.00,0.00,0.00,0.00,0.00"
					( Origin gBackEnd )
				)
				( attribute "DIFFP_MIN_SPACE" "0.00,0.00,0.00,0.00,0.00,0.00,0.00,0.00,0.00,0.00,0.00,0.00,0.00,0.00"
					( Origin gBackEnd )
				)
				( attribute "MIN_LINE_WIDTH" "6.50,8.00,8.00,8.00,8.00,8.00,8.00,8.00,8.00,8.00,8.00,8.00,8.00,6.50"
					( Origin gBackEnd )
				)
				( attribute "MAX_LINE_WIDTH" "6.50,8.00,8.00,8.00,8.00,8.00,8.00,8.00,8.00,8.00,8.00,8.00,8.00,6.50"
					( Origin gBackEnd )
				)
				( attribute "DIFFP_NECK_GAP" "0.00,0.00,0.00,0.00,0.00,0.00,0.00,0.00,0.00,0.00,0.00,0.00,0.00,0.00"
					( Origin gBackEnd )
				)
				( attribute "MIN_NECK_WIDTH" "3.50,3.50,3.50,3.50,3.50,3.50,3.50,3.50,3.50,3.50,3.50,3.50,3.50,3.50"
					( Origin gBackEnd )
				)
				( attribute "MAXIMUM_NECK_LENGTH" "2000.00,2000.00,2000.00,2000.00,2000.00,2000.00,2000.00,2000.00,2000.00,2000.00,2000.00,2000.00,2000.00,2000.00"
					( Origin gBackEnd )
				)
				( attribute "VIA_LIST" "V_C20P10AP28,V_C20P10C26AP28_TP,V_C20P10AP28_TP,TP_C26B,TP_C30T"
					( Origin gBackEnd )
				)
				( attribute "ALLOW_ON_ETCH_SUBCLASS" "TRUE,TRUE,TRUE,TRUE,TRUE,TRUE,TRUE,TRUE,TRUE,TRUE,TRUE,TRUE,TRUE,TRUE"
					( Origin gBackEnd )
				)
				( attribute "TS_ALLOWED" "ANYWHERE,ANYWHERE,ANYWHERE,ANYWHERE,ANYWHERE,ANYWHERE,ANYWHERE,ANYWHERE,ANYWHERE,ANYWHERE,ANYWHERE,ANYWHERE,ANYWHERE,ANYWHERE"
					( Origin gBackEnd )
				)
				( attribute "MIN_BVIA_STAGGER" "5.00,5.00,5.00,5.00,5.00,5.00,5.00,5.00,5.00,5.00,5.00,5.00,5.00,5.00"
					( Origin gBackEnd )
				)
				( attribute "MAX_BVIA_STAGGER" "0.00,0.00,0.00,0.00,0.00,0.00,0.00,0.00,0.00,0.00,0.00,0.00,0.00,0.00"
					( Origin gBackEnd )
				)
				( attribute "PAD_PAD_DIRECT_CONNECT" "ALL_ALLOWED,ALL_ALLOWED,ALL_ALLOWED,ALL_ALLOWED,ALL_ALLOWED,ALL_ALLOWED,ALL_ALLOWED,ALL_ALLOWED,ALL_ALLOWED,ALL_ALLOWED,ALL_ALLOWED,ALL_ALLOWED,ALL_ALLOWED,ALL_ALLOWED"
					( Origin gBackEnd )
				)
				( objectStatus "DDR4_2SPC_CAC" )
			)
			( physicalCSet "@sapphirecity_baseboard_lib.sapphirecity_baseboard(sch_1):\85_OHMS-DIFF\"
				( attribute "DIFFP_PRIMARY_GAP" "5.00,7.00,7.00,7.00,7.00,7.00,7.00,7.00,7.00,7.00,7.00,7.00,7.00,5.00"
					( Origin gBackEnd )
				)
				( attribute "DIFFP_COUPLED_PLUS" "0.10,0.10,0.10,0.10,0.10,0.10,0.10,0.10,0.10,0.10,0.10,0.10,0.10,0.10"
					( Origin gBackEnd )
				)
				( attribute "DIFFP_COUPLED_MINUS" "0.01,0.01,0.01,0.01,0.01,0.01,0.01,0.01,0.01,0.01,0.01,0.01,0.01,0.01"
					( Origin gBackEnd )
				)
				( attribute "DIFFP_MIN_SPACE" "3.90,3.90,3.90,3.90,3.90,3.90,3.90,3.90,3.90,3.90,3.90,3.90,3.90,3.90"
					( Origin gBackEnd )
				)
				( attribute "MIN_LINE_WIDTH" "4.50,4.50,4.50,4.50,4.50,4.50,4.50,4.50,4.50,4.50,4.50,4.50,4.50,4.50"
					( Origin gBackEnd )
				)
				( attribute "MAX_LINE_WIDTH" "4.50,4.50,4.50,4.50,4.50,4.50,4.50,4.50,4.50,4.50,4.50,4.50,4.50,4.50"
					( Origin gBackEnd )
				)
				( attribute "DIFFP_NECK_GAP" "4.00,4.00,4.00,4.00,4.00,4.00,4.00,4.00,4.00,4.00,4.00,4.00,4.00,4.00"
					( Origin gBackEnd )
				)
				( attribute "MIN_NECK_WIDTH" "3.50,3.50,3.50,3.50,3.50,3.50,3.50,3.50,3.50,3.50,3.50,3.50,3.50,3.50"
					( Origin gBackEnd )
				)
				( attribute "MAXIMUM_NECK_LENGTH" "1250.00,1250.00,1250.00,1250.00,1250.00,1250.00,1250.00,1250.00,1250.00,1250.00,1250.00,1250.00,1250.00,1250.00"
					( Origin gBackEnd )
				)
				( attribute "VIA_LIST" "V_C20P10AP28,V_C20P10C26AP28_TP,V_C20P10AP28_TP,TP_C26B,TP_C30T,R20X5R20X7D16S,R20X5R20X7D16SB"
					( Origin gBackEnd )
				)
				( attribute "ALLOW_ON_ETCH_SUBCLASS" "TRUE,FALSE,TRUE,FALSE,TRUE,FALSE,FALSE,FALSE,FALSE,TRUE,FALSE,TRUE,FALSE,TRUE"
					( Origin gBackEnd )
				)
				( attribute "TS_ALLOWED" "ANYWHERE,ANYWHERE,ANYWHERE,ANYWHERE,ANYWHERE,ANYWHERE,ANYWHERE,ANYWHERE,ANYWHERE,ANYWHERE,ANYWHERE,ANYWHERE,ANYWHERE,ANYWHERE"
					( Origin gBackEnd )
				)
				( attribute "MIN_BVIA_STAGGER" "5.00,5.00,5.00,5.00,5.00,5.00,5.00,5.00,5.00,5.00,5.00,5.00,5.00,5.00"
					( Origin gBackEnd )
				)
				( attribute "MAX_BVIA_STAGGER" "0.00,0.00,0.00,0.00,0.00,0.00,0.00,0.00,0.00,0.00,0.00,0.00,0.00,0.00"
					( Origin gBackEnd )
				)
				( attribute "PAD_PAD_DIRECT_CONNECT" "ALL_ALLOWED,ALL_ALLOWED,ALL_ALLOWED,ALL_ALLOWED,ALL_ALLOWED,ALL_ALLOWED,ALL_ALLOWED,ALL_ALLOWED,ALL_ALLOWED,ALL_ALLOWED,ALL_ALLOWED,ALL_ALLOWED,ALL_ALLOWED,ALL_ALLOWED"
					( Origin gBackEnd )
				)
				( objectStatus "85_OHM_DIFF" )
			)
			( physicalCSet "@crescent_city_bb_fab1_lib.crescent_city_bb_fab1(sch_1):\BGA_3.5MILS\"
				( attribute "DIFFP_PRIMARY_GAP" "0.00,0.00,0.00,0.00,0.00,0.00,0.00,0.00,0.00,0.00,0.00,0.00,0.00,0.00"
					( Origin gBackEnd )
				)
				( attribute "DIFFP_COUPLED_PLUS" "0.00,0.00,0.00,0.00,0.00,0.00,0.00,0.00,0.00,0.00,0.00,0.00,0.00,0.00"
					( Origin gBackEnd )
				)
				( attribute "DIFFP_COUPLED_MINUS" "0.00,0.00,0.00,0.00,0.00,0.00,0.00,0.00,0.00,0.00,0.00,0.00,0.00,0.00"
					( Origin gBackEnd )
				)
				( attribute "DIFFP_MIN_SPACE" "0.00,0.00,0.00,0.00,0.00,0.00,0.00,0.00,0.00,0.00,0.00,0.00,0.00,0.00"
					( Origin gBackEnd )
				)
				( attribute "MIN_LINE_WIDTH" "3.50,3.50,3.50,3.50,3.50,3.50,3.50,3.50,3.50,3.50,3.50,3.50,3.50,3.50"
					( Origin gBackEnd )
				)
				( attribute "MAX_LINE_WIDTH" "0.00,0.00,0.00,0.00,0.00,0.00,0.00,0.00,0.00,0.00,0.00,0.00,0.00,0.00"
					( Origin gBackEnd )
				)
				( attribute "DIFFP_NECK_GAP" "0.00,0.00,0.00,0.00,0.00,0.00,0.00,0.00,0.00,0.00,0.00,0.00,0.00,0.00"
					( Origin gBackEnd )
				)
				( attribute "MIN_NECK_WIDTH" "3.50,3.50,3.50,3.50,3.50,3.50,3.50,3.50,3.50,3.50,3.50,3.50,3.50,3.50"
					( Origin gBackEnd )
				)
				( attribute "MAXIMUM_NECK_LENGTH" "100.00,100.00,100.00,100.00,100.00,100.00,100.00,100.00,100.00,100.00,100.00,100.00,100.00,100.00"
					( Origin gBackEnd )
				)
				( attribute "VIA_LIST" "V_C20P10AP28,V_C20P10C26AP28_TP,V_C20P10AP28_TP,TP_C26B,TP_C30T"
					( Origin gBackEnd )
				)
				( attribute "ALLOW_ON_ETCH_SUBCLASS" "TRUE,TRUE,TRUE,TRUE,TRUE,TRUE,TRUE,TRUE,TRUE,TRUE,TRUE,TRUE,TRUE,TRUE"
					( Origin gBackEnd )
				)
				( attribute "TS_ALLOWED" "ANYWHERE,ANYWHERE,ANYWHERE,ANYWHERE,ANYWHERE,ANYWHERE,ANYWHERE,ANYWHERE,ANYWHERE,ANYWHERE,ANYWHERE,ANYWHERE,ANYWHERE,ANYWHERE"
					( Origin gBackEnd )
				)
				( attribute "MIN_BVIA_STAGGER" "5.00,5.00,5.00,5.00,5.00,5.00,5.00,5.00,5.00,5.00,5.00,5.00,5.00,5.00"
					( Origin gBackEnd )
				)
				( attribute "MAX_BVIA_STAGGER" "0.00,0.00,0.00,0.00,0.00,0.00,0.00,0.00,0.00,0.00,0.00,0.00,0.00,0.00"
					( Origin gBackEnd )
				)
				( attribute "PAD_PAD_DIRECT_CONNECT" "ALL_ALLOWED,ALL_ALLOWED,ALL_ALLOWED,ALL_ALLOWED,ALL_ALLOWED,ALL_ALLOWED,ALL_ALLOWED,ALL_ALLOWED,ALL_ALLOWED,ALL_ALLOWED,ALL_ALLOWED,ALL_ALLOWED,ALL_ALLOWED,ALL_ALLOWED"
					( Origin gBackEnd )
				)
				( objectStatus "BGA_3.5MILS" )
			)
			( physicalCSet "@crescent_city_bb_fab1_lib.crescent_city_bb_fab1(sch_1):\GND/PWR\"
				( attribute "DIFFP_PRIMARY_GAP" "0.00,0.00,0.00,0.00,0.00,0.00,0.00,0.00,0.00,0.00,0.00,0.00,0.00,0.00"
					( Origin gBackEnd )
				)
				( attribute "DIFFP_COUPLED_PLUS" "0.01,0.01,0.01,0.01,0.01,0.01,0.01,0.01,0.01,0.01,0.01,0.01,0.01,0.01"
					( Origin gBackEnd )
				)
				( attribute "DIFFP_COUPLED_MINUS" "0.00,0.00,0.00,0.00,0.00,0.00,0.00,0.00,0.00,0.00,0.00,0.00,0.00,0.00"
					( Origin gBackEnd )
				)
				( attribute "DIFFP_MIN_SPACE" "4.00,4.00,4.00,4.00,4.00,4.00,4.00,4.00,4.00,4.00,4.00,4.00,4.00,4.00"
					( Origin gBackEnd )
				)
				( attribute "MIN_LINE_WIDTH" "10.00,10.00,10.00,10.00,10.00,10.00,10.00,10.00,10.00,10.00,10.00,10.00,10.00,10.00"
					( Origin gBackEnd )
				)
				( attribute "MAX_LINE_WIDTH" "25.00,25.00,25.00,25.00,25.00,25.00,25.00,25.00,25.00,25.00,25.00,25.00,25.00,25.00"
					( Origin gBackEnd )
				)
				( attribute "DIFFP_NECK_GAP" "4.00,4.00,4.00,4.00,4.00,4.00,4.00,4.00,4.00,4.00,4.00,4.00,4.00,4.00"
					( Origin gBackEnd )
				)
				( attribute "MIN_NECK_WIDTH" "4.00,4.00,4.00,4.00,4.00,4.00,4.00,4.00,4.00,4.00,4.00,4.00,4.00,4.00"
					( Origin gBackEnd )
				)
				( attribute "MAXIMUM_NECK_LENGTH" "1000.00,1000.00,1000.00,1000.00,1000.00,1000.00,1000.00,1000.00,1000.00,1000.00,1000.00,1000.00,1000.00,1000.00"
					( Origin gBackEnd )
				)
				( attribute "VIA_LIST" "V_C20P10AP28,V_C20P10C26AP28_TP,V_C20P10AP28_TP,TP_C26B,TP_C30T,R20X5R20X7D16S,R20X5R20X7D16SB"
					( Origin gBackEnd )
				)
				( attribute "ALLOW_ON_ETCH_SUBCLASS" "TRUE,TRUE,TRUE,TRUE,TRUE,TRUE,TRUE,TRUE,TRUE,TRUE,TRUE,TRUE,TRUE,TRUE"
					( Origin gBackEnd )
				)
				( attribute "TS_ALLOWED" "ANYWHERE,ANYWHERE,ANYWHERE,ANYWHERE,ANYWHERE,ANYWHERE,ANYWHERE,ANYWHERE,ANYWHERE,ANYWHERE,ANYWHERE,ANYWHERE,ANYWHERE,ANYWHERE"
					( Origin gBackEnd )
				)
				( attribute "MIN_BVIA_STAGGER" "5.00,5.00,5.00,5.00,5.00,5.00,5.00,5.00,5.00,5.00,5.00,5.00,5.00,5.00"
					( Origin gBackEnd )
				)
				( attribute "MAX_BVIA_STAGGER" "0.00,0.00,0.00,0.00,0.00,0.00,0.00,0.00,0.00,0.00,0.00,0.00,0.00,0.00"
					( Origin gBackEnd )
				)
				( attribute "PAD_PAD_DIRECT_CONNECT" "ALL_ALLOWED,ALL_ALLOWED,ALL_ALLOWED,ALL_ALLOWED,ALL_ALLOWED,ALL_ALLOWED,ALL_ALLOWED,ALL_ALLOWED,ALL_ALLOWED,ALL_ALLOWED,ALL_ALLOWED,ALL_ALLOWED,ALL_ALLOWED,ALL_ALLOWED"
					( Origin gBackEnd )
				)
				( objectStatus "GND/PWR" )
			)
			( physicalCSet "@crescent_city_bb_fab1_lib.crescent_city_bb_fab1(sch_1):\DEFAULT\"
				( attribute "DIFFP_PRIMARY_GAP" "0.00,0.00,0.00,0.00,0.00,0.00,0.00,0.00,0.00,0.00,0.00,0.00,0.00,0.00"
					( Origin gBackEnd )
				)
				( attribute "DIFFP_COUPLED_PLUS" "0.00,0.00,0.00,0.00,0.00,0.00,0.00,0.00,0.00,0.00,0.00,0.00,0.00,0.00"
					( Origin gBackEnd )
				)
				( attribute "DIFFP_COUPLED_MINUS" "0.00,0.00,0.00,0.00,0.00,0.00,0.00,0.00,0.00,0.00,0.00,0.00,0.00,0.00"
					( Origin gBackEnd )
				)
				( attribute "DIFFP_MIN_SPACE" "0.00,0.00,0.00,0.00,0.00,0.00,0.00,0.00,0.00,0.00,0.00,0.00,0.00,0.00"
					( Origin gBackEnd )
				)
				( attribute "MIN_LINE_WIDTH" "4.25,3.52,3.52,3.52,3.52,3.52,3.52,3.52,3.52,3.52,3.52,3.52,3.52,4.25"
					( Origin gBackEnd )
				)
				( attribute "MAX_LINE_WIDTH" "25.00,25.00,25.00,25.00,25.00,25.00,25.00,25.00,25.00,25.00,25.00,25.00,25.00,25.00"
					( Origin gBackEnd )
				)
				( attribute "DIFFP_NECK_GAP" "0.00,0.00,0.00,0.00,0.00,0.00,0.00,0.00,0.00,0.00,0.00,0.00,0.00,0.00"
					( Origin gBackEnd )
				)
				( attribute "MIN_NECK_WIDTH" "3.50,3.50,3.50,3.50,3.50,3.50,3.50,3.50,3.50,3.50,3.50,3.50,3.50,3.50"
					( Origin gBackEnd )
				)
				( attribute "MAXIMUM_NECK_LENGTH" "800.00,800.00,800.00,800.00,800.00,800.00,800.00,800.00,800.00,800.00,800.00,800.00,800.00,800.00"
					( Origin gBackEnd )
				)
				( attribute "VIA_LIST" "V_C20P10AP28,V_C20P10C26AP28_TP,V_C20P10AP28_TP,TP_C26B,TP_C30T,R20X5R20X7D16S,R20X5R20X7D16SB"
					( Origin gBackEnd )
				)
				( attribute "ALLOW_ON_ETCH_SUBCLASS" "TRUE,TRUE,TRUE,TRUE,TRUE,TRUE,TRUE,TRUE,TRUE,TRUE,TRUE,TRUE,TRUE,TRUE"
					( Origin gBackEnd )
				)
				( attribute "TS_ALLOWED" "ANYWHERE,ANYWHERE,ANYWHERE,ANYWHERE,ANYWHERE,ANYWHERE,ANYWHERE,ANYWHERE,ANYWHERE,ANYWHERE,ANYWHERE,ANYWHERE,ANYWHERE,ANYWHERE"
					( Origin gBackEnd )
				)
				( attribute "MIN_BVIA_STAGGER" "5.00,5.00,5.00,5.00,5.00,5.00,5.00,5.00,5.00,5.00,5.00,5.00,5.00,5.00"
					( Origin gBackEnd )
				)
				( attribute "MAX_BVIA_STAGGER" "0.00,0.00,0.00,0.00,0.00,0.00,0.00,0.00,0.00,0.00,0.00,0.00,0.00,0.00"
					( Origin gBackEnd )
				)
				( attribute "PAD_PAD_DIRECT_CONNECT" "ALL_ALLOWED,ALL_ALLOWED,ALL_ALLOWED,ALL_ALLOWED,ALL_ALLOWED,ALL_ALLOWED,ALL_ALLOWED,ALL_ALLOWED,ALL_ALLOWED,ALL_ALLOWED,ALL_ALLOWED,ALL_ALLOWED,ALL_ALLOWED,ALL_ALLOWED"
					( Origin gBackEnd )
				)
				( objectStatus "DEFAULT" )
			)
			( spacingCSet "@baseboard_fab2_lib.baseboard_fab2(sch_1):\NEW_KR_15H_US_&_7H_SL_VIA_2H+A\"
				( attribute "THRUPIN_TO_THRUPIN_SPACING" "5.00,5.00,5.00,5.00,5.00,5.00,5.00,5.00,5.00,5.00,5.00,5.00,5.00,5.00"
					( Origin gBackEnd )
				)
				( attribute "THRUPIN_TO_SMDPIN_SPACING" "5.00,5.00,5.00,5.00,5.00,5.00,5.00,5.00,5.00,5.00,5.00,5.00,5.00,5.00"
					( Origin gBackEnd )
				)
				( attribute "TESTPIN_TO_THRUPIN_SPACING" "5.00,5.00,5.00,5.00,5.00,5.00,5.00,5.00,5.00,5.00,5.00,5.00,5.00,5.00"
					( Origin gBackEnd )
				)
				( attribute "THRUPIN_TO_THRUVIA_SPACING" "5.00,5.00,5.00,5.00,5.00,5.00,5.00,5.00,5.00,5.00,5.00,5.00,5.00,5.00"
					( Origin gBackEnd )
				)
				( attribute "TESTVIA_TO_THRUPIN_SPACING" "5.00,5.00,5.00,5.00,5.00,5.00,5.00,5.00,5.00,5.00,5.00,5.00,5.00,5.00"
					( Origin gBackEnd )
				)
				( attribute "BBV_TO_THRUPIN_SPACING" "5.00,5.00,5.00,5.00,5.00,5.00,5.00,5.00,5.00,5.00,5.00,5.00,5.00,5.00"
					( Origin gBackEnd )
				)
				( attribute "THRUPIN_TO_BONDPAD_SPACING" "5.00,5.00,5.00,5.00,5.00,5.00,5.00,5.00,5.00,5.00,5.00,5.00,5.00,5.00"
					( Origin gBackEnd )
				)
				( attribute "LINE_TO_THRUPIN_SPACING" "4.50,4.00,4.00,4.00,4.00,4.00,4.00,4.00,4.00,4.00,4.00,4.00,4.00,4.50"
					( Origin gBackEnd )
				)
				( attribute "THRUPIN_TO_SHAPE_SPACING" "5.00,5.00,5.00,5.00,5.00,5.00,5.00,5.00,5.00,5.00,5.00,5.00,5.00,5.00"
					( Origin gBackEnd )
				)
				( attribute "SMDPIN_TO_SMDPIN_SPACING" "5.00,5.00,5.00,5.00,5.00,5.00,5.00,5.00,5.00,5.00,5.00,5.00,5.00,5.00"
					( Origin gBackEnd )
				)
				( attribute "SMDPIN_TO_TESTPIN_SPACING" "5.00,5.00,5.00,5.00,5.00,5.00,5.00,5.00,5.00,5.00,5.00,5.00,5.00,25.00"
					( Origin gBackEnd )
				)
				( attribute "SMDPIN_TO_THRUVIA_SPACING" "5.00,5.00,5.00,5.00,5.00,5.00,5.00,5.00,5.00,5.00,5.00,5.00,5.00,5.00"
					( Origin gBackEnd )
				)
				( attribute "SMDPIN_TO_TESTVIA_SPACING" "5.00,5.00,5.00,5.00,5.00,5.00,5.00,5.00,5.00,5.00,5.00,5.00,5.00,5.00"
					( Origin gBackEnd )
				)
				( attribute "BBV_TO_SMDPIN_SPACING" "5.00,5.00,5.00,5.00,5.00,5.00,5.00,5.00,5.00,5.00,5.00,5.00,5.00,5.00"
					( Origin gBackEnd )
				)
				( attribute "SMDPIN_TO_BONDPAD_SPACING" "5.00,5.00,5.00,5.00,5.00,5.00,5.00,5.00,5.00,5.00,5.00,5.00,5.00,5.00"
					( Origin gBackEnd )
				)
				( attribute "LINE_TO_SMDPIN_SPACING" "4.50,4.50,4.50,4.50,4.50,4.50,4.50,4.50,4.50,4.50,4.50,4.50,4.50,4.50"
					( Origin gBackEnd )
				)
				( attribute "SHAPE_TO_SMDPIN_SPACING" "5.00,5.00,5.00,5.00,5.00,5.00,5.00,5.00,5.00,5.00,5.00,5.00,5.00,5.00"
					( Origin gBackEnd )
				)
				( attribute "TESTPIN_TO_TESTPIN_SPACING" "5.00,5.00,5.00,5.00,5.00,5.00,5.00,5.00,5.00,5.00,5.00,5.00,5.00,5.00"
					( Origin gBackEnd )
				)
				( attribute "TESTPIN_TO_THRUVIA_SPACING" "5.00,5.00,5.00,5.00,5.00,5.00,5.00,5.00,5.00,5.00,5.00,5.00,5.00,5.00"
					( Origin gBackEnd )
				)
				( attribute "TESTPIN_TO_TESTVIA_SPACING" "5.00,5.00,5.00,5.00,5.00,5.00,5.00,5.00,5.00,5.00,5.00,5.00,5.00,5.00"
					( Origin gBackEnd )
				)
				( attribute "BBV_TO_TESTPIN_SPACING" "5.00,5.00,5.00,5.00,5.00,5.00,5.00,5.00,5.00,5.00,5.00,5.00,5.00,5.00"
					( Origin gBackEnd )
				)
				( attribute "BONDPAD_TO_TESTPIN_SPACING" "5.00,5.00,5.00,5.00,5.00,5.00,5.00,5.00,5.00,5.00,5.00,5.00,5.00,5.00"
					( Origin gBackEnd )
				)
				( attribute "LINE_TO_TESTPIN_SPACING" "5.00,4.00,4.00,4.00,4.00,4.00,4.00,4.00,4.00,4.00,4.00,4.00,4.00,5.00"
					( Origin gBackEnd )
				)
				( attribute "SHAPE_TO_TESTPIN_SPACING" "5.00,5.00,5.00,5.00,5.00,5.00,5.00,5.00,5.00,5.00,5.00,5.00,5.00,5.00"
					( Origin gBackEnd )
				)
				( attribute "THRUVIA_TO_THRUVIA_SPACING" "5.00,5.00,5.00,5.00,5.00,5.00,5.00,5.00,5.00,5.00,5.00,5.00,5.00,5.00"
					( Origin gBackEnd )
				)
				( attribute "TESTVIA_TO_THRUVIA_SPACING" "6.00,6.00,6.00,6.00,6.00,6.00,6.00,6.00,6.00,6.00,6.00,6.00,6.00,6.00"
					( Origin gBackEnd )
				)
				( attribute "BBV_TO_THRUVIA_SPACING" "5.00,5.00,5.00,5.00,5.00,5.00,5.00,5.00,5.00,5.00,5.00,5.00,5.00,5.00"
					( Origin gBackEnd )
				)
				( attribute "BONDPAD_TO_THRUVIA_SPACING" "5.00,5.00,5.00,5.00,5.00,5.00,5.00,5.00,5.00,5.00,5.00,5.00,5.00,5.00"
					( Origin gBackEnd )
				)
				( attribute "LINE_TO_THRUVIA_SPACING" "6.02,5.80,5.80,5.80,5.80,5.80,5.80,5.80,5.80,5.80,5.80,5.80,5.80,6.02"
					( Origin gBackEnd )
				)
				( attribute "SHAPE_TO_THRUVIA_SPACING" "5.00,5.00,5.00,5.00,5.00,5.00,5.00,5.00,5.00,5.00,5.00,5.00,5.00,5.00"
					( Origin gBackEnd )
				)
				( attribute "TESTVIA_TO_TESTVIA_SPACING" "6.00,6.00,6.00,6.00,6.00,6.00,6.00,6.00,6.00,6.00,6.00,6.00,6.00,6.00"
					( Origin gBackEnd )
				)
				( attribute "BBV_TO_TESTVIA_SPACING" "5.00,5.00,5.00,5.00,5.00,5.00,5.00,5.00,5.00,5.00,5.00,5.00,5.00,5.00"
					( Origin gBackEnd )
				)
				( attribute "BONDPAD_TO_TESTVIA_SPACING" "5.00,5.00,5.00,5.00,5.00,5.00,5.00,5.00,5.00,5.00,5.00,5.00,5.00,5.00"
					( Origin gBackEnd )
				)
				( attribute "LINE_TO_TESTVIA_SPACING" "4.50,4.00,4.00,4.00,4.00,4.00,4.00,4.00,4.00,4.00,4.00,4.00,4.00,4.50"
					( Origin gBackEnd )
				)
				( attribute "SHAPE_TO_TESTVIA_SPACING" "5.00,5.00,5.00,5.00,5.00,5.00,5.00,5.00,5.00,5.00,5.00,5.00,5.00,5.00"
					( Origin gBackEnd )
				)
				( attribute "BBV_TO_BBV_SPACING" "5.00,5.00,5.00,5.00,5.00,5.00,5.00,5.00,5.00,5.00,5.00,5.00,5.00,5.00"
					( Origin gBackEnd )
				)
				( attribute "BONDPAD_TO_BBV_SPACING" "5.00,5.00,5.00,5.00,5.00,5.00,5.00,5.00,5.00,5.00,5.00,5.00,5.00,5.00"
					( Origin gBackEnd )
				)
				( attribute "BBV_TO_LINE_SPACING" "5.00,5.00,5.00,5.00,5.00,5.00,5.00,5.00,5.00,5.00,5.00,5.00,5.00,5.00"
					( Origin gBackEnd )
				)
				( attribute "BBV_TO_SHAPE_SPACING" "5.00,5.00,5.00,5.00,5.00,5.00,5.00,5.00,5.00,5.00,5.00,5.00,5.00,5.00"
					( Origin gBackEnd )
				)
				( attribute "BONDPAD_TO_BONDPAD_SPACING" "5.00,5.00,5.00,5.00,5.00,5.00,5.00,5.00,5.00,5.00,5.00,5.00,5.00,5.00"
					( Origin gBackEnd )
				)
				( attribute "BONDPAD_TO_LINE_SPACING" "5.00,5.00,5.00,5.00,5.00,5.00,5.00,5.00,5.00,5.00,5.00,5.00,5.00,5.00"
					( Origin gBackEnd )
				)
				( attribute "BONDPAD_TO_SHAPE_SPACING" "5.00,5.00,5.00,5.00,5.00,5.00,5.00,5.00,5.00,5.00,5.00,5.00,5.00,5.00"
					( Origin gBackEnd )
				)
				( attribute "LINE_TO_LINE_SPACING" "45.15,20.30,20.30,20.30,20.30,20.30,20.30,20.30,20.30,20.30,20.30,20.30,20.30,45.15"
					( Origin gBackEnd )
				)
				( attribute "LINE_TO_SHAPE_SPACING" "10.00,10.00,10.00,10.00,10.00,10.00,10.00,10.00,10.00,10.00,10.00,10.00,10.00,10.00"
					( Origin gBackEnd )
				)
				( attribute "SHAPE_TO_SHAPE_SPACING" "10.00,10.00,10.00,10.00,10.00,10.00,10.00,10.00,10.00,10.00,10.00,10.00,10.00,10.00"
					( Origin gBackEnd )
				)
				( attribute "HOLE_TO_PIN_SPACING" "8.00,8.00,8.00,8.00,8.00,8.00,8.00,8.00,8.00,8.00,8.00,8.00,8.00,8.00"
					( Origin gBackEnd )
				)
				( attribute "HOLE_TO_VIA_SPACING" "8.00,8.00,8.00,8.00,8.00,8.00,8.00,8.00,8.00,8.00,8.00,8.00,8.00,8.00"
					( Origin gBackEnd )
				)
				( attribute "HOLE_TO_LINE_SPACING" "8.00,8.00,8.00,8.00,8.00,8.00,8.00,8.00,8.00,8.00,8.00,8.00,8.00,8.00"
					( Origin gBackEnd )
				)
				( attribute "HOLE_TO_SHAPE_SPACING" "8.00,8.00,8.00,8.00,8.00,8.00,8.00,8.00,8.00,8.00,8.00,8.00,8.00,8.00"
					( Origin gBackEnd )
				)
				( attribute "HOLE_TO_HOLE_SPACING" "8.00,8.00,8.00,8.00,8.00,8.00,8.00,8.00,8.00,8.00,8.00,8.00,8.00,8.00"
					( Origin gBackEnd )
				)
				( attribute "MVIA_TO_MVIA_SPACING" "5.00,5.00,5.00,5.00,5.00,5.00,5.00,5.00,5.00,5.00,5.00,5.00,5.00,5.00"
					( Origin gBackEnd )
				)
				( attribute "MVIA_TO_THRUPIN_SPACING" "5.00,5.00,5.00,5.00,5.00,5.00,5.00,5.00,5.00,5.00,5.00,5.00,5.00,5.00"
					( Origin gBackEnd )
				)
				( attribute "MVIA_TO_SMDPIN_SPACING" "5.00,5.00,5.00,5.00,5.00,5.00,5.00,5.00,5.00,5.00,5.00,5.00,5.00,5.00"
					( Origin gBackEnd )
				)
				( attribute "MVIA_TO_THRUVIA_SPACING" "5.00,5.00,5.00,5.00,5.00,5.00,5.00,5.00,5.00,5.00,5.00,5.00,5.00,5.00"
					( Origin gBackEnd )
				)
				( attribute "MVIA_TO_BBV_SPACING" "5.00,5.00,5.00,5.00,5.00,5.00,5.00,5.00,5.00,5.00,5.00,5.00,5.00,5.00"
					( Origin gBackEnd )
				)
				( attribute "MVIA_TO_LINE_SPACING" "5.00,5.00,5.00,5.00,5.00,5.00,5.00,5.00,5.00,5.00,5.00,5.00,5.00,5.00"
					( Origin gBackEnd )
				)
				( attribute "MVIA_TO_SHAPE_SPACING" "5.00,5.00,5.00,5.00,5.00,5.00,5.00,5.00,5.00,5.00,5.00,5.00,5.00,5.00"
					( Origin gBackEnd )
				)
				( attribute "MVIA_TO_TESTPIN_SPACING" "5.00,5.00,5.00,5.00,5.00,5.00,5.00,5.00,5.00,5.00,5.00,5.00,5.00,5.00"
					( Origin gBackEnd )
				)
				( attribute "MVIA_TO_TESTVIA_SPACING" "5.00,5.00,5.00,5.00,5.00,5.00,5.00,5.00,5.00,5.00,5.00,5.00,5.00,5.00"
					( Origin gBackEnd )
				)
				( attribute "BONDPAD_TO_MVIA_SPACING" "5.00,5.00,5.00,5.00,5.00,5.00,5.00,5.00,5.00,5.00,5.00,5.00,5.00,5.00"
					( Origin gBackEnd )
				)
				( attribute "MIN_BVIA_GAP" "5.00"
					( Origin gBackEnd )
				)
				( attribute "BONDPAD_TO_BONDPAD_DIFFP_SPC" "5.00,5.00,5.00,5.00,5.00,5.00,5.00,5.00,5.00,5.00,5.00,5.00,5.00,5.00"
					( Origin gBackEnd )
				)
				( objectStatus "OPT2_KR_15H_US_&_7H_SL_VIA_2H+A" )
			)
			( spacingCSet "@baseboard_fab2_lib.baseboard_fab2(sch_1):\NEW_NIC_7H_US_&_6H_SL\"
				( attribute "THRUPIN_TO_THRUPIN_SPACING" "5.00,5.00,5.00,5.00,5.00,5.00,5.00,5.00,5.00,5.00,5.00,5.00,5.00,5.00"
					( Origin gBackEnd )
				)
				( attribute "THRUPIN_TO_SMDPIN_SPACING" "5.00,5.00,5.00,5.00,5.00,5.00,5.00,5.00,5.00,5.00,5.00,5.00,5.00,5.00"
					( Origin gBackEnd )
				)
				( attribute "TESTPIN_TO_THRUPIN_SPACING" "5.00,5.00,5.00,5.00,5.00,5.00,5.00,5.00,5.00,5.00,5.00,5.00,5.00,5.00"
					( Origin gBackEnd )
				)
				( attribute "THRUPIN_TO_THRUVIA_SPACING" "5.00,5.00,5.00,5.00,5.00,5.00,5.00,5.00,5.00,5.00,5.00,5.00,5.00,5.00"
					( Origin gBackEnd )
				)
				( attribute "TESTVIA_TO_THRUPIN_SPACING" "5.00,5.00,5.00,5.00,5.00,5.00,5.00,5.00,5.00,5.00,5.00,5.00,5.00,5.00"
					( Origin gBackEnd )
				)
				( attribute "BBV_TO_THRUPIN_SPACING" "5.00,5.00,5.00,5.00,5.00,5.00,5.00,5.00,5.00,5.00,5.00,5.00,5.00,5.00"
					( Origin gBackEnd )
				)
				( attribute "THRUPIN_TO_BONDPAD_SPACING" "5.00,5.00,5.00,5.00,5.00,5.00,5.00,5.00,5.00,5.00,5.00,5.00,5.00,5.00"
					( Origin gBackEnd )
				)
				( attribute "LINE_TO_THRUPIN_SPACING" "8.00,8.00,8.00,8.00,8.00,8.00,8.00,8.00,8.00,8.00,8.00,8.00,8.00,8.00"
					( Origin gBackEnd )
				)
				( attribute "THRUPIN_TO_SHAPE_SPACING" "4.50,4.00,4.00,4.00,4.00,4.00,4.00,4.00,4.00,4.00,4.00,4.00,4.00,4.00"
					( Origin gBackEnd )
				)
				( attribute "SMDPIN_TO_SMDPIN_SPACING" "5.00,5.00,5.00,5.00,5.00,5.00,5.00,5.00,5.00,5.00,5.00,5.00,5.00,5.00"
					( Origin gBackEnd )
				)
				( attribute "SMDPIN_TO_TESTPIN_SPACING" "5.00,5.00,5.00,5.00,5.00,5.00,5.00,5.00,5.00,5.00,5.00,5.00,5.00,5.00"
					( Origin gBackEnd )
				)
				( attribute "SMDPIN_TO_THRUVIA_SPACING" "5.00,5.00,5.00,5.00,5.00,5.00,5.00,5.00,5.00,5.00,5.00,5.00,5.00,5.00"
					( Origin gBackEnd )
				)
				( attribute "SMDPIN_TO_TESTVIA_SPACING" "5.00,5.00,5.00,5.00,5.00,5.00,5.00,5.00,5.00,5.00,5.00,5.00,5.00,5.00"
					( Origin gBackEnd )
				)
				( attribute "BBV_TO_SMDPIN_SPACING" "5.00,5.00,5.00,5.00,5.00,5.00,5.00,5.00,5.00,5.00,5.00,5.00,5.00,5.00"
					( Origin gBackEnd )
				)
				( attribute "SMDPIN_TO_BONDPAD_SPACING" "5.00,5.00,5.00,5.00,5.00,5.00,5.00,5.00,5.00,5.00,5.00,5.00,5.00,5.00"
					( Origin gBackEnd )
				)
				( attribute "LINE_TO_SMDPIN_SPACING" "4.50,4.50,4.50,4.50,4.50,4.50,4.50,4.50,4.50,4.50,4.50,4.50,4.50,4.50"
					( Origin gBackEnd )
				)
				( attribute "SHAPE_TO_SMDPIN_SPACING" "5.00,5.00,5.00,5.00,5.00,5.00,5.00,5.00,5.00,5.00,5.00,5.00,5.00,5.00"
					( Origin gBackEnd )
				)
				( attribute "TESTPIN_TO_TESTPIN_SPACING" "5.00,5.00,5.00,5.00,5.00,5.00,5.00,5.00,5.00,5.00,5.00,5.00,5.00,5.00"
					( Origin gBackEnd )
				)
				( attribute "TESTPIN_TO_THRUVIA_SPACING" "5.00,5.00,5.00,5.00,5.00,5.00,5.00,5.00,5.00,5.00,5.00,5.00,5.00,5.00"
					( Origin gBackEnd )
				)
				( attribute "TESTPIN_TO_TESTVIA_SPACING" "5.00,5.00,5.00,5.00,5.00,5.00,5.00,5.00,5.00,5.00,5.00,5.00,5.00,5.00"
					( Origin gBackEnd )
				)
				( attribute "BBV_TO_TESTPIN_SPACING" "5.00,5.00,5.00,5.00,5.00,5.00,5.00,5.00,5.00,5.00,5.00,5.00,5.00,5.00"
					( Origin gBackEnd )
				)
				( attribute "BONDPAD_TO_TESTPIN_SPACING" "5.00,5.00,5.00,5.00,5.00,5.00,5.00,5.00,5.00,5.00,5.00,5.00,5.00,5.00"
					( Origin gBackEnd )
				)
				( attribute "LINE_TO_TESTPIN_SPACING" "4.50,5.00,5.00,5.00,5.00,5.00,5.00,5.00,5.00,5.00,5.00,5.00,5.00,5.00"
					( Origin gBackEnd )
				)
				( attribute "SHAPE_TO_TESTPIN_SPACING" "4.50,4.00,4.00,4.00,4.00,4.00,4.00,4.00,4.00,4.00,4.00,4.00,4.00,4.00"
					( Origin gBackEnd )
				)
				( attribute "THRUVIA_TO_THRUVIA_SPACING" "5.00,5.00,5.00,5.00,5.00,5.00,5.00,5.00,5.00,5.00,5.00,5.00,5.00,5.00"
					( Origin gBackEnd )
				)
				( attribute "TESTVIA_TO_THRUVIA_SPACING" "5.00,5.00,5.00,5.00,5.00,5.00,5.00,5.00,5.00,5.00,5.00,5.00,5.00,5.00"
					( Origin gBackEnd )
				)
				( attribute "BBV_TO_THRUVIA_SPACING" "5.00,5.00,5.00,5.00,5.00,5.00,5.00,5.00,5.00,5.00,5.00,5.00,5.00,5.00"
					( Origin gBackEnd )
				)
				( attribute "BONDPAD_TO_THRUVIA_SPACING" "5.00,5.00,5.00,5.00,5.00,5.00,5.00,5.00,5.00,5.00,5.00,5.00,5.00,5.00"
					( Origin gBackEnd )
				)
				( attribute "LINE_TO_THRUVIA_SPACING" "4.50,4.00,4.00,4.00,4.00,4.00,4.00,4.00,4.00,4.00,4.00,4.00,4.00,4.50"
					( Origin gBackEnd )
				)
				( attribute "SHAPE_TO_THRUVIA_SPACING" "4.50,4.00,4.00,4.00,4.00,4.00,4.00,4.00,4.00,4.00,4.00,4.00,4.00,4.00"
					( Origin gBackEnd )
				)
				( attribute "TESTVIA_TO_TESTVIA_SPACING" "5.00,5.00,5.00,5.00,5.00,5.00,5.00,5.00,5.00,5.00,5.00,5.00,5.00,5.00"
					( Origin gBackEnd )
				)
				( attribute "BBV_TO_TESTVIA_SPACING" "5.00,5.00,5.00,5.00,5.00,5.00,5.00,5.00,5.00,5.00,5.00,5.00,5.00,5.00"
					( Origin gBackEnd )
				)
				( attribute "BONDPAD_TO_TESTVIA_SPACING" "5.00,5.00,5.00,5.00,5.00,5.00,5.00,5.00,5.00,5.00,5.00,5.00,5.00,5.00"
					( Origin gBackEnd )
				)
				( attribute "LINE_TO_TESTVIA_SPACING" "4.50,5.00,4.00,5.00,4.00,5.00,5.00,5.00,5.00,4.00,5.00,4.00,5.00,4.50"
					( Origin gBackEnd )
				)
				( attribute "SHAPE_TO_TESTVIA_SPACING" "4.50,4.00,4.00,4.00,4.00,4.00,4.00,4.00,4.00,4.00,4.00,4.00,4.00,4.00"
					( Origin gBackEnd )
				)
				( attribute "BBV_TO_BBV_SPACING" "5.00,5.00,5.00,5.00,5.00,5.00,5.00,5.00,5.00,5.00,5.00,5.00,5.00,5.00"
					( Origin gBackEnd )
				)
				( attribute "BONDPAD_TO_BBV_SPACING" "5.00,5.00,5.00,5.00,5.00,5.00,5.00,5.00,5.00,5.00,5.00,5.00,5.00,5.00"
					( Origin gBackEnd )
				)
				( attribute "BBV_TO_LINE_SPACING" "5.00,5.00,5.00,5.00,5.00,5.00,5.00,5.00,5.00,5.00,5.00,5.00,5.00,5.00"
					( Origin gBackEnd )
				)
				( attribute "BBV_TO_SHAPE_SPACING" "5.00,5.00,5.00,5.00,5.00,5.00,5.00,5.00,5.00,5.00,5.00,5.00,5.00,5.00"
					( Origin gBackEnd )
				)
				( attribute "BONDPAD_TO_BONDPAD_SPACING" "5.00,5.00,5.00,5.00,5.00,5.00,5.00,5.00,5.00,5.00,5.00,5.00,5.00,5.00"
					( Origin gBackEnd )
				)
				( attribute "BONDPAD_TO_LINE_SPACING" "5.00,5.00,5.00,5.00,5.00,5.00,5.00,5.00,5.00,5.00,5.00,5.00,5.00,5.00"
					( Origin gBackEnd )
				)
				( attribute "BONDPAD_TO_SHAPE_SPACING" "5.00,5.00,5.00,5.00,5.00,5.00,5.00,5.00,5.00,5.00,5.00,5.00,5.00,5.00"
					( Origin gBackEnd )
				)
				( attribute "LINE_TO_LINE_SPACING" "21.07,17.40,17.40,17.40,17.40,17.40,17.40,17.40,17.40,17.40,17.40,17.40,17.40,21.07"
					( Origin gBackEnd )
				)
				( attribute "LINE_TO_SHAPE_SPACING" "14.00,14.00,14.00,14.00,14.00,14.00,14.00,14.00,14.00,14.00,14.00,18.00,14.00,14.00"
					( Origin gBackEnd )
				)
				( attribute "SHAPE_TO_SHAPE_SPACING" "10.00,10.00,10.00,10.00,10.00,10.00,10.00,10.00,10.00,10.00,10.00,10.00,10.00,10.00"
					( Origin gBackEnd )
				)
				( attribute "HOLE_TO_PIN_SPACING" "8.00,8.00,8.00,8.00,8.00,8.00,8.00,8.00,8.00,8.00,8.00,8.00,8.00,8.00"
					( Origin gBackEnd )
				)
				( attribute "HOLE_TO_VIA_SPACING" "8.00,8.00,8.00,8.00,8.00,8.00,8.00,8.00,8.00,8.00,8.00,8.00,8.00,8.00"
					( Origin gBackEnd )
				)
				( attribute "HOLE_TO_LINE_SPACING" "8.00,8.00,8.00,8.00,8.00,8.00,8.00,8.00,8.00,8.00,8.00,8.00,8.00,8.00"
					( Origin gBackEnd )
				)
				( attribute "HOLE_TO_SHAPE_SPACING" "8.00,8.00,8.00,8.00,8.00,8.00,8.00,8.00,8.00,8.00,8.00,8.00,8.00,8.00"
					( Origin gBackEnd )
				)
				( attribute "HOLE_TO_HOLE_SPACING" "8.00,8.00,8.00,8.00,8.00,8.00,8.00,8.00,8.00,8.00,8.00,8.00,8.00,8.00"
					( Origin gBackEnd )
				)
				( attribute "MVIA_TO_MVIA_SPACING" "5.00,5.00,5.00,5.00,5.00,5.00,5.00,5.00,5.00,5.00,5.00,5.00,5.00,5.00"
					( Origin gBackEnd )
				)
				( attribute "MVIA_TO_THRUPIN_SPACING" "5.00,5.00,5.00,5.00,5.00,5.00,5.00,5.00,5.00,5.00,5.00,5.00,5.00,5.00"
					( Origin gBackEnd )
				)
				( attribute "MVIA_TO_SMDPIN_SPACING" "5.00,5.00,5.00,5.00,5.00,5.00,5.00,5.00,5.00,5.00,5.00,5.00,5.00,5.00"
					( Origin gBackEnd )
				)
				( attribute "MVIA_TO_THRUVIA_SPACING" "5.00,5.00,5.00,5.00,5.00,5.00,5.00,5.00,5.00,5.00,5.00,5.00,5.00,5.00"
					( Origin gBackEnd )
				)
				( attribute "MVIA_TO_BBV_SPACING" "5.00,5.00,5.00,5.00,5.00,5.00,5.00,5.00,5.00,5.00,5.00,5.00,5.00,5.00"
					( Origin gBackEnd )
				)
				( attribute "MVIA_TO_LINE_SPACING" "5.00,5.00,5.00,5.00,5.00,5.00,5.00,5.00,5.00,5.00,5.00,5.00,5.00,5.00"
					( Origin gBackEnd )
				)
				( attribute "MVIA_TO_SHAPE_SPACING" "5.00,5.00,5.00,5.00,5.00,5.00,5.00,5.00,5.00,5.00,5.00,5.00,5.00,5.00"
					( Origin gBackEnd )
				)
				( attribute "MVIA_TO_TESTPIN_SPACING" "5.00,5.00,5.00,5.00,5.00,5.00,5.00,5.00,5.00,5.00,5.00,5.00,5.00,5.00"
					( Origin gBackEnd )
				)
				( attribute "MVIA_TO_TESTVIA_SPACING" "5.00,5.00,5.00,5.00,5.00,5.00,5.00,5.00,5.00,5.00,5.00,5.00,5.00,5.00"
					( Origin gBackEnd )
				)
				( attribute "BONDPAD_TO_MVIA_SPACING" "5.00,5.00,5.00,5.00,5.00,5.00,5.00,5.00,5.00,5.00,5.00,5.00,5.00,5.00"
					( Origin gBackEnd )
				)
				( attribute "MIN_BVIA_GAP" "5.00"
					( Origin gBackEnd )
				)
				( attribute "BONDPAD_TO_BONDPAD_DIFFP_SPC" "5.00,5.00,5.00,5.00,5.00,5.00,5.00,5.00,5.00,5.00,5.00,5.00,5.00,5.00"
					( Origin gBackEnd )
				)
				( objectStatus "OPT2_NIC_7H_US_&_6H_SL" )
			)
			( spacingCSet "@baseboard_fab2_lib.baseboard_fab2(sch_1):\NEW_KR_15H_US_&_7H_SL\"
				( attribute "THRUPIN_TO_THRUPIN_SPACING" "5.00,5.00,5.00,5.00,5.00,5.00,5.00,5.00,5.00,5.00,5.00,5.00,5.00,5.00"
					( Origin gBackEnd )
				)
				( attribute "THRUPIN_TO_SMDPIN_SPACING" "5.00,5.00,5.00,5.00,5.00,5.00,5.00,5.00,5.00,5.00,5.00,5.00,5.00,5.00"
					( Origin gBackEnd )
				)
				( attribute "TESTPIN_TO_THRUPIN_SPACING" "5.00,5.00,5.00,5.00,5.00,5.00,5.00,5.00,5.00,5.00,5.00,5.00,5.00,5.00"
					( Origin gBackEnd )
				)
				( attribute "THRUPIN_TO_THRUVIA_SPACING" "5.00,5.00,5.00,5.00,5.00,5.00,5.00,5.00,5.00,5.00,5.00,5.00,5.00,5.00"
					( Origin gBackEnd )
				)
				( attribute "TESTVIA_TO_THRUPIN_SPACING" "5.00,5.00,5.00,5.00,5.00,5.00,5.00,5.00,5.00,5.00,5.00,5.00,5.00,5.00"
					( Origin gBackEnd )
				)
				( attribute "BBV_TO_THRUPIN_SPACING" "5.00,5.00,5.00,5.00,5.00,5.00,5.00,5.00,5.00,5.00,5.00,5.00,5.00,5.00"
					( Origin gBackEnd )
				)
				( attribute "THRUPIN_TO_BONDPAD_SPACING" "5.00,5.00,5.00,5.00,5.00,5.00,5.00,5.00,5.00,5.00,5.00,5.00,5.00,5.00"
					( Origin gBackEnd )
				)
				( attribute "LINE_TO_THRUPIN_SPACING" "4.50,4.00,4.00,4.00,4.00,4.00,4.00,4.00,4.00,4.00,4.00,4.00,4.00,4.50"
					( Origin gBackEnd )
				)
				( attribute "THRUPIN_TO_SHAPE_SPACING" "5.00,5.00,5.00,5.00,5.00,5.00,5.00,5.00,5.00,5.00,5.00,5.00,5.00,5.00"
					( Origin gBackEnd )
				)
				( attribute "SMDPIN_TO_SMDPIN_SPACING" "5.00,5.00,5.00,5.00,5.00,5.00,5.00,5.00,5.00,5.00,5.00,5.00,5.00,5.00"
					( Origin gBackEnd )
				)
				( attribute "SMDPIN_TO_TESTPIN_SPACING" "5.00,5.00,5.00,5.00,5.00,5.00,5.00,5.00,5.00,5.00,5.00,5.00,5.00,25.00"
					( Origin gBackEnd )
				)
				( attribute "SMDPIN_TO_THRUVIA_SPACING" "5.00,5.00,5.00,5.00,5.00,5.00,5.00,5.00,5.00,5.00,5.00,5.00,5.00,5.00"
					( Origin gBackEnd )
				)
				( attribute "SMDPIN_TO_TESTVIA_SPACING" "5.00,5.00,5.00,5.00,5.00,5.00,5.00,5.00,5.00,5.00,5.00,5.00,5.00,5.00"
					( Origin gBackEnd )
				)
				( attribute "BBV_TO_SMDPIN_SPACING" "5.00,5.00,5.00,5.00,5.00,5.00,5.00,5.00,5.00,5.00,5.00,5.00,5.00,5.00"
					( Origin gBackEnd )
				)
				( attribute "SMDPIN_TO_BONDPAD_SPACING" "5.00,5.00,5.00,5.00,5.00,5.00,5.00,5.00,5.00,5.00,5.00,5.00,5.00,5.00"
					( Origin gBackEnd )
				)
				( attribute "LINE_TO_SMDPIN_SPACING" "4.50,4.50,4.50,4.50,4.50,4.50,4.50,4.50,4.50,4.50,4.50,4.50,4.50,4.50"
					( Origin gBackEnd )
				)
				( attribute "SHAPE_TO_SMDPIN_SPACING" "5.00,5.00,5.00,5.00,5.00,5.00,5.00,5.00,5.00,5.00,5.00,5.00,5.00,5.00"
					( Origin gBackEnd )
				)
				( attribute "TESTPIN_TO_TESTPIN_SPACING" "5.00,5.00,5.00,5.00,5.00,5.00,5.00,5.00,5.00,5.00,5.00,5.00,5.00,5.00"
					( Origin gBackEnd )
				)
				( attribute "TESTPIN_TO_THRUVIA_SPACING" "5.00,5.00,5.00,5.00,5.00,5.00,5.00,5.00,5.00,5.00,5.00,5.00,5.00,5.00"
					( Origin gBackEnd )
				)
				( attribute "TESTPIN_TO_TESTVIA_SPACING" "5.00,5.00,5.00,5.00,5.00,5.00,5.00,5.00,5.00,5.00,5.00,5.00,5.00,5.00"
					( Origin gBackEnd )
				)
				( attribute "BBV_TO_TESTPIN_SPACING" "5.00,5.00,5.00,5.00,5.00,5.00,5.00,5.00,5.00,5.00,5.00,5.00,5.00,5.00"
					( Origin gBackEnd )
				)
				( attribute "BONDPAD_TO_TESTPIN_SPACING" "5.00,5.00,5.00,5.00,5.00,5.00,5.00,5.00,5.00,5.00,5.00,5.00,5.00,5.00"
					( Origin gBackEnd )
				)
				( attribute "LINE_TO_TESTPIN_SPACING" "5.00,4.00,4.00,4.00,4.00,4.00,4.00,4.00,4.00,4.00,4.00,4.00,4.00,5.00"
					( Origin gBackEnd )
				)
				( attribute "SHAPE_TO_TESTPIN_SPACING" "5.00,5.00,5.00,5.00,5.00,5.00,5.00,5.00,5.00,5.00,5.00,5.00,5.00,5.00"
					( Origin gBackEnd )
				)
				( attribute "THRUVIA_TO_THRUVIA_SPACING" "5.00,5.00,5.00,5.00,5.00,5.00,5.00,5.00,5.00,5.00,5.00,5.00,5.00,5.00"
					( Origin gBackEnd )
				)
				( attribute "TESTVIA_TO_THRUVIA_SPACING" "6.00,6.00,6.00,6.00,6.00,6.00,6.00,6.00,6.00,6.00,6.00,6.00,6.00,6.00"
					( Origin gBackEnd )
				)
				( attribute "BBV_TO_THRUVIA_SPACING" "5.00,5.00,5.00,5.00,5.00,5.00,5.00,5.00,5.00,5.00,5.00,5.00,5.00,5.00"
					( Origin gBackEnd )
				)
				( attribute "BONDPAD_TO_THRUVIA_SPACING" "5.00,5.00,5.00,5.00,5.00,5.00,5.00,5.00,5.00,5.00,5.00,5.00,5.00,5.00"
					( Origin gBackEnd )
				)
				( attribute "LINE_TO_THRUVIA_SPACING" "4.50,4.00,4.00,4.00,4.00,4.00,4.00,4.00,4.00,4.00,4.00,4.00,4.00,4.50"
					( Origin gBackEnd )
				)
				( attribute "SHAPE_TO_THRUVIA_SPACING" "5.00,5.00,5.00,5.00,5.00,5.00,5.00,5.00,5.00,5.00,5.00,5.00,5.00,5.00"
					( Origin gBackEnd )
				)
				( attribute "TESTVIA_TO_TESTVIA_SPACING" "6.00,6.00,6.00,6.00,6.00,6.00,6.00,6.00,6.00,6.00,6.00,6.00,6.00,6.00"
					( Origin gBackEnd )
				)
				( attribute "BBV_TO_TESTVIA_SPACING" "5.00,5.00,5.00,5.00,5.00,5.00,5.00,5.00,5.00,5.00,5.00,5.00,5.00,5.00"
					( Origin gBackEnd )
				)
				( attribute "BONDPAD_TO_TESTVIA_SPACING" "5.00,5.00,5.00,5.00,5.00,5.00,5.00,5.00,5.00,5.00,5.00,5.00,5.00,5.00"
					( Origin gBackEnd )
				)
				( attribute "LINE_TO_TESTVIA_SPACING" "4.50,4.00,4.00,4.00,4.00,4.00,4.00,4.00,4.00,4.00,4.00,4.00,4.00,4.50"
					( Origin gBackEnd )
				)
				( attribute "SHAPE_TO_TESTVIA_SPACING" "5.00,5.00,5.00,5.00,5.00,5.00,5.00,5.00,5.00,5.00,5.00,5.00,5.00,5.00"
					( Origin gBackEnd )
				)
				( attribute "BBV_TO_BBV_SPACING" "5.00,5.00,5.00,5.00,5.00,5.00,5.00,5.00,5.00,5.00,5.00,5.00,5.00,5.00"
					( Origin gBackEnd )
				)
				( attribute "BONDPAD_TO_BBV_SPACING" "5.00,5.00,5.00,5.00,5.00,5.00,5.00,5.00,5.00,5.00,5.00,5.00,5.00,5.00"
					( Origin gBackEnd )
				)
				( attribute "BBV_TO_LINE_SPACING" "5.00,5.00,5.00,5.00,5.00,5.00,5.00,5.00,5.00,5.00,5.00,5.00,5.00,5.00"
					( Origin gBackEnd )
				)
				( attribute "BBV_TO_SHAPE_SPACING" "5.00,5.00,5.00,5.00,5.00,5.00,5.00,5.00,5.00,5.00,5.00,5.00,5.00,5.00"
					( Origin gBackEnd )
				)
				( attribute "BONDPAD_TO_BONDPAD_SPACING" "5.00,5.00,5.00,5.00,5.00,5.00,5.00,5.00,5.00,5.00,5.00,5.00,5.00,5.00"
					( Origin gBackEnd )
				)
				( attribute "BONDPAD_TO_LINE_SPACING" "5.00,5.00,5.00,5.00,5.00,5.00,5.00,5.00,5.00,5.00,5.00,5.00,5.00,5.00"
					( Origin gBackEnd )
				)
				( attribute "BONDPAD_TO_SHAPE_SPACING" "5.00,5.00,5.00,5.00,5.00,5.00,5.00,5.00,5.00,5.00,5.00,5.00,5.00,5.00"
					( Origin gBackEnd )
				)
				( attribute "LINE_TO_LINE_SPACING" "45.15,20.30,20.30,20.30,20.30,20.30,20.30,20.30,20.30,20.30,20.30,20.30,20.30,45.15"
					( Origin gBackEnd )
				)
				( attribute "LINE_TO_SHAPE_SPACING" "10.00,10.00,10.00,10.00,10.00,10.00,10.00,10.00,10.00,10.00,10.00,10.00,10.00,10.00"
					( Origin gBackEnd )
				)
				( attribute "SHAPE_TO_SHAPE_SPACING" "10.00,10.00,10.00,10.00,10.00,10.00,10.00,10.00,10.00,10.00,10.00,10.00,10.00,10.00"
					( Origin gBackEnd )
				)
				( attribute "HOLE_TO_PIN_SPACING" "8.00,8.00,8.00,8.00,8.00,8.00,8.00,8.00,8.00,8.00,8.00,8.00,8.00,8.00"
					( Origin gBackEnd )
				)
				( attribute "HOLE_TO_VIA_SPACING" "8.00,8.00,8.00,8.00,8.00,8.00,8.00,8.00,8.00,8.00,8.00,8.00,8.00,8.00"
					( Origin gBackEnd )
				)
				( attribute "HOLE_TO_LINE_SPACING" "8.00,8.00,8.00,8.00,8.00,8.00,8.00,8.00,8.00,8.00,8.00,8.00,8.00,8.00"
					( Origin gBackEnd )
				)
				( attribute "HOLE_TO_SHAPE_SPACING" "8.00,8.00,8.00,8.00,8.00,8.00,8.00,8.00,8.00,8.00,8.00,8.00,8.00,8.00"
					( Origin gBackEnd )
				)
				( attribute "HOLE_TO_HOLE_SPACING" "8.00,8.00,8.00,8.00,8.00,8.00,8.00,8.00,8.00,8.00,8.00,8.00,8.00,8.00"
					( Origin gBackEnd )
				)
				( attribute "MVIA_TO_MVIA_SPACING" "5.00,5.00,5.00,5.00,5.00,5.00,5.00,5.00,5.00,5.00,5.00,5.00,5.00,5.00"
					( Origin gBackEnd )
				)
				( attribute "MVIA_TO_THRUPIN_SPACING" "5.00,5.00,5.00,5.00,5.00,5.00,5.00,5.00,5.00,5.00,5.00,5.00,5.00,5.00"
					( Origin gBackEnd )
				)
				( attribute "MVIA_TO_SMDPIN_SPACING" "5.00,5.00,5.00,5.00,5.00,5.00,5.00,5.00,5.00,5.00,5.00,5.00,5.00,5.00"
					( Origin gBackEnd )
				)
				( attribute "MVIA_TO_THRUVIA_SPACING" "5.00,5.00,5.00,5.00,5.00,5.00,5.00,5.00,5.00,5.00,5.00,5.00,5.00,5.00"
					( Origin gBackEnd )
				)
				( attribute "MVIA_TO_BBV_SPACING" "5.00,5.00,5.00,5.00,5.00,5.00,5.00,5.00,5.00,5.00,5.00,5.00,5.00,5.00"
					( Origin gBackEnd )
				)
				( attribute "MVIA_TO_LINE_SPACING" "5.00,5.00,5.00,5.00,5.00,5.00,5.00,5.00,5.00,5.00,5.00,5.00,5.00,5.00"
					( Origin gBackEnd )
				)
				( attribute "MVIA_TO_SHAPE_SPACING" "5.00,5.00,5.00,5.00,5.00,5.00,5.00,5.00,5.00,5.00,5.00,5.00,5.00,5.00"
					( Origin gBackEnd )
				)
				( attribute "MVIA_TO_TESTPIN_SPACING" "5.00,5.00,5.00,5.00,5.00,5.00,5.00,5.00,5.00,5.00,5.00,5.00,5.00,5.00"
					( Origin gBackEnd )
				)
				( attribute "MVIA_TO_TESTVIA_SPACING" "5.00,5.00,5.00,5.00,5.00,5.00,5.00,5.00,5.00,5.00,5.00,5.00,5.00,5.00"
					( Origin gBackEnd )
				)
				( attribute "BONDPAD_TO_MVIA_SPACING" "5.00,5.00,5.00,5.00,5.00,5.00,5.00,5.00,5.00,5.00,5.00,5.00,5.00,5.00"
					( Origin gBackEnd )
				)
				( attribute "MIN_BVIA_GAP" "5.00"
					( Origin gBackEnd )
				)
				( attribute "BONDPAD_TO_BONDPAD_DIFFP_SPC" "5.00,5.00,5.00,5.00,5.00,5.00,5.00,5.00,5.00,5.00,5.00,5.00,5.00,5.00"
					( Origin gBackEnd )
				)
				( objectStatus "OPT2_KR_15H_US_&_7H_SL" )
			)
			( spacingCSet "@baseboard_fab2_lib.baseboard_fab2(sch_1):\NEW_KR_12H_US_&_5H_SL\"
				( attribute "THRUPIN_TO_THRUPIN_SPACING" "5.00,5.00,5.00,5.00,5.00,5.00,5.00,5.00,5.00,5.00,5.00,5.00,5.00,5.00"
					( Origin gBackEnd )
				)
				( attribute "THRUPIN_TO_SMDPIN_SPACING" "5.00,5.00,5.00,5.00,5.00,5.00,5.00,5.00,5.00,5.00,5.00,5.00,5.00,5.00"
					( Origin gBackEnd )
				)
				( attribute "TESTPIN_TO_THRUPIN_SPACING" "5.00,5.00,5.00,5.00,5.00,5.00,5.00,5.00,5.00,5.00,5.00,5.00,5.00,5.00"
					( Origin gBackEnd )
				)
				( attribute "THRUPIN_TO_THRUVIA_SPACING" "5.00,5.00,5.00,5.00,5.00,5.00,5.00,5.00,5.00,5.00,5.00,5.00,5.00,5.00"
					( Origin gBackEnd )
				)
				( attribute "TESTVIA_TO_THRUPIN_SPACING" "5.00,5.00,5.00,5.00,5.00,5.00,5.00,5.00,5.00,5.00,5.00,5.00,5.00,5.00"
					( Origin gBackEnd )
				)
				( attribute "BBV_TO_THRUPIN_SPACING" "5.00,5.00,5.00,5.00,5.00,5.00,5.00,5.00,5.00,5.00,5.00,5.00,5.00,5.00"
					( Origin gBackEnd )
				)
				( attribute "THRUPIN_TO_BONDPAD_SPACING" "5.00,5.00,5.00,5.00,5.00,5.00,5.00,5.00,5.00,5.00,5.00,5.00,5.00,5.00"
					( Origin gBackEnd )
				)
				( attribute "LINE_TO_THRUPIN_SPACING" "4.50,4.00,4.00,4.00,4.00,4.00,4.00,4.00,4.00,4.00,4.00,4.00,4.00,4.50"
					( Origin gBackEnd )
				)
				( attribute "THRUPIN_TO_SHAPE_SPACING" "5.00,5.00,5.00,5.00,5.00,5.00,5.00,5.00,5.00,5.00,5.00,5.00,5.00,5.00"
					( Origin gBackEnd )
				)
				( attribute "SMDPIN_TO_SMDPIN_SPACING" "5.00,5.00,5.00,5.00,5.00,5.00,5.00,5.00,5.00,5.00,5.00,5.00,5.00,5.00"
					( Origin gBackEnd )
				)
				( attribute "SMDPIN_TO_TESTPIN_SPACING" "5.00,5.00,5.00,5.00,5.00,5.00,5.00,5.00,5.00,5.00,5.00,5.00,5.00,25.00"
					( Origin gBackEnd )
				)
				( attribute "SMDPIN_TO_THRUVIA_SPACING" "5.00,5.00,5.00,5.00,5.00,5.00,5.00,5.00,5.00,5.00,5.00,5.00,5.00,5.00"
					( Origin gBackEnd )
				)
				( attribute "SMDPIN_TO_TESTVIA_SPACING" "5.00,5.00,5.00,5.00,5.00,5.00,5.00,5.00,5.00,5.00,5.00,5.00,5.00,5.00"
					( Origin gBackEnd )
				)
				( attribute "BBV_TO_SMDPIN_SPACING" "5.00,5.00,5.00,5.00,5.00,5.00,5.00,5.00,5.00,5.00,5.00,5.00,5.00,5.00"
					( Origin gBackEnd )
				)
				( attribute "SMDPIN_TO_BONDPAD_SPACING" "5.00,5.00,5.00,5.00,5.00,5.00,5.00,5.00,5.00,5.00,5.00,5.00,5.00,5.00"
					( Origin gBackEnd )
				)
				( attribute "LINE_TO_SMDPIN_SPACING" "4.50,4.50,4.50,4.50,4.50,4.50,4.50,4.50,4.50,4.50,4.50,4.50,4.50,4.50"
					( Origin gBackEnd )
				)
				( attribute "SHAPE_TO_SMDPIN_SPACING" "5.00,5.00,5.00,5.00,5.00,5.00,5.00,5.00,5.00,5.00,5.00,5.00,5.00,5.00"
					( Origin gBackEnd )
				)
				( attribute "TESTPIN_TO_TESTPIN_SPACING" "5.00,5.00,5.00,5.00,5.00,5.00,5.00,5.00,5.00,5.00,5.00,5.00,5.00,5.00"
					( Origin gBackEnd )
				)
				( attribute "TESTPIN_TO_THRUVIA_SPACING" "5.00,5.00,5.00,5.00,5.00,5.00,5.00,5.00,5.00,5.00,5.00,5.00,5.00,5.00"
					( Origin gBackEnd )
				)
				( attribute "TESTPIN_TO_TESTVIA_SPACING" "5.00,5.00,5.00,5.00,5.00,5.00,5.00,5.00,5.00,5.00,5.00,5.00,5.00,5.00"
					( Origin gBackEnd )
				)
				( attribute "BBV_TO_TESTPIN_SPACING" "5.00,5.00,5.00,5.00,5.00,5.00,5.00,5.00,5.00,5.00,5.00,5.00,5.00,5.00"
					( Origin gBackEnd )
				)
				( attribute "BONDPAD_TO_TESTPIN_SPACING" "5.00,5.00,5.00,5.00,5.00,5.00,5.00,5.00,5.00,5.00,5.00,5.00,5.00,5.00"
					( Origin gBackEnd )
				)
				( attribute "LINE_TO_TESTPIN_SPACING" "5.00,4.00,4.00,4.00,4.00,4.00,4.00,4.00,4.00,4.00,4.00,4.00,4.00,5.00"
					( Origin gBackEnd )
				)
				( attribute "SHAPE_TO_TESTPIN_SPACING" "5.00,5.00,5.00,5.00,5.00,5.00,5.00,5.00,5.00,5.00,5.00,5.00,5.00,5.00"
					( Origin gBackEnd )
				)
				( attribute "THRUVIA_TO_THRUVIA_SPACING" "5.00,5.00,5.00,5.00,5.00,5.00,5.00,5.00,5.00,5.00,5.00,5.00,5.00,5.00"
					( Origin gBackEnd )
				)
				( attribute "TESTVIA_TO_THRUVIA_SPACING" "6.00,6.00,6.00,6.00,6.00,6.00,6.00,6.00,6.00,6.00,6.00,6.00,6.00,6.00"
					( Origin gBackEnd )
				)
				( attribute "BBV_TO_THRUVIA_SPACING" "5.00,5.00,5.00,5.00,5.00,5.00,5.00,5.00,5.00,5.00,5.00,5.00,5.00,5.00"
					( Origin gBackEnd )
				)
				( attribute "BONDPAD_TO_THRUVIA_SPACING" "5.00,5.00,5.00,5.00,5.00,5.00,5.00,5.00,5.00,5.00,5.00,5.00,5.00,5.00"
					( Origin gBackEnd )
				)
				( attribute "LINE_TO_THRUVIA_SPACING" "4.50,4.00,4.00,4.00,4.00,4.00,4.00,4.00,4.00,4.00,4.00,4.00,4.00,4.50"
					( Origin gBackEnd )
				)
				( attribute "SHAPE_TO_THRUVIA_SPACING" "5.00,5.00,5.00,5.00,5.00,5.00,5.00,5.00,5.00,5.00,5.00,5.00,5.00,5.00"
					( Origin gBackEnd )
				)
				( attribute "TESTVIA_TO_TESTVIA_SPACING" "6.00,6.00,6.00,6.00,6.00,6.00,6.00,6.00,6.00,6.00,6.00,6.00,6.00,6.00"
					( Origin gBackEnd )
				)
				( attribute "BBV_TO_TESTVIA_SPACING" "5.00,5.00,5.00,5.00,5.00,5.00,5.00,5.00,5.00,5.00,5.00,5.00,5.00,5.00"
					( Origin gBackEnd )
				)
				( attribute "BONDPAD_TO_TESTVIA_SPACING" "5.00,5.00,5.00,5.00,5.00,5.00,5.00,5.00,5.00,5.00,5.00,5.00,5.00,5.00"
					( Origin gBackEnd )
				)
				( attribute "LINE_TO_TESTVIA_SPACING" "4.50,4.00,4.00,4.00,4.00,4.00,4.00,4.00,4.00,4.00,4.00,4.00,4.00,4.50"
					( Origin gBackEnd )
				)
				( attribute "SHAPE_TO_TESTVIA_SPACING" "5.00,5.00,5.00,5.00,5.00,5.00,5.00,5.00,5.00,5.00,5.00,5.00,5.00,5.00"
					( Origin gBackEnd )
				)
				( attribute "BBV_TO_BBV_SPACING" "5.00,5.00,5.00,5.00,5.00,5.00,5.00,5.00,5.00,5.00,5.00,5.00,5.00,5.00"
					( Origin gBackEnd )
				)
				( attribute "BONDPAD_TO_BBV_SPACING" "5.00,5.00,5.00,5.00,5.00,5.00,5.00,5.00,5.00,5.00,5.00,5.00,5.00,5.00"
					( Origin gBackEnd )
				)
				( attribute "BBV_TO_LINE_SPACING" "5.00,5.00,5.00,5.00,5.00,5.00,5.00,5.00,5.00,5.00,5.00,5.00,5.00,5.00"
					( Origin gBackEnd )
				)
				( attribute "BBV_TO_SHAPE_SPACING" "5.00,5.00,5.00,5.00,5.00,5.00,5.00,5.00,5.00,5.00,5.00,5.00,5.00,5.00"
					( Origin gBackEnd )
				)
				( attribute "BONDPAD_TO_BONDPAD_SPACING" "5.00,5.00,5.00,5.00,5.00,5.00,5.00,5.00,5.00,5.00,5.00,5.00,5.00,5.00"
					( Origin gBackEnd )
				)
				( attribute "BONDPAD_TO_LINE_SPACING" "5.00,5.00,5.00,5.00,5.00,5.00,5.00,5.00,5.00,5.00,5.00,5.00,5.00,5.00"
					( Origin gBackEnd )
				)
				( attribute "BONDPAD_TO_SHAPE_SPACING" "5.00,5.00,5.00,5.00,5.00,5.00,5.00,5.00,5.00,5.00,5.00,5.00,5.00,5.00"
					( Origin gBackEnd )
				)
				( attribute "LINE_TO_LINE_SPACING" "36.12,14.50,14.50,14.50,14.50,14.50,14.50,14.50,14.50,14.50,14.50,14.50,14.50,36.12"
					( Origin gBackEnd )
				)
				( attribute "LINE_TO_SHAPE_SPACING" "10.00,10.00,10.00,10.00,10.00,10.00,10.00,10.00,10.00,10.00,10.00,10.00,10.00,10.00"
					( Origin gBackEnd )
				)
				( attribute "SHAPE_TO_SHAPE_SPACING" "10.00,10.00,10.00,10.00,10.00,10.00,10.00,10.00,10.00,10.00,10.00,10.00,10.00,10.00"
					( Origin gBackEnd )
				)
				( attribute "HOLE_TO_PIN_SPACING" "8.00,8.00,8.00,8.00,8.00,8.00,8.00,8.00,8.00,8.00,8.00,8.00,8.00,8.00"
					( Origin gBackEnd )
				)
				( attribute "HOLE_TO_VIA_SPACING" "8.00,8.00,8.00,8.00,8.00,8.00,8.00,8.00,8.00,8.00,8.00,8.00,8.00,8.00"
					( Origin gBackEnd )
				)
				( attribute "HOLE_TO_LINE_SPACING" "8.00,8.00,8.00,8.00,8.00,8.00,8.00,8.00,8.00,8.00,8.00,8.00,8.00,8.00"
					( Origin gBackEnd )
				)
				( attribute "HOLE_TO_SHAPE_SPACING" "8.00,8.00,8.00,8.00,8.00,8.00,8.00,8.00,8.00,8.00,8.00,8.00,8.00,8.00"
					( Origin gBackEnd )
				)
				( attribute "HOLE_TO_HOLE_SPACING" "8.00,8.00,8.00,8.00,8.00,8.00,8.00,8.00,8.00,8.00,8.00,8.00,8.00,8.00"
					( Origin gBackEnd )
				)
				( attribute "MVIA_TO_MVIA_SPACING" "5.00,5.00,5.00,5.00,5.00,5.00,5.00,5.00,5.00,5.00,5.00,5.00,5.00,5.00"
					( Origin gBackEnd )
				)
				( attribute "MVIA_TO_THRUPIN_SPACING" "5.00,5.00,5.00,5.00,5.00,5.00,5.00,5.00,5.00,5.00,5.00,5.00,5.00,5.00"
					( Origin gBackEnd )
				)
				( attribute "MVIA_TO_SMDPIN_SPACING" "5.00,5.00,5.00,5.00,5.00,5.00,5.00,5.00,5.00,5.00,5.00,5.00,5.00,5.00"
					( Origin gBackEnd )
				)
				( attribute "MVIA_TO_THRUVIA_SPACING" "5.00,5.00,5.00,5.00,5.00,5.00,5.00,5.00,5.00,5.00,5.00,5.00,5.00,5.00"
					( Origin gBackEnd )
				)
				( attribute "MVIA_TO_BBV_SPACING" "5.00,5.00,5.00,5.00,5.00,5.00,5.00,5.00,5.00,5.00,5.00,5.00,5.00,5.00"
					( Origin gBackEnd )
				)
				( attribute "MVIA_TO_LINE_SPACING" "5.00,5.00,5.00,5.00,5.00,5.00,5.00,5.00,5.00,5.00,5.00,5.00,5.00,5.00"
					( Origin gBackEnd )
				)
				( attribute "MVIA_TO_SHAPE_SPACING" "5.00,5.00,5.00,5.00,5.00,5.00,5.00,5.00,5.00,5.00,5.00,5.00,5.00,5.00"
					( Origin gBackEnd )
				)
				( attribute "MVIA_TO_TESTPIN_SPACING" "5.00,5.00,5.00,5.00,5.00,5.00,5.00,5.00,5.00,5.00,5.00,5.00,5.00,5.00"
					( Origin gBackEnd )
				)
				( attribute "MVIA_TO_TESTVIA_SPACING" "5.00,5.00,5.00,5.00,5.00,5.00,5.00,5.00,5.00,5.00,5.00,5.00,5.00,5.00"
					( Origin gBackEnd )
				)
				( attribute "BONDPAD_TO_MVIA_SPACING" "5.00,5.00,5.00,5.00,5.00,5.00,5.00,5.00,5.00,5.00,5.00,5.00,5.00,5.00"
					( Origin gBackEnd )
				)
				( attribute "MIN_BVIA_GAP" "5.00"
					( Origin gBackEnd )
				)
				( attribute "BONDPAD_TO_BONDPAD_DIFFP_SPC" "5.00,5.00,5.00,5.00,5.00,5.00,5.00,5.00,5.00,5.00,5.00,5.00,5.00,5.00"
					( Origin gBackEnd )
				)
				( objectStatus "OPT2_KR_12H_US_&_5H_SL" )
			)
			( spacingCSet "@baseboard_fab2_lib.baseboard_fab2(sch_1):\10_MIL_L-V_10MIL\"
				( attribute "THRUPIN_TO_THRUPIN_SPACING" "5.00,5.00,5.00,5.00,5.00,5.00,5.00,5.00,5.00,5.00,5.00,5.00,5.00,5.00"
					( Origin gBackEnd )
				)
				( attribute "THRUPIN_TO_SMDPIN_SPACING" "5.00,5.00,5.00,5.00,5.00,5.00,5.00,5.00,5.00,5.00,5.00,5.00,5.00,5.00"
					( Origin gBackEnd )
				)
				( attribute "TESTPIN_TO_THRUPIN_SPACING" "5.00,5.00,5.00,5.00,5.00,5.00,5.00,5.00,5.00,5.00,5.00,5.00,5.00,5.00"
					( Origin gBackEnd )
				)
				( attribute "THRUPIN_TO_THRUVIA_SPACING" "5.00,5.00,5.00,5.00,5.00,5.00,5.00,5.00,5.00,5.00,5.00,5.00,5.00,5.00"
					( Origin gBackEnd )
				)
				( attribute "TESTVIA_TO_THRUPIN_SPACING" "5.00,5.00,5.00,5.00,5.00,5.00,5.00,5.00,5.00,5.00,5.00,5.00,5.00,5.00"
					( Origin gBackEnd )
				)
				( attribute "BBV_TO_THRUPIN_SPACING" "5.00,5.00,5.00,5.00,5.00,5.00,5.00,5.00,5.00,5.00,5.00,5.00,5.00,5.00"
					( Origin gBackEnd )
				)
				( attribute "THRUPIN_TO_BONDPAD_SPACING" "5.00,5.00,5.00,5.00,5.00,5.00,5.00,5.00,5.00,5.00,5.00,5.00,5.00,5.00"
					( Origin gBackEnd )
				)
				( attribute "LINE_TO_THRUPIN_SPACING" "4.50,4.00,4.00,4.00,4.00,4.00,4.00,4.00,4.00,4.00,4.00,4.00,4.00,4.50"
					( Origin gBackEnd )
				)
				( attribute "THRUPIN_TO_SHAPE_SPACING" "5.00,5.00,5.00,5.00,5.00,5.00,5.00,5.00,5.00,5.00,5.00,5.00,5.00,5.00"
					( Origin gBackEnd )
				)
				( attribute "SMDPIN_TO_SMDPIN_SPACING" "5.00,5.00,5.00,5.00,5.00,5.00,5.00,5.00,5.00,5.00,5.00,5.00,5.00,5.00"
					( Origin gBackEnd )
				)
				( attribute "SMDPIN_TO_TESTPIN_SPACING" "5.00,5.00,5.00,5.00,5.00,5.00,5.00,5.00,5.00,5.00,5.00,5.00,5.00,25.00"
					( Origin gBackEnd )
				)
				( attribute "SMDPIN_TO_THRUVIA_SPACING" "5.00,5.00,5.00,5.00,5.00,5.00,5.00,5.00,5.00,5.00,5.00,5.00,5.00,5.00"
					( Origin gBackEnd )
				)
				( attribute "SMDPIN_TO_TESTVIA_SPACING" "5.00,5.00,5.00,5.00,5.00,5.00,5.00,5.00,5.00,5.00,5.00,5.00,5.00,5.00"
					( Origin gBackEnd )
				)
				( attribute "BBV_TO_SMDPIN_SPACING" "5.00,5.00,5.00,5.00,5.00,5.00,5.00,5.00,5.00,5.00,5.00,5.00,5.00,5.00"
					( Origin gBackEnd )
				)
				( attribute "SMDPIN_TO_BONDPAD_SPACING" "5.00,5.00,5.00,5.00,5.00,5.00,5.00,5.00,5.00,5.00,5.00,5.00,5.00,5.00"
					( Origin gBackEnd )
				)
				( attribute "LINE_TO_SMDPIN_SPACING" "4.50,4.50,4.50,4.50,4.50,4.50,4.50,4.50,4.50,4.50,4.50,4.50,4.50,4.50"
					( Origin gBackEnd )
				)
				( attribute "SHAPE_TO_SMDPIN_SPACING" "5.00,5.00,5.00,5.00,5.00,5.00,5.00,5.00,5.00,5.00,5.00,5.00,5.00,5.00"
					( Origin gBackEnd )
				)
				( attribute "TESTPIN_TO_TESTPIN_SPACING" "5.00,5.00,5.00,5.00,5.00,5.00,5.00,5.00,5.00,5.00,5.00,5.00,5.00,5.00"
					( Origin gBackEnd )
				)
				( attribute "TESTPIN_TO_THRUVIA_SPACING" "5.00,5.00,5.00,5.00,5.00,5.00,5.00,5.00,5.00,5.00,5.00,5.00,5.00,5.00"
					( Origin gBackEnd )
				)
				( attribute "TESTPIN_TO_TESTVIA_SPACING" "5.00,5.00,5.00,5.00,5.00,5.00,5.00,5.00,5.00,5.00,5.00,5.00,5.00,5.00"
					( Origin gBackEnd )
				)
				( attribute "BBV_TO_TESTPIN_SPACING" "5.00,5.00,5.00,5.00,5.00,5.00,5.00,5.00,5.00,5.00,5.00,5.00,5.00,5.00"
					( Origin gBackEnd )
				)
				( attribute "BONDPAD_TO_TESTPIN_SPACING" "5.00,5.00,5.00,5.00,5.00,5.00,5.00,5.00,5.00,5.00,5.00,5.00,5.00,5.00"
					( Origin gBackEnd )
				)
				( attribute "LINE_TO_TESTPIN_SPACING" "5.00,4.00,4.00,4.00,4.00,4.00,4.00,4.00,4.00,4.00,4.00,4.00,4.00,5.00"
					( Origin gBackEnd )
				)
				( attribute "SHAPE_TO_TESTPIN_SPACING" "5.00,5.00,5.00,5.00,5.00,5.00,5.00,5.00,5.00,5.00,5.00,5.00,5.00,5.00"
					( Origin gBackEnd )
				)
				( attribute "THRUVIA_TO_THRUVIA_SPACING" "5.00,5.00,5.00,5.00,5.00,5.00,5.00,5.00,5.00,5.00,5.00,5.00,5.00,5.00"
					( Origin gBackEnd )
				)
				( attribute "TESTVIA_TO_THRUVIA_SPACING" "6.00,6.00,6.00,6.00,6.00,6.00,6.00,6.00,6.00,6.00,6.00,6.00,6.00,6.00"
					( Origin gBackEnd )
				)
				( attribute "BBV_TO_THRUVIA_SPACING" "5.00,5.00,5.00,5.00,5.00,5.00,5.00,5.00,5.00,5.00,5.00,5.00,5.00,5.00"
					( Origin gBackEnd )
				)
				( attribute "BONDPAD_TO_THRUVIA_SPACING" "5.00,5.00,5.00,5.00,5.00,5.00,5.00,5.00,5.00,5.00,5.00,5.00,5.00,5.00"
					( Origin gBackEnd )
				)
				( attribute "LINE_TO_THRUVIA_SPACING" "10.00,10.00,10.00,10.00,10.00,10.00,10.00,10.00,10.00,10.00,10.00,10.00,10.00,10.00"
					( Origin gBackEnd )
				)
				( attribute "SHAPE_TO_THRUVIA_SPACING" "10.00,10.00,10.00,10.00,10.00,10.00,10.00,10.00,10.00,10.00,10.00,10.00,10.00,10.00"
					( Origin gBackEnd )
				)
				( attribute "TESTVIA_TO_TESTVIA_SPACING" "6.00,6.00,6.00,6.00,6.00,6.00,6.00,6.00,6.00,6.00,6.00,6.00,6.00,6.00"
					( Origin gBackEnd )
				)
				( attribute "BBV_TO_TESTVIA_SPACING" "5.00,5.00,5.00,5.00,5.00,5.00,5.00,5.00,5.00,5.00,5.00,5.00,5.00,5.00"
					( Origin gBackEnd )
				)
				( attribute "BONDPAD_TO_TESTVIA_SPACING" "5.00,5.00,5.00,5.00,5.00,5.00,5.00,5.00,5.00,5.00,5.00,5.00,5.00,5.00"
					( Origin gBackEnd )
				)
				( attribute "LINE_TO_TESTVIA_SPACING" "10.00,10.00,10.00,10.00,10.00,10.00,10.00,10.00,10.00,10.00,10.00,10.00,10.00,10.00"
					( Origin gBackEnd )
				)
				( attribute "SHAPE_TO_TESTVIA_SPACING" "10.00,10.00,10.00,10.00,10.00,10.00,10.00,10.00,10.00,10.00,10.00,10.00,10.00,10.00"
					( Origin gBackEnd )
				)
				( attribute "BBV_TO_BBV_SPACING" "5.00,5.00,5.00,5.00,5.00,5.00,5.00,5.00,5.00,5.00,5.00,5.00,5.00,5.00"
					( Origin gBackEnd )
				)
				( attribute "BONDPAD_TO_BBV_SPACING" "5.00,5.00,5.00,5.00,5.00,5.00,5.00,5.00,5.00,5.00,5.00,5.00,5.00,5.00"
					( Origin gBackEnd )
				)
				( attribute "BBV_TO_LINE_SPACING" "5.00,5.00,5.00,5.00,5.00,5.00,5.00,5.00,5.00,5.00,5.00,5.00,5.00,5.00"
					( Origin gBackEnd )
				)
				( attribute "BBV_TO_SHAPE_SPACING" "5.00,5.00,5.00,5.00,5.00,5.00,5.00,5.00,5.00,5.00,5.00,5.00,5.00,5.00"
					( Origin gBackEnd )
				)
				( attribute "BONDPAD_TO_BONDPAD_SPACING" "5.00,5.00,5.00,5.00,5.00,5.00,5.00,5.00,5.00,5.00,5.00,5.00,5.00,5.00"
					( Origin gBackEnd )
				)
				( attribute "BONDPAD_TO_LINE_SPACING" "5.00,5.00,5.00,5.00,5.00,5.00,5.00,5.00,5.00,5.00,5.00,5.00,5.00,5.00"
					( Origin gBackEnd )
				)
				( attribute "BONDPAD_TO_SHAPE_SPACING" "5.00,5.00,5.00,5.00,5.00,5.00,5.00,5.00,5.00,5.00,5.00,5.00,5.00,5.00"
					( Origin gBackEnd )
				)
				( attribute "LINE_TO_LINE_SPACING" "10.00,10.00,10.00,10.00,10.00,10.00,10.00,10.00,10.00,10.00,10.00,10.00,10.00,10.00"
					( Origin gBackEnd )
				)
				( attribute "LINE_TO_SHAPE_SPACING" "10.00,10.00,10.00,10.00,10.00,10.00,10.00,10.00,10.00,10.00,10.00,10.00,10.00,10.00"
					( Origin gBackEnd )
				)
				( attribute "SHAPE_TO_SHAPE_SPACING" "10.00,10.00,10.00,10.00,10.00,10.00,10.00,10.00,10.00,10.00,10.00,10.00,10.00,10.00"
					( Origin gBackEnd )
				)
				( attribute "HOLE_TO_PIN_SPACING" "8.00,8.00,8.00,8.00,8.00,8.00,8.00,8.00,8.00,8.00,8.00,8.00,8.00,8.00"
					( Origin gBackEnd )
				)
				( attribute "HOLE_TO_VIA_SPACING" "8.00,8.00,8.00,8.00,8.00,8.00,8.00,8.00,8.00,8.00,8.00,8.00,8.00,8.00"
					( Origin gBackEnd )
				)
				( attribute "HOLE_TO_LINE_SPACING" "8.00,8.00,8.00,8.00,8.00,8.00,8.00,8.00,8.00,8.00,8.00,8.00,8.00,8.00"
					( Origin gBackEnd )
				)
				( attribute "HOLE_TO_SHAPE_SPACING" "8.00,8.00,8.00,8.00,8.00,8.00,8.00,8.00,8.00,8.00,8.00,8.00,8.00,8.00"
					( Origin gBackEnd )
				)
				( attribute "HOLE_TO_HOLE_SPACING" "8.00,8.00,8.00,8.00,8.00,8.00,8.00,8.00,8.00,8.00,8.00,8.00,8.00,8.00"
					( Origin gBackEnd )
				)
				( attribute "MVIA_TO_MVIA_SPACING" "5.00,5.00,5.00,5.00,5.00,5.00,5.00,5.00,5.00,5.00,5.00,5.00,5.00,5.00"
					( Origin gBackEnd )
				)
				( attribute "MVIA_TO_THRUPIN_SPACING" "5.00,5.00,5.00,5.00,5.00,5.00,5.00,5.00,5.00,5.00,5.00,5.00,5.00,5.00"
					( Origin gBackEnd )
				)
				( attribute "MVIA_TO_SMDPIN_SPACING" "5.00,5.00,5.00,5.00,5.00,5.00,5.00,5.00,5.00,5.00,5.00,5.00,5.00,5.00"
					( Origin gBackEnd )
				)
				( attribute "MVIA_TO_THRUVIA_SPACING" "5.00,5.00,5.00,5.00,5.00,5.00,5.00,5.00,5.00,5.00,5.00,5.00,5.00,5.00"
					( Origin gBackEnd )
				)
				( attribute "MVIA_TO_BBV_SPACING" "5.00,5.00,5.00,5.00,5.00,5.00,5.00,5.00,5.00,5.00,5.00,5.00,5.00,5.00"
					( Origin gBackEnd )
				)
				( attribute "MVIA_TO_LINE_SPACING" "5.00,5.00,5.00,5.00,5.00,5.00,5.00,5.00,5.00,5.00,5.00,5.00,5.00,5.00"
					( Origin gBackEnd )
				)
				( attribute "MVIA_TO_SHAPE_SPACING" "5.00,5.00,5.00,5.00,5.00,5.00,5.00,5.00,5.00,5.00,5.00,5.00,5.00,5.00"
					( Origin gBackEnd )
				)
				( attribute "MVIA_TO_TESTPIN_SPACING" "5.00,5.00,5.00,5.00,5.00,5.00,5.00,5.00,5.00,5.00,5.00,5.00,5.00,5.00"
					( Origin gBackEnd )
				)
				( attribute "MVIA_TO_TESTVIA_SPACING" "5.00,5.00,5.00,5.00,5.00,5.00,5.00,5.00,5.00,5.00,5.00,5.00,5.00,5.00"
					( Origin gBackEnd )
				)
				( attribute "BONDPAD_TO_MVIA_SPACING" "5.00,5.00,5.00,5.00,5.00,5.00,5.00,5.00,5.00,5.00,5.00,5.00,5.00,5.00"
					( Origin gBackEnd )
				)
				( attribute "MIN_BVIA_GAP" "5.00"
					( Origin gBackEnd )
				)
				( attribute "BONDPAD_TO_BONDPAD_DIFFP_SPC" "5.00,5.00,5.00,5.00,5.00,5.00,5.00,5.00,5.00,5.00,5.00,5.00,5.00,5.00"
					( Origin gBackEnd )
				)
				( objectStatus "10_MIL_L-V_S-V_10MIL" )
			)
			( spacingCSet "@crescent_city_bb_fab1_lib.crescent_city_bb_fab1(sch_1):\RCC_DFX_1940\"
				( attribute "THRUPIN_TO_THRUPIN_SPACING" "5.00,5.00,5.00,5.00,5.00,5.00,5.00,5.00,5.00,5.00,5.00,5.00,5.00,5.00"
					( Origin gBackEnd )
				)
				( attribute "THRUPIN_TO_SMDPIN_SPACING" "5.00,5.00,5.00,5.00,5.00,5.00,5.00,5.00,5.00,5.00,5.00,5.00,5.00,5.00"
					( Origin gBackEnd )
				)
				( attribute "TESTPIN_TO_THRUPIN_SPACING" "5.00,5.00,5.00,5.00,5.00,5.00,5.00,5.00,5.00,5.00,5.00,5.00,5.00,5.00"
					( Origin gBackEnd )
				)
				( attribute "THRUPIN_TO_THRUVIA_SPACING" "4.00,4.00,4.00,4.00,4.00,4.00,4.00,4.00,4.00,4.00,4.00,4.00,4.00,5.00"
					( Origin gBackEnd )
				)
				( attribute "TESTVIA_TO_THRUPIN_SPACING" "5.00,5.00,5.00,5.00,5.00,5.00,5.00,5.00,5.00,5.00,5.00,5.00,5.00,5.00"
					( Origin gBackEnd )
				)
				( attribute "BBV_TO_THRUPIN_SPACING" "5.00,5.00,5.00,5.00,5.00,5.00,5.00,5.00,5.00,5.00,5.00,5.00,5.00,5.00"
					( Origin gBackEnd )
				)
				( attribute "THRUPIN_TO_BONDPAD_SPACING" "5.00,5.00,5.00,5.00,5.00,5.00,5.00,5.00,5.00,5.00,5.00,5.00,5.00,5.00"
					( Origin gBackEnd )
				)
				( attribute "LINE_TO_THRUPIN_SPACING" "5.00,5.00,5.00,5.00,5.00,5.00,5.00,5.00,5.00,5.00,5.00,5.00,5.00,5.00"
					( Origin gBackEnd )
				)
				( attribute "THRUPIN_TO_SHAPE_SPACING" "4.50,4.00,4.00,4.00,4.00,4.00,4.00,4.00,4.00,4.00,4.00,4.00,4.00,5.00"
					( Origin gBackEnd )
				)
				( attribute "SMDPIN_TO_SMDPIN_SPACING" "5.00,5.00,5.00,5.00,5.00,5.00,5.00,5.00,5.00,5.00,5.00,5.00,5.00,5.00"
					( Origin gBackEnd )
				)
				( attribute "SMDPIN_TO_TESTPIN_SPACING" "5.00,5.00,5.00,5.00,5.00,5.00,5.00,5.00,5.00,5.00,5.00,5.00,5.00,25.00"
					( Origin gBackEnd )
				)
				( attribute "SMDPIN_TO_THRUVIA_SPACING" "4.00,4.00,4.00,4.00,4.00,4.00,4.00,4.00,4.00,4.00,4.00,4.00,4.00,5.00"
					( Origin gBackEnd )
				)
				( attribute "SMDPIN_TO_TESTVIA_SPACING" "4.50,4.50,4.50,4.50,4.50,4.50,4.50,4.50,4.50,4.50,4.50,4.50,4.50,5.00"
					( Origin gBackEnd )
				)
				( attribute "BBV_TO_SMDPIN_SPACING" "5.00,5.00,5.00,5.00,5.00,5.00,5.00,5.00,5.00,5.00,5.00,5.00,5.00,5.00"
					( Origin gBackEnd )
				)
				( attribute "SMDPIN_TO_BONDPAD_SPACING" "5.00,5.00,5.00,5.00,5.00,5.00,5.00,5.00,5.00,5.00,5.00,5.00,5.00,5.00"
					( Origin gBackEnd )
				)
				( attribute "LINE_TO_SMDPIN_SPACING" "4.50,4.50,4.50,4.50,4.50,4.50,4.50,4.50,4.50,4.50,4.50,4.50,4.50,4.50"
					( Origin gBackEnd )
				)
				( attribute "SHAPE_TO_SMDPIN_SPACING" "5.00,5.00,5.00,5.00,5.00,5.00,5.00,5.00,5.00,5.00,5.00,5.00,5.00,5.00"
					( Origin gBackEnd )
				)
				( attribute "TESTPIN_TO_TESTPIN_SPACING" "5.00,5.00,5.00,5.00,5.00,5.00,5.00,5.00,5.00,5.00,5.00,5.00,5.00,5.00"
					( Origin gBackEnd )
				)
				( attribute "TESTPIN_TO_THRUVIA_SPACING" "5.00,5.00,5.00,5.00,5.00,5.00,5.00,5.00,5.00,5.00,5.00,5.00,5.00,5.00"
					( Origin gBackEnd )
				)
				( attribute "TESTPIN_TO_TESTVIA_SPACING" "5.00,5.00,5.00,5.00,5.00,5.00,5.00,5.00,5.00,5.00,5.00,5.00,5.00,5.00"
					( Origin gBackEnd )
				)
				( attribute "BBV_TO_TESTPIN_SPACING" "5.00,5.00,5.00,5.00,5.00,5.00,5.00,5.00,5.00,5.00,5.00,5.00,5.00,5.00"
					( Origin gBackEnd )
				)
				( attribute "BONDPAD_TO_TESTPIN_SPACING" "5.00,5.00,5.00,5.00,5.00,5.00,5.00,5.00,5.00,5.00,5.00,5.00,5.00,5.00"
					( Origin gBackEnd )
				)
				( attribute "LINE_TO_TESTPIN_SPACING" "4.50,5.00,5.00,5.00,5.00,5.00,5.00,5.00,5.00,5.00,5.00,5.00,5.00,5.00"
					( Origin gBackEnd )
				)
				( attribute "SHAPE_TO_TESTPIN_SPACING" "4.50,4.00,4.00,4.00,4.00,4.00,4.00,4.00,4.00,4.00,4.00,4.00,4.00,5.00"
					( Origin gBackEnd )
				)
				( attribute "THRUVIA_TO_THRUVIA_SPACING" "5.00,5.00,5.00,5.00,5.00,5.00,5.00,5.00,5.00,5.00,5.00,5.00,5.00,5.00"
					( Origin gBackEnd )
				)
				( attribute "TESTVIA_TO_THRUVIA_SPACING" "5.00,5.00,5.00,5.00,5.00,5.00,5.00,5.00,5.00,5.00,5.00,5.00,5.00,6.00"
					( Origin gBackEnd )
				)
				( attribute "BBV_TO_THRUVIA_SPACING" "5.00,5.00,5.00,5.00,5.00,5.00,5.00,5.00,5.00,5.00,5.00,5.00,5.00,5.00"
					( Origin gBackEnd )
				)
				( attribute "BONDPAD_TO_THRUVIA_SPACING" "5.00,5.00,5.00,5.00,5.00,5.00,5.00,5.00,5.00,5.00,5.00,5.00,5.00,5.00"
					( Origin gBackEnd )
				)
				( attribute "LINE_TO_THRUVIA_SPACING" "4.50,4.00,4.00,4.00,4.00,4.00,4.00,4.00,4.00,4.00,4.00,4.00,4.00,4.50"
					( Origin gBackEnd )
				)
				( attribute "SHAPE_TO_THRUVIA_SPACING" "4.50,4.00,4.00,4.00,4.00,4.00,4.00,4.00,4.00,4.00,4.00,4.00,4.00,5.00"
					( Origin gBackEnd )
				)
				( attribute "TESTVIA_TO_TESTVIA_SPACING" "5.00,5.00,5.00,5.00,5.00,5.00,5.00,5.00,5.00,5.00,5.00,5.00,5.00,6.00"
					( Origin gBackEnd )
				)
				( attribute "BBV_TO_TESTVIA_SPACING" "5.00,5.00,5.00,5.00,5.00,5.00,5.00,5.00,5.00,5.00,5.00,5.00,5.00,5.00"
					( Origin gBackEnd )
				)
				( attribute "BONDPAD_TO_TESTVIA_SPACING" "5.00,5.00,5.00,5.00,5.00,5.00,5.00,5.00,5.00,5.00,5.00,5.00,5.00,5.00"
					( Origin gBackEnd )
				)
				( attribute "LINE_TO_TESTVIA_SPACING" "4.50,5.00,4.00,5.00,4.00,5.00,5.00,5.00,5.00,4.00,5.00,4.00,5.00,4.50"
					( Origin gBackEnd )
				)
				( attribute "SHAPE_TO_TESTVIA_SPACING" "4.50,4.00,4.00,4.00,4.00,4.00,4.00,4.00,4.00,4.00,4.00,4.00,4.00,5.00"
					( Origin gBackEnd )
				)
				( attribute "BBV_TO_BBV_SPACING" "5.00,5.00,5.00,5.00,5.00,5.00,5.00,5.00,5.00,5.00,5.00,5.00,5.00,5.00"
					( Origin gBackEnd )
				)
				( attribute "BONDPAD_TO_BBV_SPACING" "5.00,5.00,5.00,5.00,5.00,5.00,5.00,5.00,5.00,5.00,5.00,5.00,5.00,5.00"
					( Origin gBackEnd )
				)
				( attribute "BBV_TO_LINE_SPACING" "5.00,5.00,5.00,5.00,5.00,5.00,5.00,5.00,5.00,5.00,5.00,5.00,5.00,5.00"
					( Origin gBackEnd )
				)
				( attribute "BBV_TO_SHAPE_SPACING" "5.00,5.00,5.00,5.00,5.00,5.00,5.00,5.00,5.00,5.00,5.00,5.00,5.00,5.00"
					( Origin gBackEnd )
				)
				( attribute "BONDPAD_TO_BONDPAD_SPACING" "5.00,5.00,5.00,5.00,5.00,5.00,5.00,5.00,5.00,5.00,5.00,5.00,5.00,5.00"
					( Origin gBackEnd )
				)
				( attribute "BONDPAD_TO_LINE_SPACING" "5.00,5.00,5.00,5.00,5.00,5.00,5.00,5.00,5.00,5.00,5.00,5.00,5.00,5.00"
					( Origin gBackEnd )
				)
				( attribute "BONDPAD_TO_SHAPE_SPACING" "5.00,5.00,5.00,5.00,5.00,5.00,5.00,5.00,5.00,5.00,5.00,5.00,5.00,5.00"
					( Origin gBackEnd )
				)
				( attribute "LINE_TO_LINE_SPACING" "4.00,4.00,4.00,4.00,4.00,4.00,4.00,4.00,4.00,4.00,4.00,4.00,4.00,4.00"
					( Origin gBackEnd )
				)
				( attribute "LINE_TO_SHAPE_SPACING" "5.00,5.00,5.00,5.00,5.00,5.00,5.00,5.00,5.00,5.00,5.00,5.00,5.00,10.00"
					( Origin gBackEnd )
				)
				( attribute "SHAPE_TO_SHAPE_SPACING" "10.00,10.00,10.00,10.00,10.00,10.00,10.00,10.00,10.00,10.00,10.00,10.00,10.00,10.00"
					( Origin gBackEnd )
				)
				( attribute "HOLE_TO_PIN_SPACING" "8.00,8.00,8.00,8.00,8.00,8.00,8.00,8.00,8.00,8.00,8.00,8.00,8.00,8.00"
					( Origin gBackEnd )
				)
				( attribute "HOLE_TO_VIA_SPACING" "8.00,8.00,8.00,8.00,8.00,8.00,8.00,8.00,8.00,8.00,8.00,8.00,8.00,8.00"
					( Origin gBackEnd )
				)
				( attribute "HOLE_TO_LINE_SPACING" "8.00,8.00,8.00,8.00,8.00,8.00,8.00,8.00,8.00,8.00,8.00,8.00,8.00,8.00"
					( Origin gBackEnd )
				)
				( attribute "HOLE_TO_SHAPE_SPACING" "5.00,5.00,5.00,5.00,5.00,5.00,5.00,5.00,5.00,5.00,5.00,5.00,5.00,5.00"
					( Origin gBackEnd )
				)
				( attribute "HOLE_TO_HOLE_SPACING" "8.00,8.00,8.00,8.00,8.00,8.00,8.00,8.00,8.00,8.00,8.00,8.00,8.00,8.00"
					( Origin gBackEnd )
				)
				( attribute "MVIA_TO_MVIA_SPACING" "5.00,5.00,5.00,5.00,5.00,5.00,5.00,5.00,5.00,5.00,5.00,5.00,5.00,5.00"
					( Origin gBackEnd )
				)
				( attribute "MVIA_TO_THRUPIN_SPACING" "5.00,5.00,5.00,5.00,5.00,5.00,5.00,5.00,5.00,5.00,5.00,5.00,5.00,5.00"
					( Origin gBackEnd )
				)
				( attribute "MVIA_TO_SMDPIN_SPACING" "5.00,5.00,5.00,5.00,5.00,5.00,5.00,5.00,5.00,5.00,5.00,5.00,5.00,5.00"
					( Origin gBackEnd )
				)
				( attribute "MVIA_TO_THRUVIA_SPACING" "5.00,5.00,5.00,5.00,5.00,5.00,5.00,5.00,5.00,5.00,5.00,5.00,5.00,5.00"
					( Origin gBackEnd )
				)
				( attribute "MVIA_TO_BBV_SPACING" "5.00,5.00,5.00,5.00,5.00,5.00,5.00,5.00,5.00,5.00,5.00,5.00,5.00,5.00"
					( Origin gBackEnd )
				)
				( attribute "MVIA_TO_LINE_SPACING" "5.00,5.00,5.00,5.00,5.00,5.00,5.00,5.00,5.00,5.00,5.00,5.00,5.00,5.00"
					( Origin gBackEnd )
				)
				( attribute "MVIA_TO_SHAPE_SPACING" "5.00,5.00,5.00,5.00,5.00,5.00,5.00,5.00,5.00,5.00,5.00,5.00,5.00,5.00"
					( Origin gBackEnd )
				)
				( attribute "MVIA_TO_TESTPIN_SPACING" "5.00,5.00,5.00,5.00,5.00,5.00,5.00,5.00,5.00,5.00,5.00,5.00,5.00,5.00"
					( Origin gBackEnd )
				)
				( attribute "MVIA_TO_TESTVIA_SPACING" "5.00,5.00,5.00,5.00,5.00,5.00,5.00,5.00,5.00,5.00,5.00,5.00,5.00,5.00"
					( Origin gBackEnd )
				)
				( attribute "BONDPAD_TO_MVIA_SPACING" "5.00,5.00,5.00,5.00,5.00,5.00,5.00,5.00,5.00,5.00,5.00,5.00,5.00,5.00"
					( Origin gBackEnd )
				)
				( attribute "MIN_BVIA_GAP" "5.00"
					( Origin gBackEnd )
				)
				( attribute "BONDPAD_TO_BONDPAD_DIFFP_SPC" "5.00,5.00,5.00,5.00,5.00,5.00,5.00,5.00,5.00,5.00,5.00,5.00,5.00,5.00"
					( Origin gBackEnd )
				)
				( objectStatus "RCC_DFX_1940" )
			)
			( spacingCSet "@crescent_city_bb_fab1_lib.crescent_city_bb_fab1(sch_1):\25MIL_TDT\"
				( attribute "THRUPIN_TO_THRUPIN_SPACING" "5.00,5.00,5.00,5.00,5.00,5.00,5.00,5.00,5.00,5.00,5.00,5.00,5.00,5.00"
					( Origin gBackEnd )
				)
				( attribute "THRUPIN_TO_SMDPIN_SPACING" "5.00,5.00,5.00,5.00,5.00,5.00,5.00,5.00,5.00,5.00,5.00,5.00,5.00,5.00"
					( Origin gBackEnd )
				)
				( attribute "TESTPIN_TO_THRUPIN_SPACING" "5.00,5.00,5.00,5.00,5.00,5.00,5.00,5.00,5.00,5.00,5.00,5.00,5.00,5.00"
					( Origin gBackEnd )
				)
				( attribute "THRUPIN_TO_THRUVIA_SPACING" "5.00,5.00,5.00,5.00,5.00,5.00,5.00,5.00,5.00,5.00,5.00,5.00,5.00,5.00"
					( Origin gBackEnd )
				)
				( attribute "TESTVIA_TO_THRUPIN_SPACING" "5.00,5.00,5.00,5.00,5.00,5.00,5.00,5.00,5.00,5.00,5.00,5.00,5.00,5.00"
					( Origin gBackEnd )
				)
				( attribute "BBV_TO_THRUPIN_SPACING" "5.00,5.00,5.00,5.00,5.00,5.00,5.00,5.00,5.00,5.00,5.00,5.00,5.00,5.00"
					( Origin gBackEnd )
				)
				( attribute "THRUPIN_TO_BONDPAD_SPACING" "5.00,5.00,5.00,5.00,5.00,5.00,5.00,5.00,5.00,5.00,5.00,5.00,5.00,5.00"
					( Origin gBackEnd )
				)
				( attribute "LINE_TO_THRUPIN_SPACING" "25.00,25.00,25.00,25.00,25.00,25.00,25.00,25.00,25.00,25.00,25.00,25.00,25.00,25.00"
					( Origin gBackEnd )
				)
				( attribute "THRUPIN_TO_SHAPE_SPACING" "5.00,5.00,5.00,5.00,5.00,5.00,5.00,5.00,5.00,5.00,5.00,5.00,5.00,5.00"
					( Origin gBackEnd )
				)
				( attribute "SMDPIN_TO_SMDPIN_SPACING" "5.00,5.00,5.00,5.00,5.00,5.00,5.00,5.00,5.00,5.00,5.00,5.00,5.00,5.00"
					( Origin gBackEnd )
				)
				( attribute "SMDPIN_TO_TESTPIN_SPACING" "5.00,5.00,5.00,5.00,5.00,5.00,5.00,5.00,5.00,5.00,5.00,5.00,5.00,25.00"
					( Origin gBackEnd )
				)
				( attribute "SMDPIN_TO_THRUVIA_SPACING" "5.00,5.00,5.00,5.00,5.00,5.00,5.00,5.00,5.00,5.00,5.00,5.00,5.00,5.00"
					( Origin gBackEnd )
				)
				( attribute "SMDPIN_TO_TESTVIA_SPACING" "5.00,5.00,5.00,5.00,5.00,5.00,5.00,5.00,5.00,5.00,5.00,5.00,5.00,5.00"
					( Origin gBackEnd )
				)
				( attribute "BBV_TO_SMDPIN_SPACING" "5.00,5.00,5.00,5.00,5.00,5.00,5.00,5.00,5.00,5.00,5.00,5.00,5.00,5.00"
					( Origin gBackEnd )
				)
				( attribute "SMDPIN_TO_BONDPAD_SPACING" "5.00,5.00,5.00,5.00,5.00,5.00,5.00,5.00,5.00,5.00,5.00,5.00,5.00,5.00"
					( Origin gBackEnd )
				)
				( attribute "LINE_TO_SMDPIN_SPACING" "4.50,4.50,4.50,4.50,4.50,4.50,4.50,4.50,4.50,4.50,4.50,4.50,4.50,4.50"
					( Origin gBackEnd )
				)
				( attribute "SHAPE_TO_SMDPIN_SPACING" "5.00,5.00,5.00,5.00,5.00,5.00,5.00,5.00,5.00,5.00,5.00,5.00,5.00,5.00"
					( Origin gBackEnd )
				)
				( attribute "TESTPIN_TO_TESTPIN_SPACING" "5.00,5.00,5.00,5.00,5.00,5.00,5.00,5.00,5.00,5.00,5.00,5.00,5.00,5.00"
					( Origin gBackEnd )
				)
				( attribute "TESTPIN_TO_THRUVIA_SPACING" "5.00,5.00,5.00,5.00,5.00,5.00,5.00,5.00,5.00,5.00,5.00,5.00,5.00,5.00"
					( Origin gBackEnd )
				)
				( attribute "TESTPIN_TO_TESTVIA_SPACING" "5.00,5.00,5.00,5.00,5.00,5.00,5.00,5.00,5.00,5.00,5.00,5.00,5.00,5.00"
					( Origin gBackEnd )
				)
				( attribute "BBV_TO_TESTPIN_SPACING" "5.00,5.00,5.00,5.00,5.00,5.00,5.00,5.00,5.00,5.00,5.00,5.00,5.00,5.00"
					( Origin gBackEnd )
				)
				( attribute "BONDPAD_TO_TESTPIN_SPACING" "5.00,5.00,5.00,5.00,5.00,5.00,5.00,5.00,5.00,5.00,5.00,5.00,5.00,5.00"
					( Origin gBackEnd )
				)
				( attribute "LINE_TO_TESTPIN_SPACING" "5.00,4.00,4.00,4.00,4.00,4.00,4.00,4.00,4.00,4.00,4.00,4.00,4.00,5.00"
					( Origin gBackEnd )
				)
				( attribute "SHAPE_TO_TESTPIN_SPACING" "5.00,5.00,5.00,5.00,5.00,5.00,5.00,5.00,5.00,5.00,5.00,5.00,5.00,5.00"
					( Origin gBackEnd )
				)
				( attribute "THRUVIA_TO_THRUVIA_SPACING" "6.00,6.00,6.00,6.00,6.00,6.00,6.00,6.00,6.00,6.00,6.00,6.00,6.00,6.00"
					( Origin gBackEnd )
				)
				( attribute "TESTVIA_TO_THRUVIA_SPACING" "6.00,6.00,6.00,6.00,6.00,6.00,6.00,6.00,6.00,6.00,6.00,6.00,6.00,6.00"
					( Origin gBackEnd )
				)
				( attribute "BBV_TO_THRUVIA_SPACING" "5.00,5.00,5.00,5.00,5.00,5.00,5.00,5.00,5.00,5.00,5.00,5.00,5.00,5.00"
					( Origin gBackEnd )
				)
				( attribute "BONDPAD_TO_THRUVIA_SPACING" "5.00,5.00,5.00,5.00,5.00,5.00,5.00,5.00,5.00,5.00,5.00,5.00,5.00,5.00"
					( Origin gBackEnd )
				)
				( attribute "LINE_TO_THRUVIA_SPACING" "25.00,25.00,25.00,25.00,25.00,25.00,25.00,25.00,25.00,25.00,25.00,25.00,25.00,25.00"
					( Origin gBackEnd )
				)
				( attribute "SHAPE_TO_THRUVIA_SPACING" "5.00,5.00,5.00,5.00,5.00,5.00,5.00,5.00,5.00,5.00,5.00,5.00,5.00,5.00"
					( Origin gBackEnd )
				)
				( attribute "TESTVIA_TO_TESTVIA_SPACING" "6.00,6.00,6.00,6.00,6.00,6.00,6.00,6.00,6.00,6.00,6.00,6.00,6.00,6.00"
					( Origin gBackEnd )
				)
				( attribute "BBV_TO_TESTVIA_SPACING" "5.00,5.00,5.00,5.00,5.00,5.00,5.00,5.00,5.00,5.00,5.00,5.00,5.00,5.00"
					( Origin gBackEnd )
				)
				( attribute "BONDPAD_TO_TESTVIA_SPACING" "5.00,5.00,5.00,5.00,5.00,5.00,5.00,5.00,5.00,5.00,5.00,5.00,5.00,5.00"
					( Origin gBackEnd )
				)
				( attribute "LINE_TO_TESTVIA_SPACING" "25.00,25.00,25.00,25.00,25.00,25.00,25.00,25.00,25.00,25.00,25.00,25.00,25.00,25.00"
					( Origin gBackEnd )
				)
				( attribute "SHAPE_TO_TESTVIA_SPACING" "5.00,5.00,5.00,5.00,5.00,5.00,5.00,5.00,5.00,5.00,5.00,5.00,5.00,5.00"
					( Origin gBackEnd )
				)
				( attribute "BBV_TO_BBV_SPACING" "5.00,5.00,5.00,5.00,5.00,5.00,5.00,5.00,5.00,5.00,5.00,5.00,5.00,5.00"
					( Origin gBackEnd )
				)
				( attribute "BONDPAD_TO_BBV_SPACING" "5.00,5.00,5.00,5.00,5.00,5.00,5.00,5.00,5.00,5.00,5.00,5.00,5.00,5.00"
					( Origin gBackEnd )
				)
				( attribute "BBV_TO_LINE_SPACING" "5.00,5.00,5.00,5.00,5.00,5.00,5.00,5.00,5.00,5.00,5.00,5.00,5.00,5.00"
					( Origin gBackEnd )
				)
				( attribute "BBV_TO_SHAPE_SPACING" "5.00,5.00,5.00,5.00,5.00,5.00,5.00,5.00,5.00,5.00,5.00,5.00,5.00,5.00"
					( Origin gBackEnd )
				)
				( attribute "BONDPAD_TO_BONDPAD_SPACING" "5.00,5.00,5.00,5.00,5.00,5.00,5.00,5.00,5.00,5.00,5.00,5.00,5.00,5.00"
					( Origin gBackEnd )
				)
				( attribute "BONDPAD_TO_LINE_SPACING" "5.00,5.00,5.00,5.00,5.00,5.00,5.00,5.00,5.00,5.00,5.00,5.00,5.00,5.00"
					( Origin gBackEnd )
				)
				( attribute "BONDPAD_TO_SHAPE_SPACING" "5.00,5.00,5.00,5.00,5.00,5.00,5.00,5.00,5.00,5.00,5.00,5.00,5.00,5.00"
					( Origin gBackEnd )
				)
				( attribute "LINE_TO_LINE_SPACING" "25.00,25.00,25.00,25.00,25.00,25.00,25.00,25.00,25.00,25.00,25.00,25.00,25.00,25.00"
					( Origin gBackEnd )
				)
				( attribute "LINE_TO_SHAPE_SPACING" "25.00,25.00,25.00,25.00,25.00,25.00,25.00,25.00,25.00,25.00,25.00,25.00,25.00,25.00"
					( Origin gBackEnd )
				)
				( attribute "SHAPE_TO_SHAPE_SPACING" "10.00,10.00,10.00,10.00,10.00,10.00,10.00,10.00,10.00,10.00,10.00,10.00,10.00,10.00"
					( Origin gBackEnd )
				)
				( attribute "HOLE_TO_PIN_SPACING" "8.00,8.00,8.00,8.00,8.00,8.00,8.00,8.00,8.00,8.00,8.00,8.00,8.00,8.00"
					( Origin gBackEnd )
				)
				( attribute "HOLE_TO_VIA_SPACING" "8.00,8.00,8.00,8.00,8.00,8.00,8.00,8.00,8.00,8.00,8.00,8.00,8.00,8.00"
					( Origin gBackEnd )
				)
				( attribute "HOLE_TO_LINE_SPACING" "8.00,8.00,8.00,8.00,8.00,8.00,8.00,8.00,8.00,8.00,8.00,8.00,8.00,8.00"
					( Origin gBackEnd )
				)
				( attribute "HOLE_TO_SHAPE_SPACING" "8.00,8.00,8.00,8.00,8.00,8.00,8.00,8.00,8.00,8.00,8.00,8.00,8.00,8.00"
					( Origin gBackEnd )
				)
				( attribute "HOLE_TO_HOLE_SPACING" "8.00,8.00,8.00,8.00,8.00,8.00,8.00,8.00,8.00,8.00,8.00,8.00,8.00,8.00"
					( Origin gBackEnd )
				)
				( attribute "MVIA_TO_MVIA_SPACING" "5.00,5.00,5.00,5.00,5.00,5.00,5.00,5.00,5.00,5.00,5.00,5.00,5.00,5.00"
					( Origin gBackEnd )
				)
				( attribute "MVIA_TO_THRUPIN_SPACING" "5.00,5.00,5.00,5.00,5.00,5.00,5.00,5.00,5.00,5.00,5.00,5.00,5.00,5.00"
					( Origin gBackEnd )
				)
				( attribute "MVIA_TO_SMDPIN_SPACING" "5.00,5.00,5.00,5.00,5.00,5.00,5.00,5.00,5.00,5.00,5.00,5.00,5.00,5.00"
					( Origin gBackEnd )
				)
				( attribute "MVIA_TO_THRUVIA_SPACING" "5.00,5.00,5.00,5.00,5.00,5.00,5.00,5.00,5.00,5.00,5.00,5.00,5.00,5.00"
					( Origin gBackEnd )
				)
				( attribute "MVIA_TO_BBV_SPACING" "5.00,5.00,5.00,5.00,5.00,5.00,5.00,5.00,5.00,5.00,5.00,5.00,5.00,5.00"
					( Origin gBackEnd )
				)
				( attribute "MVIA_TO_LINE_SPACING" "5.00,5.00,5.00,5.00,5.00,5.00,5.00,5.00,5.00,5.00,5.00,5.00,5.00,5.00"
					( Origin gBackEnd )
				)
				( attribute "MVIA_TO_SHAPE_SPACING" "5.00,5.00,5.00,5.00,5.00,5.00,5.00,5.00,5.00,5.00,5.00,5.00,5.00,5.00"
					( Origin gBackEnd )
				)
				( attribute "MVIA_TO_TESTPIN_SPACING" "5.00,5.00,5.00,5.00,5.00,5.00,5.00,5.00,5.00,5.00,5.00,5.00,5.00,5.00"
					( Origin gBackEnd )
				)
				( attribute "MVIA_TO_TESTVIA_SPACING" "5.00,5.00,5.00,5.00,5.00,5.00,5.00,5.00,5.00,5.00,5.00,5.00,5.00,5.00"
					( Origin gBackEnd )
				)
				( attribute "BONDPAD_TO_MVIA_SPACING" "5.00,5.00,5.00,5.00,5.00,5.00,5.00,5.00,5.00,5.00,5.00,5.00,5.00,5.00"
					( Origin gBackEnd )
				)
				( attribute "MIN_BVIA_GAP" "5.00"
					( Origin gBackEnd )
				)
				( attribute "BONDPAD_TO_BONDPAD_DIFFP_SPC" "5.00,5.00,5.00,5.00,5.00,5.00,5.00,5.00,5.00,5.00,5.00,5.00,5.00,5.00"
					( Origin gBackEnd )
				)
				( objectStatus "25MIL_TDT" )
			)
			( spacingCSet "@crescent_city_bb_fab1_lib.crescent_city_bb_fab1(sch_1):\PCS_SNAIL_PF1\"
				( attribute "THRUPIN_TO_THRUPIN_SPACING" "5.00,5.00,5.00,5.00,5.00,5.00,5.00,5.00,5.00,5.00,5.00,5.00,5.00,5.00"
					( Origin gBackEnd )
				)
				( attribute "THRUPIN_TO_SMDPIN_SPACING" "5.00,5.00,5.00,5.00,5.00,5.00,5.00,5.00,5.00,5.00,5.00,5.00,5.00,5.00"
					( Origin gBackEnd )
				)
				( attribute "TESTPIN_TO_THRUPIN_SPACING" "5.00,5.00,5.00,5.00,5.00,5.00,5.00,5.00,5.00,5.00,5.00,5.00,5.00,5.00"
					( Origin gBackEnd )
				)
				( attribute "THRUPIN_TO_THRUVIA_SPACING" "6.00,6.00,6.00,6.00,6.00,6.00,6.00,6.00,6.00,6.00,6.00,6.00,6.00,6.00"
					( Origin gBackEnd )
				)
				( attribute "TESTVIA_TO_THRUPIN_SPACING" "6.00,6.00,6.00,6.00,6.00,6.00,6.00,6.00,6.00,6.00,6.00,6.00,6.00,6.00"
					( Origin gBackEnd )
				)
				( attribute "BBV_TO_THRUPIN_SPACING" "5.00,5.00,5.00,5.00,5.00,5.00,5.00,5.00,5.00,5.00,5.00,5.00,5.00,5.00"
					( Origin gBackEnd )
				)
				( attribute "THRUPIN_TO_BONDPAD_SPACING" "5.00,5.00,5.00,5.00,5.00,5.00,5.00,5.00,5.00,5.00,5.00,5.00,5.00,5.00"
					( Origin gBackEnd )
				)
				( attribute "LINE_TO_THRUPIN_SPACING" "4.50,4.00,4.00,4.00,4.00,4.00,4.00,4.00,4.00,4.00,4.00,4.00,4.00,4.50"
					( Origin gBackEnd )
				)
				( attribute "THRUPIN_TO_SHAPE_SPACING" "5.00,5.00,5.00,5.00,5.00,5.00,5.00,5.00,5.00,5.00,5.00,5.00,5.00,5.00"
					( Origin gBackEnd )
				)
				( attribute "SMDPIN_TO_SMDPIN_SPACING" "5.00,5.00,5.00,5.00,5.00,5.00,5.00,5.00,5.00,5.00,5.00,5.00,5.00,5.00"
					( Origin gBackEnd )
				)
				( attribute "SMDPIN_TO_TESTPIN_SPACING" "5.00,5.00,5.00,5.00,5.00,5.00,5.00,5.00,5.00,5.00,5.00,5.00,5.00,5.00"
					( Origin gBackEnd )
				)
				( attribute "SMDPIN_TO_THRUVIA_SPACING" "4.00,4.00,4.00,4.00,4.00,4.00,4.00,4.00,4.00,4.00,4.00,4.00,4.00,4.00"
					( Origin gBackEnd )
				)
				( attribute "SMDPIN_TO_TESTVIA_SPACING" "4.00,4.00,4.00,4.00,4.00,4.00,4.00,4.00,4.00,4.00,4.00,4.00,4.00,4.00"
					( Origin gBackEnd )
				)
				( attribute "BBV_TO_SMDPIN_SPACING" "5.00,5.00,5.00,5.00,5.00,5.00,5.00,5.00,5.00,5.00,5.00,5.00,5.00,5.00"
					( Origin gBackEnd )
				)
				( attribute "SMDPIN_TO_BONDPAD_SPACING" "5.00,5.00,5.00,5.00,5.00,5.00,5.00,5.00,5.00,5.00,5.00,5.00,5.00,5.00"
					( Origin gBackEnd )
				)
				( attribute "LINE_TO_SMDPIN_SPACING" "4.50,4.50,4.50,4.50,4.50,4.50,4.50,4.50,4.50,4.50,4.50,4.50,4.50,4.50"
					( Origin gBackEnd )
				)
				( attribute "SHAPE_TO_SMDPIN_SPACING" "4.50,4.00,4.00,4.00,4.00,4.00,4.00,4.00,4.00,4.00,4.00,4.00,4.00,4.50"
					( Origin gBackEnd )
				)
				( attribute "TESTPIN_TO_TESTPIN_SPACING" "5.00,5.00,5.00,5.00,5.00,5.00,5.00,5.00,5.00,5.00,5.00,5.00,5.00,5.00"
					( Origin gBackEnd )
				)
				( attribute "TESTPIN_TO_THRUVIA_SPACING" "6.00,6.00,6.00,6.00,6.00,6.00,6.00,6.00,6.00,6.00,6.00,6.00,6.00,6.00"
					( Origin gBackEnd )
				)
				( attribute "TESTPIN_TO_TESTVIA_SPACING" "6.00,6.00,6.00,6.00,6.00,6.00,6.00,6.00,6.00,6.00,6.00,6.00,6.00,6.00"
					( Origin gBackEnd )
				)
				( attribute "BBV_TO_TESTPIN_SPACING" "5.00,5.00,5.00,5.00,5.00,5.00,5.00,5.00,5.00,5.00,5.00,5.00,5.00,5.00"
					( Origin gBackEnd )
				)
				( attribute "BONDPAD_TO_TESTPIN_SPACING" "5.00,5.00,5.00,5.00,5.00,5.00,5.00,5.00,5.00,5.00,5.00,5.00,5.00,5.00"
					( Origin gBackEnd )
				)
				( attribute "LINE_TO_TESTPIN_SPACING" "4.50,4.50,4.50,4.50,4.50,4.50,4.50,4.50,4.50,4.50,4.50,4.50,4.50,4.50"
					( Origin gBackEnd )
				)
				( attribute "SHAPE_TO_TESTPIN_SPACING" "5.00,5.00,5.00,5.00,5.00,5.00,5.00,5.00,5.00,5.00,5.00,5.00,5.00,5.00"
					( Origin gBackEnd )
				)
				( attribute "THRUVIA_TO_THRUVIA_SPACING" "5.00,5.00,5.00,5.00,5.00,5.00,5.00,5.00,5.00,5.00,5.00,5.00,5.00,5.00"
					( Origin gBackEnd )
				)
				( attribute "TESTVIA_TO_THRUVIA_SPACING" "5.00,5.00,5.00,5.00,5.00,5.00,5.00,5.00,5.00,5.00,5.00,5.00,5.00,5.00"
					( Origin gBackEnd )
				)
				( attribute "BBV_TO_THRUVIA_SPACING" "5.00,5.00,5.00,5.00,5.00,5.00,5.00,5.00,5.00,5.00,5.00,5.00,5.00,5.00"
					( Origin gBackEnd )
				)
				( attribute "BONDPAD_TO_THRUVIA_SPACING" "5.00,5.00,5.00,5.00,5.00,5.00,5.00,5.00,5.00,5.00,5.00,5.00,5.00,5.00"
					( Origin gBackEnd )
				)
				( attribute "LINE_TO_THRUVIA_SPACING" "3.98,3.98,3.98,3.98,3.98,3.98,3.98,3.98,3.98,3.98,3.98,3.98,3.98,3.98"
					( Origin gBackEnd )
				)
				( attribute "SHAPE_TO_THRUVIA_SPACING" "4.50,4.00,4.00,4.00,4.00,4.00,4.00,4.00,4.00,4.00,4.00,4.00,4.00,4.50"
					( Origin gBackEnd )
				)
				( attribute "TESTVIA_TO_TESTVIA_SPACING" "6.00,6.00,6.00,6.00,6.00,6.00,6.00,6.00,6.00,6.00,6.00,6.00,6.00,6.00"
					( Origin gBackEnd )
				)
				( attribute "BBV_TO_TESTVIA_SPACING" "5.00,5.00,5.00,5.00,5.00,5.00,5.00,5.00,5.00,5.00,5.00,5.00,5.00,5.00"
					( Origin gBackEnd )
				)
				( attribute "BONDPAD_TO_TESTVIA_SPACING" "5.00,5.00,5.00,5.00,5.00,5.00,5.00,5.00,5.00,5.00,5.00,5.00,5.00,5.00"
					( Origin gBackEnd )
				)
				( attribute "LINE_TO_TESTVIA_SPACING" "4.49,4.49,4.49,4.49,4.49,4.49,4.49,4.49,4.49,4.49,4.49,4.49,4.49,4.49"
					( Origin gBackEnd )
				)
				( attribute "SHAPE_TO_TESTVIA_SPACING" "5.00,4.00,4.00,4.00,4.00,4.00,4.00,4.00,4.00,4.00,4.00,4.00,4.00,5.00"
					( Origin gBackEnd )
				)
				( attribute "BBV_TO_BBV_SPACING" "5.00,5.00,5.00,5.00,5.00,5.00,5.00,5.00,5.00,5.00,5.00,5.00,5.00,5.00"
					( Origin gBackEnd )
				)
				( attribute "BONDPAD_TO_BBV_SPACING" "5.00,5.00,5.00,5.00,5.00,5.00,5.00,5.00,5.00,5.00,5.00,5.00,5.00,5.00"
					( Origin gBackEnd )
				)
				( attribute "BBV_TO_LINE_SPACING" "5.00,5.00,5.00,5.00,5.00,5.00,5.00,5.00,5.00,5.00,5.00,5.00,5.00,5.00"
					( Origin gBackEnd )
				)
				( attribute "BBV_TO_SHAPE_SPACING" "5.00,5.00,5.00,5.00,5.00,5.00,5.00,5.00,5.00,5.00,5.00,5.00,5.00,5.00"
					( Origin gBackEnd )
				)
				( attribute "BONDPAD_TO_BONDPAD_SPACING" "5.00,5.00,5.00,5.00,5.00,5.00,5.00,5.00,5.00,5.00,5.00,5.00,5.00,5.00"
					( Origin gBackEnd )
				)
				( attribute "BONDPAD_TO_LINE_SPACING" "5.00,5.00,5.00,5.00,5.00,5.00,5.00,5.00,5.00,5.00,5.00,5.00,5.00,5.00"
					( Origin gBackEnd )
				)
				( attribute "BONDPAD_TO_SHAPE_SPACING" "5.00,5.00,5.00,5.00,5.00,5.00,5.00,5.00,5.00,5.00,5.00,5.00,5.00,5.00"
					( Origin gBackEnd )
				)
				( attribute "LINE_TO_LINE_SPACING" "4.00,4.00,4.00,4.00,4.00,4.00,4.00,4.00,4.00,4.00,4.00,4.00,4.00,4.00"
					( Origin gBackEnd )
				)
				( attribute "LINE_TO_SHAPE_SPACING" "3.99,5.00,3.99,5.00,3.99,5.00,10.00,10.00,5.00,3.99,5.00,3.99,10.00,3.99"
					( Origin gBackEnd )
				)
				( attribute "SHAPE_TO_SHAPE_SPACING" "4.00,4.00,4.00,4.00,4.00,4.00,5.00,5.00,4.00,4.00,4.00,4.00,4.00,4.00"
					( Origin gBackEnd )
				)
				( attribute "HOLE_TO_PIN_SPACING" "8.00,8.00,8.00,8.00,8.00,8.00,8.00,8.00,8.00,8.00,8.00,8.00,8.00,8.00"
					( Origin gBackEnd )
				)
				( attribute "HOLE_TO_VIA_SPACING" "8.00,8.00,8.00,8.00,8.00,8.00,8.00,8.00,8.00,8.00,8.00,8.00,8.00,8.00"
					( Origin gBackEnd )
				)
				( attribute "HOLE_TO_LINE_SPACING" "8.00,8.00,8.00,8.00,8.00,8.00,8.00,8.00,8.00,8.00,8.00,8.00,8.00,8.00"
					( Origin gBackEnd )
				)
				( attribute "HOLE_TO_SHAPE_SPACING" "8.00,8.00,8.00,8.00,8.00,8.00,8.00,8.00,8.00,8.00,8.00,8.00,8.00,8.00"
					( Origin gBackEnd )
				)
				( attribute "HOLE_TO_HOLE_SPACING" "8.00,8.00,8.00,8.00,8.00,8.00,8.00,8.00,8.00,8.00,8.00,8.00,8.00,8.00"
					( Origin gBackEnd )
				)
				( attribute "MVIA_TO_MVIA_SPACING" "5.00,5.00,5.00,5.00,5.00,5.00,5.00,5.00,5.00,5.00,5.00,5.00,5.00,5.00"
					( Origin gBackEnd )
				)
				( attribute "MVIA_TO_THRUPIN_SPACING" "5.00,5.00,5.00,5.00,5.00,5.00,5.00,5.00,5.00,5.00,5.00,5.00,5.00,5.00"
					( Origin gBackEnd )
				)
				( attribute "MVIA_TO_SMDPIN_SPACING" "5.00,5.00,5.00,5.00,5.00,5.00,5.00,5.00,5.00,5.00,5.00,5.00,5.00,5.00"
					( Origin gBackEnd )
				)
				( attribute "MVIA_TO_THRUVIA_SPACING" "5.00,5.00,5.00,5.00,5.00,5.00,5.00,5.00,5.00,5.00,5.00,5.00,5.00,5.00"
					( Origin gBackEnd )
				)
				( attribute "MVIA_TO_BBV_SPACING" "5.00,5.00,5.00,5.00,5.00,5.00,5.00,5.00,5.00,5.00,5.00,5.00,5.00,5.00"
					( Origin gBackEnd )
				)
				( attribute "MVIA_TO_LINE_SPACING" "5.00,5.00,5.00,5.00,5.00,5.00,5.00,5.00,5.00,5.00,5.00,5.00,5.00,5.00"
					( Origin gBackEnd )
				)
				( attribute "MVIA_TO_SHAPE_SPACING" "5.00,5.00,5.00,5.00,5.00,5.00,5.00,5.00,5.00,5.00,5.00,5.00,5.00,5.00"
					( Origin gBackEnd )
				)
				( attribute "MVIA_TO_TESTPIN_SPACING" "5.00,5.00,5.00,5.00,5.00,5.00,5.00,5.00,5.00,5.00,5.00,5.00,5.00,5.00"
					( Origin gBackEnd )
				)
				( attribute "MVIA_TO_TESTVIA_SPACING" "5.00,5.00,5.00,5.00,5.00,5.00,5.00,5.00,5.00,5.00,5.00,5.00,5.00,5.00"
					( Origin gBackEnd )
				)
				( attribute "BONDPAD_TO_MVIA_SPACING" "5.00,5.00,5.00,5.00,5.00,5.00,5.00,5.00,5.00,5.00,5.00,5.00,5.00,5.00"
					( Origin gBackEnd )
				)
				( attribute "MIN_BVIA_GAP" "5.00"
					( Origin gBackEnd )
				)
				( attribute "BONDPAD_TO_BONDPAD_DIFFP_SPC" "5.00,5.00,5.00,5.00,5.00,5.00,5.00,5.00,5.00,5.00,5.00,5.00,5.00,5.00"
					( Origin gBackEnd )
				)
				( objectStatus "PCS_SNAIL_PF1" )
			)
			( spacingCSet "@crescent_city_bb_fab1_lib.crescent_city_bb_fab1(sch_1):\PCS_SNAIL\"
				( attribute "THRUPIN_TO_THRUPIN_SPACING" "5.00,5.00,5.00,5.00,5.00,5.00,5.00,5.00,5.00,5.00,5.00,5.00,5.00,5.00"
					( Origin gBackEnd )
				)
				( attribute "THRUPIN_TO_SMDPIN_SPACING" "5.00,5.00,5.00,5.00,5.00,5.00,5.00,5.00,5.00,5.00,5.00,5.00,5.00,5.00"
					( Origin gBackEnd )
				)
				( attribute "TESTPIN_TO_THRUPIN_SPACING" "5.00,5.00,5.00,5.00,5.00,5.00,5.00,5.00,5.00,5.00,5.00,5.00,5.00,5.00"
					( Origin gBackEnd )
				)
				( attribute "THRUPIN_TO_THRUVIA_SPACING" "6.00,6.00,6.00,6.00,6.00,6.00,6.00,6.00,6.00,6.00,6.00,6.00,6.00,6.00"
					( Origin gBackEnd )
				)
				( attribute "TESTVIA_TO_THRUPIN_SPACING" "6.00,6.00,6.00,6.00,6.00,6.00,6.00,6.00,6.00,6.00,6.00,6.00,6.00,6.00"
					( Origin gBackEnd )
				)
				( attribute "BBV_TO_THRUPIN_SPACING" "5.00,5.00,5.00,5.00,5.00,5.00,5.00,5.00,5.00,5.00,5.00,5.00,5.00,5.00"
					( Origin gBackEnd )
				)
				( attribute "THRUPIN_TO_BONDPAD_SPACING" "5.00,5.00,5.00,5.00,5.00,5.00,5.00,5.00,5.00,5.00,5.00,5.00,5.00,5.00"
					( Origin gBackEnd )
				)
				( attribute "LINE_TO_THRUPIN_SPACING" "4.50,4.00,4.00,4.00,4.00,4.00,4.00,4.00,4.00,4.00,4.00,4.00,4.00,4.50"
					( Origin gBackEnd )
				)
				( attribute "THRUPIN_TO_SHAPE_SPACING" "5.00,5.00,5.00,5.00,5.00,5.00,5.00,5.00,5.00,5.00,5.00,5.00,5.00,5.00"
					( Origin gBackEnd )
				)
				( attribute "SMDPIN_TO_SMDPIN_SPACING" "5.00,5.00,5.00,5.00,5.00,5.00,5.00,5.00,5.00,5.00,5.00,5.00,5.00,5.00"
					( Origin gBackEnd )
				)
				( attribute "SMDPIN_TO_TESTPIN_SPACING" "5.00,5.00,5.00,5.00,5.00,5.00,5.00,5.00,5.00,5.00,5.00,5.00,5.00,5.00"
					( Origin gBackEnd )
				)
				( attribute "SMDPIN_TO_THRUVIA_SPACING" "4.00,4.00,4.00,4.00,4.00,4.00,4.00,4.00,4.00,4.00,4.00,4.00,4.00,4.00"
					( Origin gBackEnd )
				)
				( attribute "SMDPIN_TO_TESTVIA_SPACING" "4.00,4.00,4.00,4.00,4.00,4.00,4.00,4.00,4.00,4.00,4.00,4.00,4.00,4.00"
					( Origin gBackEnd )
				)
				( attribute "BBV_TO_SMDPIN_SPACING" "5.00,5.00,5.00,5.00,5.00,5.00,5.00,5.00,5.00,5.00,5.00,5.00,5.00,5.00"
					( Origin gBackEnd )
				)
				( attribute "SMDPIN_TO_BONDPAD_SPACING" "5.00,5.00,5.00,5.00,5.00,5.00,5.00,5.00,5.00,5.00,5.00,5.00,5.00,5.00"
					( Origin gBackEnd )
				)
				( attribute "LINE_TO_SMDPIN_SPACING" "4.50,4.50,4.50,4.50,4.50,4.50,4.50,4.50,4.50,4.50,4.50,4.50,4.50,4.50"
					( Origin gBackEnd )
				)
				( attribute "SHAPE_TO_SMDPIN_SPACING" "4.50,4.00,4.00,4.00,4.00,4.00,4.00,4.00,4.00,4.00,4.00,4.00,4.00,4.50"
					( Origin gBackEnd )
				)
				( attribute "TESTPIN_TO_TESTPIN_SPACING" "5.00,5.00,5.00,5.00,5.00,5.00,5.00,5.00,5.00,5.00,5.00,5.00,5.00,5.00"
					( Origin gBackEnd )
				)
				( attribute "TESTPIN_TO_THRUVIA_SPACING" "6.00,6.00,6.00,6.00,6.00,6.00,6.00,6.00,6.00,6.00,6.00,6.00,6.00,6.00"
					( Origin gBackEnd )
				)
				( attribute "TESTPIN_TO_TESTVIA_SPACING" "6.00,6.00,6.00,6.00,6.00,6.00,6.00,6.00,6.00,6.00,6.00,6.00,6.00,6.00"
					( Origin gBackEnd )
				)
				( attribute "BBV_TO_TESTPIN_SPACING" "5.00,5.00,5.00,5.00,5.00,5.00,5.00,5.00,5.00,5.00,5.00,5.00,5.00,5.00"
					( Origin gBackEnd )
				)
				( attribute "BONDPAD_TO_TESTPIN_SPACING" "5.00,5.00,5.00,5.00,5.00,5.00,5.00,5.00,5.00,5.00,5.00,5.00,5.00,5.00"
					( Origin gBackEnd )
				)
				( attribute "LINE_TO_TESTPIN_SPACING" "4.50,4.50,4.50,4.50,4.50,4.50,4.50,4.50,4.50,4.50,4.50,4.50,4.50,4.50"
					( Origin gBackEnd )
				)
				( attribute "SHAPE_TO_TESTPIN_SPACING" "5.00,5.00,5.00,5.00,5.00,5.00,5.00,5.00,5.00,5.00,5.00,5.00,5.00,5.00"
					( Origin gBackEnd )
				)
				( attribute "THRUVIA_TO_THRUVIA_SPACING" "5.00,5.00,5.00,5.00,5.00,5.00,5.00,5.00,5.00,5.00,5.00,5.00,5.00,5.00"
					( Origin gBackEnd )
				)
				( attribute "TESTVIA_TO_THRUVIA_SPACING" "5.00,5.00,5.00,5.00,5.00,5.00,5.00,5.00,5.00,5.00,5.00,5.00,5.00,5.00"
					( Origin gBackEnd )
				)
				( attribute "BBV_TO_THRUVIA_SPACING" "5.00,5.00,5.00,5.00,5.00,5.00,5.00,5.00,5.00,5.00,5.00,5.00,5.00,5.00"
					( Origin gBackEnd )
				)
				( attribute "BONDPAD_TO_THRUVIA_SPACING" "5.00,5.00,5.00,5.00,5.00,5.00,5.00,5.00,5.00,5.00,5.00,5.00,5.00,5.00"
					( Origin gBackEnd )
				)
				( attribute "LINE_TO_THRUVIA_SPACING" "3.98,3.98,3.98,3.98,3.98,3.98,3.98,3.98,3.98,3.98,3.98,3.98,3.98,3.98"
					( Origin gBackEnd )
				)
				( attribute "SHAPE_TO_THRUVIA_SPACING" "4.50,4.00,4.00,4.00,4.00,4.00,4.00,4.00,4.00,4.00,4.00,4.00,4.00,4.50"
					( Origin gBackEnd )
				)
				( attribute "TESTVIA_TO_TESTVIA_SPACING" "6.00,6.00,6.00,6.00,6.00,6.00,6.00,6.00,6.00,6.00,6.00,6.00,6.00,6.00"
					( Origin gBackEnd )
				)
				( attribute "BBV_TO_TESTVIA_SPACING" "5.00,5.00,5.00,5.00,5.00,5.00,5.00,5.00,5.00,5.00,5.00,5.00,5.00,5.00"
					( Origin gBackEnd )
				)
				( attribute "BONDPAD_TO_TESTVIA_SPACING" "5.00,5.00,5.00,5.00,5.00,5.00,5.00,5.00,5.00,5.00,5.00,5.00,5.00,5.00"
					( Origin gBackEnd )
				)
				( attribute "LINE_TO_TESTVIA_SPACING" "4.49,4.49,4.49,4.49,4.49,4.49,4.49,4.49,4.49,4.49,4.49,4.49,4.49,4.49"
					( Origin gBackEnd )
				)
				( attribute "SHAPE_TO_TESTVIA_SPACING" "5.00,4.00,4.00,4.00,4.00,4.00,4.00,4.00,4.00,4.00,4.00,4.00,4.00,5.00"
					( Origin gBackEnd )
				)
				( attribute "BBV_TO_BBV_SPACING" "5.00,5.00,5.00,5.00,5.00,5.00,5.00,5.00,5.00,5.00,5.00,5.00,5.00,5.00"
					( Origin gBackEnd )
				)
				( attribute "BONDPAD_TO_BBV_SPACING" "5.00,5.00,5.00,5.00,5.00,5.00,5.00,5.00,5.00,5.00,5.00,5.00,5.00,5.00"
					( Origin gBackEnd )
				)
				( attribute "BBV_TO_LINE_SPACING" "5.00,5.00,5.00,5.00,5.00,5.00,5.00,5.00,5.00,5.00,5.00,5.00,5.00,5.00"
					( Origin gBackEnd )
				)
				( attribute "BBV_TO_SHAPE_SPACING" "5.00,5.00,5.00,5.00,5.00,5.00,5.00,5.00,5.00,5.00,5.00,5.00,5.00,5.00"
					( Origin gBackEnd )
				)
				( attribute "BONDPAD_TO_BONDPAD_SPACING" "5.00,5.00,5.00,5.00,5.00,5.00,5.00,5.00,5.00,5.00,5.00,5.00,5.00,5.00"
					( Origin gBackEnd )
				)
				( attribute "BONDPAD_TO_LINE_SPACING" "5.00,5.00,5.00,5.00,5.00,5.00,5.00,5.00,5.00,5.00,5.00,5.00,5.00,5.00"
					( Origin gBackEnd )
				)
				( attribute "BONDPAD_TO_SHAPE_SPACING" "5.00,5.00,5.00,5.00,5.00,5.00,5.00,5.00,5.00,5.00,5.00,5.00,5.00,5.00"
					( Origin gBackEnd )
				)
				( attribute "LINE_TO_LINE_SPACING" "3.98,3.98,3.98,3.98,3.98,3.98,3.98,3.98,3.98,3.98,3.98,3.98,3.98,3.98"
					( Origin gBackEnd )
				)
				( attribute "LINE_TO_SHAPE_SPACING" "3.99,5.00,3.99,5.00,3.99,5.00,10.00,10.00,5.00,3.99,5.00,3.99,10.00,3.99"
					( Origin gBackEnd )
				)
				( attribute "SHAPE_TO_SHAPE_SPACING" "4.00,4.00,4.00,4.00,4.00,4.00,5.00,5.00,4.00,4.00,4.00,4.00,4.00,4.00"
					( Origin gBackEnd )
				)
				( attribute "HOLE_TO_PIN_SPACING" "8.00,8.00,8.00,8.00,8.00,8.00,8.00,8.00,8.00,8.00,8.00,8.00,8.00,8.00"
					( Origin gBackEnd )
				)
				( attribute "HOLE_TO_VIA_SPACING" "8.00,8.00,8.00,8.00,8.00,8.00,8.00,8.00,8.00,8.00,8.00,8.00,8.00,8.00"
					( Origin gBackEnd )
				)
				( attribute "HOLE_TO_LINE_SPACING" "8.00,8.00,8.00,8.00,8.00,8.00,8.00,8.00,8.00,8.00,8.00,8.00,8.00,8.00"
					( Origin gBackEnd )
				)
				( attribute "HOLE_TO_SHAPE_SPACING" "8.00,8.00,8.00,8.00,8.00,8.00,8.00,8.00,8.00,8.00,8.00,8.00,8.00,8.00"
					( Origin gBackEnd )
				)
				( attribute "HOLE_TO_HOLE_SPACING" "8.00,8.00,8.00,8.00,8.00,8.00,8.00,8.00,8.00,8.00,8.00,8.00,8.00,8.00"
					( Origin gBackEnd )
				)
				( attribute "MVIA_TO_MVIA_SPACING" "5.00,5.00,5.00,5.00,5.00,5.00,5.00,5.00,5.00,5.00,5.00,5.00,5.00,5.00"
					( Origin gBackEnd )
				)
				( attribute "MVIA_TO_THRUPIN_SPACING" "5.00,5.00,5.00,5.00,5.00,5.00,5.00,5.00,5.00,5.00,5.00,5.00,5.00,5.00"
					( Origin gBackEnd )
				)
				( attribute "MVIA_TO_SMDPIN_SPACING" "5.00,5.00,5.00,5.00,5.00,5.00,5.00,5.00,5.00,5.00,5.00,5.00,5.00,5.00"
					( Origin gBackEnd )
				)
				( attribute "MVIA_TO_THRUVIA_SPACING" "5.00,5.00,5.00,5.00,5.00,5.00,5.00,5.00,5.00,5.00,5.00,5.00,5.00,5.00"
					( Origin gBackEnd )
				)
				( attribute "MVIA_TO_BBV_SPACING" "5.00,5.00,5.00,5.00,5.00,5.00,5.00,5.00,5.00,5.00,5.00,5.00,5.00,5.00"
					( Origin gBackEnd )
				)
				( attribute "MVIA_TO_LINE_SPACING" "5.00,5.00,5.00,5.00,5.00,5.00,5.00,5.00,5.00,5.00,5.00,5.00,5.00,5.00"
					( Origin gBackEnd )
				)
				( attribute "MVIA_TO_SHAPE_SPACING" "5.00,5.00,5.00,5.00,5.00,5.00,5.00,5.00,5.00,5.00,5.00,5.00,5.00,5.00"
					( Origin gBackEnd )
				)
				( attribute "MVIA_TO_TESTPIN_SPACING" "5.00,5.00,5.00,5.00,5.00,5.00,5.00,5.00,5.00,5.00,5.00,5.00,5.00,5.00"
					( Origin gBackEnd )
				)
				( attribute "MVIA_TO_TESTVIA_SPACING" "5.00,5.00,5.00,5.00,5.00,5.00,5.00,5.00,5.00,5.00,5.00,5.00,5.00,5.00"
					( Origin gBackEnd )
				)
				( attribute "BONDPAD_TO_MVIA_SPACING" "5.00,5.00,5.00,5.00,5.00,5.00,5.00,5.00,5.00,5.00,5.00,5.00,5.00,5.00"
					( Origin gBackEnd )
				)
				( attribute "MIN_BVIA_GAP" "5.00"
					( Origin gBackEnd )
				)
				( attribute "BONDPAD_TO_BONDPAD_DIFFP_SPC" "5.00,5.00,5.00,5.00,5.00,5.00,5.00,5.00,5.00,5.00,5.00,5.00,5.00,5.00"
					( Origin gBackEnd )
				)
				( objectStatus "PCS_SNAIL_PF2" )
			)
			( spacingCSet "@crescent_city_bb_fab1_lib.crescent_city_bb_fab1(sch_1):\SNCLS_RMII_RX\"
				( attribute "THRUPIN_TO_THRUPIN_SPACING" "5.00,5.00,5.00,5.00,5.00,5.00,5.00,5.00,5.00,5.00,5.00,5.00,5.00,5.00"
					( Origin gBackEnd )
				)
				( attribute "THRUPIN_TO_SMDPIN_SPACING" "5.00,5.00,5.00,5.00,5.00,5.00,5.00,5.00,5.00,5.00,5.00,5.00,5.00,5.00"
					( Origin gBackEnd )
				)
				( attribute "TESTPIN_TO_THRUPIN_SPACING" "5.00,5.00,5.00,5.00,5.00,5.00,5.00,5.00,5.00,5.00,5.00,5.00,5.00,5.00"
					( Origin gBackEnd )
				)
				( attribute "THRUPIN_TO_THRUVIA_SPACING" "5.00,5.00,5.00,5.00,5.00,5.00,5.00,5.00,5.00,5.00,5.00,5.00,5.00,5.00"
					( Origin gBackEnd )
				)
				( attribute "TESTVIA_TO_THRUPIN_SPACING" "5.00,5.00,5.00,5.00,5.00,5.00,5.00,5.00,5.00,5.00,5.00,5.00,5.00,5.00"
					( Origin gBackEnd )
				)
				( attribute "BBV_TO_THRUPIN_SPACING" "5.00,5.00,5.00,5.00,5.00,5.00,5.00,5.00,5.00,5.00,5.00,5.00,5.00,5.00"
					( Origin gBackEnd )
				)
				( attribute "THRUPIN_TO_BONDPAD_SPACING" "5.00,5.00,5.00,5.00,5.00,5.00,5.00,5.00,5.00,5.00,5.00,5.00,5.00,5.00"
					( Origin gBackEnd )
				)
				( attribute "LINE_TO_THRUPIN_SPACING" "5.00,4.00,4.00,4.00,4.00,4.00,4.00,4.00,4.00,4.00,4.00,4.00,4.00,5.00"
					( Origin gBackEnd )
				)
				( attribute "THRUPIN_TO_SHAPE_SPACING" "5.00,5.00,5.00,5.00,5.00,5.00,5.00,5.00,5.00,5.00,5.00,5.00,5.00,5.00"
					( Origin gBackEnd )
				)
				( attribute "SMDPIN_TO_SMDPIN_SPACING" "5.00,5.00,5.00,5.00,5.00,5.00,5.00,5.00,5.00,5.00,5.00,5.00,5.00,5.00"
					( Origin gBackEnd )
				)
				( attribute "SMDPIN_TO_TESTPIN_SPACING" "5.00,5.00,5.00,5.00,5.00,5.00,5.00,5.00,5.00,5.00,5.00,5.00,5.00,25.00"
					( Origin gBackEnd )
				)
				( attribute "SMDPIN_TO_THRUVIA_SPACING" "5.00,5.00,5.00,5.00,5.00,5.00,5.00,5.00,5.00,5.00,5.00,5.00,5.00,5.00"
					( Origin gBackEnd )
				)
				( attribute "SMDPIN_TO_TESTVIA_SPACING" "5.00,5.00,5.00,5.00,5.00,5.00,5.00,5.00,5.00,5.00,5.00,5.00,5.00,5.00"
					( Origin gBackEnd )
				)
				( attribute "BBV_TO_SMDPIN_SPACING" "5.00,5.00,5.00,5.00,5.00,5.00,5.00,5.00,5.00,5.00,5.00,5.00,5.00,5.00"
					( Origin gBackEnd )
				)
				( attribute "SMDPIN_TO_BONDPAD_SPACING" "5.00,5.00,5.00,5.00,5.00,5.00,5.00,5.00,5.00,5.00,5.00,5.00,5.00,5.00"
					( Origin gBackEnd )
				)
				( attribute "LINE_TO_SMDPIN_SPACING" "4.50,4.50,4.50,4.50,4.50,4.50,4.50,4.50,4.50,4.50,4.50,4.50,4.50,4.50"
					( Origin gBackEnd )
				)
				( attribute "SHAPE_TO_SMDPIN_SPACING" "5.00,5.00,5.00,5.00,5.00,5.00,5.00,5.00,5.00,5.00,5.00,5.00,5.00,5.00"
					( Origin gBackEnd )
				)
				( attribute "TESTPIN_TO_TESTPIN_SPACING" "5.00,5.00,5.00,5.00,5.00,5.00,5.00,5.00,5.00,5.00,5.00,5.00,5.00,5.00"
					( Origin gBackEnd )
				)
				( attribute "TESTPIN_TO_THRUVIA_SPACING" "5.00,5.00,5.00,5.00,5.00,5.00,5.00,5.00,5.00,5.00,5.00,5.00,5.00,5.00"
					( Origin gBackEnd )
				)
				( attribute "TESTPIN_TO_TESTVIA_SPACING" "5.00,5.00,5.00,5.00,5.00,5.00,5.00,5.00,5.00,5.00,5.00,5.00,5.00,5.00"
					( Origin gBackEnd )
				)
				( attribute "BBV_TO_TESTPIN_SPACING" "5.00,5.00,5.00,5.00,5.00,5.00,5.00,5.00,5.00,5.00,5.00,5.00,5.00,5.00"
					( Origin gBackEnd )
				)
				( attribute "BONDPAD_TO_TESTPIN_SPACING" "5.00,5.00,5.00,5.00,5.00,5.00,5.00,5.00,5.00,5.00,5.00,5.00,5.00,5.00"
					( Origin gBackEnd )
				)
				( attribute "LINE_TO_TESTPIN_SPACING" "5.00,4.00,4.00,4.00,4.00,4.00,4.00,4.00,4.00,4.00,4.00,4.00,4.00,5.00"
					( Origin gBackEnd )
				)
				( attribute "SHAPE_TO_TESTPIN_SPACING" "5.00,5.00,5.00,5.00,5.00,5.00,5.00,5.00,5.00,5.00,5.00,5.00,5.00,5.00"
					( Origin gBackEnd )
				)
				( attribute "THRUVIA_TO_THRUVIA_SPACING" "5.00,5.00,5.00,5.00,5.00,5.00,5.00,5.00,5.00,5.00,5.00,5.00,5.00,5.00"
					( Origin gBackEnd )
				)
				( attribute "TESTVIA_TO_THRUVIA_SPACING" "6.00,6.00,6.00,6.00,6.00,6.00,6.00,6.00,6.00,6.00,6.00,6.00,6.00,6.00"
					( Origin gBackEnd )
				)
				( attribute "BBV_TO_THRUVIA_SPACING" "5.00,5.00,5.00,5.00,5.00,5.00,5.00,5.00,5.00,5.00,5.00,5.00,5.00,5.00"
					( Origin gBackEnd )
				)
				( attribute "BONDPAD_TO_THRUVIA_SPACING" "5.00,5.00,5.00,5.00,5.00,5.00,5.00,5.00,5.00,5.00,5.00,5.00,5.00,5.00"
					( Origin gBackEnd )
				)
				( attribute "LINE_TO_THRUVIA_SPACING" "4.50,4.00,4.00,4.00,4.00,4.00,4.00,4.00,4.00,4.00,4.00,4.00,4.00,4.50"
					( Origin gBackEnd )
				)
				( attribute "SHAPE_TO_THRUVIA_SPACING" "5.00,5.00,5.00,5.00,5.00,5.00,5.00,5.00,5.00,5.00,5.00,5.00,5.00,5.00"
					( Origin gBackEnd )
				)
				( attribute "TESTVIA_TO_TESTVIA_SPACING" "6.00,6.00,6.00,6.00,6.00,6.00,6.00,6.00,6.00,6.00,6.00,6.00,6.00,6.00"
					( Origin gBackEnd )
				)
				( attribute "BBV_TO_TESTVIA_SPACING" "5.00,5.00,5.00,5.00,5.00,5.00,5.00,5.00,5.00,5.00,5.00,5.00,5.00,5.00"
					( Origin gBackEnd )
				)
				( attribute "BONDPAD_TO_TESTVIA_SPACING" "5.00,5.00,5.00,5.00,5.00,5.00,5.00,5.00,5.00,5.00,5.00,5.00,5.00,5.00"
					( Origin gBackEnd )
				)
				( attribute "LINE_TO_TESTVIA_SPACING" "4.50,4.00,4.00,4.00,4.00,4.00,4.00,4.00,4.00,4.00,4.00,4.00,4.00,4.50"
					( Origin gBackEnd )
				)
				( attribute "SHAPE_TO_TESTVIA_SPACING" "5.00,5.00,5.00,5.00,5.00,5.00,5.00,5.00,5.00,5.00,5.00,5.00,5.00,5.00"
					( Origin gBackEnd )
				)
				( attribute "BBV_TO_BBV_SPACING" "5.00,5.00,5.00,5.00,5.00,5.00,5.00,5.00,5.00,5.00,5.00,5.00,5.00,5.00"
					( Origin gBackEnd )
				)
				( attribute "BONDPAD_TO_BBV_SPACING" "5.00,5.00,5.00,5.00,5.00,5.00,5.00,5.00,5.00,5.00,5.00,5.00,5.00,5.00"
					( Origin gBackEnd )
				)
				( attribute "BBV_TO_LINE_SPACING" "5.00,5.00,5.00,5.00,5.00,5.00,5.00,5.00,5.00,5.00,5.00,5.00,5.00,5.00"
					( Origin gBackEnd )
				)
				( attribute "BBV_TO_SHAPE_SPACING" "5.00,5.00,5.00,5.00,5.00,5.00,5.00,5.00,5.00,5.00,5.00,5.00,5.00,5.00"
					( Origin gBackEnd )
				)
				( attribute "BONDPAD_TO_BONDPAD_SPACING" "5.00,5.00,5.00,5.00,5.00,5.00,5.00,5.00,5.00,5.00,5.00,5.00,5.00,5.00"
					( Origin gBackEnd )
				)
				( attribute "BONDPAD_TO_LINE_SPACING" "5.00,5.00,5.00,5.00,5.00,5.00,5.00,5.00,5.00,5.00,5.00,5.00,5.00,5.00"
					( Origin gBackEnd )
				)
				( attribute "BONDPAD_TO_SHAPE_SPACING" "5.00,5.00,5.00,5.00,5.00,5.00,5.00,5.00,5.00,5.00,5.00,5.00,5.00,5.00"
					( Origin gBackEnd )
				)
				( attribute "LINE_TO_LINE_SPACING" "15.00,13.00,13.00,13.00,13.00,13.00,13.00,13.00,13.00,13.00,13.00,13.00,13.00,15.00"
					( Origin gBackEnd )
				)
				( attribute "LINE_TO_SHAPE_SPACING" "10.00,10.00,10.00,10.00,10.00,10.00,10.00,10.00,10.00,10.00,10.00,10.00,10.00,10.00"
					( Origin gBackEnd )
				)
				( attribute "SHAPE_TO_SHAPE_SPACING" "10.00,10.00,10.00,10.00,10.00,10.00,10.00,10.00,10.00,10.00,10.00,10.00,10.00,10.00"
					( Origin gBackEnd )
				)
				( attribute "HOLE_TO_PIN_SPACING" "8.00,8.00,8.00,8.00,8.00,8.00,8.00,8.00,8.00,8.00,8.00,8.00,8.00,8.00"
					( Origin gBackEnd )
				)
				( attribute "HOLE_TO_VIA_SPACING" "8.00,8.00,8.00,8.00,8.00,8.00,8.00,8.00,8.00,8.00,8.00,8.00,8.00,8.00"
					( Origin gBackEnd )
				)
				( attribute "HOLE_TO_LINE_SPACING" "8.00,8.00,8.00,8.00,8.00,8.00,8.00,8.00,8.00,8.00,8.00,8.00,8.00,8.00"
					( Origin gBackEnd )
				)
				( attribute "HOLE_TO_SHAPE_SPACING" "8.00,8.00,8.00,8.00,8.00,8.00,8.00,8.00,8.00,8.00,8.00,8.00,8.00,8.00"
					( Origin gBackEnd )
				)
				( attribute "HOLE_TO_HOLE_SPACING" "8.00,8.00,8.00,8.00,8.00,8.00,8.00,8.00,8.00,8.00,8.00,8.00,8.00,8.00"
					( Origin gBackEnd )
				)
				( attribute "MVIA_TO_MVIA_SPACING" "5.00,5.00,5.00,5.00,5.00,5.00,5.00,5.00,5.00,5.00,5.00,5.00,5.00,5.00"
					( Origin gBackEnd )
				)
				( attribute "MVIA_TO_THRUPIN_SPACING" "5.00,5.00,5.00,5.00,5.00,5.00,5.00,5.00,5.00,5.00,5.00,5.00,5.00,5.00"
					( Origin gBackEnd )
				)
				( attribute "MVIA_TO_SMDPIN_SPACING" "5.00,5.00,5.00,5.00,5.00,5.00,5.00,5.00,5.00,5.00,5.00,5.00,5.00,5.00"
					( Origin gBackEnd )
				)
				( attribute "MVIA_TO_THRUVIA_SPACING" "5.00,5.00,5.00,5.00,5.00,5.00,5.00,5.00,5.00,5.00,5.00,5.00,5.00,5.00"
					( Origin gBackEnd )
				)
				( attribute "MVIA_TO_BBV_SPACING" "5.00,5.00,5.00,5.00,5.00,5.00,5.00,5.00,5.00,5.00,5.00,5.00,5.00,5.00"
					( Origin gBackEnd )
				)
				( attribute "MVIA_TO_LINE_SPACING" "5.00,5.00,5.00,5.00,5.00,5.00,5.00,5.00,5.00,5.00,5.00,5.00,5.00,5.00"
					( Origin gBackEnd )
				)
				( attribute "MVIA_TO_SHAPE_SPACING" "5.00,5.00,5.00,5.00,5.00,5.00,5.00,5.00,5.00,5.00,5.00,5.00,5.00,5.00"
					( Origin gBackEnd )
				)
				( attribute "MVIA_TO_TESTPIN_SPACING" "5.00,5.00,5.00,5.00,5.00,5.00,5.00,5.00,5.00,5.00,5.00,5.00,5.00,5.00"
					( Origin gBackEnd )
				)
				( attribute "MVIA_TO_TESTVIA_SPACING" "5.00,5.00,5.00,5.00,5.00,5.00,5.00,5.00,5.00,5.00,5.00,5.00,5.00,5.00"
					( Origin gBackEnd )
				)
				( attribute "BONDPAD_TO_MVIA_SPACING" "5.00,5.00,5.00,5.00,5.00,5.00,5.00,5.00,5.00,5.00,5.00,5.00,5.00,5.00"
					( Origin gBackEnd )
				)
				( attribute "MIN_BVIA_GAP" "5.00"
					( Origin gBackEnd )
				)
				( attribute "BONDPAD_TO_BONDPAD_DIFFP_SPC" "5.00,5.00,5.00,5.00,5.00,5.00,5.00,5.00,5.00,5.00,5.00,5.00,5.00,5.00"
					( Origin gBackEnd )
				)
				( objectStatus "PCS_RMII_RX" )
			)
			( spacingCSet "@crescent_city_bb_fab1_lib.crescent_city_bb_fab1(sch_1):\6H_US_&_3H_SL_VIA_3H+A\"
				( attribute "THRUPIN_TO_THRUPIN_SPACING" "5.00,5.00,5.00,5.00,5.00,5.00,5.00,5.00,5.00,5.00,5.00,5.00,5.00,5.00"
					( Origin gBackEnd )
				)
				( attribute "THRUPIN_TO_SMDPIN_SPACING" "5.00,5.00,5.00,5.00,5.00,5.00,5.00,5.00,5.00,5.00,5.00,5.00,5.00,5.00"
					( Origin gBackEnd )
				)
				( attribute "TESTPIN_TO_THRUPIN_SPACING" "5.00,5.00,5.00,5.00,5.00,5.00,5.00,5.00,5.00,5.00,5.00,5.00,5.00,5.00"
					( Origin gBackEnd )
				)
				( attribute "THRUPIN_TO_THRUVIA_SPACING" "5.00,5.00,5.00,5.00,5.00,5.00,5.00,5.00,5.00,5.00,5.00,5.00,5.00,5.00"
					( Origin gBackEnd )
				)
				( attribute "TESTVIA_TO_THRUPIN_SPACING" "5.00,5.00,5.00,5.00,5.00,5.00,5.00,5.00,5.00,5.00,5.00,5.00,5.00,5.00"
					( Origin gBackEnd )
				)
				( attribute "BBV_TO_THRUPIN_SPACING" "5.00,5.00,5.00,5.00,5.00,5.00,5.00,5.00,5.00,5.00,5.00,5.00,5.00,5.00"
					( Origin gBackEnd )
				)
				( attribute "THRUPIN_TO_BONDPAD_SPACING" "5.00,5.00,5.00,5.00,5.00,5.00,5.00,5.00,5.00,5.00,5.00,5.00,5.00,5.00"
					( Origin gBackEnd )
				)
				( attribute "LINE_TO_THRUPIN_SPACING" "4.50,4.00,4.00,4.00,4.00,4.00,4.00,4.00,4.00,4.00,4.00,4.00,4.00,4.50"
					( Origin gBackEnd )
				)
				( attribute "THRUPIN_TO_SHAPE_SPACING" "5.00,5.00,5.00,5.00,5.00,5.00,5.00,5.00,5.00,5.00,5.00,5.00,5.00,5.00"
					( Origin gBackEnd )
				)
				( attribute "SMDPIN_TO_SMDPIN_SPACING" "5.00,5.00,5.00,5.00,5.00,5.00,5.00,5.00,5.00,5.00,5.00,5.00,5.00,5.00"
					( Origin gBackEnd )
				)
				( attribute "SMDPIN_TO_TESTPIN_SPACING" "5.00,5.00,5.00,5.00,5.00,5.00,5.00,5.00,5.00,5.00,5.00,5.00,5.00,25.00"
					( Origin gBackEnd )
				)
				( attribute "SMDPIN_TO_THRUVIA_SPACING" "5.00,5.00,5.00,5.00,5.00,5.00,5.00,5.00,5.00,5.00,5.00,5.00,5.00,5.00"
					( Origin gBackEnd )
				)
				( attribute "SMDPIN_TO_TESTVIA_SPACING" "5.00,5.00,5.00,5.00,5.00,5.00,5.00,5.00,5.00,5.00,5.00,5.00,5.00,5.00"
					( Origin gBackEnd )
				)
				( attribute "BBV_TO_SMDPIN_SPACING" "5.00,5.00,5.00,5.00,5.00,5.00,5.00,5.00,5.00,5.00,5.00,5.00,5.00,5.00"
					( Origin gBackEnd )
				)
				( attribute "SMDPIN_TO_BONDPAD_SPACING" "5.00,5.00,5.00,5.00,5.00,5.00,5.00,5.00,5.00,5.00,5.00,5.00,5.00,5.00"
					( Origin gBackEnd )
				)
				( attribute "LINE_TO_SMDPIN_SPACING" "4.50,4.50,4.50,4.50,4.50,4.50,4.50,4.50,4.50,4.50,4.50,4.50,4.50,4.50"
					( Origin gBackEnd )
				)
				( attribute "SHAPE_TO_SMDPIN_SPACING" "5.00,5.00,5.00,5.00,5.00,5.00,5.00,5.00,5.00,5.00,5.00,5.00,5.00,5.00"
					( Origin gBackEnd )
				)
				( attribute "TESTPIN_TO_TESTPIN_SPACING" "5.00,5.00,5.00,5.00,5.00,5.00,5.00,5.00,5.00,5.00,5.00,5.00,5.00,5.00"
					( Origin gBackEnd )
				)
				( attribute "TESTPIN_TO_THRUVIA_SPACING" "5.00,5.00,5.00,5.00,5.00,5.00,5.00,5.00,5.00,5.00,5.00,5.00,5.00,5.00"
					( Origin gBackEnd )
				)
				( attribute "TESTPIN_TO_TESTVIA_SPACING" "5.00,5.00,5.00,5.00,5.00,5.00,5.00,5.00,5.00,5.00,5.00,5.00,5.00,5.00"
					( Origin gBackEnd )
				)
				( attribute "BBV_TO_TESTPIN_SPACING" "5.00,5.00,5.00,5.00,5.00,5.00,5.00,5.00,5.00,5.00,5.00,5.00,5.00,5.00"
					( Origin gBackEnd )
				)
				( attribute "BONDPAD_TO_TESTPIN_SPACING" "5.00,5.00,5.00,5.00,5.00,5.00,5.00,5.00,5.00,5.00,5.00,5.00,5.00,5.00"
					( Origin gBackEnd )
				)
				( attribute "LINE_TO_TESTPIN_SPACING" "5.00,5.00,5.00,5.00,5.00,5.00,5.00,5.00,5.00,5.00,5.00,5.00,5.00,5.00"
					( Origin gBackEnd )
				)
				( attribute "SHAPE_TO_TESTPIN_SPACING" "5.00,5.00,5.00,5.00,5.00,5.00,5.00,5.00,5.00,5.00,5.00,5.00,5.00,5.00"
					( Origin gBackEnd )
				)
				( attribute "THRUVIA_TO_THRUVIA_SPACING" "6.00,6.00,6.00,6.00,6.00,6.00,6.00,6.00,6.00,6.00,6.00,6.00,6.00,6.00"
					( Origin gBackEnd )
				)
				( attribute "TESTVIA_TO_THRUVIA_SPACING" "6.00,6.00,6.00,6.00,6.00,6.00,6.00,6.00,6.00,6.00,6.00,6.00,6.00,6.00"
					( Origin gBackEnd )
				)
				( attribute "BBV_TO_THRUVIA_SPACING" "5.00,5.00,5.00,5.00,5.00,5.00,5.00,5.00,5.00,5.00,5.00,5.00,5.00,5.00"
					( Origin gBackEnd )
				)
				( attribute "BONDPAD_TO_THRUVIA_SPACING" "5.00,5.00,5.00,5.00,5.00,5.00,5.00,5.00,5.00,5.00,5.00,5.00,5.00,5.00"
					( Origin gBackEnd )
				)
				( attribute "LINE_TO_THRUVIA_SPACING" "12.00,5.00,13.00,5.00,13.00,5.00,5.00,5.00,5.00,13.00,5.00,13.00,5.00,12.00"
					( Origin gBackEnd )
				)
				( attribute "SHAPE_TO_THRUVIA_SPACING" "5.00,5.00,5.00,5.00,5.00,5.00,5.00,5.00,5.00,5.00,5.00,5.00,5.00,5.00"
					( Origin gBackEnd )
				)
				( attribute "TESTVIA_TO_TESTVIA_SPACING" "6.00,6.00,6.00,6.00,6.00,6.00,6.00,6.00,6.00,6.00,6.00,6.00,6.00,6.00"
					( Origin gBackEnd )
				)
				( attribute "BBV_TO_TESTVIA_SPACING" "5.00,5.00,5.00,5.00,5.00,5.00,5.00,5.00,5.00,5.00,5.00,5.00,5.00,5.00"
					( Origin gBackEnd )
				)
				( attribute "BONDPAD_TO_TESTVIA_SPACING" "5.00,5.00,5.00,5.00,5.00,5.00,5.00,5.00,5.00,5.00,5.00,5.00,5.00,5.00"
					( Origin gBackEnd )
				)
				( attribute "LINE_TO_TESTVIA_SPACING" "12.00,5.00,13.00,5.00,13.00,5.00,5.00,5.00,5.00,13.00,5.00,13.00,5.00,12.00"
					( Origin gBackEnd )
				)
				( attribute "SHAPE_TO_TESTVIA_SPACING" "5.00,5.00,5.00,5.00,5.00,5.00,5.00,5.00,5.00,5.00,5.00,5.00,5.00,5.00"
					( Origin gBackEnd )
				)
				( attribute "BBV_TO_BBV_SPACING" "5.00,5.00,5.00,5.00,5.00,5.00,5.00,5.00,5.00,5.00,5.00,5.00,5.00,5.00"
					( Origin gBackEnd )
				)
				( attribute "BONDPAD_TO_BBV_SPACING" "5.00,5.00,5.00,5.00,5.00,5.00,5.00,5.00,5.00,5.00,5.00,5.00,5.00,5.00"
					( Origin gBackEnd )
				)
				( attribute "BBV_TO_LINE_SPACING" "5.00,5.00,5.00,5.00,5.00,5.00,5.00,5.00,5.00,5.00,5.00,5.00,5.00,5.00"
					( Origin gBackEnd )
				)
				( attribute "BBV_TO_SHAPE_SPACING" "5.00,5.00,5.00,5.00,5.00,5.00,5.00,5.00,5.00,5.00,5.00,5.00,5.00,5.00"
					( Origin gBackEnd )
				)
				( attribute "BONDPAD_TO_BONDPAD_SPACING" "5.00,5.00,5.00,5.00,5.00,5.00,5.00,5.00,5.00,5.00,5.00,5.00,5.00,5.00"
					( Origin gBackEnd )
				)
				( attribute "BONDPAD_TO_LINE_SPACING" "5.00,5.00,5.00,5.00,5.00,5.00,5.00,5.00,5.00,5.00,5.00,5.00,5.00,5.00"
					( Origin gBackEnd )
				)
				( attribute "BONDPAD_TO_SHAPE_SPACING" "5.00,5.00,5.00,5.00,5.00,5.00,5.00,5.00,5.00,5.00,5.00,5.00,5.00,5.00"
					( Origin gBackEnd )
				)
				( attribute "LINE_TO_LINE_SPACING" "16.02,9.00,9.00,9.00,9.00,9.00,9.00,9.00,9.00,9.00,9.00,9.00,9.00,16.02"
					( Origin gBackEnd )
				)
				( attribute "LINE_TO_SHAPE_SPACING" "5.00,5.00,5.00,5.00,5.00,5.00,5.00,5.00,5.00,5.00,5.00,5.00,5.00,5.00"
					( Origin gBackEnd )
				)
				( attribute "SHAPE_TO_SHAPE_SPACING" "10.00,10.00,10.00,10.00,10.00,10.00,10.00,10.00,10.00,10.00,10.00,10.00,10.00,10.00"
					( Origin gBackEnd )
				)
				( attribute "HOLE_TO_PIN_SPACING" "8.00,8.00,8.00,8.00,8.00,8.00,8.00,8.00,8.00,8.00,8.00,8.00,8.00,8.00"
					( Origin gBackEnd )
				)
				( attribute "HOLE_TO_VIA_SPACING" "8.00,8.00,8.00,8.00,8.00,8.00,8.00,8.00,8.00,8.00,8.00,8.00,8.00,8.00"
					( Origin gBackEnd )
				)
				( attribute "HOLE_TO_LINE_SPACING" "8.00,8.00,8.00,8.00,8.00,8.00,8.00,8.00,8.00,8.00,8.00,8.00,8.00,8.00"
					( Origin gBackEnd )
				)
				( attribute "HOLE_TO_SHAPE_SPACING" "8.00,8.00,8.00,8.00,8.00,8.00,8.00,8.00,8.00,8.00,8.00,8.00,8.00,8.00"
					( Origin gBackEnd )
				)
				( attribute "HOLE_TO_HOLE_SPACING" "8.00,8.00,8.00,8.00,8.00,8.00,8.00,8.00,8.00,8.00,8.00,8.00,8.00,8.00"
					( Origin gBackEnd )
				)
				( attribute "MVIA_TO_MVIA_SPACING" "5.00,5.00,5.00,5.00,5.00,5.00,5.00,5.00,5.00,5.00,5.00,5.00,5.00,5.00"
					( Origin gBackEnd )
				)
				( attribute "MVIA_TO_THRUPIN_SPACING" "5.00,5.00,5.00,5.00,5.00,5.00,5.00,5.00,5.00,5.00,5.00,5.00,5.00,5.00"
					( Origin gBackEnd )
				)
				( attribute "MVIA_TO_SMDPIN_SPACING" "5.00,5.00,5.00,5.00,5.00,5.00,5.00,5.00,5.00,5.00,5.00,5.00,5.00,5.00"
					( Origin gBackEnd )
				)
				( attribute "MVIA_TO_THRUVIA_SPACING" "5.00,5.00,5.00,5.00,5.00,5.00,5.00,5.00,5.00,5.00,5.00,5.00,5.00,5.00"
					( Origin gBackEnd )
				)
				( attribute "MVIA_TO_BBV_SPACING" "5.00,5.00,5.00,5.00,5.00,5.00,5.00,5.00,5.00,5.00,5.00,5.00,5.00,5.00"
					( Origin gBackEnd )
				)
				( attribute "MVIA_TO_LINE_SPACING" "5.00,5.00,5.00,5.00,5.00,5.00,5.00,5.00,5.00,5.00,5.00,5.00,5.00,5.00"
					( Origin gBackEnd )
				)
				( attribute "MVIA_TO_SHAPE_SPACING" "5.00,5.00,5.00,5.00,5.00,5.00,5.00,5.00,5.00,5.00,5.00,5.00,5.00,5.00"
					( Origin gBackEnd )
				)
				( attribute "MVIA_TO_TESTPIN_SPACING" "5.00,5.00,5.00,5.00,5.00,5.00,5.00,5.00,5.00,5.00,5.00,5.00,5.00,5.00"
					( Origin gBackEnd )
				)
				( attribute "MVIA_TO_TESTVIA_SPACING" "5.00,5.00,5.00,5.00,5.00,5.00,5.00,5.00,5.00,5.00,5.00,5.00,5.00,5.00"
					( Origin gBackEnd )
				)
				( attribute "BONDPAD_TO_MVIA_SPACING" "5.00,5.00,5.00,5.00,5.00,5.00,5.00,5.00,5.00,5.00,5.00,5.00,5.00,5.00"
					( Origin gBackEnd )
				)
				( attribute "MIN_BVIA_GAP" "5.00"
					( Origin gBackEnd )
				)
				( attribute "BONDPAD_TO_BONDPAD_DIFFP_SPC" "5.00,5.00,5.00,5.00,5.00,5.00,5.00,5.00,5.00,5.00,5.00,5.00,5.00,5.00"
					( Origin gBackEnd )
				)
				( objectStatus "6H_US_&_3H_SL_VIA_3H+A" )
			)
			( spacingCSet "@crescent_city_bb_fab1_lib.crescent_city_bb_fab1(sch_1):\11H_US_&_2H_SL_VIA_3H+A\"
				( attribute "THRUPIN_TO_THRUPIN_SPACING" "5.00,5.00,5.00,5.00,5.00,5.00,5.00,5.00,5.00,5.00,5.00,5.00,5.00,5.00"
					( Origin gBackEnd )
				)
				( attribute "THRUPIN_TO_SMDPIN_SPACING" "5.00,5.00,5.00,5.00,5.00,5.00,5.00,5.00,5.00,5.00,5.00,5.00,5.00,5.00"
					( Origin gBackEnd )
				)
				( attribute "TESTPIN_TO_THRUPIN_SPACING" "5.00,5.00,5.00,5.00,5.00,5.00,5.00,5.00,5.00,5.00,5.00,5.00,5.00,5.00"
					( Origin gBackEnd )
				)
				( attribute "THRUPIN_TO_THRUVIA_SPACING" "5.00,5.00,5.00,5.00,5.00,5.00,5.00,5.00,5.00,5.00,5.00,5.00,5.00,5.00"
					( Origin gBackEnd )
				)
				( attribute "TESTVIA_TO_THRUPIN_SPACING" "5.00,5.00,5.00,5.00,5.00,5.00,5.00,5.00,5.00,5.00,5.00,5.00,5.00,5.00"
					( Origin gBackEnd )
				)
				( attribute "BBV_TO_THRUPIN_SPACING" "5.00,5.00,5.00,5.00,5.00,5.00,5.00,5.00,5.00,5.00,5.00,5.00,5.00,5.00"
					( Origin gBackEnd )
				)
				( attribute "THRUPIN_TO_BONDPAD_SPACING" "5.00,5.00,5.00,5.00,5.00,5.00,5.00,5.00,5.00,5.00,5.00,5.00,5.00,5.00"
					( Origin gBackEnd )
				)
				( attribute "LINE_TO_THRUPIN_SPACING" "4.50,4.00,4.00,4.00,4.00,4.00,4.00,4.00,4.00,4.00,4.00,4.00,4.00,4.50"
					( Origin gBackEnd )
				)
				( attribute "THRUPIN_TO_SHAPE_SPACING" "4.50,4.00,4.00,4.00,4.00,4.00,4.00,4.00,4.00,4.00,4.00,4.00,4.00,4.00"
					( Origin gBackEnd )
				)
				( attribute "SMDPIN_TO_SMDPIN_SPACING" "5.00,5.00,5.00,5.00,5.00,5.00,5.00,5.00,5.00,5.00,5.00,5.00,5.00,5.00"
					( Origin gBackEnd )
				)
				( attribute "SMDPIN_TO_TESTPIN_SPACING" "5.00,5.00,5.00,5.00,5.00,5.00,5.00,5.00,5.00,5.00,5.00,5.00,5.00,5.00"
					( Origin gBackEnd )
				)
				( attribute "SMDPIN_TO_THRUVIA_SPACING" "5.00,5.00,5.00,5.00,5.00,5.00,5.00,5.00,5.00,5.00,5.00,5.00,5.00,5.00"
					( Origin gBackEnd )
				)
				( attribute "SMDPIN_TO_TESTVIA_SPACING" "5.00,5.00,5.00,5.00,5.00,5.00,5.00,5.00,5.00,5.00,5.00,5.00,5.00,5.00"
					( Origin gBackEnd )
				)
				( attribute "BBV_TO_SMDPIN_SPACING" "5.00,5.00,5.00,5.00,5.00,5.00,5.00,5.00,5.00,5.00,5.00,5.00,5.00,5.00"
					( Origin gBackEnd )
				)
				( attribute "SMDPIN_TO_BONDPAD_SPACING" "5.00,5.00,5.00,5.00,5.00,5.00,5.00,5.00,5.00,5.00,5.00,5.00,5.00,5.00"
					( Origin gBackEnd )
				)
				( attribute "LINE_TO_SMDPIN_SPACING" "4.50,4.50,4.50,4.50,4.50,4.50,4.50,4.50,4.50,4.50,4.50,4.50,4.50,4.50"
					( Origin gBackEnd )
				)
				( attribute "SHAPE_TO_SMDPIN_SPACING" "5.00,5.00,5.00,5.00,5.00,5.00,5.00,5.00,5.00,5.00,5.00,5.00,5.00,5.00"
					( Origin gBackEnd )
				)
				( attribute "TESTPIN_TO_TESTPIN_SPACING" "5.00,5.00,5.00,5.00,5.00,5.00,5.00,5.00,5.00,5.00,5.00,5.00,5.00,5.00"
					( Origin gBackEnd )
				)
				( attribute "TESTPIN_TO_THRUVIA_SPACING" "5.00,5.00,5.00,5.00,5.00,5.00,5.00,5.00,5.00,5.00,5.00,5.00,5.00,5.00"
					( Origin gBackEnd )
				)
				( attribute "TESTPIN_TO_TESTVIA_SPACING" "5.00,5.00,5.00,5.00,5.00,5.00,5.00,5.00,5.00,5.00,5.00,5.00,5.00,5.00"
					( Origin gBackEnd )
				)
				( attribute "BBV_TO_TESTPIN_SPACING" "5.00,5.00,5.00,5.00,5.00,5.00,5.00,5.00,5.00,5.00,5.00,5.00,5.00,5.00"
					( Origin gBackEnd )
				)
				( attribute "BONDPAD_TO_TESTPIN_SPACING" "5.00,5.00,5.00,5.00,5.00,5.00,5.00,5.00,5.00,5.00,5.00,5.00,5.00,5.00"
					( Origin gBackEnd )
				)
				( attribute "LINE_TO_TESTPIN_SPACING" "4.50,5.00,5.00,5.00,5.00,5.00,5.00,5.00,5.00,5.00,5.00,5.00,5.00,5.00"
					( Origin gBackEnd )
				)
				( attribute "SHAPE_TO_TESTPIN_SPACING" "4.50,4.00,4.00,4.00,4.00,4.00,4.00,4.00,4.00,4.00,4.00,4.00,4.00,4.00"
					( Origin gBackEnd )
				)
				( attribute "THRUVIA_TO_THRUVIA_SPACING" "5.00,5.00,5.00,5.00,5.00,5.00,5.00,5.00,5.00,5.00,5.00,5.00,5.00,5.00"
					( Origin gBackEnd )
				)
				( attribute "TESTVIA_TO_THRUVIA_SPACING" "5.00,5.00,5.00,5.00,5.00,5.00,5.00,5.00,5.00,5.00,5.00,5.00,5.00,5.00"
					( Origin gBackEnd )
				)
				( attribute "BBV_TO_THRUVIA_SPACING" "5.00,5.00,5.00,5.00,5.00,5.00,5.00,5.00,5.00,5.00,5.00,5.00,5.00,5.00"
					( Origin gBackEnd )
				)
				( attribute "BONDPAD_TO_THRUVIA_SPACING" "5.00,5.00,5.00,5.00,5.00,5.00,5.00,5.00,5.00,5.00,5.00,5.00,5.00,5.00"
					( Origin gBackEnd )
				)
				( attribute "LINE_TO_THRUVIA_SPACING" "12.00,5.00,13.00,5.00,13.00,5.00,5.00,5.00,5.00,13.00,5.00,13.00,5.00,12.00"
					( Origin gBackEnd )
				)
				( attribute "SHAPE_TO_THRUVIA_SPACING" "4.50,4.00,4.00,4.00,4.00,4.00,4.00,4.00,4.00,4.00,4.00,4.00,4.00,4.00"
					( Origin gBackEnd )
				)
				( attribute "TESTVIA_TO_TESTVIA_SPACING" "5.00,5.00,5.00,5.00,5.00,5.00,5.00,5.00,5.00,5.00,5.00,5.00,5.00,5.00"
					( Origin gBackEnd )
				)
				( attribute "BBV_TO_TESTVIA_SPACING" "5.00,5.00,5.00,5.00,5.00,5.00,5.00,5.00,5.00,5.00,5.00,5.00,5.00,5.00"
					( Origin gBackEnd )
				)
				( attribute "BONDPAD_TO_TESTVIA_SPACING" "5.00,5.00,5.00,5.00,5.00,5.00,5.00,5.00,5.00,5.00,5.00,5.00,5.00,5.00"
					( Origin gBackEnd )
				)
				( attribute "LINE_TO_TESTVIA_SPACING" "12.00,5.00,13.00,5.00,13.00,5.00,5.00,5.00,5.00,13.00,5.00,13.00,5.00,12.00"
					( Origin gBackEnd )
				)
				( attribute "SHAPE_TO_TESTVIA_SPACING" "4.50,4.00,4.00,4.00,4.00,4.00,4.00,4.00,4.00,4.00,4.00,4.00,4.00,4.00"
					( Origin gBackEnd )
				)
				( attribute "BBV_TO_BBV_SPACING" "5.00,5.00,5.00,5.00,5.00,5.00,5.00,5.00,5.00,5.00,5.00,5.00,5.00,5.00"
					( Origin gBackEnd )
				)
				( attribute "BONDPAD_TO_BBV_SPACING" "5.00,5.00,5.00,5.00,5.00,5.00,5.00,5.00,5.00,5.00,5.00,5.00,5.00,5.00"
					( Origin gBackEnd )
				)
				( attribute "BBV_TO_LINE_SPACING" "5.00,5.00,5.00,5.00,5.00,5.00,5.00,5.00,5.00,5.00,5.00,5.00,5.00,5.00"
					( Origin gBackEnd )
				)
				( attribute "BBV_TO_SHAPE_SPACING" "5.00,5.00,5.00,5.00,5.00,5.00,5.00,5.00,5.00,5.00,5.00,5.00,5.00,5.00"
					( Origin gBackEnd )
				)
				( attribute "BONDPAD_TO_BONDPAD_SPACING" "5.00,5.00,5.00,5.00,5.00,5.00,5.00,5.00,5.00,5.00,5.00,5.00,5.00,5.00"
					( Origin gBackEnd )
				)
				( attribute "BONDPAD_TO_LINE_SPACING" "5.00,5.00,5.00,5.00,5.00,5.00,5.00,5.00,5.00,5.00,5.00,5.00,5.00,5.00"
					( Origin gBackEnd )
				)
				( attribute "BONDPAD_TO_SHAPE_SPACING" "5.00,5.00,5.00,5.00,5.00,5.00,5.00,5.00,5.00,5.00,5.00,5.00,5.00,5.00"
					( Origin gBackEnd )
				)
				( attribute "LINE_TO_LINE_SPACING" "29.37,9.00,6.00,9.00,6.00,9.00,9.00,9.00,9.00,6.00,9.00,6.00,9.00,29.37"
					( Origin gBackEnd )
				)
				( attribute "LINE_TO_SHAPE_SPACING" "5.00,5.00,5.00,5.00,5.00,5.00,5.00,5.00,5.00,5.00,5.00,5.00,5.00,5.00"
					( Origin gBackEnd )
				)
				( attribute "SHAPE_TO_SHAPE_SPACING" "10.00,10.00,10.00,10.00,10.00,10.00,10.00,10.00,10.00,10.00,10.00,10.00,10.00,10.00"
					( Origin gBackEnd )
				)
				( attribute "HOLE_TO_PIN_SPACING" "8.00,8.00,8.00,8.00,8.00,8.00,8.00,8.00,8.00,8.00,8.00,8.00,8.00,8.00"
					( Origin gBackEnd )
				)
				( attribute "HOLE_TO_VIA_SPACING" "8.00,8.00,8.00,8.00,8.00,8.00,8.00,8.00,8.00,8.00,8.00,8.00,8.00,8.00"
					( Origin gBackEnd )
				)
				( attribute "HOLE_TO_LINE_SPACING" "8.00,8.00,8.00,8.00,8.00,8.00,8.00,8.00,8.00,8.00,8.00,8.00,8.00,8.00"
					( Origin gBackEnd )
				)
				( attribute "HOLE_TO_SHAPE_SPACING" "8.00,8.00,8.00,8.00,8.00,8.00,8.00,8.00,8.00,8.00,8.00,8.00,8.00,8.00"
					( Origin gBackEnd )
				)
				( attribute "HOLE_TO_HOLE_SPACING" "8.00,8.00,8.00,8.00,8.00,8.00,8.00,8.00,8.00,8.00,8.00,8.00,8.00,8.00"
					( Origin gBackEnd )
				)
				( attribute "MVIA_TO_MVIA_SPACING" "5.00,5.00,5.00,5.00,5.00,5.00,5.00,5.00,5.00,5.00,5.00,5.00,5.00,5.00"
					( Origin gBackEnd )
				)
				( attribute "MVIA_TO_THRUPIN_SPACING" "5.00,5.00,5.00,5.00,5.00,5.00,5.00,5.00,5.00,5.00,5.00,5.00,5.00,5.00"
					( Origin gBackEnd )
				)
				( attribute "MVIA_TO_SMDPIN_SPACING" "5.00,5.00,5.00,5.00,5.00,5.00,5.00,5.00,5.00,5.00,5.00,5.00,5.00,5.00"
					( Origin gBackEnd )
				)
				( attribute "MVIA_TO_THRUVIA_SPACING" "5.00,5.00,5.00,5.00,5.00,5.00,5.00,5.00,5.00,5.00,5.00,5.00,5.00,5.00"
					( Origin gBackEnd )
				)
				( attribute "MVIA_TO_BBV_SPACING" "5.00,5.00,5.00,5.00,5.00,5.00,5.00,5.00,5.00,5.00,5.00,5.00,5.00,5.00"
					( Origin gBackEnd )
				)
				( attribute "MVIA_TO_LINE_SPACING" "5.00,5.00,5.00,5.00,5.00,5.00,5.00,5.00,5.00,5.00,5.00,5.00,5.00,5.00"
					( Origin gBackEnd )
				)
				( attribute "MVIA_TO_SHAPE_SPACING" "5.00,5.00,5.00,5.00,5.00,5.00,5.00,5.00,5.00,5.00,5.00,5.00,5.00,5.00"
					( Origin gBackEnd )
				)
				( attribute "MVIA_TO_TESTPIN_SPACING" "5.00,5.00,5.00,5.00,5.00,5.00,5.00,5.00,5.00,5.00,5.00,5.00,5.00,5.00"
					( Origin gBackEnd )
				)
				( attribute "MVIA_TO_TESTVIA_SPACING" "5.00,5.00,5.00,5.00,5.00,5.00,5.00,5.00,5.00,5.00,5.00,5.00,5.00,5.00"
					( Origin gBackEnd )
				)
				( attribute "BONDPAD_TO_MVIA_SPACING" "5.00,5.00,5.00,5.00,5.00,5.00,5.00,5.00,5.00,5.00,5.00,5.00,5.00,5.00"
					( Origin gBackEnd )
				)
				( attribute "MIN_BVIA_GAP" "5.00"
					( Origin gBackEnd )
				)
				( attribute "BONDPAD_TO_BONDPAD_DIFFP_SPC" "5.00,5.00,5.00,5.00,5.00,5.00,5.00,5.00,5.00,5.00,5.00,5.00,5.00,5.00"
					( Origin gBackEnd )
				)
				( objectStatus "11H_US_&_2H_SL_VIA_3H+A" )
			)
			( spacingCSet "@crescent_city_bb_fab1_lib.crescent_city_bb_fab1(sch_1):\6_MILS\"
				( attribute "THRUPIN_TO_THRUPIN_SPACING" "5.00,5.00,5.00,5.00,5.00,5.00,5.00,5.00,5.00,5.00,5.00,5.00,5.00,5.00"
					( Origin gBackEnd )
				)
				( attribute "THRUPIN_TO_SMDPIN_SPACING" "5.00,5.00,5.00,5.00,5.00,5.00,5.00,5.00,5.00,5.00,5.00,5.00,5.00,5.00"
					( Origin gBackEnd )
				)
				( attribute "TESTPIN_TO_THRUPIN_SPACING" "5.00,5.00,5.00,5.00,5.00,5.00,5.00,5.00,5.00,5.00,5.00,5.00,5.00,5.00"
					( Origin gBackEnd )
				)
				( attribute "THRUPIN_TO_THRUVIA_SPACING" "5.00,5.00,5.00,5.00,5.00,5.00,5.00,5.00,5.00,5.00,5.00,5.00,5.00,5.00"
					( Origin gBackEnd )
				)
				( attribute "TESTVIA_TO_THRUPIN_SPACING" "5.00,5.00,5.00,5.00,5.00,5.00,5.00,5.00,5.00,5.00,5.00,5.00,5.00,5.00"
					( Origin gBackEnd )
				)
				( attribute "BBV_TO_THRUPIN_SPACING" "5.00,5.00,5.00,5.00,5.00,5.00,5.00,5.00,5.00,5.00,5.00,5.00,5.00,5.00"
					( Origin gBackEnd )
				)
				( attribute "THRUPIN_TO_BONDPAD_SPACING" "5.00,5.00,5.00,5.00,5.00,5.00,5.00,5.00,5.00,5.00,5.00,5.00,5.00,5.00"
					( Origin gBackEnd )
				)
				( attribute "LINE_TO_THRUPIN_SPACING" "4.50,4.00,4.00,4.00,4.00,4.00,4.00,4.00,4.00,4.00,4.00,4.00,4.00,4.50"
					( Origin gBackEnd )
				)
				( attribute "THRUPIN_TO_SHAPE_SPACING" "4.50,4.00,4.00,4.00,4.00,4.00,4.00,4.00,4.00,4.00,4.00,4.00,4.00,4.00"
					( Origin gBackEnd )
				)
				( attribute "SMDPIN_TO_SMDPIN_SPACING" "5.00,5.00,5.00,5.00,5.00,5.00,5.00,5.00,5.00,5.00,5.00,5.00,5.00,5.00"
					( Origin gBackEnd )
				)
				( attribute "SMDPIN_TO_TESTPIN_SPACING" "5.00,5.00,5.00,5.00,5.00,5.00,5.00,5.00,5.00,5.00,5.00,5.00,5.00,5.00"
					( Origin gBackEnd )
				)
				( attribute "SMDPIN_TO_THRUVIA_SPACING" "5.00,5.00,5.00,5.00,5.00,5.00,5.00,5.00,5.00,5.00,5.00,5.00,5.00,5.00"
					( Origin gBackEnd )
				)
				( attribute "SMDPIN_TO_TESTVIA_SPACING" "5.00,5.00,5.00,5.00,5.00,5.00,5.00,5.00,5.00,5.00,5.00,5.00,5.00,5.00"
					( Origin gBackEnd )
				)
				( attribute "BBV_TO_SMDPIN_SPACING" "5.00,5.00,5.00,5.00,5.00,5.00,5.00,5.00,5.00,5.00,5.00,5.00,5.00,5.00"
					( Origin gBackEnd )
				)
				( attribute "SMDPIN_TO_BONDPAD_SPACING" "5.00,5.00,5.00,5.00,5.00,5.00,5.00,5.00,5.00,5.00,5.00,5.00,5.00,5.00"
					( Origin gBackEnd )
				)
				( attribute "LINE_TO_SMDPIN_SPACING" "4.50,4.50,4.50,4.50,4.50,4.50,4.50,4.50,4.50,4.50,4.50,4.50,4.50,4.50"
					( Origin gBackEnd )
				)
				( attribute "SHAPE_TO_SMDPIN_SPACING" "5.00,5.00,5.00,5.00,5.00,5.00,5.00,5.00,5.00,5.00,5.00,5.00,5.00,5.00"
					( Origin gBackEnd )
				)
				( attribute "TESTPIN_TO_TESTPIN_SPACING" "5.00,5.00,5.00,5.00,5.00,5.00,5.00,5.00,5.00,5.00,5.00,5.00,5.00,5.00"
					( Origin gBackEnd )
				)
				( attribute "TESTPIN_TO_THRUVIA_SPACING" "5.00,5.00,5.00,5.00,5.00,5.00,5.00,5.00,5.00,5.00,5.00,5.00,5.00,5.00"
					( Origin gBackEnd )
				)
				( attribute "TESTPIN_TO_TESTVIA_SPACING" "5.00,5.00,5.00,5.00,5.00,5.00,5.00,5.00,5.00,5.00,5.00,5.00,5.00,5.00"
					( Origin gBackEnd )
				)
				( attribute "BBV_TO_TESTPIN_SPACING" "5.00,5.00,5.00,5.00,5.00,5.00,5.00,5.00,5.00,5.00,5.00,5.00,5.00,5.00"
					( Origin gBackEnd )
				)
				( attribute "BONDPAD_TO_TESTPIN_SPACING" "5.00,5.00,5.00,5.00,5.00,5.00,5.00,5.00,5.00,5.00,5.00,5.00,5.00,5.00"
					( Origin gBackEnd )
				)
				( attribute "LINE_TO_TESTPIN_SPACING" "4.50,5.00,5.00,5.00,5.00,5.00,5.00,5.00,5.00,5.00,5.00,5.00,5.00,5.00"
					( Origin gBackEnd )
				)
				( attribute "SHAPE_TO_TESTPIN_SPACING" "4.50,4.00,4.00,4.00,4.00,4.00,4.00,4.00,4.00,4.00,4.00,4.00,4.00,4.00"
					( Origin gBackEnd )
				)
				( attribute "THRUVIA_TO_THRUVIA_SPACING" "5.00,5.00,5.00,5.00,5.00,5.00,5.00,5.00,5.00,5.00,5.00,5.00,5.00,5.00"
					( Origin gBackEnd )
				)
				( attribute "TESTVIA_TO_THRUVIA_SPACING" "5.00,5.00,5.00,5.00,5.00,5.00,5.00,5.00,5.00,5.00,5.00,5.00,5.00,5.00"
					( Origin gBackEnd )
				)
				( attribute "BBV_TO_THRUVIA_SPACING" "5.00,5.00,5.00,5.00,5.00,5.00,5.00,5.00,5.00,5.00,5.00,5.00,5.00,5.00"
					( Origin gBackEnd )
				)
				( attribute "BONDPAD_TO_THRUVIA_SPACING" "5.00,5.00,5.00,5.00,5.00,5.00,5.00,5.00,5.00,5.00,5.00,5.00,5.00,5.00"
					( Origin gBackEnd )
				)
				( attribute "LINE_TO_THRUVIA_SPACING" "4.50,4.00,4.00,4.00,4.00,4.00,4.00,4.00,4.00,4.00,4.00,4.00,4.00,4.50"
					( Origin gBackEnd )
				)
				( attribute "SHAPE_TO_THRUVIA_SPACING" "4.50,4.00,4.00,4.00,4.00,4.00,4.00,4.00,4.00,4.00,4.00,4.00,4.00,4.00"
					( Origin gBackEnd )
				)
				( attribute "TESTVIA_TO_TESTVIA_SPACING" "5.00,5.00,5.00,5.00,5.00,5.00,5.00,5.00,5.00,5.00,5.00,5.00,5.00,5.00"
					( Origin gBackEnd )
				)
				( attribute "BBV_TO_TESTVIA_SPACING" "5.00,5.00,5.00,5.00,5.00,5.00,5.00,5.00,5.00,5.00,5.00,5.00,5.00,5.00"
					( Origin gBackEnd )
				)
				( attribute "BONDPAD_TO_TESTVIA_SPACING" "5.00,5.00,5.00,5.00,5.00,5.00,5.00,5.00,5.00,5.00,5.00,5.00,5.00,5.00"
					( Origin gBackEnd )
				)
				( attribute "LINE_TO_TESTVIA_SPACING" "4.50,5.00,4.00,5.00,4.00,5.00,5.00,5.00,5.00,4.00,5.00,4.00,5.00,4.50"
					( Origin gBackEnd )
				)
				( attribute "SHAPE_TO_TESTVIA_SPACING" "4.50,4.00,4.00,4.00,4.00,4.00,4.00,4.00,4.00,4.00,4.00,4.00,4.00,4.00"
					( Origin gBackEnd )
				)
				( attribute "BBV_TO_BBV_SPACING" "5.00,5.00,5.00,5.00,5.00,5.00,5.00,5.00,5.00,5.00,5.00,5.00,5.00,5.00"
					( Origin gBackEnd )
				)
				( attribute "BONDPAD_TO_BBV_SPACING" "5.00,5.00,5.00,5.00,5.00,5.00,5.00,5.00,5.00,5.00,5.00,5.00,5.00,5.00"
					( Origin gBackEnd )
				)
				( attribute "BBV_TO_LINE_SPACING" "5.00,5.00,5.00,5.00,5.00,5.00,5.00,5.00,5.00,5.00,5.00,5.00,5.00,5.00"
					( Origin gBackEnd )
				)
				( attribute "BBV_TO_SHAPE_SPACING" "5.00,5.00,5.00,5.00,5.00,5.00,5.00,5.00,5.00,5.00,5.00,5.00,5.00,5.00"
					( Origin gBackEnd )
				)
				( attribute "BONDPAD_TO_BONDPAD_SPACING" "5.00,5.00,5.00,5.00,5.00,5.00,5.00,5.00,5.00,5.00,5.00,5.00,5.00,5.00"
					( Origin gBackEnd )
				)
				( attribute "BONDPAD_TO_LINE_SPACING" "5.00,5.00,5.00,5.00,5.00,5.00,5.00,5.00,5.00,5.00,5.00,5.00,5.00,5.00"
					( Origin gBackEnd )
				)
				( attribute "BONDPAD_TO_SHAPE_SPACING" "5.00,5.00,5.00,5.00,5.00,5.00,5.00,5.00,5.00,5.00,5.00,5.00,5.00,5.00"
					( Origin gBackEnd )
				)
				( attribute "LINE_TO_LINE_SPACING" "6.00,6.00,6.00,6.00,6.00,6.00,6.00,6.00,6.00,6.00,6.00,6.00,6.00,6.00"
					( Origin gBackEnd )
				)
				( attribute "LINE_TO_SHAPE_SPACING" "5.00,5.00,5.00,5.00,5.00,5.00,5.00,5.00,5.00,5.00,5.00,5.00,5.00,5.00"
					( Origin gBackEnd )
				)
				( attribute "SHAPE_TO_SHAPE_SPACING" "10.00,10.00,10.00,10.00,10.00,10.00,10.00,10.00,10.00,10.00,10.00,10.00,10.00,10.00"
					( Origin gBackEnd )
				)
				( attribute "HOLE_TO_PIN_SPACING" "8.00,8.00,8.00,8.00,8.00,8.00,8.00,8.00,8.00,8.00,8.00,8.00,8.00,8.00"
					( Origin gBackEnd )
				)
				( attribute "HOLE_TO_VIA_SPACING" "8.00,8.00,8.00,8.00,8.00,8.00,8.00,8.00,8.00,8.00,8.00,8.00,8.00,8.00"
					( Origin gBackEnd )
				)
				( attribute "HOLE_TO_LINE_SPACING" "8.00,8.00,8.00,8.00,8.00,8.00,8.00,8.00,8.00,8.00,8.00,8.00,8.00,8.00"
					( Origin gBackEnd )
				)
				( attribute "HOLE_TO_SHAPE_SPACING" "8.00,8.00,8.00,8.00,8.00,8.00,8.00,8.00,8.00,8.00,8.00,8.00,8.00,8.00"
					( Origin gBackEnd )
				)
				( attribute "HOLE_TO_HOLE_SPACING" "8.00,8.00,8.00,8.00,8.00,8.00,8.00,8.00,8.00,8.00,8.00,8.00,8.00,8.00"
					( Origin gBackEnd )
				)
				( attribute "MVIA_TO_MVIA_SPACING" "5.00,5.00,5.00,5.00,5.00,5.00,5.00,5.00,5.00,5.00,5.00,5.00,5.00,5.00"
					( Origin gBackEnd )
				)
				( attribute "MVIA_TO_THRUPIN_SPACING" "5.00,5.00,5.00,5.00,5.00,5.00,5.00,5.00,5.00,5.00,5.00,5.00,5.00,5.00"
					( Origin gBackEnd )
				)
				( attribute "MVIA_TO_SMDPIN_SPACING" "5.00,5.00,5.00,5.00,5.00,5.00,5.00,5.00,5.00,5.00,5.00,5.00,5.00,5.00"
					( Origin gBackEnd )
				)
				( attribute "MVIA_TO_THRUVIA_SPACING" "5.00,5.00,5.00,5.00,5.00,5.00,5.00,5.00,5.00,5.00,5.00,5.00,5.00,5.00"
					( Origin gBackEnd )
				)
				( attribute "MVIA_TO_BBV_SPACING" "5.00,5.00,5.00,5.00,5.00,5.00,5.00,5.00,5.00,5.00,5.00,5.00,5.00,5.00"
					( Origin gBackEnd )
				)
				( attribute "MVIA_TO_LINE_SPACING" "5.00,5.00,5.00,5.00,5.00,5.00,5.00,5.00,5.00,5.00,5.00,5.00,5.00,5.00"
					( Origin gBackEnd )
				)
				( attribute "MVIA_TO_SHAPE_SPACING" "5.00,5.00,5.00,5.00,5.00,5.00,5.00,5.00,5.00,5.00,5.00,5.00,5.00,5.00"
					( Origin gBackEnd )
				)
				( attribute "MVIA_TO_TESTPIN_SPACING" "5.00,5.00,5.00,5.00,5.00,5.00,5.00,5.00,5.00,5.00,5.00,5.00,5.00,5.00"
					( Origin gBackEnd )
				)
				( attribute "MVIA_TO_TESTVIA_SPACING" "5.00,5.00,5.00,5.00,5.00,5.00,5.00,5.00,5.00,5.00,5.00,5.00,5.00,5.00"
					( Origin gBackEnd )
				)
				( attribute "BONDPAD_TO_MVIA_SPACING" "5.00,5.00,5.00,5.00,5.00,5.00,5.00,5.00,5.00,5.00,5.00,5.00,5.00,5.00"
					( Origin gBackEnd )
				)
				( attribute "MIN_BVIA_GAP" "5.00"
					( Origin gBackEnd )
				)
				( attribute "BONDPAD_TO_BONDPAD_DIFFP_SPC" "5.00,5.00,5.00,5.00,5.00,5.00,5.00,5.00,5.00,5.00,5.00,5.00,5.00,5.00"
					( Origin gBackEnd )
				)
				( objectStatus "6_MILS" )
			)
			( spacingCSet "@crescent_city_bb_fab1_lib.crescent_city_bb_fab1(sch_1):\15H_US_&_7H_SL\"
				( attribute "THRUPIN_TO_THRUPIN_SPACING" "5.00,5.00,5.00,5.00,5.00,5.00,5.00,5.00,5.00,5.00,5.00,5.00,5.00,5.00"
					( Origin gBackEnd )
				)
				( attribute "THRUPIN_TO_SMDPIN_SPACING" "5.00,5.00,5.00,5.00,5.00,5.00,5.00,5.00,5.00,5.00,5.00,5.00,5.00,5.00"
					( Origin gBackEnd )
				)
				( attribute "TESTPIN_TO_THRUPIN_SPACING" "5.00,5.00,5.00,5.00,5.00,5.00,5.00,5.00,5.00,5.00,5.00,5.00,5.00,5.00"
					( Origin gBackEnd )
				)
				( attribute "THRUPIN_TO_THRUVIA_SPACING" "5.00,5.00,5.00,5.00,5.00,5.00,5.00,5.00,5.00,5.00,5.00,5.00,5.00,5.00"
					( Origin gBackEnd )
				)
				( attribute "TESTVIA_TO_THRUPIN_SPACING" "5.00,5.00,5.00,5.00,5.00,5.00,5.00,5.00,5.00,5.00,5.00,5.00,5.00,5.00"
					( Origin gBackEnd )
				)
				( attribute "BBV_TO_THRUPIN_SPACING" "5.00,5.00,5.00,5.00,5.00,5.00,5.00,5.00,5.00,5.00,5.00,5.00,5.00,5.00"
					( Origin gBackEnd )
				)
				( attribute "THRUPIN_TO_BONDPAD_SPACING" "5.00,5.00,5.00,5.00,5.00,5.00,5.00,5.00,5.00,5.00,5.00,5.00,5.00,5.00"
					( Origin gBackEnd )
				)
				( attribute "LINE_TO_THRUPIN_SPACING" "4.50,4.00,4.00,4.00,4.00,4.00,4.00,4.00,4.00,4.00,4.00,4.00,4.00,4.50"
					( Origin gBackEnd )
				)
				( attribute "THRUPIN_TO_SHAPE_SPACING" "5.00,5.00,5.00,5.00,5.00,5.00,5.00,5.00,5.00,5.00,5.00,5.00,5.00,5.00"
					( Origin gBackEnd )
				)
				( attribute "SMDPIN_TO_SMDPIN_SPACING" "5.00,5.00,5.00,5.00,5.00,5.00,5.00,5.00,5.00,5.00,5.00,5.00,5.00,5.00"
					( Origin gBackEnd )
				)
				( attribute "SMDPIN_TO_TESTPIN_SPACING" "5.00,5.00,5.00,5.00,5.00,5.00,5.00,5.00,5.00,5.00,5.00,5.00,5.00,25.00"
					( Origin gBackEnd )
				)
				( attribute "SMDPIN_TO_THRUVIA_SPACING" "5.00,5.00,5.00,5.00,5.00,5.00,5.00,5.00,5.00,5.00,5.00,5.00,5.00,5.00"
					( Origin gBackEnd )
				)
				( attribute "SMDPIN_TO_TESTVIA_SPACING" "5.00,5.00,5.00,5.00,5.00,5.00,5.00,5.00,5.00,5.00,5.00,5.00,5.00,5.00"
					( Origin gBackEnd )
				)
				( attribute "BBV_TO_SMDPIN_SPACING" "5.00,5.00,5.00,5.00,5.00,5.00,5.00,5.00,5.00,5.00,5.00,5.00,5.00,5.00"
					( Origin gBackEnd )
				)
				( attribute "SMDPIN_TO_BONDPAD_SPACING" "5.00,5.00,5.00,5.00,5.00,5.00,5.00,5.00,5.00,5.00,5.00,5.00,5.00,5.00"
					( Origin gBackEnd )
				)
				( attribute "LINE_TO_SMDPIN_SPACING" "4.50,4.50,4.50,4.50,4.50,4.50,4.50,4.50,4.50,4.50,4.50,4.50,4.50,4.50"
					( Origin gBackEnd )
				)
				( attribute "SHAPE_TO_SMDPIN_SPACING" "5.00,5.00,5.00,5.00,5.00,5.00,5.00,5.00,5.00,5.00,5.00,5.00,5.00,5.00"
					( Origin gBackEnd )
				)
				( attribute "TESTPIN_TO_TESTPIN_SPACING" "5.00,5.00,5.00,5.00,5.00,5.00,5.00,5.00,5.00,5.00,5.00,5.00,5.00,5.00"
					( Origin gBackEnd )
				)
				( attribute "TESTPIN_TO_THRUVIA_SPACING" "5.00,5.00,5.00,5.00,5.00,5.00,5.00,5.00,5.00,5.00,5.00,5.00,5.00,5.00"
					( Origin gBackEnd )
				)
				( attribute "TESTPIN_TO_TESTVIA_SPACING" "5.00,5.00,5.00,5.00,5.00,5.00,5.00,5.00,5.00,5.00,5.00,5.00,5.00,5.00"
					( Origin gBackEnd )
				)
				( attribute "BBV_TO_TESTPIN_SPACING" "5.00,5.00,5.00,5.00,5.00,5.00,5.00,5.00,5.00,5.00,5.00,5.00,5.00,5.00"
					( Origin gBackEnd )
				)
				( attribute "BONDPAD_TO_TESTPIN_SPACING" "5.00,5.00,5.00,5.00,5.00,5.00,5.00,5.00,5.00,5.00,5.00,5.00,5.00,5.00"
					( Origin gBackEnd )
				)
				( attribute "LINE_TO_TESTPIN_SPACING" "5.00,4.00,4.00,4.00,4.00,4.00,4.00,4.00,4.00,4.00,4.00,4.00,4.00,5.00"
					( Origin gBackEnd )
				)
				( attribute "SHAPE_TO_TESTPIN_SPACING" "5.00,5.00,5.00,5.00,5.00,5.00,5.00,5.00,5.00,5.00,5.00,5.00,5.00,5.00"
					( Origin gBackEnd )
				)
				( attribute "THRUVIA_TO_THRUVIA_SPACING" "5.00,5.00,5.00,5.00,5.00,5.00,5.00,5.00,5.00,5.00,5.00,5.00,5.00,5.00"
					( Origin gBackEnd )
				)
				( attribute "TESTVIA_TO_THRUVIA_SPACING" "6.00,6.00,6.00,6.00,6.00,6.00,6.00,6.00,6.00,6.00,6.00,6.00,6.00,6.00"
					( Origin gBackEnd )
				)
				( attribute "BBV_TO_THRUVIA_SPACING" "5.00,5.00,5.00,5.00,5.00,5.00,5.00,5.00,5.00,5.00,5.00,5.00,5.00,5.00"
					( Origin gBackEnd )
				)
				( attribute "BONDPAD_TO_THRUVIA_SPACING" "5.00,5.00,5.00,5.00,5.00,5.00,5.00,5.00,5.00,5.00,5.00,5.00,5.00,5.00"
					( Origin gBackEnd )
				)
				( attribute "LINE_TO_THRUVIA_SPACING" "4.50,4.00,4.00,4.00,4.00,4.00,4.00,4.00,4.00,4.00,4.00,4.00,4.00,4.50"
					( Origin gBackEnd )
				)
				( attribute "SHAPE_TO_THRUVIA_SPACING" "5.00,5.00,5.00,5.00,5.00,5.00,5.00,5.00,5.00,5.00,5.00,5.00,5.00,5.00"
					( Origin gBackEnd )
				)
				( attribute "TESTVIA_TO_TESTVIA_SPACING" "6.00,6.00,6.00,6.00,6.00,6.00,6.00,6.00,6.00,6.00,6.00,6.00,6.00,6.00"
					( Origin gBackEnd )
				)
				( attribute "BBV_TO_TESTVIA_SPACING" "5.00,5.00,5.00,5.00,5.00,5.00,5.00,5.00,5.00,5.00,5.00,5.00,5.00,5.00"
					( Origin gBackEnd )
				)
				( attribute "BONDPAD_TO_TESTVIA_SPACING" "5.00,5.00,5.00,5.00,5.00,5.00,5.00,5.00,5.00,5.00,5.00,5.00,5.00,5.00"
					( Origin gBackEnd )
				)
				( attribute "LINE_TO_TESTVIA_SPACING" "4.50,4.00,4.00,4.00,4.00,4.00,4.00,4.00,4.00,4.00,4.00,4.00,4.00,4.50"
					( Origin gBackEnd )
				)
				( attribute "SHAPE_TO_TESTVIA_SPACING" "5.00,5.00,5.00,5.00,5.00,5.00,5.00,5.00,5.00,5.00,5.00,5.00,5.00,5.00"
					( Origin gBackEnd )
				)
				( attribute "BBV_TO_BBV_SPACING" "5.00,5.00,5.00,5.00,5.00,5.00,5.00,5.00,5.00,5.00,5.00,5.00,5.00,5.00"
					( Origin gBackEnd )
				)
				( attribute "BONDPAD_TO_BBV_SPACING" "5.00,5.00,5.00,5.00,5.00,5.00,5.00,5.00,5.00,5.00,5.00,5.00,5.00,5.00"
					( Origin gBackEnd )
				)
				( attribute "BBV_TO_LINE_SPACING" "5.00,5.00,5.00,5.00,5.00,5.00,5.00,5.00,5.00,5.00,5.00,5.00,5.00,5.00"
					( Origin gBackEnd )
				)
				( attribute "BBV_TO_SHAPE_SPACING" "5.00,5.00,5.00,5.00,5.00,5.00,5.00,5.00,5.00,5.00,5.00,5.00,5.00,5.00"
					( Origin gBackEnd )
				)
				( attribute "BONDPAD_TO_BONDPAD_SPACING" "5.00,5.00,5.00,5.00,5.00,5.00,5.00,5.00,5.00,5.00,5.00,5.00,5.00,5.00"
					( Origin gBackEnd )
				)
				( attribute "BONDPAD_TO_LINE_SPACING" "5.00,5.00,5.00,5.00,5.00,5.00,5.00,5.00,5.00,5.00,5.00,5.00,5.00,5.00"
					( Origin gBackEnd )
				)
				( attribute "BONDPAD_TO_SHAPE_SPACING" "5.00,5.00,5.00,5.00,5.00,5.00,5.00,5.00,5.00,5.00,5.00,5.00,5.00,5.00"
					( Origin gBackEnd )
				)
				( attribute "LINE_TO_LINE_SPACING" "40.50,21.00,21.00,21.00,21.00,21.00,21.00,21.00,21.00,21.00,21.00,21.00,21.00,40.50"
					( Origin gBackEnd )
				)
				( attribute "LINE_TO_SHAPE_SPACING" "10.00,10.00,10.00,10.00,10.00,10.00,10.00,10.00,10.00,10.00,10.00,10.00,10.00,10.00"
					( Origin gBackEnd )
				)
				( attribute "SHAPE_TO_SHAPE_SPACING" "10.00,10.00,10.00,10.00,10.00,10.00,10.00,10.00,10.00,10.00,10.00,10.00,10.00,10.00"
					( Origin gBackEnd )
				)
				( attribute "HOLE_TO_PIN_SPACING" "8.00,8.00,8.00,8.00,8.00,8.00,8.00,8.00,8.00,8.00,8.00,8.00,8.00,8.00"
					( Origin gBackEnd )
				)
				( attribute "HOLE_TO_VIA_SPACING" "8.00,8.00,8.00,8.00,8.00,8.00,8.00,8.00,8.00,8.00,8.00,8.00,8.00,8.00"
					( Origin gBackEnd )
				)
				( attribute "HOLE_TO_LINE_SPACING" "8.00,8.00,8.00,8.00,8.00,8.00,8.00,8.00,8.00,8.00,8.00,8.00,8.00,8.00"
					( Origin gBackEnd )
				)
				( attribute "HOLE_TO_SHAPE_SPACING" "8.00,8.00,8.00,8.00,8.00,8.00,8.00,8.00,8.00,8.00,8.00,8.00,8.00,8.00"
					( Origin gBackEnd )
				)
				( attribute "HOLE_TO_HOLE_SPACING" "8.00,8.00,8.00,8.00,8.00,8.00,8.00,8.00,8.00,8.00,8.00,8.00,8.00,8.00"
					( Origin gBackEnd )
				)
				( attribute "MVIA_TO_MVIA_SPACING" "5.00,5.00,5.00,5.00,5.00,5.00,5.00,5.00,5.00,5.00,5.00,5.00,5.00,5.00"
					( Origin gBackEnd )
				)
				( attribute "MVIA_TO_THRUPIN_SPACING" "5.00,5.00,5.00,5.00,5.00,5.00,5.00,5.00,5.00,5.00,5.00,5.00,5.00,5.00"
					( Origin gBackEnd )
				)
				( attribute "MVIA_TO_SMDPIN_SPACING" "5.00,5.00,5.00,5.00,5.00,5.00,5.00,5.00,5.00,5.00,5.00,5.00,5.00,5.00"
					( Origin gBackEnd )
				)
				( attribute "MVIA_TO_THRUVIA_SPACING" "5.00,5.00,5.00,5.00,5.00,5.00,5.00,5.00,5.00,5.00,5.00,5.00,5.00,5.00"
					( Origin gBackEnd )
				)
				( attribute "MVIA_TO_BBV_SPACING" "5.00,5.00,5.00,5.00,5.00,5.00,5.00,5.00,5.00,5.00,5.00,5.00,5.00,5.00"
					( Origin gBackEnd )
				)
				( attribute "MVIA_TO_LINE_SPACING" "5.00,5.00,5.00,5.00,5.00,5.00,5.00,5.00,5.00,5.00,5.00,5.00,5.00,5.00"
					( Origin gBackEnd )
				)
				( attribute "MVIA_TO_SHAPE_SPACING" "5.00,5.00,5.00,5.00,5.00,5.00,5.00,5.00,5.00,5.00,5.00,5.00,5.00,5.00"
					( Origin gBackEnd )
				)
				( attribute "MVIA_TO_TESTPIN_SPACING" "5.00,5.00,5.00,5.00,5.00,5.00,5.00,5.00,5.00,5.00,5.00,5.00,5.00,5.00"
					( Origin gBackEnd )
				)
				( attribute "MVIA_TO_TESTVIA_SPACING" "5.00,5.00,5.00,5.00,5.00,5.00,5.00,5.00,5.00,5.00,5.00,5.00,5.00,5.00"
					( Origin gBackEnd )
				)
				( attribute "BONDPAD_TO_MVIA_SPACING" "5.00,5.00,5.00,5.00,5.00,5.00,5.00,5.00,5.00,5.00,5.00,5.00,5.00,5.00"
					( Origin gBackEnd )
				)
				( attribute "MIN_BVIA_GAP" "5.00"
					( Origin gBackEnd )
				)
				( attribute "BONDPAD_TO_BONDPAD_DIFFP_SPC" "5.00,5.00,5.00,5.00,5.00,5.00,5.00,5.00,5.00,5.00,5.00,5.00,5.00,5.00"
					( Origin gBackEnd )
				)
				( objectStatus "15H_US_&_7H_SL" )
			)
			( spacingCSet "@crescent_city_bb_fab1_lib.crescent_city_bb_fab1(sch_1):\12H_US_&_5H_SL\"
				( attribute "THRUPIN_TO_THRUPIN_SPACING" "5.00,5.00,5.00,5.00,5.00,5.00,5.00,5.00,5.00,5.00,5.00,5.00,5.00,5.00"
					( Origin gBackEnd )
				)
				( attribute "THRUPIN_TO_SMDPIN_SPACING" "5.00,5.00,5.00,5.00,5.00,5.00,5.00,5.00,5.00,5.00,5.00,5.00,5.00,5.00"
					( Origin gBackEnd )
				)
				( attribute "TESTPIN_TO_THRUPIN_SPACING" "5.00,5.00,5.00,5.00,5.00,5.00,5.00,5.00,5.00,5.00,5.00,5.00,5.00,5.00"
					( Origin gBackEnd )
				)
				( attribute "THRUPIN_TO_THRUVIA_SPACING" "5.00,5.00,5.00,5.00,5.00,5.00,5.00,5.00,5.00,5.00,5.00,5.00,5.00,5.00"
					( Origin gBackEnd )
				)
				( attribute "TESTVIA_TO_THRUPIN_SPACING" "5.00,5.00,5.00,5.00,5.00,5.00,5.00,5.00,5.00,5.00,5.00,5.00,5.00,5.00"
					( Origin gBackEnd )
				)
				( attribute "BBV_TO_THRUPIN_SPACING" "5.00,5.00,5.00,5.00,5.00,5.00,5.00,5.00,5.00,5.00,5.00,5.00,5.00,5.00"
					( Origin gBackEnd )
				)
				( attribute "THRUPIN_TO_BONDPAD_SPACING" "5.00,5.00,5.00,5.00,5.00,5.00,5.00,5.00,5.00,5.00,5.00,5.00,5.00,5.00"
					( Origin gBackEnd )
				)
				( attribute "LINE_TO_THRUPIN_SPACING" "4.50,4.00,4.00,4.00,4.00,4.00,4.00,4.00,4.00,4.00,4.00,4.00,4.00,4.50"
					( Origin gBackEnd )
				)
				( attribute "THRUPIN_TO_SHAPE_SPACING" "5.00,5.00,5.00,5.00,5.00,5.00,5.00,5.00,5.00,5.00,5.00,5.00,5.00,5.00"
					( Origin gBackEnd )
				)
				( attribute "SMDPIN_TO_SMDPIN_SPACING" "5.00,5.00,5.00,5.00,5.00,5.00,5.00,5.00,5.00,5.00,5.00,5.00,5.00,5.00"
					( Origin gBackEnd )
				)
				( attribute "SMDPIN_TO_TESTPIN_SPACING" "5.00,5.00,5.00,5.00,5.00,5.00,5.00,5.00,5.00,5.00,5.00,5.00,5.00,25.00"
					( Origin gBackEnd )
				)
				( attribute "SMDPIN_TO_THRUVIA_SPACING" "5.00,5.00,5.00,5.00,5.00,5.00,5.00,5.00,5.00,5.00,5.00,5.00,5.00,5.00"
					( Origin gBackEnd )
				)
				( attribute "SMDPIN_TO_TESTVIA_SPACING" "5.00,5.00,5.00,5.00,5.00,5.00,5.00,5.00,5.00,5.00,5.00,5.00,5.00,5.00"
					( Origin gBackEnd )
				)
				( attribute "BBV_TO_SMDPIN_SPACING" "5.00,5.00,5.00,5.00,5.00,5.00,5.00,5.00,5.00,5.00,5.00,5.00,5.00,5.00"
					( Origin gBackEnd )
				)
				( attribute "SMDPIN_TO_BONDPAD_SPACING" "5.00,5.00,5.00,5.00,5.00,5.00,5.00,5.00,5.00,5.00,5.00,5.00,5.00,5.00"
					( Origin gBackEnd )
				)
				( attribute "LINE_TO_SMDPIN_SPACING" "4.50,4.50,4.50,4.50,4.50,4.50,4.50,4.50,4.50,4.50,4.50,4.50,4.50,4.50"
					( Origin gBackEnd )
				)
				( attribute "SHAPE_TO_SMDPIN_SPACING" "5.00,5.00,5.00,5.00,5.00,5.00,5.00,5.00,5.00,5.00,5.00,5.00,5.00,5.00"
					( Origin gBackEnd )
				)
				( attribute "TESTPIN_TO_TESTPIN_SPACING" "5.00,5.00,5.00,5.00,5.00,5.00,5.00,5.00,5.00,5.00,5.00,5.00,5.00,5.00"
					( Origin gBackEnd )
				)
				( attribute "TESTPIN_TO_THRUVIA_SPACING" "5.00,5.00,5.00,5.00,5.00,5.00,5.00,5.00,5.00,5.00,5.00,5.00,5.00,5.00"
					( Origin gBackEnd )
				)
				( attribute "TESTPIN_TO_TESTVIA_SPACING" "5.00,5.00,5.00,5.00,5.00,5.00,5.00,5.00,5.00,5.00,5.00,5.00,5.00,5.00"
					( Origin gBackEnd )
				)
				( attribute "BBV_TO_TESTPIN_SPACING" "5.00,5.00,5.00,5.00,5.00,5.00,5.00,5.00,5.00,5.00,5.00,5.00,5.00,5.00"
					( Origin gBackEnd )
				)
				( attribute "BONDPAD_TO_TESTPIN_SPACING" "5.00,5.00,5.00,5.00,5.00,5.00,5.00,5.00,5.00,5.00,5.00,5.00,5.00,5.00"
					( Origin gBackEnd )
				)
				( attribute "LINE_TO_TESTPIN_SPACING" "5.00,4.00,4.00,4.00,4.00,4.00,4.00,4.00,4.00,4.00,4.00,4.00,4.00,5.00"
					( Origin gBackEnd )
				)
				( attribute "SHAPE_TO_TESTPIN_SPACING" "5.00,5.00,5.00,5.00,5.00,5.00,5.00,5.00,5.00,5.00,5.00,5.00,5.00,5.00"
					( Origin gBackEnd )
				)
				( attribute "THRUVIA_TO_THRUVIA_SPACING" "5.00,5.00,5.00,5.00,5.00,5.00,5.00,5.00,5.00,5.00,5.00,5.00,5.00,5.00"
					( Origin gBackEnd )
				)
				( attribute "TESTVIA_TO_THRUVIA_SPACING" "6.00,6.00,6.00,6.00,6.00,6.00,6.00,6.00,6.00,6.00,6.00,6.00,6.00,6.00"
					( Origin gBackEnd )
				)
				( attribute "BBV_TO_THRUVIA_SPACING" "5.00,5.00,5.00,5.00,5.00,5.00,5.00,5.00,5.00,5.00,5.00,5.00,5.00,5.00"
					( Origin gBackEnd )
				)
				( attribute "BONDPAD_TO_THRUVIA_SPACING" "5.00,5.00,5.00,5.00,5.00,5.00,5.00,5.00,5.00,5.00,5.00,5.00,5.00,5.00"
					( Origin gBackEnd )
				)
				( attribute "LINE_TO_THRUVIA_SPACING" "4.50,4.00,4.00,4.00,4.00,4.00,4.00,4.00,4.00,4.00,4.00,4.00,4.00,4.50"
					( Origin gBackEnd )
				)
				( attribute "SHAPE_TO_THRUVIA_SPACING" "5.00,5.00,5.00,5.00,5.00,5.00,5.00,5.00,5.00,5.00,5.00,5.00,5.00,5.00"
					( Origin gBackEnd )
				)
				( attribute "TESTVIA_TO_TESTVIA_SPACING" "6.00,6.00,6.00,6.00,6.00,6.00,6.00,6.00,6.00,6.00,6.00,6.00,6.00,6.00"
					( Origin gBackEnd )
				)
				( attribute "BBV_TO_TESTVIA_SPACING" "5.00,5.00,5.00,5.00,5.00,5.00,5.00,5.00,5.00,5.00,5.00,5.00,5.00,5.00"
					( Origin gBackEnd )
				)
				( attribute "BONDPAD_TO_TESTVIA_SPACING" "5.00,5.00,5.00,5.00,5.00,5.00,5.00,5.00,5.00,5.00,5.00,5.00,5.00,5.00"
					( Origin gBackEnd )
				)
				( attribute "LINE_TO_TESTVIA_SPACING" "4.50,4.00,4.00,4.00,4.00,4.00,4.00,4.00,4.00,4.00,4.00,4.00,4.00,4.50"
					( Origin gBackEnd )
				)
				( attribute "SHAPE_TO_TESTVIA_SPACING" "5.00,5.00,5.00,5.00,5.00,5.00,5.00,5.00,5.00,5.00,5.00,5.00,5.00,5.00"
					( Origin gBackEnd )
				)
				( attribute "BBV_TO_BBV_SPACING" "5.00,5.00,5.00,5.00,5.00,5.00,5.00,5.00,5.00,5.00,5.00,5.00,5.00,5.00"
					( Origin gBackEnd )
				)
				( attribute "BONDPAD_TO_BBV_SPACING" "5.00,5.00,5.00,5.00,5.00,5.00,5.00,5.00,5.00,5.00,5.00,5.00,5.00,5.00"
					( Origin gBackEnd )
				)
				( attribute "BBV_TO_LINE_SPACING" "5.00,5.00,5.00,5.00,5.00,5.00,5.00,5.00,5.00,5.00,5.00,5.00,5.00,5.00"
					( Origin gBackEnd )
				)
				( attribute "BBV_TO_SHAPE_SPACING" "5.00,5.00,5.00,5.00,5.00,5.00,5.00,5.00,5.00,5.00,5.00,5.00,5.00,5.00"
					( Origin gBackEnd )
				)
				( attribute "BONDPAD_TO_BONDPAD_SPACING" "5.00,5.00,5.00,5.00,5.00,5.00,5.00,5.00,5.00,5.00,5.00,5.00,5.00,5.00"
					( Origin gBackEnd )
				)
				( attribute "BONDPAD_TO_LINE_SPACING" "5.00,5.00,5.00,5.00,5.00,5.00,5.00,5.00,5.00,5.00,5.00,5.00,5.00,5.00"
					( Origin gBackEnd )
				)
				( attribute "BONDPAD_TO_SHAPE_SPACING" "5.00,5.00,5.00,5.00,5.00,5.00,5.00,5.00,5.00,5.00,5.00,5.00,5.00,5.00"
					( Origin gBackEnd )
				)
				( attribute "LINE_TO_LINE_SPACING" "32.40,15.00,15.00,15.00,15.00,15.00,15.00,15.00,15.00,15.00,15.00,15.00,15.00,32.40"
					( Origin gBackEnd )
				)
				( attribute "LINE_TO_SHAPE_SPACING" "10.00,10.00,10.00,10.00,10.00,10.00,10.00,10.00,10.00,10.00,10.00,10.00,10.00,10.00"
					( Origin gBackEnd )
				)
				( attribute "SHAPE_TO_SHAPE_SPACING" "10.00,10.00,10.00,10.00,10.00,10.00,10.00,10.00,10.00,10.00,10.00,10.00,10.00,10.00"
					( Origin gBackEnd )
				)
				( attribute "HOLE_TO_PIN_SPACING" "8.00,8.00,8.00,8.00,8.00,8.00,8.00,8.00,8.00,8.00,8.00,8.00,8.00,8.00"
					( Origin gBackEnd )
				)
				( attribute "HOLE_TO_VIA_SPACING" "8.00,8.00,8.00,8.00,8.00,8.00,8.00,8.00,8.00,8.00,8.00,8.00,8.00,8.00"
					( Origin gBackEnd )
				)
				( attribute "HOLE_TO_LINE_SPACING" "8.00,8.00,8.00,8.00,8.00,8.00,8.00,8.00,8.00,8.00,8.00,8.00,8.00,8.00"
					( Origin gBackEnd )
				)
				( attribute "HOLE_TO_SHAPE_SPACING" "8.00,8.00,8.00,8.00,8.00,8.00,8.00,8.00,8.00,8.00,8.00,8.00,8.00,8.00"
					( Origin gBackEnd )
				)
				( attribute "HOLE_TO_HOLE_SPACING" "8.00,8.00,8.00,8.00,8.00,8.00,8.00,8.00,8.00,8.00,8.00,8.00,8.00,8.00"
					( Origin gBackEnd )
				)
				( attribute "MVIA_TO_MVIA_SPACING" "5.00,5.00,5.00,5.00,5.00,5.00,5.00,5.00,5.00,5.00,5.00,5.00,5.00,5.00"
					( Origin gBackEnd )
				)
				( attribute "MVIA_TO_THRUPIN_SPACING" "5.00,5.00,5.00,5.00,5.00,5.00,5.00,5.00,5.00,5.00,5.00,5.00,5.00,5.00"
					( Origin gBackEnd )
				)
				( attribute "MVIA_TO_SMDPIN_SPACING" "5.00,5.00,5.00,5.00,5.00,5.00,5.00,5.00,5.00,5.00,5.00,5.00,5.00,5.00"
					( Origin gBackEnd )
				)
				( attribute "MVIA_TO_THRUVIA_SPACING" "5.00,5.00,5.00,5.00,5.00,5.00,5.00,5.00,5.00,5.00,5.00,5.00,5.00,5.00"
					( Origin gBackEnd )
				)
				( attribute "MVIA_TO_BBV_SPACING" "5.00,5.00,5.00,5.00,5.00,5.00,5.00,5.00,5.00,5.00,5.00,5.00,5.00,5.00"
					( Origin gBackEnd )
				)
				( attribute "MVIA_TO_LINE_SPACING" "5.00,5.00,5.00,5.00,5.00,5.00,5.00,5.00,5.00,5.00,5.00,5.00,5.00,5.00"
					( Origin gBackEnd )
				)
				( attribute "MVIA_TO_SHAPE_SPACING" "5.00,5.00,5.00,5.00,5.00,5.00,5.00,5.00,5.00,5.00,5.00,5.00,5.00,5.00"
					( Origin gBackEnd )
				)
				( attribute "MVIA_TO_TESTPIN_SPACING" "5.00,5.00,5.00,5.00,5.00,5.00,5.00,5.00,5.00,5.00,5.00,5.00,5.00,5.00"
					( Origin gBackEnd )
				)
				( attribute "MVIA_TO_TESTVIA_SPACING" "5.00,5.00,5.00,5.00,5.00,5.00,5.00,5.00,5.00,5.00,5.00,5.00,5.00,5.00"
					( Origin gBackEnd )
				)
				( attribute "BONDPAD_TO_MVIA_SPACING" "5.00,5.00,5.00,5.00,5.00,5.00,5.00,5.00,5.00,5.00,5.00,5.00,5.00,5.00"
					( Origin gBackEnd )
				)
				( attribute "MIN_BVIA_GAP" "5.00"
					( Origin gBackEnd )
				)
				( attribute "BONDPAD_TO_BONDPAD_DIFFP_SPC" "5.00,5.00,5.00,5.00,5.00,5.00,5.00,5.00,5.00,5.00,5.00,5.00,5.00,5.00"
					( Origin gBackEnd )
				)
				( objectStatus "12H_US_&_5H_SL" )
			)
			( spacingCSet "@crescent_city_bb_fab1_lib.crescent_city_bb_fab1(sch_1):\24_MIL\"
				( attribute "THRUPIN_TO_THRUPIN_SPACING" "5.00,5.00,5.00,5.00,5.00,5.00,5.00,5.00,5.00,5.00,5.00,5.00,5.00,5.00"
					( Origin gBackEnd )
				)
				( attribute "THRUPIN_TO_SMDPIN_SPACING" "5.00,5.00,5.00,5.00,5.00,5.00,5.00,5.00,5.00,5.00,5.00,5.00,5.00,5.00"
					( Origin gBackEnd )
				)
				( attribute "TESTPIN_TO_THRUPIN_SPACING" "5.00,5.00,5.00,5.00,5.00,5.00,5.00,5.00,5.00,5.00,5.00,5.00,5.00,5.00"
					( Origin gBackEnd )
				)
				( attribute "THRUPIN_TO_THRUVIA_SPACING" "5.00,5.00,5.00,5.00,5.00,5.00,5.00,5.00,5.00,5.00,5.00,5.00,5.00,5.00"
					( Origin gBackEnd )
				)
				( attribute "TESTVIA_TO_THRUPIN_SPACING" "5.00,5.00,5.00,5.00,5.00,5.00,5.00,5.00,5.00,5.00,5.00,5.00,5.00,5.00"
					( Origin gBackEnd )
				)
				( attribute "BBV_TO_THRUPIN_SPACING" "5.00,5.00,5.00,5.00,5.00,5.00,5.00,5.00,5.00,5.00,5.00,5.00,5.00,5.00"
					( Origin gBackEnd )
				)
				( attribute "THRUPIN_TO_BONDPAD_SPACING" "5.00,5.00,5.00,5.00,5.00,5.00,5.00,5.00,5.00,5.00,5.00,5.00,5.00,5.00"
					( Origin gBackEnd )
				)
				( attribute "LINE_TO_THRUPIN_SPACING" "4.50,4.00,4.00,4.00,4.00,4.00,4.00,4.00,4.00,4.00,4.00,4.00,4.00,4.50"
					( Origin gBackEnd )
				)
				( attribute "THRUPIN_TO_SHAPE_SPACING" "4.50,4.00,4.00,4.00,4.00,4.00,4.00,4.00,4.00,4.00,4.00,4.00,4.00,4.00"
					( Origin gBackEnd )
				)
				( attribute "SMDPIN_TO_SMDPIN_SPACING" "5.00,5.00,5.00,5.00,5.00,5.00,5.00,5.00,5.00,5.00,5.00,5.00,5.00,5.00"
					( Origin gBackEnd )
				)
				( attribute "SMDPIN_TO_TESTPIN_SPACING" "5.00,5.00,5.00,5.00,5.00,5.00,5.00,5.00,5.00,5.00,5.00,5.00,5.00,25.00"
					( Origin gBackEnd )
				)
				( attribute "SMDPIN_TO_THRUVIA_SPACING" "5.00,5.00,5.00,5.00,5.00,5.00,5.00,5.00,5.00,5.00,5.00,5.00,5.00,5.00"
					( Origin gBackEnd )
				)
				( attribute "SMDPIN_TO_TESTVIA_SPACING" "5.00,5.00,5.00,5.00,5.00,5.00,5.00,5.00,5.00,5.00,5.00,5.00,5.00,5.00"
					( Origin gBackEnd )
				)
				( attribute "BBV_TO_SMDPIN_SPACING" "5.00,5.00,5.00,5.00,5.00,5.00,5.00,5.00,5.00,5.00,5.00,5.00,5.00,5.00"
					( Origin gBackEnd )
				)
				( attribute "SMDPIN_TO_BONDPAD_SPACING" "5.00,5.00,5.00,5.00,5.00,5.00,5.00,5.00,5.00,5.00,5.00,5.00,5.00,5.00"
					( Origin gBackEnd )
				)
				( attribute "LINE_TO_SMDPIN_SPACING" "4.50,4.50,4.50,4.50,4.50,4.50,4.50,4.50,4.50,4.50,4.50,4.50,4.50,4.50"
					( Origin gBackEnd )
				)
				( attribute "SHAPE_TO_SMDPIN_SPACING" "5.00,5.00,5.00,5.00,5.00,5.00,5.00,5.00,5.00,5.00,5.00,5.00,5.00,5.00"
					( Origin gBackEnd )
				)
				( attribute "TESTPIN_TO_TESTPIN_SPACING" "5.00,5.00,5.00,5.00,5.00,5.00,5.00,5.00,5.00,5.00,5.00,5.00,5.00,5.00"
					( Origin gBackEnd )
				)
				( attribute "TESTPIN_TO_THRUVIA_SPACING" "5.00,5.00,5.00,5.00,5.00,5.00,5.00,5.00,5.00,5.00,5.00,5.00,5.00,5.00"
					( Origin gBackEnd )
				)
				( attribute "TESTPIN_TO_TESTVIA_SPACING" "5.00,5.00,5.00,5.00,5.00,5.00,5.00,5.00,5.00,5.00,5.00,5.00,5.00,5.00"
					( Origin gBackEnd )
				)
				( attribute "BBV_TO_TESTPIN_SPACING" "5.00,5.00,5.00,5.00,5.00,5.00,5.00,5.00,5.00,5.00,5.00,5.00,5.00,5.00"
					( Origin gBackEnd )
				)
				( attribute "BONDPAD_TO_TESTPIN_SPACING" "5.00,5.00,5.00,5.00,5.00,5.00,5.00,5.00,5.00,5.00,5.00,5.00,5.00,5.00"
					( Origin gBackEnd )
				)
				( attribute "LINE_TO_TESTPIN_SPACING" "4.50,5.00,5.00,5.00,5.00,5.00,5.00,5.00,5.00,5.00,5.00,5.00,5.00,5.00"
					( Origin gBackEnd )
				)
				( attribute "SHAPE_TO_TESTPIN_SPACING" "4.50,4.00,4.00,4.00,4.00,4.00,4.00,4.00,4.00,4.00,4.00,4.00,4.00,4.00"
					( Origin gBackEnd )
				)
				( attribute "THRUVIA_TO_THRUVIA_SPACING" "5.00,5.00,5.00,5.00,5.00,5.00,5.00,5.00,5.00,5.00,5.00,5.00,5.00,5.00"
					( Origin gBackEnd )
				)
				( attribute "TESTVIA_TO_THRUVIA_SPACING" "5.00,5.00,5.00,5.00,5.00,5.00,5.00,5.00,5.00,5.00,5.00,5.00,5.00,5.00"
					( Origin gBackEnd )
				)
				( attribute "BBV_TO_THRUVIA_SPACING" "5.00,5.00,5.00,5.00,5.00,5.00,5.00,5.00,5.00,5.00,5.00,5.00,5.00,5.00"
					( Origin gBackEnd )
				)
				( attribute "BONDPAD_TO_THRUVIA_SPACING" "5.00,5.00,5.00,5.00,5.00,5.00,5.00,5.00,5.00,5.00,5.00,5.00,5.00,5.00"
					( Origin gBackEnd )
				)
				( attribute "LINE_TO_THRUVIA_SPACING" "4.50,4.00,4.00,4.00,4.00,4.00,4.00,4.00,4.00,4.00,4.00,4.00,4.00,4.50"
					( Origin gBackEnd )
				)
				( attribute "SHAPE_TO_THRUVIA_SPACING" "4.50,4.00,4.00,4.00,4.00,4.00,4.00,4.00,4.00,4.00,4.00,4.00,4.00,4.00"
					( Origin gBackEnd )
				)
				( attribute "TESTVIA_TO_TESTVIA_SPACING" "5.00,5.00,5.00,5.00,5.00,5.00,5.00,5.00,5.00,5.00,5.00,5.00,5.00,5.00"
					( Origin gBackEnd )
				)
				( attribute "BBV_TO_TESTVIA_SPACING" "5.00,5.00,5.00,5.00,5.00,5.00,5.00,5.00,5.00,5.00,5.00,5.00,5.00,5.00"
					( Origin gBackEnd )
				)
				( attribute "BONDPAD_TO_TESTVIA_SPACING" "5.00,5.00,5.00,5.00,5.00,5.00,5.00,5.00,5.00,5.00,5.00,5.00,5.00,5.00"
					( Origin gBackEnd )
				)
				( attribute "LINE_TO_TESTVIA_SPACING" "4.50,5.00,4.00,5.00,4.00,5.00,5.00,5.00,5.00,4.00,5.00,4.00,5.00,4.50"
					( Origin gBackEnd )
				)
				( attribute "SHAPE_TO_TESTVIA_SPACING" "4.50,4.00,4.00,4.00,4.00,4.00,4.00,4.00,4.00,4.00,4.00,4.00,4.00,4.00"
					( Origin gBackEnd )
				)
				( attribute "BBV_TO_BBV_SPACING" "5.00,5.00,5.00,5.00,5.00,5.00,5.00,5.00,5.00,5.00,5.00,5.00,5.00,5.00"
					( Origin gBackEnd )
				)
				( attribute "BONDPAD_TO_BBV_SPACING" "5.00,5.00,5.00,5.00,5.00,5.00,5.00,5.00,5.00,5.00,5.00,5.00,5.00,5.00"
					( Origin gBackEnd )
				)
				( attribute "BBV_TO_LINE_SPACING" "5.00,5.00,5.00,5.00,5.00,5.00,5.00,5.00,5.00,5.00,5.00,5.00,5.00,5.00"
					( Origin gBackEnd )
				)
				( attribute "BBV_TO_SHAPE_SPACING" "5.00,5.00,5.00,5.00,5.00,5.00,5.00,5.00,5.00,5.00,5.00,5.00,5.00,5.00"
					( Origin gBackEnd )
				)
				( attribute "BONDPAD_TO_BONDPAD_SPACING" "5.00,5.00,5.00,5.00,5.00,5.00,5.00,5.00,5.00,5.00,5.00,5.00,5.00,5.00"
					( Origin gBackEnd )
				)
				( attribute "BONDPAD_TO_LINE_SPACING" "5.00,5.00,5.00,5.00,5.00,5.00,5.00,5.00,5.00,5.00,5.00,5.00,5.00,5.00"
					( Origin gBackEnd )
				)
				( attribute "BONDPAD_TO_SHAPE_SPACING" "5.00,5.00,5.00,5.00,5.00,5.00,5.00,5.00,5.00,5.00,5.00,5.00,5.00,5.00"
					( Origin gBackEnd )
				)
				( attribute "LINE_TO_LINE_SPACING" "24.00,24.00,24.00,24.00,24.00,24.00,24.00,24.00,24.00,24.00,24.00,24.00,24.00,24.00"
					( Origin gBackEnd )
				)
				( attribute "LINE_TO_SHAPE_SPACING" "5.00,5.00,5.00,5.00,5.00,5.00,5.00,5.00,5.00,5.00,5.00,5.00,5.00,5.00"
					( Origin gBackEnd )
				)
				( attribute "SHAPE_TO_SHAPE_SPACING" "10.00,10.00,10.00,10.00,10.00,10.00,10.00,10.00,10.00,10.00,10.00,10.00,10.00,10.00"
					( Origin gBackEnd )
				)
				( attribute "HOLE_TO_PIN_SPACING" "8.00,8.00,8.00,8.00,8.00,8.00,8.00,8.00,8.00,8.00,8.00,8.00,8.00,8.00"
					( Origin gBackEnd )
				)
				( attribute "HOLE_TO_VIA_SPACING" "8.00,8.00,8.00,8.00,8.00,8.00,8.00,8.00,8.00,8.00,8.00,8.00,8.00,8.00"
					( Origin gBackEnd )
				)
				( attribute "HOLE_TO_LINE_SPACING" "8.00,8.00,8.00,8.00,8.00,8.00,8.00,8.00,8.00,8.00,8.00,8.00,8.00,8.00"
					( Origin gBackEnd )
				)
				( attribute "HOLE_TO_SHAPE_SPACING" "8.00,8.00,8.00,8.00,8.00,8.00,8.00,8.00,8.00,8.00,8.00,8.00,8.00,8.00"
					( Origin gBackEnd )
				)
				( attribute "HOLE_TO_HOLE_SPACING" "8.00,8.00,8.00,8.00,8.00,8.00,8.00,8.00,8.00,8.00,8.00,8.00,8.00,8.00"
					( Origin gBackEnd )
				)
				( attribute "MVIA_TO_MVIA_SPACING" "5.00,5.00,5.00,5.00,5.00,5.00,5.00,5.00,5.00,5.00,5.00,5.00,5.00,5.00"
					( Origin gBackEnd )
				)
				( attribute "MVIA_TO_THRUPIN_SPACING" "5.00,5.00,5.00,5.00,5.00,5.00,5.00,5.00,5.00,5.00,5.00,5.00,5.00,5.00"
					( Origin gBackEnd )
				)
				( attribute "MVIA_TO_SMDPIN_SPACING" "5.00,5.00,5.00,5.00,5.00,5.00,5.00,5.00,5.00,5.00,5.00,5.00,5.00,5.00"
					( Origin gBackEnd )
				)
				( attribute "MVIA_TO_THRUVIA_SPACING" "5.00,5.00,5.00,5.00,5.00,5.00,5.00,5.00,5.00,5.00,5.00,5.00,5.00,5.00"
					( Origin gBackEnd )
				)
				( attribute "MVIA_TO_BBV_SPACING" "5.00,5.00,5.00,5.00,5.00,5.00,5.00,5.00,5.00,5.00,5.00,5.00,5.00,5.00"
					( Origin gBackEnd )
				)
				( attribute "MVIA_TO_LINE_SPACING" "5.00,5.00,5.00,5.00,5.00,5.00,5.00,5.00,5.00,5.00,5.00,5.00,5.00,5.00"
					( Origin gBackEnd )
				)
				( attribute "MVIA_TO_SHAPE_SPACING" "5.00,5.00,5.00,5.00,5.00,5.00,5.00,5.00,5.00,5.00,5.00,5.00,5.00,5.00"
					( Origin gBackEnd )
				)
				( attribute "MVIA_TO_TESTPIN_SPACING" "5.00,5.00,5.00,5.00,5.00,5.00,5.00,5.00,5.00,5.00,5.00,5.00,5.00,5.00"
					( Origin gBackEnd )
				)
				( attribute "MVIA_TO_TESTVIA_SPACING" "5.00,5.00,5.00,5.00,5.00,5.00,5.00,5.00,5.00,5.00,5.00,5.00,5.00,5.00"
					( Origin gBackEnd )
				)
				( attribute "BONDPAD_TO_MVIA_SPACING" "5.00,5.00,5.00,5.00,5.00,5.00,5.00,5.00,5.00,5.00,5.00,5.00,5.00,5.00"
					( Origin gBackEnd )
				)
				( attribute "MIN_BVIA_GAP" "5.00"
					( Origin gBackEnd )
				)
				( attribute "BONDPAD_TO_BONDPAD_DIFFP_SPC" "5.00,5.00,5.00,5.00,5.00,5.00,5.00,5.00,5.00,5.00,5.00,5.00,5.00,5.00"
					( Origin gBackEnd )
				)
				( objectStatus "24_MIL" )
			)
			( spacingCSet "@crescent_city_bb_fab1_lib.crescent_city_bb_fab1(sch_1):\45\"
				( attribute "THRUPIN_TO_THRUPIN_SPACING" "5.00,5.00,5.00,5.00,5.00,5.00,5.00,5.00,5.00,5.00,5.00,5.00,5.00,5.00"
					( Origin gBackEnd )
				)
				( attribute "THRUPIN_TO_SMDPIN_SPACING" "5.00,5.00,5.00,5.00,5.00,5.00,5.00,5.00,5.00,5.00,5.00,5.00,5.00,5.00"
					( Origin gBackEnd )
				)
				( attribute "TESTPIN_TO_THRUPIN_SPACING" "5.00,5.00,5.00,5.00,5.00,5.00,5.00,5.00,5.00,5.00,5.00,5.00,5.00,5.00"
					( Origin gBackEnd )
				)
				( attribute "THRUPIN_TO_THRUVIA_SPACING" "5.00,5.00,5.00,5.00,5.00,5.00,5.00,5.00,5.00,5.00,5.00,5.00,5.00,5.00"
					( Origin gBackEnd )
				)
				( attribute "TESTVIA_TO_THRUPIN_SPACING" "5.00,5.00,5.00,5.00,5.00,5.00,5.00,5.00,5.00,5.00,5.00,5.00,5.00,5.00"
					( Origin gBackEnd )
				)
				( attribute "BBV_TO_THRUPIN_SPACING" "5.00,5.00,5.00,5.00,5.00,5.00,5.00,5.00,5.00,5.00,5.00,5.00,5.00,5.00"
					( Origin gBackEnd )
				)
				( attribute "THRUPIN_TO_BONDPAD_SPACING" "5.00,5.00,5.00,5.00,5.00,5.00,5.00,5.00,5.00,5.00,5.00,5.00,5.00,5.00"
					( Origin gBackEnd )
				)
				( attribute "LINE_TO_THRUPIN_SPACING" "4.50,4.00,4.00,4.00,4.00,4.00,4.00,4.00,4.00,4.00,4.00,4.00,4.00,4.50"
					( Origin gBackEnd )
				)
				( attribute "THRUPIN_TO_SHAPE_SPACING" "4.50,4.00,4.00,4.00,4.00,4.00,4.00,4.00,4.00,4.00,4.00,4.00,4.00,4.00"
					( Origin gBackEnd )
				)
				( attribute "SMDPIN_TO_SMDPIN_SPACING" "5.00,5.00,5.00,5.00,5.00,5.00,5.00,5.00,5.00,5.00,5.00,5.00,5.00,5.00"
					( Origin gBackEnd )
				)
				( attribute "SMDPIN_TO_TESTPIN_SPACING" "5.00,5.00,5.00,5.00,5.00,5.00,5.00,5.00,5.00,5.00,5.00,5.00,5.00,25.00"
					( Origin gBackEnd )
				)
				( attribute "SMDPIN_TO_THRUVIA_SPACING" "5.00,5.00,5.00,5.00,5.00,5.00,5.00,5.00,5.00,5.00,5.00,5.00,5.00,5.00"
					( Origin gBackEnd )
				)
				( attribute "SMDPIN_TO_TESTVIA_SPACING" "5.00,5.00,5.00,5.00,5.00,5.00,5.00,5.00,5.00,5.00,5.00,5.00,5.00,5.00"
					( Origin gBackEnd )
				)
				( attribute "BBV_TO_SMDPIN_SPACING" "5.00,5.00,5.00,5.00,5.00,5.00,5.00,5.00,5.00,5.00,5.00,5.00,5.00,5.00"
					( Origin gBackEnd )
				)
				( attribute "SMDPIN_TO_BONDPAD_SPACING" "5.00,5.00,5.00,5.00,5.00,5.00,5.00,5.00,5.00,5.00,5.00,5.00,5.00,5.00"
					( Origin gBackEnd )
				)
				( attribute "LINE_TO_SMDPIN_SPACING" "4.50,4.50,4.50,4.50,4.50,4.50,4.50,4.50,4.50,4.50,4.50,4.50,4.50,4.50"
					( Origin gBackEnd )
				)
				( attribute "SHAPE_TO_SMDPIN_SPACING" "5.00,5.00,5.00,5.00,5.00,5.00,5.00,5.00,5.00,5.00,5.00,5.00,5.00,5.00"
					( Origin gBackEnd )
				)
				( attribute "TESTPIN_TO_TESTPIN_SPACING" "5.00,5.00,5.00,5.00,5.00,5.00,5.00,5.00,5.00,5.00,5.00,5.00,5.00,5.00"
					( Origin gBackEnd )
				)
				( attribute "TESTPIN_TO_THRUVIA_SPACING" "5.00,5.00,5.00,5.00,5.00,5.00,5.00,5.00,5.00,5.00,5.00,5.00,5.00,5.00"
					( Origin gBackEnd )
				)
				( attribute "TESTPIN_TO_TESTVIA_SPACING" "5.00,5.00,5.00,5.00,5.00,5.00,5.00,5.00,5.00,5.00,5.00,5.00,5.00,5.00"
					( Origin gBackEnd )
				)
				( attribute "BBV_TO_TESTPIN_SPACING" "5.00,5.00,5.00,5.00,5.00,5.00,5.00,5.00,5.00,5.00,5.00,5.00,5.00,5.00"
					( Origin gBackEnd )
				)
				( attribute "BONDPAD_TO_TESTPIN_SPACING" "5.00,5.00,5.00,5.00,5.00,5.00,5.00,5.00,5.00,5.00,5.00,5.00,5.00,5.00"
					( Origin gBackEnd )
				)
				( attribute "LINE_TO_TESTPIN_SPACING" "4.50,5.00,5.00,5.00,5.00,5.00,5.00,5.00,5.00,5.00,5.00,5.00,5.00,5.00"
					( Origin gBackEnd )
				)
				( attribute "SHAPE_TO_TESTPIN_SPACING" "4.50,4.00,4.00,4.00,4.00,4.00,4.00,4.00,4.00,4.00,4.00,4.00,4.00,4.00"
					( Origin gBackEnd )
				)
				( attribute "THRUVIA_TO_THRUVIA_SPACING" "5.00,5.00,5.00,5.00,5.00,5.00,5.00,5.00,5.00,5.00,5.00,5.00,5.00,5.00"
					( Origin gBackEnd )
				)
				( attribute "TESTVIA_TO_THRUVIA_SPACING" "5.00,5.00,5.00,5.00,5.00,5.00,5.00,5.00,5.00,5.00,5.00,5.00,5.00,5.00"
					( Origin gBackEnd )
				)
				( attribute "BBV_TO_THRUVIA_SPACING" "5.00,5.00,5.00,5.00,5.00,5.00,5.00,5.00,5.00,5.00,5.00,5.00,5.00,5.00"
					( Origin gBackEnd )
				)
				( attribute "BONDPAD_TO_THRUVIA_SPACING" "5.00,5.00,5.00,5.00,5.00,5.00,5.00,5.00,5.00,5.00,5.00,5.00,5.00,5.00"
					( Origin gBackEnd )
				)
				( attribute "LINE_TO_THRUVIA_SPACING" "4.50,4.00,4.00,4.00,4.00,4.00,4.00,4.00,4.00,4.00,4.00,4.00,4.00,4.50"
					( Origin gBackEnd )
				)
				( attribute "SHAPE_TO_THRUVIA_SPACING" "4.50,4.00,4.00,4.00,4.00,4.00,4.00,4.00,4.00,4.00,4.00,4.00,4.00,4.00"
					( Origin gBackEnd )
				)
				( attribute "TESTVIA_TO_TESTVIA_SPACING" "5.00,5.00,5.00,5.00,5.00,5.00,5.00,5.00,5.00,5.00,5.00,5.00,5.00,5.00"
					( Origin gBackEnd )
				)
				( attribute "BBV_TO_TESTVIA_SPACING" "5.00,5.00,5.00,5.00,5.00,5.00,5.00,5.00,5.00,5.00,5.00,5.00,5.00,5.00"
					( Origin gBackEnd )
				)
				( attribute "BONDPAD_TO_TESTVIA_SPACING" "5.00,5.00,5.00,5.00,5.00,5.00,5.00,5.00,5.00,5.00,5.00,5.00,5.00,5.00"
					( Origin gBackEnd )
				)
				( attribute "LINE_TO_TESTVIA_SPACING" "4.50,5.00,4.00,5.00,4.00,5.00,5.00,5.00,5.00,4.00,5.00,4.00,5.00,4.50"
					( Origin gBackEnd )
				)
				( attribute "SHAPE_TO_TESTVIA_SPACING" "4.50,4.00,4.00,4.00,4.00,4.00,4.00,4.00,4.00,4.00,4.00,4.00,4.00,4.00"
					( Origin gBackEnd )
				)
				( attribute "BBV_TO_BBV_SPACING" "5.00,5.00,5.00,5.00,5.00,5.00,5.00,5.00,5.00,5.00,5.00,5.00,5.00,5.00"
					( Origin gBackEnd )
				)
				( attribute "BONDPAD_TO_BBV_SPACING" "5.00,5.00,5.00,5.00,5.00,5.00,5.00,5.00,5.00,5.00,5.00,5.00,5.00,5.00"
					( Origin gBackEnd )
				)
				( attribute "BBV_TO_LINE_SPACING" "5.00,5.00,5.00,5.00,5.00,5.00,5.00,5.00,5.00,5.00,5.00,5.00,5.00,5.00"
					( Origin gBackEnd )
				)
				( attribute "BBV_TO_SHAPE_SPACING" "5.00,5.00,5.00,5.00,5.00,5.00,5.00,5.00,5.00,5.00,5.00,5.00,5.00,5.00"
					( Origin gBackEnd )
				)
				( attribute "BONDPAD_TO_BONDPAD_SPACING" "5.00,5.00,5.00,5.00,5.00,5.00,5.00,5.00,5.00,5.00,5.00,5.00,5.00,5.00"
					( Origin gBackEnd )
				)
				( attribute "BONDPAD_TO_LINE_SPACING" "5.00,5.00,5.00,5.00,5.00,5.00,5.00,5.00,5.00,5.00,5.00,5.00,5.00,5.00"
					( Origin gBackEnd )
				)
				( attribute "BONDPAD_TO_SHAPE_SPACING" "5.00,5.00,5.00,5.00,5.00,5.00,5.00,5.00,5.00,5.00,5.00,5.00,5.00,5.00"
					( Origin gBackEnd )
				)
				( attribute "LINE_TO_LINE_SPACING" "45.00,45.00,45.00,45.00,45.00,45.00,45.00,45.00,45.00,45.00,45.00,45.00,45.00,45.00"
					( Origin gBackEnd )
				)
				( attribute "LINE_TO_SHAPE_SPACING" "5.00,5.00,5.00,5.00,5.00,5.00,5.00,5.00,5.00,5.00,5.00,5.00,5.00,5.00"
					( Origin gBackEnd )
				)
				( attribute "SHAPE_TO_SHAPE_SPACING" "10.00,10.00,10.00,10.00,10.00,10.00,10.00,10.00,10.00,10.00,10.00,10.00,10.00,10.00"
					( Origin gBackEnd )
				)
				( attribute "HOLE_TO_PIN_SPACING" "8.00,8.00,8.00,8.00,8.00,8.00,8.00,8.00,8.00,8.00,8.00,8.00,8.00,8.00"
					( Origin gBackEnd )
				)
				( attribute "HOLE_TO_VIA_SPACING" "8.00,8.00,8.00,8.00,8.00,8.00,8.00,8.00,8.00,8.00,8.00,8.00,8.00,8.00"
					( Origin gBackEnd )
				)
				( attribute "HOLE_TO_LINE_SPACING" "8.00,8.00,8.00,8.00,8.00,8.00,8.00,8.00,8.00,8.00,8.00,8.00,8.00,8.00"
					( Origin gBackEnd )
				)
				( attribute "HOLE_TO_SHAPE_SPACING" "8.00,8.00,8.00,8.00,8.00,8.00,8.00,8.00,8.00,8.00,8.00,8.00,8.00,8.00"
					( Origin gBackEnd )
				)
				( attribute "HOLE_TO_HOLE_SPACING" "8.00,8.00,8.00,8.00,8.00,8.00,8.00,8.00,8.00,8.00,8.00,8.00,8.00,8.00"
					( Origin gBackEnd )
				)
				( attribute "MVIA_TO_MVIA_SPACING" "5.00,5.00,5.00,5.00,5.00,5.00,5.00,5.00,5.00,5.00,5.00,5.00,5.00,5.00"
					( Origin gBackEnd )
				)
				( attribute "MVIA_TO_THRUPIN_SPACING" "5.00,5.00,5.00,5.00,5.00,5.00,5.00,5.00,5.00,5.00,5.00,5.00,5.00,5.00"
					( Origin gBackEnd )
				)
				( attribute "MVIA_TO_SMDPIN_SPACING" "5.00,5.00,5.00,5.00,5.00,5.00,5.00,5.00,5.00,5.00,5.00,5.00,5.00,5.00"
					( Origin gBackEnd )
				)
				( attribute "MVIA_TO_THRUVIA_SPACING" "5.00,5.00,5.00,5.00,5.00,5.00,5.00,5.00,5.00,5.00,5.00,5.00,5.00,5.00"
					( Origin gBackEnd )
				)
				( attribute "MVIA_TO_BBV_SPACING" "5.00,5.00,5.00,5.00,5.00,5.00,5.00,5.00,5.00,5.00,5.00,5.00,5.00,5.00"
					( Origin gBackEnd )
				)
				( attribute "MVIA_TO_LINE_SPACING" "5.00,5.00,5.00,5.00,5.00,5.00,5.00,5.00,5.00,5.00,5.00,5.00,5.00,5.00"
					( Origin gBackEnd )
				)
				( attribute "MVIA_TO_SHAPE_SPACING" "5.00,5.00,5.00,5.00,5.00,5.00,5.00,5.00,5.00,5.00,5.00,5.00,5.00,5.00"
					( Origin gBackEnd )
				)
				( attribute "MVIA_TO_TESTPIN_SPACING" "5.00,5.00,5.00,5.00,5.00,5.00,5.00,5.00,5.00,5.00,5.00,5.00,5.00,5.00"
					( Origin gBackEnd )
				)
				( attribute "MVIA_TO_TESTVIA_SPACING" "5.00,5.00,5.00,5.00,5.00,5.00,5.00,5.00,5.00,5.00,5.00,5.00,5.00,5.00"
					( Origin gBackEnd )
				)
				( attribute "BONDPAD_TO_MVIA_SPACING" "5.00,5.00,5.00,5.00,5.00,5.00,5.00,5.00,5.00,5.00,5.00,5.00,5.00,5.00"
					( Origin gBackEnd )
				)
				( attribute "MIN_BVIA_GAP" "5.00"
					( Origin gBackEnd )
				)
				( attribute "BONDPAD_TO_BONDPAD_DIFFP_SPC" "5.00,5.00,5.00,5.00,5.00,5.00,5.00,5.00,5.00,5.00,5.00,5.00,5.00,5.00"
					( Origin gBackEnd )
				)
				( objectStatus "45_MILS" )
			)
			( spacingCSet "@crescent_city_bb_fab1_lib.crescent_city_bb_fab1(sch_1):\7H_US_&_6H_SL\"
				( attribute "THRUPIN_TO_THRUPIN_SPACING" "5.00,5.00,5.00,5.00,5.00,5.00,5.00,5.00,5.00,5.00,5.00,5.00,5.00,5.00"
					( Origin gBackEnd )
				)
				( attribute "THRUPIN_TO_SMDPIN_SPACING" "5.00,5.00,5.00,5.00,5.00,5.00,5.00,5.00,5.00,5.00,5.00,5.00,5.00,5.00"
					( Origin gBackEnd )
				)
				( attribute "TESTPIN_TO_THRUPIN_SPACING" "5.00,5.00,5.00,5.00,5.00,5.00,5.00,5.00,5.00,5.00,5.00,5.00,5.00,5.00"
					( Origin gBackEnd )
				)
				( attribute "THRUPIN_TO_THRUVIA_SPACING" "5.00,5.00,5.00,5.00,5.00,5.00,5.00,5.00,5.00,5.00,5.00,5.00,5.00,5.00"
					( Origin gBackEnd )
				)
				( attribute "TESTVIA_TO_THRUPIN_SPACING" "5.00,5.00,5.00,5.00,5.00,5.00,5.00,5.00,5.00,5.00,5.00,5.00,5.00,5.00"
					( Origin gBackEnd )
				)
				( attribute "BBV_TO_THRUPIN_SPACING" "5.00,5.00,5.00,5.00,5.00,5.00,5.00,5.00,5.00,5.00,5.00,5.00,5.00,5.00"
					( Origin gBackEnd )
				)
				( attribute "THRUPIN_TO_BONDPAD_SPACING" "5.00,5.00,5.00,5.00,5.00,5.00,5.00,5.00,5.00,5.00,5.00,5.00,5.00,5.00"
					( Origin gBackEnd )
				)
				( attribute "LINE_TO_THRUPIN_SPACING" "8.00,8.00,8.00,8.00,8.00,8.00,8.00,8.00,8.00,8.00,8.00,8.00,8.00,8.00"
					( Origin gBackEnd )
				)
				( attribute "THRUPIN_TO_SHAPE_SPACING" "4.50,4.00,4.00,4.00,4.00,4.00,4.00,4.00,4.00,4.00,4.00,4.00,4.00,4.00"
					( Origin gBackEnd )
				)
				( attribute "SMDPIN_TO_SMDPIN_SPACING" "5.00,5.00,5.00,5.00,5.00,5.00,5.00,5.00,5.00,5.00,5.00,5.00,5.00,5.00"
					( Origin gBackEnd )
				)
				( attribute "SMDPIN_TO_TESTPIN_SPACING" "5.00,5.00,5.00,5.00,5.00,5.00,5.00,5.00,5.00,5.00,5.00,5.00,5.00,5.00"
					( Origin gBackEnd )
				)
				( attribute "SMDPIN_TO_THRUVIA_SPACING" "5.00,5.00,5.00,5.00,5.00,5.00,5.00,5.00,5.00,5.00,5.00,5.00,5.00,5.00"
					( Origin gBackEnd )
				)
				( attribute "SMDPIN_TO_TESTVIA_SPACING" "5.00,5.00,5.00,5.00,5.00,5.00,5.00,5.00,5.00,5.00,5.00,5.00,5.00,5.00"
					( Origin gBackEnd )
				)
				( attribute "BBV_TO_SMDPIN_SPACING" "5.00,5.00,5.00,5.00,5.00,5.00,5.00,5.00,5.00,5.00,5.00,5.00,5.00,5.00"
					( Origin gBackEnd )
				)
				( attribute "SMDPIN_TO_BONDPAD_SPACING" "5.00,5.00,5.00,5.00,5.00,5.00,5.00,5.00,5.00,5.00,5.00,5.00,5.00,5.00"
					( Origin gBackEnd )
				)
				( attribute "LINE_TO_SMDPIN_SPACING" "4.50,4.50,4.50,4.50,4.50,4.50,4.50,4.50,4.50,4.50,4.50,4.50,4.50,4.50"
					( Origin gBackEnd )
				)
				( attribute "SHAPE_TO_SMDPIN_SPACING" "5.00,5.00,5.00,5.00,5.00,5.00,5.00,5.00,5.00,5.00,5.00,5.00,5.00,5.00"
					( Origin gBackEnd )
				)
				( attribute "TESTPIN_TO_TESTPIN_SPACING" "5.00,5.00,5.00,5.00,5.00,5.00,5.00,5.00,5.00,5.00,5.00,5.00,5.00,5.00"
					( Origin gBackEnd )
				)
				( attribute "TESTPIN_TO_THRUVIA_SPACING" "5.00,5.00,5.00,5.00,5.00,5.00,5.00,5.00,5.00,5.00,5.00,5.00,5.00,5.00"
					( Origin gBackEnd )
				)
				( attribute "TESTPIN_TO_TESTVIA_SPACING" "5.00,5.00,5.00,5.00,5.00,5.00,5.00,5.00,5.00,5.00,5.00,5.00,5.00,5.00"
					( Origin gBackEnd )
				)
				( attribute "BBV_TO_TESTPIN_SPACING" "5.00,5.00,5.00,5.00,5.00,5.00,5.00,5.00,5.00,5.00,5.00,5.00,5.00,5.00"
					( Origin gBackEnd )
				)
				( attribute "BONDPAD_TO_TESTPIN_SPACING" "5.00,5.00,5.00,5.00,5.00,5.00,5.00,5.00,5.00,5.00,5.00,5.00,5.00,5.00"
					( Origin gBackEnd )
				)
				( attribute "LINE_TO_TESTPIN_SPACING" "4.50,5.00,5.00,5.00,5.00,5.00,5.00,5.00,5.00,5.00,5.00,5.00,5.00,5.00"
					( Origin gBackEnd )
				)
				( attribute "SHAPE_TO_TESTPIN_SPACING" "4.50,4.00,4.00,4.00,4.00,4.00,4.00,4.00,4.00,4.00,4.00,4.00,4.00,4.00"
					( Origin gBackEnd )
				)
				( attribute "THRUVIA_TO_THRUVIA_SPACING" "5.00,5.00,5.00,5.00,5.00,5.00,5.00,5.00,5.00,5.00,5.00,5.00,5.00,5.00"
					( Origin gBackEnd )
				)
				( attribute "TESTVIA_TO_THRUVIA_SPACING" "5.00,5.00,5.00,5.00,5.00,5.00,5.00,5.00,5.00,5.00,5.00,5.00,5.00,5.00"
					( Origin gBackEnd )
				)
				( attribute "BBV_TO_THRUVIA_SPACING" "5.00,5.00,5.00,5.00,5.00,5.00,5.00,5.00,5.00,5.00,5.00,5.00,5.00,5.00"
					( Origin gBackEnd )
				)
				( attribute "BONDPAD_TO_THRUVIA_SPACING" "5.00,5.00,5.00,5.00,5.00,5.00,5.00,5.00,5.00,5.00,5.00,5.00,5.00,5.00"
					( Origin gBackEnd )
				)
				( attribute "LINE_TO_THRUVIA_SPACING" "4.50,4.00,4.00,4.00,4.00,4.00,4.00,4.00,4.00,4.00,4.00,4.00,4.00,4.50"
					( Origin gBackEnd )
				)
				( attribute "SHAPE_TO_THRUVIA_SPACING" "4.50,4.00,4.00,4.00,4.00,4.00,4.00,4.00,4.00,4.00,4.00,4.00,4.00,4.00"
					( Origin gBackEnd )
				)
				( attribute "TESTVIA_TO_TESTVIA_SPACING" "5.00,5.00,5.00,5.00,5.00,5.00,5.00,5.00,5.00,5.00,5.00,5.00,5.00,5.00"
					( Origin gBackEnd )
				)
				( attribute "BBV_TO_TESTVIA_SPACING" "5.00,5.00,5.00,5.00,5.00,5.00,5.00,5.00,5.00,5.00,5.00,5.00,5.00,5.00"
					( Origin gBackEnd )
				)
				( attribute "BONDPAD_TO_TESTVIA_SPACING" "5.00,5.00,5.00,5.00,5.00,5.00,5.00,5.00,5.00,5.00,5.00,5.00,5.00,5.00"
					( Origin gBackEnd )
				)
				( attribute "LINE_TO_TESTVIA_SPACING" "4.50,5.00,4.00,5.00,4.00,5.00,5.00,5.00,5.00,4.00,5.00,4.00,5.00,4.50"
					( Origin gBackEnd )
				)
				( attribute "SHAPE_TO_TESTVIA_SPACING" "4.50,4.00,4.00,4.00,4.00,4.00,4.00,4.00,4.00,4.00,4.00,4.00,4.00,4.00"
					( Origin gBackEnd )
				)
				( attribute "BBV_TO_BBV_SPACING" "5.00,5.00,5.00,5.00,5.00,5.00,5.00,5.00,5.00,5.00,5.00,5.00,5.00,5.00"
					( Origin gBackEnd )
				)
				( attribute "BONDPAD_TO_BBV_SPACING" "5.00,5.00,5.00,5.00,5.00,5.00,5.00,5.00,5.00,5.00,5.00,5.00,5.00,5.00"
					( Origin gBackEnd )
				)
				( attribute "BBV_TO_LINE_SPACING" "5.00,5.00,5.00,5.00,5.00,5.00,5.00,5.00,5.00,5.00,5.00,5.00,5.00,5.00"
					( Origin gBackEnd )
				)
				( attribute "BBV_TO_SHAPE_SPACING" "5.00,5.00,5.00,5.00,5.00,5.00,5.00,5.00,5.00,5.00,5.00,5.00,5.00,5.00"
					( Origin gBackEnd )
				)
				( attribute "BONDPAD_TO_BONDPAD_SPACING" "5.00,5.00,5.00,5.00,5.00,5.00,5.00,5.00,5.00,5.00,5.00,5.00,5.00,5.00"
					( Origin gBackEnd )
				)
				( attribute "BONDPAD_TO_LINE_SPACING" "5.00,5.00,5.00,5.00,5.00,5.00,5.00,5.00,5.00,5.00,5.00,5.00,5.00,5.00"
					( Origin gBackEnd )
				)
				( attribute "BONDPAD_TO_SHAPE_SPACING" "5.00,5.00,5.00,5.00,5.00,5.00,5.00,5.00,5.00,5.00,5.00,5.00,5.00,5.00"
					( Origin gBackEnd )
				)
				( attribute "LINE_TO_LINE_SPACING" "19.00,18.00,18.00,18.00,18.00,18.00,18.00,18.00,18.00,18.00,18.00,18.00,18.00,19.00"
					( Origin gBackEnd )
				)
				( attribute "LINE_TO_SHAPE_SPACING" "14.00,14.00,14.00,14.00,14.00,14.00,14.00,14.00,14.00,14.00,14.00,18.00,14.00,14.00"
					( Origin gBackEnd )
				)
				( attribute "SHAPE_TO_SHAPE_SPACING" "10.00,10.00,10.00,10.00,10.00,10.00,10.00,10.00,10.00,10.00,10.00,10.00,10.00,10.00"
					( Origin gBackEnd )
				)
				( attribute "HOLE_TO_PIN_SPACING" "8.00,8.00,8.00,8.00,8.00,8.00,8.00,8.00,8.00,8.00,8.00,8.00,8.00,8.00"
					( Origin gBackEnd )
				)
				( attribute "HOLE_TO_VIA_SPACING" "8.00,8.00,8.00,8.00,8.00,8.00,8.00,8.00,8.00,8.00,8.00,8.00,8.00,8.00"
					( Origin gBackEnd )
				)
				( attribute "HOLE_TO_LINE_SPACING" "8.00,8.00,8.00,8.00,8.00,8.00,8.00,8.00,8.00,8.00,8.00,8.00,8.00,8.00"
					( Origin gBackEnd )
				)
				( attribute "HOLE_TO_SHAPE_SPACING" "8.00,8.00,8.00,8.00,8.00,8.00,8.00,8.00,8.00,8.00,8.00,8.00,8.00,8.00"
					( Origin gBackEnd )
				)
				( attribute "HOLE_TO_HOLE_SPACING" "8.00,8.00,8.00,8.00,8.00,8.00,8.00,8.00,8.00,8.00,8.00,8.00,8.00,8.00"
					( Origin gBackEnd )
				)
				( attribute "MVIA_TO_MVIA_SPACING" "5.00,5.00,5.00,5.00,5.00,5.00,5.00,5.00,5.00,5.00,5.00,5.00,5.00,5.00"
					( Origin gBackEnd )
				)
				( attribute "MVIA_TO_THRUPIN_SPACING" "5.00,5.00,5.00,5.00,5.00,5.00,5.00,5.00,5.00,5.00,5.00,5.00,5.00,5.00"
					( Origin gBackEnd )
				)
				( attribute "MVIA_TO_SMDPIN_SPACING" "5.00,5.00,5.00,5.00,5.00,5.00,5.00,5.00,5.00,5.00,5.00,5.00,5.00,5.00"
					( Origin gBackEnd )
				)
				( attribute "MVIA_TO_THRUVIA_SPACING" "5.00,5.00,5.00,5.00,5.00,5.00,5.00,5.00,5.00,5.00,5.00,5.00,5.00,5.00"
					( Origin gBackEnd )
				)
				( attribute "MVIA_TO_BBV_SPACING" "5.00,5.00,5.00,5.00,5.00,5.00,5.00,5.00,5.00,5.00,5.00,5.00,5.00,5.00"
					( Origin gBackEnd )
				)
				( attribute "MVIA_TO_LINE_SPACING" "5.00,5.00,5.00,5.00,5.00,5.00,5.00,5.00,5.00,5.00,5.00,5.00,5.00,5.00"
					( Origin gBackEnd )
				)
				( attribute "MVIA_TO_SHAPE_SPACING" "5.00,5.00,5.00,5.00,5.00,5.00,5.00,5.00,5.00,5.00,5.00,5.00,5.00,5.00"
					( Origin gBackEnd )
				)
				( attribute "MVIA_TO_TESTPIN_SPACING" "5.00,5.00,5.00,5.00,5.00,5.00,5.00,5.00,5.00,5.00,5.00,5.00,5.00,5.00"
					( Origin gBackEnd )
				)
				( attribute "MVIA_TO_TESTVIA_SPACING" "5.00,5.00,5.00,5.00,5.00,5.00,5.00,5.00,5.00,5.00,5.00,5.00,5.00,5.00"
					( Origin gBackEnd )
				)
				( attribute "BONDPAD_TO_MVIA_SPACING" "5.00,5.00,5.00,5.00,5.00,5.00,5.00,5.00,5.00,5.00,5.00,5.00,5.00,5.00"
					( Origin gBackEnd )
				)
				( attribute "MIN_BVIA_GAP" "5.00"
					( Origin gBackEnd )
				)
				( attribute "BONDPAD_TO_BONDPAD_DIFFP_SPC" "5.00,5.00,5.00,5.00,5.00,5.00,5.00,5.00,5.00,5.00,5.00,5.00,5.00,5.00"
					( Origin gBackEnd )
				)
				( objectStatus "7H_US_&_6H_SL" )
			)
			( spacingCSet "@crescent_city_bb_fab1_lib.crescent_city_bb_fab1(sch_1):\15MIL_US_&_13MIL_SL\"
				( attribute "THRUPIN_TO_THRUPIN_SPACING" "5.00,5.00,5.00,5.00,5.00,5.00,5.00,5.00,5.00,5.00,5.00,5.00,5.00,5.00"
					( Origin gBackEnd )
				)
				( attribute "THRUPIN_TO_SMDPIN_SPACING" "5.00,5.00,5.00,5.00,5.00,5.00,5.00,5.00,5.00,5.00,5.00,5.00,5.00,5.00"
					( Origin gBackEnd )
				)
				( attribute "TESTPIN_TO_THRUPIN_SPACING" "5.00,5.00,5.00,5.00,5.00,5.00,5.00,5.00,5.00,5.00,5.00,5.00,5.00,5.00"
					( Origin gBackEnd )
				)
				( attribute "THRUPIN_TO_THRUVIA_SPACING" "5.00,5.00,5.00,5.00,5.00,5.00,5.00,5.00,5.00,5.00,5.00,5.00,5.00,5.00"
					( Origin gBackEnd )
				)
				( attribute "TESTVIA_TO_THRUPIN_SPACING" "5.00,5.00,5.00,5.00,5.00,5.00,5.00,5.00,5.00,5.00,5.00,5.00,5.00,5.00"
					( Origin gBackEnd )
				)
				( attribute "BBV_TO_THRUPIN_SPACING" "5.00,5.00,5.00,5.00,5.00,5.00,5.00,5.00,5.00,5.00,5.00,5.00,5.00,5.00"
					( Origin gBackEnd )
				)
				( attribute "THRUPIN_TO_BONDPAD_SPACING" "5.00,5.00,5.00,5.00,5.00,5.00,5.00,5.00,5.00,5.00,5.00,5.00,5.00,5.00"
					( Origin gBackEnd )
				)
				( attribute "LINE_TO_THRUPIN_SPACING" "5.00,4.00,4.00,4.00,4.00,4.00,4.00,4.00,4.00,4.00,4.00,4.00,4.00,5.00"
					( Origin gBackEnd )
				)
				( attribute "THRUPIN_TO_SHAPE_SPACING" "5.00,5.00,5.00,5.00,5.00,5.00,5.00,5.00,5.00,5.00,5.00,5.00,5.00,5.00"
					( Origin gBackEnd )
				)
				( attribute "SMDPIN_TO_SMDPIN_SPACING" "5.00,5.00,5.00,5.00,5.00,5.00,5.00,5.00,5.00,5.00,5.00,5.00,5.00,5.00"
					( Origin gBackEnd )
				)
				( attribute "SMDPIN_TO_TESTPIN_SPACING" "5.00,5.00,5.00,5.00,5.00,5.00,5.00,5.00,5.00,5.00,5.00,5.00,5.00,25.00"
					( Origin gBackEnd )
				)
				( attribute "SMDPIN_TO_THRUVIA_SPACING" "5.00,5.00,5.00,5.00,5.00,5.00,5.00,5.00,5.00,5.00,5.00,5.00,5.00,5.00"
					( Origin gBackEnd )
				)
				( attribute "SMDPIN_TO_TESTVIA_SPACING" "5.00,5.00,5.00,5.00,5.00,5.00,5.00,5.00,5.00,5.00,5.00,5.00,5.00,5.00"
					( Origin gBackEnd )
				)
				( attribute "BBV_TO_SMDPIN_SPACING" "5.00,5.00,5.00,5.00,5.00,5.00,5.00,5.00,5.00,5.00,5.00,5.00,5.00,5.00"
					( Origin gBackEnd )
				)
				( attribute "SMDPIN_TO_BONDPAD_SPACING" "5.00,5.00,5.00,5.00,5.00,5.00,5.00,5.00,5.00,5.00,5.00,5.00,5.00,5.00"
					( Origin gBackEnd )
				)
				( attribute "LINE_TO_SMDPIN_SPACING" "4.50,4.50,4.50,4.50,4.50,4.50,4.50,4.50,4.50,4.50,4.50,4.50,4.50,4.50"
					( Origin gBackEnd )
				)
				( attribute "SHAPE_TO_SMDPIN_SPACING" "5.00,5.00,5.00,5.00,5.00,5.00,5.00,5.00,5.00,5.00,5.00,5.00,5.00,5.00"
					( Origin gBackEnd )
				)
				( attribute "TESTPIN_TO_TESTPIN_SPACING" "5.00,5.00,5.00,5.00,5.00,5.00,5.00,5.00,5.00,5.00,5.00,5.00,5.00,5.00"
					( Origin gBackEnd )
				)
				( attribute "TESTPIN_TO_THRUVIA_SPACING" "5.00,5.00,5.00,5.00,5.00,5.00,5.00,5.00,5.00,5.00,5.00,5.00,5.00,5.00"
					( Origin gBackEnd )
				)
				( attribute "TESTPIN_TO_TESTVIA_SPACING" "5.00,5.00,5.00,5.00,5.00,5.00,5.00,5.00,5.00,5.00,5.00,5.00,5.00,5.00"
					( Origin gBackEnd )
				)
				( attribute "BBV_TO_TESTPIN_SPACING" "5.00,5.00,5.00,5.00,5.00,5.00,5.00,5.00,5.00,5.00,5.00,5.00,5.00,5.00"
					( Origin gBackEnd )
				)
				( attribute "BONDPAD_TO_TESTPIN_SPACING" "5.00,5.00,5.00,5.00,5.00,5.00,5.00,5.00,5.00,5.00,5.00,5.00,5.00,5.00"
					( Origin gBackEnd )
				)
				( attribute "LINE_TO_TESTPIN_SPACING" "5.00,4.00,4.00,4.00,4.00,4.00,4.00,4.00,4.00,4.00,4.00,4.00,4.00,5.00"
					( Origin gBackEnd )
				)
				( attribute "SHAPE_TO_TESTPIN_SPACING" "5.00,5.00,5.00,5.00,5.00,5.00,5.00,5.00,5.00,5.00,5.00,5.00,5.00,5.00"
					( Origin gBackEnd )
				)
				( attribute "THRUVIA_TO_THRUVIA_SPACING" "5.00,5.00,5.00,5.00,5.00,5.00,5.00,5.00,5.00,5.00,5.00,5.00,5.00,5.00"
					( Origin gBackEnd )
				)
				( attribute "TESTVIA_TO_THRUVIA_SPACING" "6.00,6.00,6.00,6.00,6.00,6.00,6.00,6.00,6.00,6.00,6.00,6.00,6.00,6.00"
					( Origin gBackEnd )
				)
				( attribute "BBV_TO_THRUVIA_SPACING" "5.00,5.00,5.00,5.00,5.00,5.00,5.00,5.00,5.00,5.00,5.00,5.00,5.00,5.00"
					( Origin gBackEnd )
				)
				( attribute "BONDPAD_TO_THRUVIA_SPACING" "5.00,5.00,5.00,5.00,5.00,5.00,5.00,5.00,5.00,5.00,5.00,5.00,5.00,5.00"
					( Origin gBackEnd )
				)
				( attribute "LINE_TO_THRUVIA_SPACING" "4.50,4.00,4.00,4.00,4.00,4.00,4.00,4.00,4.00,4.00,4.00,4.00,4.00,4.50"
					( Origin gBackEnd )
				)
				( attribute "SHAPE_TO_THRUVIA_SPACING" "5.00,5.00,5.00,5.00,5.00,5.00,5.00,5.00,5.00,5.00,5.00,5.00,5.00,5.00"
					( Origin gBackEnd )
				)
				( attribute "TESTVIA_TO_TESTVIA_SPACING" "6.00,6.00,6.00,6.00,6.00,6.00,6.00,6.00,6.00,6.00,6.00,6.00,6.00,6.00"
					( Origin gBackEnd )
				)
				( attribute "BBV_TO_TESTVIA_SPACING" "5.00,5.00,5.00,5.00,5.00,5.00,5.00,5.00,5.00,5.00,5.00,5.00,5.00,5.00"
					( Origin gBackEnd )
				)
				( attribute "BONDPAD_TO_TESTVIA_SPACING" "5.00,5.00,5.00,5.00,5.00,5.00,5.00,5.00,5.00,5.00,5.00,5.00,5.00,5.00"
					( Origin gBackEnd )
				)
				( attribute "LINE_TO_TESTVIA_SPACING" "4.50,4.00,4.00,4.00,4.00,4.00,4.00,4.00,4.00,4.00,4.00,4.00,4.00,4.50"
					( Origin gBackEnd )
				)
				( attribute "SHAPE_TO_TESTVIA_SPACING" "5.00,5.00,5.00,5.00,5.00,5.00,5.00,5.00,5.00,5.00,5.00,5.00,5.00,5.00"
					( Origin gBackEnd )
				)
				( attribute "BBV_TO_BBV_SPACING" "5.00,5.00,5.00,5.00,5.00,5.00,5.00,5.00,5.00,5.00,5.00,5.00,5.00,5.00"
					( Origin gBackEnd )
				)
				( attribute "BONDPAD_TO_BBV_SPACING" "5.00,5.00,5.00,5.00,5.00,5.00,5.00,5.00,5.00,5.00,5.00,5.00,5.00,5.00"
					( Origin gBackEnd )
				)
				( attribute "BBV_TO_LINE_SPACING" "5.00,5.00,5.00,5.00,5.00,5.00,5.00,5.00,5.00,5.00,5.00,5.00,5.00,5.00"
					( Origin gBackEnd )
				)
				( attribute "BBV_TO_SHAPE_SPACING" "5.00,5.00,5.00,5.00,5.00,5.00,5.00,5.00,5.00,5.00,5.00,5.00,5.00,5.00"
					( Origin gBackEnd )
				)
				( attribute "BONDPAD_TO_BONDPAD_SPACING" "5.00,5.00,5.00,5.00,5.00,5.00,5.00,5.00,5.00,5.00,5.00,5.00,5.00,5.00"
					( Origin gBackEnd )
				)
				( attribute "BONDPAD_TO_LINE_SPACING" "5.00,5.00,5.00,5.00,5.00,5.00,5.00,5.00,5.00,5.00,5.00,5.00,5.00,5.00"
					( Origin gBackEnd )
				)
				( attribute "BONDPAD_TO_SHAPE_SPACING" "5.00,5.00,5.00,5.00,5.00,5.00,5.00,5.00,5.00,5.00,5.00,5.00,5.00,5.00"
					( Origin gBackEnd )
				)
				( attribute "LINE_TO_LINE_SPACING" "15.00,13.00,13.00,13.00,13.00,13.00,13.00,13.00,13.00,13.00,13.00,13.00,13.00,15.00"
					( Origin gBackEnd )
				)
				( attribute "LINE_TO_SHAPE_SPACING" "10.00,10.00,10.00,10.00,10.00,10.00,10.00,10.00,10.00,10.00,10.00,10.00,10.00,10.00"
					( Origin gBackEnd )
				)
				( attribute "SHAPE_TO_SHAPE_SPACING" "10.00,10.00,10.00,10.00,10.00,10.00,10.00,10.00,10.00,10.00,10.00,10.00,10.00,10.00"
					( Origin gBackEnd )
				)
				( attribute "HOLE_TO_PIN_SPACING" "8.00,8.00,8.00,8.00,8.00,8.00,8.00,8.00,8.00,8.00,8.00,8.00,8.00,8.00"
					( Origin gBackEnd )
				)
				( attribute "HOLE_TO_VIA_SPACING" "8.00,8.00,8.00,8.00,8.00,8.00,8.00,8.00,8.00,8.00,8.00,8.00,8.00,8.00"
					( Origin gBackEnd )
				)
				( attribute "HOLE_TO_LINE_SPACING" "8.00,8.00,8.00,8.00,8.00,8.00,8.00,8.00,8.00,8.00,8.00,8.00,8.00,8.00"
					( Origin gBackEnd )
				)
				( attribute "HOLE_TO_SHAPE_SPACING" "8.00,8.00,8.00,8.00,8.00,8.00,8.00,8.00,8.00,8.00,8.00,8.00,8.00,8.00"
					( Origin gBackEnd )
				)
				( attribute "HOLE_TO_HOLE_SPACING" "8.00,8.00,8.00,8.00,8.00,8.00,8.00,8.00,8.00,8.00,8.00,8.00,8.00,8.00"
					( Origin gBackEnd )
				)
				( attribute "MVIA_TO_MVIA_SPACING" "5.00,5.00,5.00,5.00,5.00,5.00,5.00,5.00,5.00,5.00,5.00,5.00,5.00,5.00"
					( Origin gBackEnd )
				)
				( attribute "MVIA_TO_THRUPIN_SPACING" "5.00,5.00,5.00,5.00,5.00,5.00,5.00,5.00,5.00,5.00,5.00,5.00,5.00,5.00"
					( Origin gBackEnd )
				)
				( attribute "MVIA_TO_SMDPIN_SPACING" "5.00,5.00,5.00,5.00,5.00,5.00,5.00,5.00,5.00,5.00,5.00,5.00,5.00,5.00"
					( Origin gBackEnd )
				)
				( attribute "MVIA_TO_THRUVIA_SPACING" "5.00,5.00,5.00,5.00,5.00,5.00,5.00,5.00,5.00,5.00,5.00,5.00,5.00,5.00"
					( Origin gBackEnd )
				)
				( attribute "MVIA_TO_BBV_SPACING" "5.00,5.00,5.00,5.00,5.00,5.00,5.00,5.00,5.00,5.00,5.00,5.00,5.00,5.00"
					( Origin gBackEnd )
				)
				( attribute "MVIA_TO_LINE_SPACING" "5.00,5.00,5.00,5.00,5.00,5.00,5.00,5.00,5.00,5.00,5.00,5.00,5.00,5.00"
					( Origin gBackEnd )
				)
				( attribute "MVIA_TO_SHAPE_SPACING" "5.00,5.00,5.00,5.00,5.00,5.00,5.00,5.00,5.00,5.00,5.00,5.00,5.00,5.00"
					( Origin gBackEnd )
				)
				( attribute "MVIA_TO_TESTPIN_SPACING" "5.00,5.00,5.00,5.00,5.00,5.00,5.00,5.00,5.00,5.00,5.00,5.00,5.00,5.00"
					( Origin gBackEnd )
				)
				( attribute "MVIA_TO_TESTVIA_SPACING" "5.00,5.00,5.00,5.00,5.00,5.00,5.00,5.00,5.00,5.00,5.00,5.00,5.00,5.00"
					( Origin gBackEnd )
				)
				( attribute "BONDPAD_TO_MVIA_SPACING" "5.00,5.00,5.00,5.00,5.00,5.00,5.00,5.00,5.00,5.00,5.00,5.00,5.00,5.00"
					( Origin gBackEnd )
				)
				( attribute "MIN_BVIA_GAP" "5.00"
					( Origin gBackEnd )
				)
				( attribute "BONDPAD_TO_BONDPAD_DIFFP_SPC" "5.00,5.00,5.00,5.00,5.00,5.00,5.00,5.00,5.00,5.00,5.00,5.00,5.00,5.00"
					( Origin gBackEnd )
				)
				( objectStatus "15MIL_US_&_13MIL_SL" )
			)
			( spacingCSet "@crescent_city_bb_fab1_lib.crescent_city_bb_fab1(sch_1):\4_MILS\"
				( attribute "THRUPIN_TO_THRUPIN_SPACING" "5.00,5.00,5.00,5.00,5.00,5.00,5.00,5.00,5.00,5.00,5.00,5.00,5.00,5.00"
					( Origin gBackEnd )
				)
				( attribute "THRUPIN_TO_SMDPIN_SPACING" "5.00,5.00,5.00,5.00,5.00,5.00,5.00,5.00,5.00,5.00,5.00,5.00,5.00,5.00"
					( Origin gBackEnd )
				)
				( attribute "TESTPIN_TO_THRUPIN_SPACING" "5.00,5.00,5.00,5.00,5.00,5.00,5.00,5.00,5.00,5.00,5.00,5.00,5.00,5.00"
					( Origin gBackEnd )
				)
				( attribute "THRUPIN_TO_THRUVIA_SPACING" "5.00,5.00,5.00,5.00,5.00,5.00,5.00,5.00,5.00,5.00,5.00,5.00,5.00,5.00"
					( Origin gBackEnd )
				)
				( attribute "TESTVIA_TO_THRUPIN_SPACING" "5.00,5.00,5.00,5.00,5.00,5.00,5.00,5.00,5.00,5.00,5.00,5.00,5.00,5.00"
					( Origin gBackEnd )
				)
				( attribute "BBV_TO_THRUPIN_SPACING" "5.00,5.00,5.00,5.00,5.00,5.00,5.00,5.00,5.00,5.00,5.00,5.00,5.00,5.00"
					( Origin gBackEnd )
				)
				( attribute "THRUPIN_TO_BONDPAD_SPACING" "5.00,5.00,5.00,5.00,5.00,5.00,5.00,5.00,5.00,5.00,5.00,5.00,5.00,5.00"
					( Origin gBackEnd )
				)
				( attribute "LINE_TO_THRUPIN_SPACING" "4.50,4.00,4.00,4.00,4.00,4.00,4.00,4.00,4.00,4.00,4.00,4.00,4.00,4.50"
					( Origin gBackEnd )
				)
				( attribute "THRUPIN_TO_SHAPE_SPACING" "4.50,4.00,4.00,4.00,4.00,4.00,4.00,4.00,4.00,4.00,4.00,4.00,4.00,4.00"
					( Origin gBackEnd )
				)
				( attribute "SMDPIN_TO_SMDPIN_SPACING" "5.00,5.00,5.00,5.00,5.00,5.00,5.00,5.00,5.00,5.00,5.00,5.00,5.00,5.00"
					( Origin gBackEnd )
				)
				( attribute "SMDPIN_TO_TESTPIN_SPACING" "5.00,5.00,5.00,5.00,5.00,5.00,5.00,5.00,5.00,5.00,5.00,5.00,5.00,5.00"
					( Origin gBackEnd )
				)
				( attribute "SMDPIN_TO_THRUVIA_SPACING" "5.00,5.00,5.00,5.00,5.00,5.00,5.00,5.00,5.00,5.00,5.00,5.00,5.00,5.00"
					( Origin gBackEnd )
				)
				( attribute "SMDPIN_TO_TESTVIA_SPACING" "5.00,5.00,5.00,5.00,5.00,5.00,5.00,5.00,5.00,5.00,5.00,5.00,5.00,5.00"
					( Origin gBackEnd )
				)
				( attribute "BBV_TO_SMDPIN_SPACING" "5.00,5.00,5.00,5.00,5.00,5.00,5.00,5.00,5.00,5.00,5.00,5.00,5.00,5.00"
					( Origin gBackEnd )
				)
				( attribute "SMDPIN_TO_BONDPAD_SPACING" "5.00,5.00,5.00,5.00,5.00,5.00,5.00,5.00,5.00,5.00,5.00,5.00,5.00,5.00"
					( Origin gBackEnd )
				)
				( attribute "LINE_TO_SMDPIN_SPACING" "4.50,4.50,4.50,4.50,4.50,4.50,4.50,4.50,4.50,4.50,4.50,4.50,4.50,4.50"
					( Origin gBackEnd )
				)
				( attribute "SHAPE_TO_SMDPIN_SPACING" "5.00,5.00,5.00,5.00,5.00,5.00,5.00,5.00,5.00,5.00,5.00,5.00,5.00,5.00"
					( Origin gBackEnd )
				)
				( attribute "TESTPIN_TO_TESTPIN_SPACING" "5.00,5.00,5.00,5.00,5.00,5.00,5.00,5.00,5.00,5.00,5.00,5.00,5.00,5.00"
					( Origin gBackEnd )
				)
				( attribute "TESTPIN_TO_THRUVIA_SPACING" "5.00,5.00,5.00,5.00,5.00,5.00,5.00,5.00,5.00,5.00,5.00,5.00,5.00,5.00"
					( Origin gBackEnd )
				)
				( attribute "TESTPIN_TO_TESTVIA_SPACING" "5.00,5.00,5.00,5.00,5.00,5.00,5.00,5.00,5.00,5.00,5.00,5.00,5.00,5.00"
					( Origin gBackEnd )
				)
				( attribute "BBV_TO_TESTPIN_SPACING" "5.00,5.00,5.00,5.00,5.00,5.00,5.00,5.00,5.00,5.00,5.00,5.00,5.00,5.00"
					( Origin gBackEnd )
				)
				( attribute "BONDPAD_TO_TESTPIN_SPACING" "5.00,5.00,5.00,5.00,5.00,5.00,5.00,5.00,5.00,5.00,5.00,5.00,5.00,5.00"
					( Origin gBackEnd )
				)
				( attribute "LINE_TO_TESTPIN_SPACING" "4.50,5.00,5.00,5.00,5.00,5.00,5.00,5.00,5.00,5.00,5.00,5.00,5.00,5.00"
					( Origin gBackEnd )
				)
				( attribute "SHAPE_TO_TESTPIN_SPACING" "4.50,4.00,4.00,4.00,4.00,4.00,4.00,4.00,4.00,4.00,4.00,4.00,4.00,4.00"
					( Origin gBackEnd )
				)
				( attribute "THRUVIA_TO_THRUVIA_SPACING" "5.00,5.00,5.00,5.00,5.00,5.00,5.00,5.00,5.00,5.00,5.00,5.00,5.00,5.00"
					( Origin gBackEnd )
				)
				( attribute "TESTVIA_TO_THRUVIA_SPACING" "5.00,5.00,5.00,5.00,5.00,5.00,5.00,5.00,5.00,5.00,5.00,5.00,5.00,5.00"
					( Origin gBackEnd )
				)
				( attribute "BBV_TO_THRUVIA_SPACING" "5.00,5.00,5.00,5.00,5.00,5.00,5.00,5.00,5.00,5.00,5.00,5.00,5.00,5.00"
					( Origin gBackEnd )
				)
				( attribute "BONDPAD_TO_THRUVIA_SPACING" "5.00,5.00,5.00,5.00,5.00,5.00,5.00,5.00,5.00,5.00,5.00,5.00,5.00,5.00"
					( Origin gBackEnd )
				)
				( attribute "LINE_TO_THRUVIA_SPACING" "4.50,4.00,4.00,4.00,4.00,4.00,4.00,4.00,4.00,4.00,4.00,4.00,4.00,4.50"
					( Origin gBackEnd )
				)
				( attribute "SHAPE_TO_THRUVIA_SPACING" "4.50,4.00,4.00,4.00,4.00,4.00,4.00,4.00,4.00,4.00,4.00,4.00,4.00,4.00"
					( Origin gBackEnd )
				)
				( attribute "TESTVIA_TO_TESTVIA_SPACING" "5.00,5.00,5.00,5.00,5.00,5.00,5.00,5.00,5.00,5.00,5.00,5.00,5.00,5.00"
					( Origin gBackEnd )
				)
				( attribute "BBV_TO_TESTVIA_SPACING" "5.00,5.00,5.00,5.00,5.00,5.00,5.00,5.00,5.00,5.00,5.00,5.00,5.00,5.00"
					( Origin gBackEnd )
				)
				( attribute "BONDPAD_TO_TESTVIA_SPACING" "5.00,5.00,5.00,5.00,5.00,5.00,5.00,5.00,5.00,5.00,5.00,5.00,5.00,5.00"
					( Origin gBackEnd )
				)
				( attribute "LINE_TO_TESTVIA_SPACING" "4.50,5.00,4.00,5.00,4.00,5.00,5.00,5.00,5.00,4.00,5.00,4.00,5.00,4.50"
					( Origin gBackEnd )
				)
				( attribute "SHAPE_TO_TESTVIA_SPACING" "4.50,4.00,4.00,4.00,4.00,4.00,4.00,4.00,4.00,4.00,4.00,4.00,4.00,4.00"
					( Origin gBackEnd )
				)
				( attribute "BBV_TO_BBV_SPACING" "5.00,5.00,5.00,5.00,5.00,5.00,5.00,5.00,5.00,5.00,5.00,5.00,5.00,5.00"
					( Origin gBackEnd )
				)
				( attribute "BONDPAD_TO_BBV_SPACING" "5.00,5.00,5.00,5.00,5.00,5.00,5.00,5.00,5.00,5.00,5.00,5.00,5.00,5.00"
					( Origin gBackEnd )
				)
				( attribute "BBV_TO_LINE_SPACING" "5.00,5.00,5.00,5.00,5.00,5.00,5.00,5.00,5.00,5.00,5.00,5.00,5.00,5.00"
					( Origin gBackEnd )
				)
				( attribute "BBV_TO_SHAPE_SPACING" "5.00,5.00,5.00,5.00,5.00,5.00,5.00,5.00,5.00,5.00,5.00,5.00,5.00,5.00"
					( Origin gBackEnd )
				)
				( attribute "BONDPAD_TO_BONDPAD_SPACING" "5.00,5.00,5.00,5.00,5.00,5.00,5.00,5.00,5.00,5.00,5.00,5.00,5.00,5.00"
					( Origin gBackEnd )
				)
				( attribute "BONDPAD_TO_LINE_SPACING" "5.00,5.00,5.00,5.00,5.00,5.00,5.00,5.00,5.00,5.00,5.00,5.00,5.00,5.00"
					( Origin gBackEnd )
				)
				( attribute "BONDPAD_TO_SHAPE_SPACING" "5.00,5.00,5.00,5.00,5.00,5.00,5.00,5.00,5.00,5.00,5.00,5.00,5.00,5.00"
					( Origin gBackEnd )
				)
				( attribute "LINE_TO_LINE_SPACING" "4.00,4.00,4.00,4.00,4.00,4.00,4.00,4.00,4.00,4.00,4.00,4.00,4.00,4.00"
					( Origin gBackEnd )
				)
				( attribute "LINE_TO_SHAPE_SPACING" "5.00,5.00,5.00,5.00,5.00,5.00,5.00,5.00,5.00,5.00,5.00,5.00,5.00,5.00"
					( Origin gBackEnd )
				)
				( attribute "SHAPE_TO_SHAPE_SPACING" "10.00,10.00,10.00,10.00,10.00,10.00,10.00,10.00,10.00,10.00,10.00,10.00,10.00,10.00"
					( Origin gBackEnd )
				)
				( attribute "HOLE_TO_PIN_SPACING" "8.00,8.00,8.00,8.00,8.00,8.00,8.00,8.00,8.00,8.00,8.00,8.00,8.00,8.00"
					( Origin gBackEnd )
				)
				( attribute "HOLE_TO_VIA_SPACING" "8.00,8.00,8.00,8.00,8.00,8.00,8.00,8.00,8.00,8.00,8.00,8.00,8.00,8.00"
					( Origin gBackEnd )
				)
				( attribute "HOLE_TO_LINE_SPACING" "8.00,8.00,8.00,8.00,8.00,8.00,8.00,8.00,8.00,8.00,8.00,8.00,8.00,8.00"
					( Origin gBackEnd )
				)
				( attribute "HOLE_TO_SHAPE_SPACING" "8.00,8.00,8.00,8.00,8.00,8.00,8.00,8.00,8.00,8.00,8.00,8.00,8.00,8.00"
					( Origin gBackEnd )
				)
				( attribute "HOLE_TO_HOLE_SPACING" "8.00,8.00,8.00,8.00,8.00,8.00,8.00,8.00,8.00,8.00,8.00,8.00,8.00,8.00"
					( Origin gBackEnd )
				)
				( attribute "MVIA_TO_MVIA_SPACING" "5.00,5.00,5.00,5.00,5.00,5.00,5.00,5.00,5.00,5.00,5.00,5.00,5.00,5.00"
					( Origin gBackEnd )
				)
				( attribute "MVIA_TO_THRUPIN_SPACING" "5.00,5.00,5.00,5.00,5.00,5.00,5.00,5.00,5.00,5.00,5.00,5.00,5.00,5.00"
					( Origin gBackEnd )
				)
				( attribute "MVIA_TO_SMDPIN_SPACING" "5.00,5.00,5.00,5.00,5.00,5.00,5.00,5.00,5.00,5.00,5.00,5.00,5.00,5.00"
					( Origin gBackEnd )
				)
				( attribute "MVIA_TO_THRUVIA_SPACING" "5.00,5.00,5.00,5.00,5.00,5.00,5.00,5.00,5.00,5.00,5.00,5.00,5.00,5.00"
					( Origin gBackEnd )
				)
				( attribute "MVIA_TO_BBV_SPACING" "5.00,5.00,5.00,5.00,5.00,5.00,5.00,5.00,5.00,5.00,5.00,5.00,5.00,5.00"
					( Origin gBackEnd )
				)
				( attribute "MVIA_TO_LINE_SPACING" "5.00,5.00,5.00,5.00,5.00,5.00,5.00,5.00,5.00,5.00,5.00,5.00,5.00,5.00"
					( Origin gBackEnd )
				)
				( attribute "MVIA_TO_SHAPE_SPACING" "5.00,5.00,5.00,5.00,5.00,5.00,5.00,5.00,5.00,5.00,5.00,5.00,5.00,5.00"
					( Origin gBackEnd )
				)
				( attribute "MVIA_TO_TESTPIN_SPACING" "5.00,5.00,5.00,5.00,5.00,5.00,5.00,5.00,5.00,5.00,5.00,5.00,5.00,5.00"
					( Origin gBackEnd )
				)
				( attribute "MVIA_TO_TESTVIA_SPACING" "5.00,5.00,5.00,5.00,5.00,5.00,5.00,5.00,5.00,5.00,5.00,5.00,5.00,5.00"
					( Origin gBackEnd )
				)
				( attribute "BONDPAD_TO_MVIA_SPACING" "5.00,5.00,5.00,5.00,5.00,5.00,5.00,5.00,5.00,5.00,5.00,5.00,5.00,5.00"
					( Origin gBackEnd )
				)
				( attribute "MIN_BVIA_GAP" "5.00"
					( Origin gBackEnd )
				)
				( attribute "BONDPAD_TO_BONDPAD_DIFFP_SPC" "5.00,5.00,5.00,5.00,5.00,5.00,5.00,5.00,5.00,5.00,5.00,5.00,5.00,5.00"
					( Origin gBackEnd )
				)
				( objectStatus "4_MILS" )
			)
			( spacingCSet "@crescent_city_bb_fab1_lib.crescent_city_bb_fab1(sch_1):\11H_US_&_7H_SL_VIA+3H_A\"
				( attribute "THRUPIN_TO_THRUPIN_SPACING" "5.00,5.00,5.00,5.00,5.00,5.00,5.00,5.00,5.00,5.00,5.00,5.00,5.00,5.00"
					( Origin gBackEnd )
				)
				( attribute "THRUPIN_TO_SMDPIN_SPACING" "5.00,5.00,5.00,5.00,5.00,5.00,5.00,5.00,5.00,5.00,5.00,5.00,5.00,5.00"
					( Origin gBackEnd )
				)
				( attribute "TESTPIN_TO_THRUPIN_SPACING" "5.00,5.00,5.00,5.00,5.00,5.00,5.00,5.00,5.00,5.00,5.00,5.00,5.00,5.00"
					( Origin gBackEnd )
				)
				( attribute "THRUPIN_TO_THRUVIA_SPACING" "5.00,5.00,5.00,5.00,5.00,5.00,5.00,5.00,5.00,5.00,5.00,5.00,5.00,5.00"
					( Origin gBackEnd )
				)
				( attribute "TESTVIA_TO_THRUPIN_SPACING" "5.00,5.00,5.00,5.00,5.00,5.00,5.00,5.00,5.00,5.00,5.00,5.00,5.00,5.00"
					( Origin gBackEnd )
				)
				( attribute "BBV_TO_THRUPIN_SPACING" "5.00,5.00,5.00,5.00,5.00,5.00,5.00,5.00,5.00,5.00,5.00,5.00,5.00,5.00"
					( Origin gBackEnd )
				)
				( attribute "THRUPIN_TO_BONDPAD_SPACING" "5.00,5.00,5.00,5.00,5.00,5.00,5.00,5.00,5.00,5.00,5.00,5.00,5.00,5.00"
					( Origin gBackEnd )
				)
				( attribute "LINE_TO_THRUPIN_SPACING" "4.50,4.00,4.00,4.00,4.00,4.00,4.00,4.00,4.00,4.00,4.00,4.00,4.00,4.50"
					( Origin gBackEnd )
				)
				( attribute "THRUPIN_TO_SHAPE_SPACING" "4.50,4.00,4.00,4.00,4.00,4.00,4.00,4.00,4.00,4.00,4.00,4.00,4.00,4.00"
					( Origin gBackEnd )
				)
				( attribute "SMDPIN_TO_SMDPIN_SPACING" "5.00,5.00,5.00,5.00,5.00,5.00,5.00,5.00,5.00,5.00,5.00,5.00,5.00,5.00"
					( Origin gBackEnd )
				)
				( attribute "SMDPIN_TO_TESTPIN_SPACING" "5.00,5.00,5.00,5.00,5.00,5.00,5.00,5.00,5.00,5.00,5.00,5.00,5.00,5.00"
					( Origin gBackEnd )
				)
				( attribute "SMDPIN_TO_THRUVIA_SPACING" "5.00,5.00,5.00,5.00,5.00,5.00,5.00,5.00,5.00,5.00,5.00,5.00,5.00,5.00"
					( Origin gBackEnd )
				)
				( attribute "SMDPIN_TO_TESTVIA_SPACING" "5.00,5.00,5.00,5.00,5.00,5.00,5.00,5.00,5.00,5.00,5.00,5.00,5.00,5.00"
					( Origin gBackEnd )
				)
				( attribute "BBV_TO_SMDPIN_SPACING" "5.00,5.00,5.00,5.00,5.00,5.00,5.00,5.00,5.00,5.00,5.00,5.00,5.00,5.00"
					( Origin gBackEnd )
				)
				( attribute "SMDPIN_TO_BONDPAD_SPACING" "5.00,5.00,5.00,5.00,5.00,5.00,5.00,5.00,5.00,5.00,5.00,5.00,5.00,5.00"
					( Origin gBackEnd )
				)
				( attribute "LINE_TO_SMDPIN_SPACING" "4.50,4.50,4.50,4.50,4.50,4.50,4.50,4.50,4.50,4.50,4.50,4.50,4.50,4.50"
					( Origin gBackEnd )
				)
				( attribute "SHAPE_TO_SMDPIN_SPACING" "5.00,5.00,5.00,5.00,5.00,5.00,5.00,5.00,5.00,5.00,5.00,5.00,5.00,5.00"
					( Origin gBackEnd )
				)
				( attribute "TESTPIN_TO_TESTPIN_SPACING" "5.00,5.00,5.00,5.00,5.00,5.00,5.00,5.00,5.00,5.00,5.00,5.00,5.00,5.00"
					( Origin gBackEnd )
				)
				( attribute "TESTPIN_TO_THRUVIA_SPACING" "5.00,5.00,5.00,5.00,5.00,5.00,5.00,5.00,5.00,5.00,5.00,5.00,5.00,5.00"
					( Origin gBackEnd )
				)
				( attribute "TESTPIN_TO_TESTVIA_SPACING" "5.00,5.00,5.00,5.00,5.00,5.00,5.00,5.00,5.00,5.00,5.00,5.00,5.00,5.00"
					( Origin gBackEnd )
				)
				( attribute "BBV_TO_TESTPIN_SPACING" "5.00,5.00,5.00,5.00,5.00,5.00,5.00,5.00,5.00,5.00,5.00,5.00,5.00,5.00"
					( Origin gBackEnd )
				)
				( attribute "BONDPAD_TO_TESTPIN_SPACING" "5.00,5.00,5.00,5.00,5.00,5.00,5.00,5.00,5.00,5.00,5.00,5.00,5.00,5.00"
					( Origin gBackEnd )
				)
				( attribute "LINE_TO_TESTPIN_SPACING" "4.50,5.00,5.00,5.00,5.00,5.00,5.00,5.00,5.00,5.00,5.00,5.00,5.00,5.00"
					( Origin gBackEnd )
				)
				( attribute "SHAPE_TO_TESTPIN_SPACING" "4.50,4.00,4.00,4.00,4.00,4.00,4.00,4.00,4.00,4.00,4.00,4.00,4.00,4.00"
					( Origin gBackEnd )
				)
				( attribute "THRUVIA_TO_THRUVIA_SPACING" "5.00,5.00,5.00,5.00,5.00,5.00,5.00,5.00,5.00,5.00,5.00,5.00,5.00,5.00"
					( Origin gBackEnd )
				)
				( attribute "TESTVIA_TO_THRUVIA_SPACING" "5.00,5.00,5.00,5.00,5.00,5.00,5.00,5.00,5.00,5.00,5.00,5.00,5.00,5.00"
					( Origin gBackEnd )
				)
				( attribute "BBV_TO_THRUVIA_SPACING" "5.00,5.00,5.00,5.00,5.00,5.00,5.00,5.00,5.00,5.00,5.00,5.00,5.00,5.00"
					( Origin gBackEnd )
				)
				( attribute "BONDPAD_TO_THRUVIA_SPACING" "5.00,5.00,5.00,5.00,5.00,5.00,5.00,5.00,5.00,5.00,5.00,5.00,5.00,5.00"
					( Origin gBackEnd )
				)
				( attribute "LINE_TO_THRUVIA_SPACING" "12.00,5.00,13.00,5.00,13.00,5.00,5.00,5.00,5.00,13.00,5.00,13.00,5.00,12.00"
					( Origin gBackEnd )
				)
				( attribute "SHAPE_TO_THRUVIA_SPACING" "4.50,4.00,4.00,4.00,4.00,4.00,4.00,4.00,4.00,4.00,4.00,4.00,4.00,4.00"
					( Origin gBackEnd )
				)
				( attribute "TESTVIA_TO_TESTVIA_SPACING" "5.00,5.00,5.00,5.00,5.00,5.00,5.00,5.00,5.00,5.00,5.00,5.00,5.00,5.00"
					( Origin gBackEnd )
				)
				( attribute "BBV_TO_TESTVIA_SPACING" "5.00,5.00,5.00,5.00,5.00,5.00,5.00,5.00,5.00,5.00,5.00,5.00,5.00,5.00"
					( Origin gBackEnd )
				)
				( attribute "BONDPAD_TO_TESTVIA_SPACING" "5.00,5.00,5.00,5.00,5.00,5.00,5.00,5.00,5.00,5.00,5.00,5.00,5.00,5.00"
					( Origin gBackEnd )
				)
				( attribute "LINE_TO_TESTVIA_SPACING" "12.00,5.00,13.00,5.00,13.00,5.00,5.00,5.00,5.00,13.00,5.00,13.00,5.00,12.00"
					( Origin gBackEnd )
				)
				( attribute "SHAPE_TO_TESTVIA_SPACING" "4.50,4.00,4.00,4.00,4.00,4.00,4.00,4.00,4.00,4.00,4.00,4.00,4.00,4.00"
					( Origin gBackEnd )
				)
				( attribute "BBV_TO_BBV_SPACING" "5.00,5.00,5.00,5.00,5.00,5.00,5.00,5.00,5.00,5.00,5.00,5.00,5.00,5.00"
					( Origin gBackEnd )
				)
				( attribute "BONDPAD_TO_BBV_SPACING" "5.00,5.00,5.00,5.00,5.00,5.00,5.00,5.00,5.00,5.00,5.00,5.00,5.00,5.00"
					( Origin gBackEnd )
				)
				( attribute "BBV_TO_LINE_SPACING" "5.00,5.00,5.00,5.00,5.00,5.00,5.00,5.00,5.00,5.00,5.00,5.00,5.00,5.00"
					( Origin gBackEnd )
				)
				( attribute "BBV_TO_SHAPE_SPACING" "5.00,5.00,5.00,5.00,5.00,5.00,5.00,5.00,5.00,5.00,5.00,5.00,5.00,5.00"
					( Origin gBackEnd )
				)
				( attribute "BONDPAD_TO_BONDPAD_SPACING" "5.00,5.00,5.00,5.00,5.00,5.00,5.00,5.00,5.00,5.00,5.00,5.00,5.00,5.00"
					( Origin gBackEnd )
				)
				( attribute "BONDPAD_TO_LINE_SPACING" "5.00,5.00,5.00,5.00,5.00,5.00,5.00,5.00,5.00,5.00,5.00,5.00,5.00,5.00"
					( Origin gBackEnd )
				)
				( attribute "BONDPAD_TO_SHAPE_SPACING" "5.00,5.00,5.00,5.00,5.00,5.00,5.00,5.00,5.00,5.00,5.00,5.00,5.00,5.00"
					( Origin gBackEnd )
				)
				( attribute "LINE_TO_LINE_SPACING" "29.37,21.00,21.00,21.00,21.00,21.00,21.00,21.00,21.00,21.00,21.00,21.00,21.00,29.37"
					( Origin gBackEnd )
				)
				( attribute "LINE_TO_SHAPE_SPACING" "5.00,5.00,5.00,5.00,5.00,5.00,5.00,5.00,5.00,5.00,5.00,5.00,5.00,5.00"
					( Origin gBackEnd )
				)
				( attribute "SHAPE_TO_SHAPE_SPACING" "10.00,10.00,10.00,10.00,10.00,10.00,10.00,10.00,10.00,10.00,10.00,10.00,10.00,10.00"
					( Origin gBackEnd )
				)
				( attribute "HOLE_TO_PIN_SPACING" "8.00,8.00,8.00,8.00,8.00,8.00,8.00,8.00,8.00,8.00,8.00,8.00,8.00,8.00"
					( Origin gBackEnd )
				)
				( attribute "HOLE_TO_VIA_SPACING" "8.00,8.00,8.00,8.00,8.00,8.00,8.00,8.00,8.00,8.00,8.00,8.00,8.00,8.00"
					( Origin gBackEnd )
				)
				( attribute "HOLE_TO_LINE_SPACING" "8.00,8.00,8.00,8.00,8.00,8.00,8.00,8.00,8.00,8.00,8.00,8.00,8.00,8.00"
					( Origin gBackEnd )
				)
				( attribute "HOLE_TO_SHAPE_SPACING" "8.00,8.00,8.00,8.00,8.00,8.00,8.00,8.00,8.00,8.00,8.00,8.00,8.00,8.00"
					( Origin gBackEnd )
				)
				( attribute "HOLE_TO_HOLE_SPACING" "8.00,8.00,8.00,8.00,8.00,8.00,8.00,8.00,8.00,8.00,8.00,8.00,8.00,8.00"
					( Origin gBackEnd )
				)
				( attribute "MVIA_TO_MVIA_SPACING" "5.00,5.00,5.00,5.00,5.00,5.00,5.00,5.00,5.00,5.00,5.00,5.00,5.00,5.00"
					( Origin gBackEnd )
				)
				( attribute "MVIA_TO_THRUPIN_SPACING" "5.00,5.00,5.00,5.00,5.00,5.00,5.00,5.00,5.00,5.00,5.00,5.00,5.00,5.00"
					( Origin gBackEnd )
				)
				( attribute "MVIA_TO_SMDPIN_SPACING" "5.00,5.00,5.00,5.00,5.00,5.00,5.00,5.00,5.00,5.00,5.00,5.00,5.00,5.00"
					( Origin gBackEnd )
				)
				( attribute "MVIA_TO_THRUVIA_SPACING" "5.00,5.00,5.00,5.00,5.00,5.00,5.00,5.00,5.00,5.00,5.00,5.00,5.00,5.00"
					( Origin gBackEnd )
				)
				( attribute "MVIA_TO_BBV_SPACING" "5.00,5.00,5.00,5.00,5.00,5.00,5.00,5.00,5.00,5.00,5.00,5.00,5.00,5.00"
					( Origin gBackEnd )
				)
				( attribute "MVIA_TO_LINE_SPACING" "5.00,5.00,5.00,5.00,5.00,5.00,5.00,5.00,5.00,5.00,5.00,5.00,5.00,5.00"
					( Origin gBackEnd )
				)
				( attribute "MVIA_TO_SHAPE_SPACING" "5.00,5.00,5.00,5.00,5.00,5.00,5.00,5.00,5.00,5.00,5.00,5.00,5.00,5.00"
					( Origin gBackEnd )
				)
				( attribute "MVIA_TO_TESTPIN_SPACING" "5.00,5.00,5.00,5.00,5.00,5.00,5.00,5.00,5.00,5.00,5.00,5.00,5.00,5.00"
					( Origin gBackEnd )
				)
				( attribute "MVIA_TO_TESTVIA_SPACING" "5.00,5.00,5.00,5.00,5.00,5.00,5.00,5.00,5.00,5.00,5.00,5.00,5.00,5.00"
					( Origin gBackEnd )
				)
				( attribute "BONDPAD_TO_MVIA_SPACING" "5.00,5.00,5.00,5.00,5.00,5.00,5.00,5.00,5.00,5.00,5.00,5.00,5.00,5.00"
					( Origin gBackEnd )
				)
				( attribute "MIN_BVIA_GAP" "5.00"
					( Origin gBackEnd )
				)
				( attribute "BONDPAD_TO_BONDPAD_DIFFP_SPC" "5.00,5.00,5.00,5.00,5.00,5.00,5.00,5.00,5.00,5.00,5.00,5.00,5.00,5.00"
					( Origin gBackEnd )
				)
				( objectStatus "11H_US_&_7H_SL_VIA_3H+A" )
			)
			( spacingCSet "@crescent_city_bb_fab1_lib.crescent_city_bb_fab1(sch_1):\19MIL_US_&_15MIL_SL\"
				( attribute "THRUPIN_TO_THRUPIN_SPACING" "5.00,5.00,5.00,5.00,5.00,5.00,5.00,5.00,5.00,5.00,5.00,5.00,5.00,5.00"
					( Origin gBackEnd )
				)
				( attribute "THRUPIN_TO_SMDPIN_SPACING" "5.00,5.00,5.00,5.00,5.00,5.00,5.00,5.00,5.00,5.00,5.00,5.00,5.00,5.00"
					( Origin gBackEnd )
				)
				( attribute "TESTPIN_TO_THRUPIN_SPACING" "5.00,5.00,5.00,5.00,5.00,5.00,5.00,5.00,5.00,5.00,5.00,5.00,5.00,5.00"
					( Origin gBackEnd )
				)
				( attribute "THRUPIN_TO_THRUVIA_SPACING" "5.00,5.00,5.00,5.00,5.00,5.00,5.00,5.00,5.00,5.00,5.00,5.00,5.00,5.00"
					( Origin gBackEnd )
				)
				( attribute "TESTVIA_TO_THRUPIN_SPACING" "5.00,5.00,5.00,5.00,5.00,5.00,5.00,5.00,5.00,5.00,5.00,5.00,5.00,5.00"
					( Origin gBackEnd )
				)
				( attribute "BBV_TO_THRUPIN_SPACING" "5.00,5.00,5.00,5.00,5.00,5.00,5.00,5.00,5.00,5.00,5.00,5.00,5.00,5.00"
					( Origin gBackEnd )
				)
				( attribute "THRUPIN_TO_BONDPAD_SPACING" "5.00,5.00,5.00,5.00,5.00,5.00,5.00,5.00,5.00,5.00,5.00,5.00,5.00,5.00"
					( Origin gBackEnd )
				)
				( attribute "LINE_TO_THRUPIN_SPACING" "4.50,4.00,4.00,4.00,4.00,4.00,4.00,4.00,4.00,4.00,4.00,4.00,4.00,4.50"
					( Origin gBackEnd )
				)
				( attribute "THRUPIN_TO_SHAPE_SPACING" "4.50,4.00,4.00,4.00,4.00,4.00,4.00,4.00,4.00,4.00,4.00,4.00,4.00,4.00"
					( Origin gBackEnd )
				)
				( attribute "SMDPIN_TO_SMDPIN_SPACING" "5.00,5.00,5.00,5.00,5.00,5.00,5.00,5.00,5.00,5.00,5.00,5.00,5.00,5.00"
					( Origin gBackEnd )
				)
				( attribute "SMDPIN_TO_TESTPIN_SPACING" "5.00,5.00,5.00,5.00,5.00,5.00,5.00,5.00,5.00,5.00,5.00,5.00,5.00,25.00"
					( Origin gBackEnd )
				)
				( attribute "SMDPIN_TO_THRUVIA_SPACING" "5.00,5.00,5.00,5.00,5.00,5.00,5.00,5.00,5.00,5.00,5.00,5.00,5.00,5.00"
					( Origin gBackEnd )
				)
				( attribute "SMDPIN_TO_TESTVIA_SPACING" "5.00,5.00,5.00,5.00,5.00,5.00,5.00,5.00,5.00,5.00,5.00,5.00,5.00,5.00"
					( Origin gBackEnd )
				)
				( attribute "BBV_TO_SMDPIN_SPACING" "5.00,5.00,5.00,5.00,5.00,5.00,5.00,5.00,5.00,5.00,5.00,5.00,5.00,5.00"
					( Origin gBackEnd )
				)
				( attribute "SMDPIN_TO_BONDPAD_SPACING" "5.00,5.00,5.00,5.00,5.00,5.00,5.00,5.00,5.00,5.00,5.00,5.00,5.00,5.00"
					( Origin gBackEnd )
				)
				( attribute "LINE_TO_SMDPIN_SPACING" "4.50,4.50,4.50,4.50,4.50,4.50,4.50,4.50,4.50,4.50,4.50,4.50,4.50,4.50"
					( Origin gBackEnd )
				)
				( attribute "SHAPE_TO_SMDPIN_SPACING" "5.00,5.00,5.00,5.00,5.00,5.00,5.00,5.00,5.00,5.00,5.00,5.00,5.00,5.00"
					( Origin gBackEnd )
				)
				( attribute "TESTPIN_TO_TESTPIN_SPACING" "5.00,5.00,5.00,5.00,5.00,5.00,5.00,5.00,5.00,5.00,5.00,5.00,5.00,5.00"
					( Origin gBackEnd )
				)
				( attribute "TESTPIN_TO_THRUVIA_SPACING" "5.00,5.00,5.00,5.00,5.00,5.00,5.00,5.00,5.00,5.00,5.00,5.00,5.00,5.00"
					( Origin gBackEnd )
				)
				( attribute "TESTPIN_TO_TESTVIA_SPACING" "5.00,5.00,5.00,5.00,5.00,5.00,5.00,5.00,5.00,5.00,5.00,5.00,5.00,5.00"
					( Origin gBackEnd )
				)
				( attribute "BBV_TO_TESTPIN_SPACING" "5.00,5.00,5.00,5.00,5.00,5.00,5.00,5.00,5.00,5.00,5.00,5.00,5.00,5.00"
					( Origin gBackEnd )
				)
				( attribute "BONDPAD_TO_TESTPIN_SPACING" "5.00,5.00,5.00,5.00,5.00,5.00,5.00,5.00,5.00,5.00,5.00,5.00,5.00,5.00"
					( Origin gBackEnd )
				)
				( attribute "LINE_TO_TESTPIN_SPACING" "4.50,5.00,5.00,5.00,5.00,5.00,5.00,5.00,5.00,5.00,5.00,5.00,5.00,5.00"
					( Origin gBackEnd )
				)
				( attribute "SHAPE_TO_TESTPIN_SPACING" "4.50,4.00,4.00,4.00,4.00,4.00,4.00,4.00,4.00,4.00,4.00,4.00,4.00,4.00"
					( Origin gBackEnd )
				)
				( attribute "THRUVIA_TO_THRUVIA_SPACING" "5.00,5.00,5.00,5.00,5.00,5.00,5.00,5.00,5.00,5.00,5.00,5.00,5.00,5.00"
					( Origin gBackEnd )
				)
				( attribute "TESTVIA_TO_THRUVIA_SPACING" "5.00,5.00,5.00,5.00,5.00,5.00,5.00,5.00,5.00,5.00,5.00,5.00,5.00,5.00"
					( Origin gBackEnd )
				)
				( attribute "BBV_TO_THRUVIA_SPACING" "5.00,5.00,5.00,5.00,5.00,5.00,5.00,5.00,5.00,5.00,5.00,5.00,5.00,5.00"
					( Origin gBackEnd )
				)
				( attribute "BONDPAD_TO_THRUVIA_SPACING" "5.00,5.00,5.00,5.00,5.00,5.00,5.00,5.00,5.00,5.00,5.00,5.00,5.00,5.00"
					( Origin gBackEnd )
				)
				( attribute "LINE_TO_THRUVIA_SPACING" "4.50,4.00,4.00,4.00,4.00,4.00,4.00,4.00,4.00,4.00,4.00,4.00,4.00,4.50"
					( Origin gBackEnd )
				)
				( attribute "SHAPE_TO_THRUVIA_SPACING" "4.50,4.00,4.00,4.00,4.00,4.00,4.00,4.00,4.00,4.00,4.00,4.00,4.00,4.00"
					( Origin gBackEnd )
				)
				( attribute "TESTVIA_TO_TESTVIA_SPACING" "5.00,5.00,5.00,5.00,5.00,5.00,5.00,5.00,5.00,5.00,5.00,5.00,5.00,5.00"
					( Origin gBackEnd )
				)
				( attribute "BBV_TO_TESTVIA_SPACING" "5.00,5.00,5.00,5.00,5.00,5.00,5.00,5.00,5.00,5.00,5.00,5.00,5.00,5.00"
					( Origin gBackEnd )
				)
				( attribute "BONDPAD_TO_TESTVIA_SPACING" "5.00,5.00,5.00,5.00,5.00,5.00,5.00,5.00,5.00,5.00,5.00,5.00,5.00,5.00"
					( Origin gBackEnd )
				)
				( attribute "LINE_TO_TESTVIA_SPACING" "4.50,5.00,4.00,5.00,4.00,5.00,5.00,5.00,5.00,4.00,5.00,4.00,5.00,4.50"
					( Origin gBackEnd )
				)
				( attribute "SHAPE_TO_TESTVIA_SPACING" "4.50,4.00,4.00,4.00,4.00,4.00,4.00,4.00,4.00,4.00,4.00,4.00,4.00,4.00"
					( Origin gBackEnd )
				)
				( attribute "BBV_TO_BBV_SPACING" "5.00,5.00,5.00,5.00,5.00,5.00,5.00,5.00,5.00,5.00,5.00,5.00,5.00,5.00"
					( Origin gBackEnd )
				)
				( attribute "BONDPAD_TO_BBV_SPACING" "5.00,5.00,5.00,5.00,5.00,5.00,5.00,5.00,5.00,5.00,5.00,5.00,5.00,5.00"
					( Origin gBackEnd )
				)
				( attribute "BBV_TO_LINE_SPACING" "5.00,5.00,5.00,5.00,5.00,5.00,5.00,5.00,5.00,5.00,5.00,5.00,5.00,5.00"
					( Origin gBackEnd )
				)
				( attribute "BBV_TO_SHAPE_SPACING" "5.00,5.00,5.00,5.00,5.00,5.00,5.00,5.00,5.00,5.00,5.00,5.00,5.00,5.00"
					( Origin gBackEnd )
				)
				( attribute "BONDPAD_TO_BONDPAD_SPACING" "5.00,5.00,5.00,5.00,5.00,5.00,5.00,5.00,5.00,5.00,5.00,5.00,5.00,5.00"
					( Origin gBackEnd )
				)
				( attribute "BONDPAD_TO_LINE_SPACING" "5.00,5.00,5.00,5.00,5.00,5.00,5.00,5.00,5.00,5.00,5.00,5.00,5.00,5.00"
					( Origin gBackEnd )
				)
				( attribute "BONDPAD_TO_SHAPE_SPACING" "5.00,5.00,5.00,5.00,5.00,5.00,5.00,5.00,5.00,5.00,5.00,5.00,5.00,5.00"
					( Origin gBackEnd )
				)
				( attribute "LINE_TO_LINE_SPACING" "19.00,15.00,15.00,15.00,15.00,15.00,15.00,15.00,15.00,15.00,15.00,15.00,15.00,19.00"
					( Origin gBackEnd )
				)
				( attribute "LINE_TO_SHAPE_SPACING" "5.00,5.00,5.00,5.00,5.00,5.00,5.00,5.00,5.00,5.00,5.00,5.00,5.00,5.00"
					( Origin gBackEnd )
				)
				( attribute "SHAPE_TO_SHAPE_SPACING" "10.00,10.00,10.00,10.00,10.00,10.00,10.00,10.00,10.00,10.00,10.00,10.00,10.00,10.00"
					( Origin gBackEnd )
				)
				( attribute "HOLE_TO_PIN_SPACING" "8.00,8.00,8.00,8.00,8.00,8.00,8.00,8.00,8.00,8.00,8.00,8.00,8.00,8.00"
					( Origin gBackEnd )
				)
				( attribute "HOLE_TO_VIA_SPACING" "8.00,8.00,8.00,8.00,8.00,8.00,8.00,8.00,8.00,8.00,8.00,8.00,8.00,8.00"
					( Origin gBackEnd )
				)
				( attribute "HOLE_TO_LINE_SPACING" "8.00,8.00,8.00,8.00,8.00,8.00,8.00,8.00,8.00,8.00,8.00,8.00,8.00,8.00"
					( Origin gBackEnd )
				)
				( attribute "HOLE_TO_SHAPE_SPACING" "8.00,8.00,8.00,8.00,8.00,8.00,8.00,8.00,8.00,8.00,8.00,8.00,8.00,8.00"
					( Origin gBackEnd )
				)
				( attribute "HOLE_TO_HOLE_SPACING" "8.00,8.00,8.00,8.00,8.00,8.00,8.00,8.00,8.00,8.00,8.00,8.00,8.00,8.00"
					( Origin gBackEnd )
				)
				( attribute "MVIA_TO_MVIA_SPACING" "5.00,5.00,5.00,5.00,5.00,5.00,5.00,5.00,5.00,5.00,5.00,5.00,5.00,5.00"
					( Origin gBackEnd )
				)
				( attribute "MVIA_TO_THRUPIN_SPACING" "5.00,5.00,5.00,5.00,5.00,5.00,5.00,5.00,5.00,5.00,5.00,5.00,5.00,5.00"
					( Origin gBackEnd )
				)
				( attribute "MVIA_TO_SMDPIN_SPACING" "5.00,5.00,5.00,5.00,5.00,5.00,5.00,5.00,5.00,5.00,5.00,5.00,5.00,5.00"
					( Origin gBackEnd )
				)
				( attribute "MVIA_TO_THRUVIA_SPACING" "5.00,5.00,5.00,5.00,5.00,5.00,5.00,5.00,5.00,5.00,5.00,5.00,5.00,5.00"
					( Origin gBackEnd )
				)
				( attribute "MVIA_TO_BBV_SPACING" "5.00,5.00,5.00,5.00,5.00,5.00,5.00,5.00,5.00,5.00,5.00,5.00,5.00,5.00"
					( Origin gBackEnd )
				)
				( attribute "MVIA_TO_LINE_SPACING" "5.00,5.00,5.00,5.00,5.00,5.00,5.00,5.00,5.00,5.00,5.00,5.00,5.00,5.00"
					( Origin gBackEnd )
				)
				( attribute "MVIA_TO_SHAPE_SPACING" "5.00,5.00,5.00,5.00,5.00,5.00,5.00,5.00,5.00,5.00,5.00,5.00,5.00,5.00"
					( Origin gBackEnd )
				)
				( attribute "MVIA_TO_TESTPIN_SPACING" "5.00,5.00,5.00,5.00,5.00,5.00,5.00,5.00,5.00,5.00,5.00,5.00,5.00,5.00"
					( Origin gBackEnd )
				)
				( attribute "MVIA_TO_TESTVIA_SPACING" "5.00,5.00,5.00,5.00,5.00,5.00,5.00,5.00,5.00,5.00,5.00,5.00,5.00,5.00"
					( Origin gBackEnd )
				)
				( attribute "BONDPAD_TO_MVIA_SPACING" "5.00,5.00,5.00,5.00,5.00,5.00,5.00,5.00,5.00,5.00,5.00,5.00,5.00,5.00"
					( Origin gBackEnd )
				)
				( attribute "MIN_BVIA_GAP" "5.00"
					( Origin gBackEnd )
				)
				( attribute "BONDPAD_TO_BONDPAD_DIFFP_SPC" "5.00,5.00,5.00,5.00,5.00,5.00,5.00,5.00,5.00,5.00,5.00,5.00,5.00,5.00"
					( Origin gBackEnd )
				)
				( objectStatus "19MIL_US_&_15MIL_SL" )
			)
			( spacingCSet "@crescent_city_bb_fab1_lib.crescent_city_bb_fab1(sch_1):\24MIL_US_&_21MIL_SL\"
				( attribute "THRUPIN_TO_THRUPIN_SPACING" "5.00,5.00,5.00,5.00,5.00,5.00,5.00,5.00,5.00,5.00,5.00,5.00,5.00,5.00"
					( Origin gBackEnd )
				)
				( attribute "THRUPIN_TO_SMDPIN_SPACING" "5.00,5.00,5.00,5.00,5.00,5.00,5.00,5.00,5.00,5.00,5.00,5.00,5.00,5.00"
					( Origin gBackEnd )
				)
				( attribute "TESTPIN_TO_THRUPIN_SPACING" "5.00,5.00,5.00,5.00,5.00,5.00,5.00,5.00,5.00,5.00,5.00,5.00,5.00,5.00"
					( Origin gBackEnd )
				)
				( attribute "THRUPIN_TO_THRUVIA_SPACING" "5.00,5.00,5.00,5.00,5.00,5.00,5.00,5.00,5.00,5.00,5.00,5.00,5.00,5.00"
					( Origin gBackEnd )
				)
				( attribute "TESTVIA_TO_THRUPIN_SPACING" "5.00,5.00,5.00,5.00,5.00,5.00,5.00,5.00,5.00,5.00,5.00,5.00,5.00,5.00"
					( Origin gBackEnd )
				)
				( attribute "BBV_TO_THRUPIN_SPACING" "5.00,5.00,5.00,5.00,5.00,5.00,5.00,5.00,5.00,5.00,5.00,5.00,5.00,5.00"
					( Origin gBackEnd )
				)
				( attribute "THRUPIN_TO_BONDPAD_SPACING" "5.00,5.00,5.00,5.00,5.00,5.00,5.00,5.00,5.00,5.00,5.00,5.00,5.00,5.00"
					( Origin gBackEnd )
				)
				( attribute "LINE_TO_THRUPIN_SPACING" "4.50,4.00,4.00,4.00,4.00,4.00,4.00,4.00,4.00,4.00,4.00,4.00,4.00,4.50"
					( Origin gBackEnd )
				)
				( attribute "THRUPIN_TO_SHAPE_SPACING" "4.50,4.00,4.00,4.00,4.00,4.00,4.00,4.00,4.00,4.00,4.00,4.00,4.00,4.00"
					( Origin gBackEnd )
				)
				( attribute "SMDPIN_TO_SMDPIN_SPACING" "5.00,5.00,5.00,5.00,5.00,5.00,5.00,5.00,5.00,5.00,5.00,5.00,5.00,5.00"
					( Origin gBackEnd )
				)
				( attribute "SMDPIN_TO_TESTPIN_SPACING" "5.00,5.00,5.00,5.00,5.00,5.00,5.00,5.00,5.00,5.00,5.00,5.00,5.00,25.00"
					( Origin gBackEnd )
				)
				( attribute "SMDPIN_TO_THRUVIA_SPACING" "5.00,5.00,5.00,5.00,5.00,5.00,5.00,5.00,5.00,5.00,5.00,5.00,5.00,5.00"
					( Origin gBackEnd )
				)
				( attribute "SMDPIN_TO_TESTVIA_SPACING" "5.00,5.00,5.00,5.00,5.00,5.00,5.00,5.00,5.00,5.00,5.00,5.00,5.00,5.00"
					( Origin gBackEnd )
				)
				( attribute "BBV_TO_SMDPIN_SPACING" "5.00,5.00,5.00,5.00,5.00,5.00,5.00,5.00,5.00,5.00,5.00,5.00,5.00,5.00"
					( Origin gBackEnd )
				)
				( attribute "SMDPIN_TO_BONDPAD_SPACING" "5.00,5.00,5.00,5.00,5.00,5.00,5.00,5.00,5.00,5.00,5.00,5.00,5.00,5.00"
					( Origin gBackEnd )
				)
				( attribute "LINE_TO_SMDPIN_SPACING" "4.50,4.50,4.50,4.50,4.50,4.50,4.50,4.50,4.50,4.50,4.50,4.50,4.50,4.50"
					( Origin gBackEnd )
				)
				( attribute "SHAPE_TO_SMDPIN_SPACING" "5.00,5.00,5.00,5.00,5.00,5.00,5.00,5.00,5.00,5.00,5.00,5.00,5.00,5.00"
					( Origin gBackEnd )
				)
				( attribute "TESTPIN_TO_TESTPIN_SPACING" "5.00,5.00,5.00,5.00,5.00,5.00,5.00,5.00,5.00,5.00,5.00,5.00,5.00,5.00"
					( Origin gBackEnd )
				)
				( attribute "TESTPIN_TO_THRUVIA_SPACING" "5.00,5.00,5.00,5.00,5.00,5.00,5.00,5.00,5.00,5.00,5.00,5.00,5.00,5.00"
					( Origin gBackEnd )
				)
				( attribute "TESTPIN_TO_TESTVIA_SPACING" "5.00,5.00,5.00,5.00,5.00,5.00,5.00,5.00,5.00,5.00,5.00,5.00,5.00,5.00"
					( Origin gBackEnd )
				)
				( attribute "BBV_TO_TESTPIN_SPACING" "5.00,5.00,5.00,5.00,5.00,5.00,5.00,5.00,5.00,5.00,5.00,5.00,5.00,5.00"
					( Origin gBackEnd )
				)
				( attribute "BONDPAD_TO_TESTPIN_SPACING" "5.00,5.00,5.00,5.00,5.00,5.00,5.00,5.00,5.00,5.00,5.00,5.00,5.00,5.00"
					( Origin gBackEnd )
				)
				( attribute "LINE_TO_TESTPIN_SPACING" "4.50,5.00,5.00,5.00,5.00,5.00,5.00,5.00,5.00,5.00,5.00,5.00,5.00,5.00"
					( Origin gBackEnd )
				)
				( attribute "SHAPE_TO_TESTPIN_SPACING" "4.50,4.00,4.00,4.00,4.00,4.00,4.00,4.00,4.00,4.00,4.00,4.00,4.00,4.00"
					( Origin gBackEnd )
				)
				( attribute "THRUVIA_TO_THRUVIA_SPACING" "5.00,5.00,5.00,5.00,5.00,5.00,5.00,5.00,5.00,5.00,5.00,5.00,5.00,5.00"
					( Origin gBackEnd )
				)
				( attribute "TESTVIA_TO_THRUVIA_SPACING" "5.00,5.00,5.00,5.00,5.00,5.00,5.00,5.00,5.00,5.00,5.00,5.00,5.00,5.00"
					( Origin gBackEnd )
				)
				( attribute "BBV_TO_THRUVIA_SPACING" "5.00,5.00,5.00,5.00,5.00,5.00,5.00,5.00,5.00,5.00,5.00,5.00,5.00,5.00"
					( Origin gBackEnd )
				)
				( attribute "BONDPAD_TO_THRUVIA_SPACING" "5.00,5.00,5.00,5.00,5.00,5.00,5.00,5.00,5.00,5.00,5.00,5.00,5.00,5.00"
					( Origin gBackEnd )
				)
				( attribute "LINE_TO_THRUVIA_SPACING" "4.50,4.00,4.00,4.00,4.00,4.00,4.00,4.00,4.00,4.00,4.00,4.00,4.00,4.50"
					( Origin gBackEnd )
				)
				( attribute "SHAPE_TO_THRUVIA_SPACING" "4.50,4.00,4.00,4.00,4.00,4.00,4.00,4.00,4.00,4.00,4.00,4.00,4.00,4.00"
					( Origin gBackEnd )
				)
				( attribute "TESTVIA_TO_TESTVIA_SPACING" "5.00,5.00,5.00,5.00,5.00,5.00,5.00,5.00,5.00,5.00,5.00,5.00,5.00,5.00"
					( Origin gBackEnd )
				)
				( attribute "BBV_TO_TESTVIA_SPACING" "5.00,5.00,5.00,5.00,5.00,5.00,5.00,5.00,5.00,5.00,5.00,5.00,5.00,5.00"
					( Origin gBackEnd )
				)
				( attribute "BONDPAD_TO_TESTVIA_SPACING" "5.00,5.00,5.00,5.00,5.00,5.00,5.00,5.00,5.00,5.00,5.00,5.00,5.00,5.00"
					( Origin gBackEnd )
				)
				( attribute "LINE_TO_TESTVIA_SPACING" "4.50,5.00,4.00,5.00,4.00,5.00,5.00,5.00,5.00,4.00,5.00,4.00,5.00,4.50"
					( Origin gBackEnd )
				)
				( attribute "SHAPE_TO_TESTVIA_SPACING" "4.50,4.00,4.00,4.00,4.00,4.00,4.00,4.00,4.00,4.00,4.00,4.00,4.00,4.00"
					( Origin gBackEnd )
				)
				( attribute "BBV_TO_BBV_SPACING" "5.00,5.00,5.00,5.00,5.00,5.00,5.00,5.00,5.00,5.00,5.00,5.00,5.00,5.00"
					( Origin gBackEnd )
				)
				( attribute "BONDPAD_TO_BBV_SPACING" "5.00,5.00,5.00,5.00,5.00,5.00,5.00,5.00,5.00,5.00,5.00,5.00,5.00,5.00"
					( Origin gBackEnd )
				)
				( attribute "BBV_TO_LINE_SPACING" "5.00,5.00,5.00,5.00,5.00,5.00,5.00,5.00,5.00,5.00,5.00,5.00,5.00,5.00"
					( Origin gBackEnd )
				)
				( attribute "BBV_TO_SHAPE_SPACING" "5.00,5.00,5.00,5.00,5.00,5.00,5.00,5.00,5.00,5.00,5.00,5.00,5.00,5.00"
					( Origin gBackEnd )
				)
				( attribute "BONDPAD_TO_BONDPAD_SPACING" "5.00,5.00,5.00,5.00,5.00,5.00,5.00,5.00,5.00,5.00,5.00,5.00,5.00,5.00"
					( Origin gBackEnd )
				)
				( attribute "BONDPAD_TO_LINE_SPACING" "5.00,5.00,5.00,5.00,5.00,5.00,5.00,5.00,5.00,5.00,5.00,5.00,5.00,5.00"
					( Origin gBackEnd )
				)
				( attribute "BONDPAD_TO_SHAPE_SPACING" "5.00,5.00,5.00,5.00,5.00,5.00,5.00,5.00,5.00,5.00,5.00,5.00,5.00,5.00"
					( Origin gBackEnd )
				)
				( attribute "LINE_TO_LINE_SPACING" "24.00,21.00,21.00,21.00,21.00,21.00,21.00,21.00,21.00,21.00,21.00,21.00,21.00,24.00"
					( Origin gBackEnd )
				)
				( attribute "LINE_TO_SHAPE_SPACING" "5.00,5.00,5.00,5.00,5.00,5.00,5.00,5.00,5.00,5.00,5.00,5.00,5.00,5.00"
					( Origin gBackEnd )
				)
				( attribute "SHAPE_TO_SHAPE_SPACING" "10.00,10.00,10.00,10.00,10.00,10.00,10.00,10.00,10.00,10.00,10.00,10.00,10.00,10.00"
					( Origin gBackEnd )
				)
				( attribute "HOLE_TO_PIN_SPACING" "8.00,8.00,8.00,8.00,8.00,8.00,8.00,8.00,8.00,8.00,8.00,8.00,8.00,8.00"
					( Origin gBackEnd )
				)
				( attribute "HOLE_TO_VIA_SPACING" "8.00,8.00,8.00,8.00,8.00,8.00,8.00,8.00,8.00,8.00,8.00,8.00,8.00,8.00"
					( Origin gBackEnd )
				)
				( attribute "HOLE_TO_LINE_SPACING" "8.00,8.00,8.00,8.00,8.00,8.00,8.00,8.00,8.00,8.00,8.00,8.00,8.00,8.00"
					( Origin gBackEnd )
				)
				( attribute "HOLE_TO_SHAPE_SPACING" "8.00,8.00,8.00,8.00,8.00,8.00,8.00,8.00,8.00,8.00,8.00,8.00,8.00,8.00"
					( Origin gBackEnd )
				)
				( attribute "HOLE_TO_HOLE_SPACING" "8.00,8.00,8.00,8.00,8.00,8.00,8.00,8.00,8.00,8.00,8.00,8.00,8.00,8.00"
					( Origin gBackEnd )
				)
				( attribute "MVIA_TO_MVIA_SPACING" "5.00,5.00,5.00,5.00,5.00,5.00,5.00,5.00,5.00,5.00,5.00,5.00,5.00,5.00"
					( Origin gBackEnd )
				)
				( attribute "MVIA_TO_THRUPIN_SPACING" "5.00,5.00,5.00,5.00,5.00,5.00,5.00,5.00,5.00,5.00,5.00,5.00,5.00,5.00"
					( Origin gBackEnd )
				)
				( attribute "MVIA_TO_SMDPIN_SPACING" "5.00,5.00,5.00,5.00,5.00,5.00,5.00,5.00,5.00,5.00,5.00,5.00,5.00,5.00"
					( Origin gBackEnd )
				)
				( attribute "MVIA_TO_THRUVIA_SPACING" "5.00,5.00,5.00,5.00,5.00,5.00,5.00,5.00,5.00,5.00,5.00,5.00,5.00,5.00"
					( Origin gBackEnd )
				)
				( attribute "MVIA_TO_BBV_SPACING" "5.00,5.00,5.00,5.00,5.00,5.00,5.00,5.00,5.00,5.00,5.00,5.00,5.00,5.00"
					( Origin gBackEnd )
				)
				( attribute "MVIA_TO_LINE_SPACING" "5.00,5.00,5.00,5.00,5.00,5.00,5.00,5.00,5.00,5.00,5.00,5.00,5.00,5.00"
					( Origin gBackEnd )
				)
				( attribute "MVIA_TO_SHAPE_SPACING" "5.00,5.00,5.00,5.00,5.00,5.00,5.00,5.00,5.00,5.00,5.00,5.00,5.00,5.00"
					( Origin gBackEnd )
				)
				( attribute "MVIA_TO_TESTPIN_SPACING" "5.00,5.00,5.00,5.00,5.00,5.00,5.00,5.00,5.00,5.00,5.00,5.00,5.00,5.00"
					( Origin gBackEnd )
				)
				( attribute "MVIA_TO_TESTVIA_SPACING" "5.00,5.00,5.00,5.00,5.00,5.00,5.00,5.00,5.00,5.00,5.00,5.00,5.00,5.00"
					( Origin gBackEnd )
				)
				( attribute "BONDPAD_TO_MVIA_SPACING" "5.00,5.00,5.00,5.00,5.00,5.00,5.00,5.00,5.00,5.00,5.00,5.00,5.00,5.00"
					( Origin gBackEnd )
				)
				( attribute "MIN_BVIA_GAP" "5.00"
					( Origin gBackEnd )
				)
				( attribute "BONDPAD_TO_BONDPAD_DIFFP_SPC" "5.00,5.00,5.00,5.00,5.00,5.00,5.00,5.00,5.00,5.00,5.00,5.00,5.00,5.00"
					( Origin gBackEnd )
				)
				( objectStatus "24MIL_US_&_21MIL_SL" )
			)
			( spacingCSet "@crescent_city_bb_fab1_lib.crescent_city_bb_fab1(sch_1):\12MILS_US_&_15MILS_SL\"
				( attribute "THRUPIN_TO_THRUPIN_SPACING" "5.00,5.00,5.00,5.00,5.00,5.00,5.00,5.00,5.00,5.00,5.00,5.00,5.00,5.00"
					( Origin gBackEnd )
				)
				( attribute "THRUPIN_TO_SMDPIN_SPACING" "5.00,5.00,5.00,5.00,5.00,5.00,5.00,5.00,5.00,5.00,5.00,5.00,5.00,5.00"
					( Origin gBackEnd )
				)
				( attribute "TESTPIN_TO_THRUPIN_SPACING" "5.00,5.00,5.00,5.00,5.00,5.00,5.00,5.00,5.00,5.00,5.00,5.00,5.00,5.00"
					( Origin gBackEnd )
				)
				( attribute "THRUPIN_TO_THRUVIA_SPACING" "5.00,5.00,5.00,5.00,5.00,5.00,5.00,5.00,5.00,5.00,5.00,5.00,5.00,5.00"
					( Origin gBackEnd )
				)
				( attribute "TESTVIA_TO_THRUPIN_SPACING" "5.00,5.00,5.00,5.00,5.00,5.00,5.00,5.00,5.00,5.00,5.00,5.00,5.00,5.00"
					( Origin gBackEnd )
				)
				( attribute "BBV_TO_THRUPIN_SPACING" "5.00,5.00,5.00,5.00,5.00,5.00,5.00,5.00,5.00,5.00,5.00,5.00,5.00,5.00"
					( Origin gBackEnd )
				)
				( attribute "THRUPIN_TO_BONDPAD_SPACING" "5.00,5.00,5.00,5.00,5.00,5.00,5.00,5.00,5.00,5.00,5.00,5.00,5.00,5.00"
					( Origin gBackEnd )
				)
				( attribute "LINE_TO_THRUPIN_SPACING" "4.50,4.00,4.00,4.00,4.00,4.00,4.00,4.00,4.00,4.00,4.00,4.00,4.00,4.50"
					( Origin gBackEnd )
				)
				( attribute "THRUPIN_TO_SHAPE_SPACING" "4.50,4.00,4.00,4.00,4.00,4.00,4.00,4.00,4.00,4.00,4.00,4.00,4.00,4.00"
					( Origin gBackEnd )
				)
				( attribute "SMDPIN_TO_SMDPIN_SPACING" "5.00,5.00,5.00,5.00,5.00,5.00,5.00,5.00,5.00,5.00,5.00,5.00,5.00,5.00"
					( Origin gBackEnd )
				)
				( attribute "SMDPIN_TO_TESTPIN_SPACING" "5.00,5.00,5.00,5.00,5.00,5.00,5.00,5.00,5.00,5.00,5.00,5.00,5.00,25.00"
					( Origin gBackEnd )
				)
				( attribute "SMDPIN_TO_THRUVIA_SPACING" "5.00,5.00,5.00,5.00,5.00,5.00,5.00,5.00,5.00,5.00,5.00,5.00,5.00,5.00"
					( Origin gBackEnd )
				)
				( attribute "SMDPIN_TO_TESTVIA_SPACING" "5.00,5.00,5.00,5.00,5.00,5.00,5.00,5.00,5.00,5.00,5.00,5.00,5.00,5.00"
					( Origin gBackEnd )
				)
				( attribute "BBV_TO_SMDPIN_SPACING" "5.00,5.00,5.00,5.00,5.00,5.00,5.00,5.00,5.00,5.00,5.00,5.00,5.00,5.00"
					( Origin gBackEnd )
				)
				( attribute "SMDPIN_TO_BONDPAD_SPACING" "5.00,5.00,5.00,5.00,5.00,5.00,5.00,5.00,5.00,5.00,5.00,5.00,5.00,5.00"
					( Origin gBackEnd )
				)
				( attribute "LINE_TO_SMDPIN_SPACING" "4.50,4.50,4.50,4.50,4.50,4.50,4.50,4.50,4.50,4.50,4.50,4.50,4.50,4.50"
					( Origin gBackEnd )
				)
				( attribute "SHAPE_TO_SMDPIN_SPACING" "5.00,5.00,5.00,5.00,5.00,5.00,5.00,5.00,5.00,5.00,5.00,5.00,5.00,5.00"
					( Origin gBackEnd )
				)
				( attribute "TESTPIN_TO_TESTPIN_SPACING" "5.00,5.00,5.00,5.00,5.00,5.00,5.00,5.00,5.00,5.00,5.00,5.00,5.00,5.00"
					( Origin gBackEnd )
				)
				( attribute "TESTPIN_TO_THRUVIA_SPACING" "5.00,5.00,5.00,5.00,5.00,5.00,5.00,5.00,5.00,5.00,5.00,5.00,5.00,5.00"
					( Origin gBackEnd )
				)
				( attribute "TESTPIN_TO_TESTVIA_SPACING" "5.00,5.00,5.00,5.00,5.00,5.00,5.00,5.00,5.00,5.00,5.00,5.00,5.00,5.00"
					( Origin gBackEnd )
				)
				( attribute "BBV_TO_TESTPIN_SPACING" "5.00,5.00,5.00,5.00,5.00,5.00,5.00,5.00,5.00,5.00,5.00,5.00,5.00,5.00"
					( Origin gBackEnd )
				)
				( attribute "BONDPAD_TO_TESTPIN_SPACING" "5.00,5.00,5.00,5.00,5.00,5.00,5.00,5.00,5.00,5.00,5.00,5.00,5.00,5.00"
					( Origin gBackEnd )
				)
				( attribute "LINE_TO_TESTPIN_SPACING" "4.50,5.00,5.00,5.00,5.00,5.00,5.00,5.00,5.00,5.00,5.00,5.00,5.00,5.00"
					( Origin gBackEnd )
				)
				( attribute "SHAPE_TO_TESTPIN_SPACING" "4.50,4.00,4.00,4.00,4.00,4.00,4.00,4.00,4.00,4.00,4.00,4.00,4.00,4.00"
					( Origin gBackEnd )
				)
				( attribute "THRUVIA_TO_THRUVIA_SPACING" "5.00,5.00,5.00,5.00,5.00,5.00,5.00,5.00,5.00,5.00,5.00,5.00,5.00,5.00"
					( Origin gBackEnd )
				)
				( attribute "TESTVIA_TO_THRUVIA_SPACING" "5.00,5.00,5.00,5.00,5.00,5.00,5.00,5.00,5.00,5.00,5.00,5.00,5.00,5.00"
					( Origin gBackEnd )
				)
				( attribute "BBV_TO_THRUVIA_SPACING" "5.00,5.00,5.00,5.00,5.00,5.00,5.00,5.00,5.00,5.00,5.00,5.00,5.00,5.00"
					( Origin gBackEnd )
				)
				( attribute "BONDPAD_TO_THRUVIA_SPACING" "5.00,5.00,5.00,5.00,5.00,5.00,5.00,5.00,5.00,5.00,5.00,5.00,5.00,5.00"
					( Origin gBackEnd )
				)
				( attribute "LINE_TO_THRUVIA_SPACING" "4.50,4.00,4.00,4.00,4.00,4.00,4.00,4.00,4.00,4.00,4.00,4.00,4.00,4.50"
					( Origin gBackEnd )
				)
				( attribute "SHAPE_TO_THRUVIA_SPACING" "4.50,4.00,4.00,4.00,4.00,4.00,4.00,4.00,4.00,4.00,4.00,4.00,4.00,4.00"
					( Origin gBackEnd )
				)
				( attribute "TESTVIA_TO_TESTVIA_SPACING" "5.00,5.00,5.00,5.00,5.00,5.00,5.00,5.00,5.00,5.00,5.00,5.00,5.00,5.00"
					( Origin gBackEnd )
				)
				( attribute "BBV_TO_TESTVIA_SPACING" "5.00,5.00,5.00,5.00,5.00,5.00,5.00,5.00,5.00,5.00,5.00,5.00,5.00,5.00"
					( Origin gBackEnd )
				)
				( attribute "BONDPAD_TO_TESTVIA_SPACING" "5.00,5.00,5.00,5.00,5.00,5.00,5.00,5.00,5.00,5.00,5.00,5.00,5.00,5.00"
					( Origin gBackEnd )
				)
				( attribute "LINE_TO_TESTVIA_SPACING" "4.50,5.00,4.00,5.00,4.00,5.00,5.00,5.00,5.00,4.00,5.00,4.00,5.00,4.50"
					( Origin gBackEnd )
				)
				( attribute "SHAPE_TO_TESTVIA_SPACING" "4.50,4.00,4.00,4.00,4.00,4.00,4.00,4.00,4.00,4.00,4.00,4.00,4.00,4.00"
					( Origin gBackEnd )
				)
				( attribute "BBV_TO_BBV_SPACING" "5.00,5.00,5.00,5.00,5.00,5.00,5.00,5.00,5.00,5.00,5.00,5.00,5.00,5.00"
					( Origin gBackEnd )
				)
				( attribute "BONDPAD_TO_BBV_SPACING" "5.00,5.00,5.00,5.00,5.00,5.00,5.00,5.00,5.00,5.00,5.00,5.00,5.00,5.00"
					( Origin gBackEnd )
				)
				( attribute "BBV_TO_LINE_SPACING" "5.00,5.00,5.00,5.00,5.00,5.00,5.00,5.00,5.00,5.00,5.00,5.00,5.00,5.00"
					( Origin gBackEnd )
				)
				( attribute "BBV_TO_SHAPE_SPACING" "5.00,5.00,5.00,5.00,5.00,5.00,5.00,5.00,5.00,5.00,5.00,5.00,5.00,5.00"
					( Origin gBackEnd )
				)
				( attribute "BONDPAD_TO_BONDPAD_SPACING" "5.00,5.00,5.00,5.00,5.00,5.00,5.00,5.00,5.00,5.00,5.00,5.00,5.00,5.00"
					( Origin gBackEnd )
				)
				( attribute "BONDPAD_TO_LINE_SPACING" "5.00,5.00,5.00,5.00,5.00,5.00,5.00,5.00,5.00,5.00,5.00,5.00,5.00,5.00"
					( Origin gBackEnd )
				)
				( attribute "BONDPAD_TO_SHAPE_SPACING" "5.00,5.00,5.00,5.00,5.00,5.00,5.00,5.00,5.00,5.00,5.00,5.00,5.00,5.00"
					( Origin gBackEnd )
				)
				( attribute "LINE_TO_LINE_SPACING" "12.00,15.00,15.00,15.00,15.00,15.00,15.00,15.00,15.00,15.00,15.00,15.00,15.00,15.00"
					( Origin gBackEnd )
				)
				( attribute "LINE_TO_SHAPE_SPACING" "5.00,5.00,5.00,5.00,5.00,5.00,5.00,5.00,5.00,5.00,5.00,5.00,5.00,5.00"
					( Origin gBackEnd )
				)
				( attribute "SHAPE_TO_SHAPE_SPACING" "10.00,10.00,10.00,10.00,10.00,10.00,10.00,10.00,10.00,10.00,10.00,10.00,10.00,10.00"
					( Origin gBackEnd )
				)
				( attribute "HOLE_TO_PIN_SPACING" "8.00,8.00,8.00,8.00,8.00,8.00,8.00,8.00,8.00,8.00,8.00,8.00,8.00,8.00"
					( Origin gBackEnd )
				)
				( attribute "HOLE_TO_VIA_SPACING" "8.00,8.00,8.00,8.00,8.00,8.00,8.00,8.00,8.00,8.00,8.00,8.00,8.00,8.00"
					( Origin gBackEnd )
				)
				( attribute "HOLE_TO_LINE_SPACING" "8.00,8.00,8.00,8.00,8.00,8.00,8.00,8.00,8.00,8.00,8.00,8.00,8.00,8.00"
					( Origin gBackEnd )
				)
				( attribute "HOLE_TO_SHAPE_SPACING" "8.00,8.00,8.00,8.00,8.00,8.00,8.00,8.00,8.00,8.00,8.00,8.00,8.00,8.00"
					( Origin gBackEnd )
				)
				( attribute "HOLE_TO_HOLE_SPACING" "8.00,8.00,8.00,8.00,8.00,8.00,8.00,8.00,8.00,8.00,8.00,8.00,8.00,8.00"
					( Origin gBackEnd )
				)
				( attribute "MVIA_TO_MVIA_SPACING" "5.00,5.00,5.00,5.00,5.00,5.00,5.00,5.00,5.00,5.00,5.00,5.00,5.00,5.00"
					( Origin gBackEnd )
				)
				( attribute "MVIA_TO_THRUPIN_SPACING" "5.00,5.00,5.00,5.00,5.00,5.00,5.00,5.00,5.00,5.00,5.00,5.00,5.00,5.00"
					( Origin gBackEnd )
				)
				( attribute "MVIA_TO_SMDPIN_SPACING" "5.00,5.00,5.00,5.00,5.00,5.00,5.00,5.00,5.00,5.00,5.00,5.00,5.00,5.00"
					( Origin gBackEnd )
				)
				( attribute "MVIA_TO_THRUVIA_SPACING" "5.00,5.00,5.00,5.00,5.00,5.00,5.00,5.00,5.00,5.00,5.00,5.00,5.00,5.00"
					( Origin gBackEnd )
				)
				( attribute "MVIA_TO_BBV_SPACING" "5.00,5.00,5.00,5.00,5.00,5.00,5.00,5.00,5.00,5.00,5.00,5.00,5.00,5.00"
					( Origin gBackEnd )
				)
				( attribute "MVIA_TO_LINE_SPACING" "5.00,5.00,5.00,5.00,5.00,5.00,5.00,5.00,5.00,5.00,5.00,5.00,5.00,5.00"
					( Origin gBackEnd )
				)
				( attribute "MVIA_TO_SHAPE_SPACING" "5.00,5.00,5.00,5.00,5.00,5.00,5.00,5.00,5.00,5.00,5.00,5.00,5.00,5.00"
					( Origin gBackEnd )
				)
				( attribute "MVIA_TO_TESTPIN_SPACING" "5.00,5.00,5.00,5.00,5.00,5.00,5.00,5.00,5.00,5.00,5.00,5.00,5.00,5.00"
					( Origin gBackEnd )
				)
				( attribute "MVIA_TO_TESTVIA_SPACING" "5.00,5.00,5.00,5.00,5.00,5.00,5.00,5.00,5.00,5.00,5.00,5.00,5.00,5.00"
					( Origin gBackEnd )
				)
				( attribute "BONDPAD_TO_MVIA_SPACING" "5.00,5.00,5.00,5.00,5.00,5.00,5.00,5.00,5.00,5.00,5.00,5.00,5.00,5.00"
					( Origin gBackEnd )
				)
				( attribute "MIN_BVIA_GAP" "5.00"
					( Origin gBackEnd )
				)
				( attribute "BONDPAD_TO_BONDPAD_DIFFP_SPC" "5.00,5.00,5.00,5.00,5.00,5.00,5.00,5.00,5.00,5.00,5.00,5.00,5.00,5.00"
					( Origin gBackEnd )
				)
				( objectStatus "12MIL_US_&_15MIL_SL" )
			)
			( spacingCSet "@crescent_city_bb_fab1_lib.crescent_city_bb_fab1(sch_1):\9H_US_&_5H_SL_VIA+3H_A\"
				( attribute "THRUPIN_TO_THRUPIN_SPACING" "5.00,5.00,5.00,5.00,5.00,5.00,5.00,5.00,5.00,5.00,5.00,5.00,5.00,5.00"
					( Origin gBackEnd )
				)
				( attribute "THRUPIN_TO_SMDPIN_SPACING" "5.00,5.00,5.00,5.00,5.00,5.00,5.00,5.00,5.00,5.00,5.00,5.00,5.00,5.00"
					( Origin gBackEnd )
				)
				( attribute "TESTPIN_TO_THRUPIN_SPACING" "5.00,5.00,5.00,5.00,5.00,5.00,5.00,5.00,5.00,5.00,5.00,5.00,5.00,5.00"
					( Origin gBackEnd )
				)
				( attribute "THRUPIN_TO_THRUVIA_SPACING" "5.00,5.00,5.00,5.00,5.00,5.00,5.00,5.00,5.00,5.00,5.00,5.00,5.00,5.00"
					( Origin gBackEnd )
				)
				( attribute "TESTVIA_TO_THRUPIN_SPACING" "5.00,5.00,5.00,5.00,5.00,5.00,5.00,5.00,5.00,5.00,5.00,5.00,5.00,5.00"
					( Origin gBackEnd )
				)
				( attribute "BBV_TO_THRUPIN_SPACING" "5.00,5.00,5.00,5.00,5.00,5.00,5.00,5.00,5.00,5.00,5.00,5.00,5.00,5.00"
					( Origin gBackEnd )
				)
				( attribute "THRUPIN_TO_BONDPAD_SPACING" "5.00,5.00,5.00,5.00,5.00,5.00,5.00,5.00,5.00,5.00,5.00,5.00,5.00,5.00"
					( Origin gBackEnd )
				)
				( attribute "LINE_TO_THRUPIN_SPACING" "4.50,4.00,4.00,4.00,4.00,4.00,4.00,4.00,4.00,4.00,4.00,4.00,4.00,4.50"
					( Origin gBackEnd )
				)
				( attribute "THRUPIN_TO_SHAPE_SPACING" "4.50,4.00,4.00,4.00,4.00,4.00,4.00,4.00,4.00,4.00,4.00,4.00,4.00,4.00"
					( Origin gBackEnd )
				)
				( attribute "SMDPIN_TO_SMDPIN_SPACING" "5.00,5.00,5.00,5.00,5.00,5.00,5.00,5.00,5.00,5.00,5.00,5.00,5.00,5.00"
					( Origin gBackEnd )
				)
				( attribute "SMDPIN_TO_TESTPIN_SPACING" "5.00,5.00,5.00,5.00,5.00,5.00,5.00,5.00,5.00,5.00,5.00,5.00,5.00,5.00"
					( Origin gBackEnd )
				)
				( attribute "SMDPIN_TO_THRUVIA_SPACING" "5.00,5.00,5.00,5.00,5.00,5.00,5.00,5.00,5.00,5.00,5.00,5.00,5.00,5.00"
					( Origin gBackEnd )
				)
				( attribute "SMDPIN_TO_TESTVIA_SPACING" "5.00,5.00,5.00,5.00,5.00,5.00,5.00,5.00,5.00,5.00,5.00,5.00,5.00,5.00"
					( Origin gBackEnd )
				)
				( attribute "BBV_TO_SMDPIN_SPACING" "5.00,5.00,5.00,5.00,5.00,5.00,5.00,5.00,5.00,5.00,5.00,5.00,5.00,5.00"
					( Origin gBackEnd )
				)
				( attribute "SMDPIN_TO_BONDPAD_SPACING" "5.00,5.00,5.00,5.00,5.00,5.00,5.00,5.00,5.00,5.00,5.00,5.00,5.00,5.00"
					( Origin gBackEnd )
				)
				( attribute "LINE_TO_SMDPIN_SPACING" "4.50,4.50,4.50,4.50,4.50,4.50,4.50,4.50,4.50,4.50,4.50,4.50,4.50,4.50"
					( Origin gBackEnd )
				)
				( attribute "SHAPE_TO_SMDPIN_SPACING" "5.00,5.00,5.00,5.00,5.00,5.00,5.00,5.00,5.00,5.00,5.00,5.00,5.00,5.00"
					( Origin gBackEnd )
				)
				( attribute "TESTPIN_TO_TESTPIN_SPACING" "5.00,5.00,5.00,5.00,5.00,5.00,5.00,5.00,5.00,5.00,5.00,5.00,5.00,5.00"
					( Origin gBackEnd )
				)
				( attribute "TESTPIN_TO_THRUVIA_SPACING" "5.00,5.00,5.00,5.00,5.00,5.00,5.00,5.00,5.00,5.00,5.00,5.00,5.00,5.00"
					( Origin gBackEnd )
				)
				( attribute "TESTPIN_TO_TESTVIA_SPACING" "5.00,5.00,5.00,5.00,5.00,5.00,5.00,5.00,5.00,5.00,5.00,5.00,5.00,5.00"
					( Origin gBackEnd )
				)
				( attribute "BBV_TO_TESTPIN_SPACING" "5.00,5.00,5.00,5.00,5.00,5.00,5.00,5.00,5.00,5.00,5.00,5.00,5.00,5.00"
					( Origin gBackEnd )
				)
				( attribute "BONDPAD_TO_TESTPIN_SPACING" "5.00,5.00,5.00,5.00,5.00,5.00,5.00,5.00,5.00,5.00,5.00,5.00,5.00,5.00"
					( Origin gBackEnd )
				)
				( attribute "LINE_TO_TESTPIN_SPACING" "4.50,5.00,5.00,5.00,5.00,5.00,5.00,5.00,5.00,5.00,5.00,5.00,5.00,5.00"
					( Origin gBackEnd )
				)
				( attribute "SHAPE_TO_TESTPIN_SPACING" "4.50,4.00,4.00,4.00,4.00,4.00,4.00,4.00,4.00,4.00,4.00,4.00,4.00,4.00"
					( Origin gBackEnd )
				)
				( attribute "THRUVIA_TO_THRUVIA_SPACING" "5.00,5.00,5.00,5.00,5.00,5.00,5.00,5.00,5.00,5.00,5.00,5.00,5.00,5.00"
					( Origin gBackEnd )
				)
				( attribute "TESTVIA_TO_THRUVIA_SPACING" "5.00,5.00,5.00,5.00,5.00,5.00,5.00,5.00,5.00,5.00,5.00,5.00,5.00,5.00"
					( Origin gBackEnd )
				)
				( attribute "BBV_TO_THRUVIA_SPACING" "5.00,5.00,5.00,5.00,5.00,5.00,5.00,5.00,5.00,5.00,5.00,5.00,5.00,5.00"
					( Origin gBackEnd )
				)
				( attribute "BONDPAD_TO_THRUVIA_SPACING" "5.00,5.00,5.00,5.00,5.00,5.00,5.00,5.00,5.00,5.00,5.00,5.00,5.00,5.00"
					( Origin gBackEnd )
				)
				( attribute "LINE_TO_THRUVIA_SPACING" "12.00,5.00,13.00,5.00,13.00,5.00,5.00,5.00,5.00,13.00,5.00,13.00,5.00,12.00"
					( Origin gBackEnd )
				)
				( attribute "SHAPE_TO_THRUVIA_SPACING" "4.50,4.00,4.00,4.00,4.00,4.00,4.00,4.00,4.00,4.00,4.00,4.00,4.00,4.00"
					( Origin gBackEnd )
				)
				( attribute "TESTVIA_TO_TESTVIA_SPACING" "5.00,5.00,5.00,5.00,5.00,5.00,5.00,5.00,5.00,5.00,5.00,5.00,5.00,5.00"
					( Origin gBackEnd )
				)
				( attribute "BBV_TO_TESTVIA_SPACING" "5.00,5.00,5.00,5.00,5.00,5.00,5.00,5.00,5.00,5.00,5.00,5.00,5.00,5.00"
					( Origin gBackEnd )
				)
				( attribute "BONDPAD_TO_TESTVIA_SPACING" "5.00,5.00,5.00,5.00,5.00,5.00,5.00,5.00,5.00,5.00,5.00,5.00,5.00,5.00"
					( Origin gBackEnd )
				)
				( attribute "LINE_TO_TESTVIA_SPACING" "12.00,5.00,13.00,5.00,13.00,5.00,5.00,5.00,5.00,13.00,5.00,13.00,5.00,12.00"
					( Origin gBackEnd )
				)
				( attribute "SHAPE_TO_TESTVIA_SPACING" "4.50,4.00,4.00,4.00,4.00,4.00,4.00,4.00,4.00,4.00,4.00,4.00,4.00,4.00"
					( Origin gBackEnd )
				)
				( attribute "BBV_TO_BBV_SPACING" "5.00,5.00,5.00,5.00,5.00,5.00,5.00,5.00,5.00,5.00,5.00,5.00,5.00,5.00"
					( Origin gBackEnd )
				)
				( attribute "BONDPAD_TO_BBV_SPACING" "5.00,5.00,5.00,5.00,5.00,5.00,5.00,5.00,5.00,5.00,5.00,5.00,5.00,5.00"
					( Origin gBackEnd )
				)
				( attribute "BBV_TO_LINE_SPACING" "5.00,5.00,5.00,5.00,5.00,5.00,5.00,5.00,5.00,5.00,5.00,5.00,5.00,5.00"
					( Origin gBackEnd )
				)
				( attribute "BBV_TO_SHAPE_SPACING" "5.00,5.00,5.00,5.00,5.00,5.00,5.00,5.00,5.00,5.00,5.00,5.00,5.00,5.00"
					( Origin gBackEnd )
				)
				( attribute "BONDPAD_TO_BONDPAD_SPACING" "5.00,5.00,5.00,5.00,5.00,5.00,5.00,5.00,5.00,5.00,5.00,5.00,5.00,5.00"
					( Origin gBackEnd )
				)
				( attribute "BONDPAD_TO_LINE_SPACING" "5.00,5.00,5.00,5.00,5.00,5.00,5.00,5.00,5.00,5.00,5.00,5.00,5.00,5.00"
					( Origin gBackEnd )
				)
				( attribute "BONDPAD_TO_SHAPE_SPACING" "5.00,5.00,5.00,5.00,5.00,5.00,5.00,5.00,5.00,5.00,5.00,5.00,5.00,5.00"
					( Origin gBackEnd )
				)
				( attribute "LINE_TO_LINE_SPACING" "24.30,15.00,15.00,15.00,15.00,15.00,15.00,15.00,15.00,15.00,15.00,15.00,15.00,24.30"
					( Origin gBackEnd )
				)
				( attribute "LINE_TO_SHAPE_SPACING" "5.00,5.00,5.00,5.00,5.00,5.00,5.00,5.00,5.00,5.00,5.00,5.00,5.00,5.00"
					( Origin gBackEnd )
				)
				( attribute "SHAPE_TO_SHAPE_SPACING" "10.00,10.00,10.00,10.00,10.00,10.00,10.00,10.00,10.00,10.00,10.00,10.00,10.00,10.00"
					( Origin gBackEnd )
				)
				( attribute "HOLE_TO_PIN_SPACING" "8.00,8.00,8.00,8.00,8.00,8.00,8.00,8.00,8.00,8.00,8.00,8.00,8.00,8.00"
					( Origin gBackEnd )
				)
				( attribute "HOLE_TO_VIA_SPACING" "8.00,8.00,8.00,8.00,8.00,8.00,8.00,8.00,8.00,8.00,8.00,8.00,8.00,8.00"
					( Origin gBackEnd )
				)
				( attribute "HOLE_TO_LINE_SPACING" "8.00,8.00,8.00,8.00,8.00,8.00,8.00,8.00,8.00,8.00,8.00,8.00,8.00,8.00"
					( Origin gBackEnd )
				)
				( attribute "HOLE_TO_SHAPE_SPACING" "8.00,8.00,8.00,8.00,8.00,8.00,8.00,8.00,8.00,8.00,8.00,8.00,8.00,8.00"
					( Origin gBackEnd )
				)
				( attribute "HOLE_TO_HOLE_SPACING" "8.00,8.00,8.00,8.00,8.00,8.00,8.00,8.00,8.00,8.00,8.00,8.00,8.00,8.00"
					( Origin gBackEnd )
				)
				( attribute "MVIA_TO_MVIA_SPACING" "5.00,5.00,5.00,5.00,5.00,5.00,5.00,5.00,5.00,5.00,5.00,5.00,5.00,5.00"
					( Origin gBackEnd )
				)
				( attribute "MVIA_TO_THRUPIN_SPACING" "5.00,5.00,5.00,5.00,5.00,5.00,5.00,5.00,5.00,5.00,5.00,5.00,5.00,5.00"
					( Origin gBackEnd )
				)
				( attribute "MVIA_TO_SMDPIN_SPACING" "5.00,5.00,5.00,5.00,5.00,5.00,5.00,5.00,5.00,5.00,5.00,5.00,5.00,5.00"
					( Origin gBackEnd )
				)
				( attribute "MVIA_TO_THRUVIA_SPACING" "5.00,5.00,5.00,5.00,5.00,5.00,5.00,5.00,5.00,5.00,5.00,5.00,5.00,5.00"
					( Origin gBackEnd )
				)
				( attribute "MVIA_TO_BBV_SPACING" "5.00,5.00,5.00,5.00,5.00,5.00,5.00,5.00,5.00,5.00,5.00,5.00,5.00,5.00"
					( Origin gBackEnd )
				)
				( attribute "MVIA_TO_LINE_SPACING" "5.00,5.00,5.00,5.00,5.00,5.00,5.00,5.00,5.00,5.00,5.00,5.00,5.00,5.00"
					( Origin gBackEnd )
				)
				( attribute "MVIA_TO_SHAPE_SPACING" "5.00,5.00,5.00,5.00,5.00,5.00,5.00,5.00,5.00,5.00,5.00,5.00,5.00,5.00"
					( Origin gBackEnd )
				)
				( attribute "MVIA_TO_TESTPIN_SPACING" "5.00,5.00,5.00,5.00,5.00,5.00,5.00,5.00,5.00,5.00,5.00,5.00,5.00,5.00"
					( Origin gBackEnd )
				)
				( attribute "MVIA_TO_TESTVIA_SPACING" "5.00,5.00,5.00,5.00,5.00,5.00,5.00,5.00,5.00,5.00,5.00,5.00,5.00,5.00"
					( Origin gBackEnd )
				)
				( attribute "BONDPAD_TO_MVIA_SPACING" "5.00,5.00,5.00,5.00,5.00,5.00,5.00,5.00,5.00,5.00,5.00,5.00,5.00,5.00"
					( Origin gBackEnd )
				)
				( attribute "MIN_BVIA_GAP" "5.00"
					( Origin gBackEnd )
				)
				( attribute "BONDPAD_TO_BONDPAD_DIFFP_SPC" "5.00,5.00,5.00,5.00,5.00,5.00,5.00,5.00,5.00,5.00,5.00,5.00,5.00,5.00"
					( Origin gBackEnd )
				)
				( objectStatus "9H_US_&_5H_SL_VIA_3H+A" )
			)
			( spacingCSet "@crescent_city_bb_fab1_lib.crescent_city_bb_fab1(sch_1):\5MIL_US_&_4MIL_SL\"
				( attribute "THRUPIN_TO_THRUPIN_SPACING" "5.00,5.00,5.00,5.00,5.00,5.00,5.00,5.00,5.00,5.00,5.00,5.00,5.00,5.00"
					( Origin gBackEnd )
				)
				( attribute "THRUPIN_TO_SMDPIN_SPACING" "5.00,5.00,5.00,5.00,5.00,5.00,5.00,5.00,5.00,5.00,5.00,5.00,5.00,5.00"
					( Origin gBackEnd )
				)
				( attribute "TESTPIN_TO_THRUPIN_SPACING" "5.00,5.00,5.00,5.00,5.00,5.00,5.00,5.00,5.00,5.00,5.00,5.00,5.00,5.00"
					( Origin gBackEnd )
				)
				( attribute "THRUPIN_TO_THRUVIA_SPACING" "5.00,5.00,5.00,5.00,5.00,5.00,5.00,5.00,5.00,5.00,5.00,5.00,5.00,5.00"
					( Origin gBackEnd )
				)
				( attribute "TESTVIA_TO_THRUPIN_SPACING" "5.00,5.00,5.00,5.00,5.00,5.00,5.00,5.00,5.00,5.00,5.00,5.00,5.00,5.00"
					( Origin gBackEnd )
				)
				( attribute "BBV_TO_THRUPIN_SPACING" "5.00,5.00,5.00,5.00,5.00,5.00,5.00,5.00,5.00,5.00,5.00,5.00,5.00,5.00"
					( Origin gBackEnd )
				)
				( attribute "THRUPIN_TO_BONDPAD_SPACING" "5.00,5.00,5.00,5.00,5.00,5.00,5.00,5.00,5.00,5.00,5.00,5.00,5.00,5.00"
					( Origin gBackEnd )
				)
				( attribute "LINE_TO_THRUPIN_SPACING" "4.50,4.00,4.00,4.00,4.00,4.00,4.00,4.00,4.00,4.00,4.00,4.00,4.00,4.50"
					( Origin gBackEnd )
				)
				( attribute "THRUPIN_TO_SHAPE_SPACING" "4.50,4.00,4.00,4.00,4.00,4.00,4.00,4.00,4.00,4.00,4.00,4.00,4.00,4.00"
					( Origin gBackEnd )
				)
				( attribute "SMDPIN_TO_SMDPIN_SPACING" "5.00,5.00,5.00,5.00,5.00,5.00,5.00,5.00,5.00,5.00,5.00,5.00,5.00,5.00"
					( Origin gBackEnd )
				)
				( attribute "SMDPIN_TO_TESTPIN_SPACING" "5.00,5.00,5.00,5.00,5.00,5.00,5.00,5.00,5.00,5.00,5.00,5.00,5.00,5.00"
					( Origin gBackEnd )
				)
				( attribute "SMDPIN_TO_THRUVIA_SPACING" "5.00,5.00,5.00,5.00,5.00,5.00,5.00,5.00,5.00,5.00,5.00,5.00,5.00,5.00"
					( Origin gBackEnd )
				)
				( attribute "SMDPIN_TO_TESTVIA_SPACING" "5.00,5.00,5.00,5.00,5.00,5.00,5.00,5.00,5.00,5.00,5.00,5.00,5.00,5.00"
					( Origin gBackEnd )
				)
				( attribute "BBV_TO_SMDPIN_SPACING" "5.00,5.00,5.00,5.00,5.00,5.00,5.00,5.00,5.00,5.00,5.00,5.00,5.00,5.00"
					( Origin gBackEnd )
				)
				( attribute "SMDPIN_TO_BONDPAD_SPACING" "5.00,5.00,5.00,5.00,5.00,5.00,5.00,5.00,5.00,5.00,5.00,5.00,5.00,5.00"
					( Origin gBackEnd )
				)
				( attribute "LINE_TO_SMDPIN_SPACING" "4.50,4.50,4.50,4.50,4.50,4.50,4.50,4.50,4.50,4.50,4.50,4.50,4.50,4.50"
					( Origin gBackEnd )
				)
				( attribute "SHAPE_TO_SMDPIN_SPACING" "5.00,5.00,5.00,5.00,5.00,5.00,5.00,5.00,5.00,5.00,5.00,5.00,5.00,5.00"
					( Origin gBackEnd )
				)
				( attribute "TESTPIN_TO_TESTPIN_SPACING" "5.00,5.00,5.00,5.00,5.00,5.00,5.00,5.00,5.00,5.00,5.00,5.00,5.00,5.00"
					( Origin gBackEnd )
				)
				( attribute "TESTPIN_TO_THRUVIA_SPACING" "5.00,5.00,5.00,5.00,5.00,5.00,5.00,5.00,5.00,5.00,5.00,5.00,5.00,5.00"
					( Origin gBackEnd )
				)
				( attribute "TESTPIN_TO_TESTVIA_SPACING" "5.00,5.00,5.00,5.00,5.00,5.00,5.00,5.00,5.00,5.00,5.00,5.00,5.00,5.00"
					( Origin gBackEnd )
				)
				( attribute "BBV_TO_TESTPIN_SPACING" "5.00,5.00,5.00,5.00,5.00,5.00,5.00,5.00,5.00,5.00,5.00,5.00,5.00,5.00"
					( Origin gBackEnd )
				)
				( attribute "BONDPAD_TO_TESTPIN_SPACING" "5.00,5.00,5.00,5.00,5.00,5.00,5.00,5.00,5.00,5.00,5.00,5.00,5.00,5.00"
					( Origin gBackEnd )
				)
				( attribute "LINE_TO_TESTPIN_SPACING" "4.50,5.00,5.00,5.00,5.00,5.00,5.00,5.00,5.00,5.00,5.00,5.00,5.00,5.00"
					( Origin gBackEnd )
				)
				( attribute "SHAPE_TO_TESTPIN_SPACING" "4.50,4.00,4.00,4.00,4.00,4.00,4.00,4.00,4.00,4.00,4.00,4.00,4.00,4.00"
					( Origin gBackEnd )
				)
				( attribute "THRUVIA_TO_THRUVIA_SPACING" "5.00,5.00,5.00,5.00,5.00,5.00,5.00,5.00,5.00,5.00,5.00,5.00,5.00,5.00"
					( Origin gBackEnd )
				)
				( attribute "TESTVIA_TO_THRUVIA_SPACING" "5.00,5.00,5.00,5.00,5.00,5.00,5.00,5.00,5.00,5.00,5.00,5.00,5.00,5.00"
					( Origin gBackEnd )
				)
				( attribute "BBV_TO_THRUVIA_SPACING" "5.00,5.00,5.00,5.00,5.00,5.00,5.00,5.00,5.00,5.00,5.00,5.00,5.00,5.00"
					( Origin gBackEnd )
				)
				( attribute "BONDPAD_TO_THRUVIA_SPACING" "5.00,5.00,5.00,5.00,5.00,5.00,5.00,5.00,5.00,5.00,5.00,5.00,5.00,5.00"
					( Origin gBackEnd )
				)
				( attribute "LINE_TO_THRUVIA_SPACING" "4.50,4.00,4.00,4.00,4.00,4.00,4.00,4.00,4.00,4.00,4.00,4.00,4.00,4.50"
					( Origin gBackEnd )
				)
				( attribute "SHAPE_TO_THRUVIA_SPACING" "4.50,4.00,4.00,4.00,4.00,4.00,4.00,4.00,4.00,4.00,4.00,4.00,4.00,4.00"
					( Origin gBackEnd )
				)
				( attribute "TESTVIA_TO_TESTVIA_SPACING" "5.00,5.00,5.00,5.00,5.00,5.00,5.00,5.00,5.00,5.00,5.00,5.00,5.00,5.00"
					( Origin gBackEnd )
				)
				( attribute "BBV_TO_TESTVIA_SPACING" "5.00,5.00,5.00,5.00,5.00,5.00,5.00,5.00,5.00,5.00,5.00,5.00,5.00,5.00"
					( Origin gBackEnd )
				)
				( attribute "BONDPAD_TO_TESTVIA_SPACING" "5.00,5.00,5.00,5.00,5.00,5.00,5.00,5.00,5.00,5.00,5.00,5.00,5.00,5.00"
					( Origin gBackEnd )
				)
				( attribute "LINE_TO_TESTVIA_SPACING" "4.50,5.00,4.00,5.00,4.00,5.00,5.00,5.00,5.00,4.00,5.00,4.00,5.00,4.50"
					( Origin gBackEnd )
				)
				( attribute "SHAPE_TO_TESTVIA_SPACING" "4.50,4.00,4.00,4.00,4.00,4.00,4.00,4.00,4.00,4.00,4.00,4.00,4.00,4.00"
					( Origin gBackEnd )
				)
				( attribute "BBV_TO_BBV_SPACING" "5.00,5.00,5.00,5.00,5.00,5.00,5.00,5.00,5.00,5.00,5.00,5.00,5.00,5.00"
					( Origin gBackEnd )
				)
				( attribute "BONDPAD_TO_BBV_SPACING" "5.00,5.00,5.00,5.00,5.00,5.00,5.00,5.00,5.00,5.00,5.00,5.00,5.00,5.00"
					( Origin gBackEnd )
				)
				( attribute "BBV_TO_LINE_SPACING" "5.00,5.00,5.00,5.00,5.00,5.00,5.00,5.00,5.00,5.00,5.00,5.00,5.00,5.00"
					( Origin gBackEnd )
				)
				( attribute "BBV_TO_SHAPE_SPACING" "5.00,5.00,5.00,5.00,5.00,5.00,5.00,5.00,5.00,5.00,5.00,5.00,5.00,5.00"
					( Origin gBackEnd )
				)
				( attribute "BONDPAD_TO_BONDPAD_SPACING" "5.00,5.00,5.00,5.00,5.00,5.00,5.00,5.00,5.00,5.00,5.00,5.00,5.00,5.00"
					( Origin gBackEnd )
				)
				( attribute "BONDPAD_TO_LINE_SPACING" "5.00,5.00,5.00,5.00,5.00,5.00,5.00,5.00,5.00,5.00,5.00,5.00,5.00,5.00"
					( Origin gBackEnd )
				)
				( attribute "BONDPAD_TO_SHAPE_SPACING" "5.00,5.00,5.00,5.00,5.00,5.00,5.00,5.00,5.00,5.00,5.00,5.00,5.00,5.00"
					( Origin gBackEnd )
				)
				( attribute "LINE_TO_LINE_SPACING" "5.00,5.00,4.00,5.00,4.00,5.00,5.00,5.00,5.00,4.00,5.00,4.00,5.00,5.00"
					( Origin gBackEnd )
				)
				( attribute "LINE_TO_SHAPE_SPACING" "5.00,5.00,5.00,5.00,5.00,5.00,5.00,5.00,5.00,5.00,5.00,5.00,5.00,5.00"
					( Origin gBackEnd )
				)
				( attribute "SHAPE_TO_SHAPE_SPACING" "10.00,10.00,10.00,10.00,10.00,10.00,10.00,10.00,10.00,10.00,10.00,10.00,10.00,10.00"
					( Origin gBackEnd )
				)
				( attribute "HOLE_TO_PIN_SPACING" "8.00,8.00,8.00,8.00,8.00,8.00,8.00,8.00,8.00,8.00,8.00,8.00,8.00,8.00"
					( Origin gBackEnd )
				)
				( attribute "HOLE_TO_VIA_SPACING" "8.00,8.00,8.00,8.00,8.00,8.00,8.00,8.00,8.00,8.00,8.00,8.00,8.00,8.00"
					( Origin gBackEnd )
				)
				( attribute "HOLE_TO_LINE_SPACING" "8.00,8.00,8.00,8.00,8.00,8.00,8.00,8.00,8.00,8.00,8.00,8.00,8.00,8.00"
					( Origin gBackEnd )
				)
				( attribute "HOLE_TO_SHAPE_SPACING" "8.00,8.00,8.00,8.00,8.00,8.00,8.00,8.00,8.00,8.00,8.00,8.00,8.00,8.00"
					( Origin gBackEnd )
				)
				( attribute "HOLE_TO_HOLE_SPACING" "8.00,8.00,8.00,8.00,8.00,8.00,8.00,8.00,8.00,8.00,8.00,8.00,8.00,8.00"
					( Origin gBackEnd )
				)
				( attribute "MVIA_TO_MVIA_SPACING" "5.00,5.00,5.00,5.00,5.00,5.00,5.00,5.00,5.00,5.00,5.00,5.00,5.00,5.00"
					( Origin gBackEnd )
				)
				( attribute "MVIA_TO_THRUPIN_SPACING" "5.00,5.00,5.00,5.00,5.00,5.00,5.00,5.00,5.00,5.00,5.00,5.00,5.00,5.00"
					( Origin gBackEnd )
				)
				( attribute "MVIA_TO_SMDPIN_SPACING" "5.00,5.00,5.00,5.00,5.00,5.00,5.00,5.00,5.00,5.00,5.00,5.00,5.00,5.00"
					( Origin gBackEnd )
				)
				( attribute "MVIA_TO_THRUVIA_SPACING" "5.00,5.00,5.00,5.00,5.00,5.00,5.00,5.00,5.00,5.00,5.00,5.00,5.00,5.00"
					( Origin gBackEnd )
				)
				( attribute "MVIA_TO_BBV_SPACING" "5.00,5.00,5.00,5.00,5.00,5.00,5.00,5.00,5.00,5.00,5.00,5.00,5.00,5.00"
					( Origin gBackEnd )
				)
				( attribute "MVIA_TO_LINE_SPACING" "5.00,5.00,5.00,5.00,5.00,5.00,5.00,5.00,5.00,5.00,5.00,5.00,5.00,5.00"
					( Origin gBackEnd )
				)
				( attribute "MVIA_TO_SHAPE_SPACING" "5.00,5.00,5.00,5.00,5.00,5.00,5.00,5.00,5.00,5.00,5.00,5.00,5.00,5.00"
					( Origin gBackEnd )
				)
				( attribute "MVIA_TO_TESTPIN_SPACING" "5.00,5.00,5.00,5.00,5.00,5.00,5.00,5.00,5.00,5.00,5.00,5.00,5.00,5.00"
					( Origin gBackEnd )
				)
				( attribute "MVIA_TO_TESTVIA_SPACING" "5.00,5.00,5.00,5.00,5.00,5.00,5.00,5.00,5.00,5.00,5.00,5.00,5.00,5.00"
					( Origin gBackEnd )
				)
				( attribute "BONDPAD_TO_MVIA_SPACING" "5.00,5.00,5.00,5.00,5.00,5.00,5.00,5.00,5.00,5.00,5.00,5.00,5.00,5.00"
					( Origin gBackEnd )
				)
				( attribute "MIN_BVIA_GAP" "5.00"
					( Origin gBackEnd )
				)
				( attribute "BONDPAD_TO_BONDPAD_DIFFP_SPC" "5.00,5.00,5.00,5.00,5.00,5.00,5.00,5.00,5.00,5.00,5.00,5.00,5.00,5.00"
					( Origin gBackEnd )
				)
				( objectStatus "5MIL_US_&_4MIL_SL" )
			)
			( spacingCSet "@crescent_city_bb_fab1_lib.crescent_city_bb_fab1(sch_1):\11H_US_AND_3H_SL_VIA+3H_A\"
				( attribute "THRUPIN_TO_THRUPIN_SPACING" "5.00,5.00,5.00,5.00,5.00,5.00,5.00,5.00,5.00,5.00,5.00,5.00,5.00,5.00"
					( Origin gBackEnd )
				)
				( attribute "THRUPIN_TO_SMDPIN_SPACING" "5.00,5.00,5.00,5.00,5.00,5.00,5.00,5.00,5.00,5.00,5.00,5.00,5.00,5.00"
					( Origin gBackEnd )
				)
				( attribute "TESTPIN_TO_THRUPIN_SPACING" "5.00,5.00,5.00,5.00,5.00,5.00,5.00,5.00,5.00,5.00,5.00,5.00,5.00,5.00"
					( Origin gBackEnd )
				)
				( attribute "THRUPIN_TO_THRUVIA_SPACING" "5.00,5.00,5.00,5.00,5.00,5.00,5.00,5.00,5.00,5.00,5.00,5.00,5.00,5.00"
					( Origin gBackEnd )
				)
				( attribute "TESTVIA_TO_THRUPIN_SPACING" "5.00,5.00,5.00,5.00,5.00,5.00,5.00,5.00,5.00,5.00,5.00,5.00,5.00,5.00"
					( Origin gBackEnd )
				)
				( attribute "BBV_TO_THRUPIN_SPACING" "5.00,5.00,5.00,5.00,5.00,5.00,5.00,5.00,5.00,5.00,5.00,5.00,5.00,5.00"
					( Origin gBackEnd )
				)
				( attribute "THRUPIN_TO_BONDPAD_SPACING" "5.00,5.00,5.00,5.00,5.00,5.00,5.00,5.00,5.00,5.00,5.00,5.00,5.00,5.00"
					( Origin gBackEnd )
				)
				( attribute "LINE_TO_THRUPIN_SPACING" "4.50,4.00,4.00,4.00,4.00,4.00,4.00,4.00,4.00,4.00,4.00,4.00,4.00,4.50"
					( Origin gBackEnd )
				)
				( attribute "THRUPIN_TO_SHAPE_SPACING" "4.50,4.00,4.00,4.00,4.00,4.00,4.00,4.00,4.00,4.00,4.00,4.00,4.00,4.00"
					( Origin gBackEnd )
				)
				( attribute "SMDPIN_TO_SMDPIN_SPACING" "5.00,5.00,5.00,5.00,5.00,5.00,5.00,5.00,5.00,5.00,5.00,5.00,5.00,5.00"
					( Origin gBackEnd )
				)
				( attribute "SMDPIN_TO_TESTPIN_SPACING" "5.00,5.00,5.00,5.00,5.00,5.00,5.00,5.00,5.00,5.00,5.00,5.00,5.00,5.00"
					( Origin gBackEnd )
				)
				( attribute "SMDPIN_TO_THRUVIA_SPACING" "5.00,5.00,5.00,5.00,5.00,5.00,5.00,5.00,5.00,5.00,5.00,5.00,5.00,5.00"
					( Origin gBackEnd )
				)
				( attribute "SMDPIN_TO_TESTVIA_SPACING" "5.00,5.00,5.00,5.00,5.00,5.00,5.00,5.00,5.00,5.00,5.00,5.00,5.00,5.00"
					( Origin gBackEnd )
				)
				( attribute "BBV_TO_SMDPIN_SPACING" "5.00,5.00,5.00,5.00,5.00,5.00,5.00,5.00,5.00,5.00,5.00,5.00,5.00,5.00"
					( Origin gBackEnd )
				)
				( attribute "SMDPIN_TO_BONDPAD_SPACING" "5.00,5.00,5.00,5.00,5.00,5.00,5.00,5.00,5.00,5.00,5.00,5.00,5.00,5.00"
					( Origin gBackEnd )
				)
				( attribute "LINE_TO_SMDPIN_SPACING" "4.50,4.50,4.50,4.50,4.50,4.50,4.50,4.50,4.50,4.50,4.50,4.50,4.50,4.50"
					( Origin gBackEnd )
				)
				( attribute "SHAPE_TO_SMDPIN_SPACING" "5.00,5.00,5.00,5.00,5.00,5.00,5.00,5.00,5.00,5.00,5.00,5.00,5.00,5.00"
					( Origin gBackEnd )
				)
				( attribute "TESTPIN_TO_TESTPIN_SPACING" "5.00,5.00,5.00,5.00,5.00,5.00,5.00,5.00,5.00,5.00,5.00,5.00,5.00,5.00"
					( Origin gBackEnd )
				)
				( attribute "TESTPIN_TO_THRUVIA_SPACING" "5.00,5.00,5.00,5.00,5.00,5.00,5.00,5.00,5.00,5.00,5.00,5.00,5.00,5.00"
					( Origin gBackEnd )
				)
				( attribute "TESTPIN_TO_TESTVIA_SPACING" "5.00,5.00,5.00,5.00,5.00,5.00,5.00,5.00,5.00,5.00,5.00,5.00,5.00,5.00"
					( Origin gBackEnd )
				)
				( attribute "BBV_TO_TESTPIN_SPACING" "5.00,5.00,5.00,5.00,5.00,5.00,5.00,5.00,5.00,5.00,5.00,5.00,5.00,5.00"
					( Origin gBackEnd )
				)
				( attribute "BONDPAD_TO_TESTPIN_SPACING" "5.00,5.00,5.00,5.00,5.00,5.00,5.00,5.00,5.00,5.00,5.00,5.00,5.00,5.00"
					( Origin gBackEnd )
				)
				( attribute "LINE_TO_TESTPIN_SPACING" "4.50,5.00,5.00,5.00,5.00,5.00,5.00,5.00,5.00,5.00,5.00,5.00,5.00,5.00"
					( Origin gBackEnd )
				)
				( attribute "SHAPE_TO_TESTPIN_SPACING" "4.50,4.00,4.00,4.00,4.00,4.00,4.00,4.00,4.00,4.00,4.00,4.00,4.00,4.00"
					( Origin gBackEnd )
				)
				( attribute "THRUVIA_TO_THRUVIA_SPACING" "5.00,5.00,5.00,5.00,5.00,5.00,5.00,5.00,5.00,5.00,5.00,5.00,5.00,5.00"
					( Origin gBackEnd )
				)
				( attribute "TESTVIA_TO_THRUVIA_SPACING" "5.00,5.00,5.00,5.00,5.00,5.00,5.00,5.00,5.00,5.00,5.00,5.00,5.00,5.00"
					( Origin gBackEnd )
				)
				( attribute "BBV_TO_THRUVIA_SPACING" "5.00,5.00,5.00,5.00,5.00,5.00,5.00,5.00,5.00,5.00,5.00,5.00,5.00,5.00"
					( Origin gBackEnd )
				)
				( attribute "BONDPAD_TO_THRUVIA_SPACING" "5.00,5.00,5.00,5.00,5.00,5.00,5.00,5.00,5.00,5.00,5.00,5.00,5.00,5.00"
					( Origin gBackEnd )
				)
				( attribute "LINE_TO_THRUVIA_SPACING" "12.00,5.00,13.00,5.00,13.00,5.00,5.00,5.00,5.00,13.00,5.00,13.00,5.00,12.00"
					( Origin gBackEnd )
				)
				( attribute "SHAPE_TO_THRUVIA_SPACING" "4.50,4.00,4.00,4.00,4.00,4.00,4.00,4.00,4.00,4.00,4.00,4.00,4.00,4.00"
					( Origin gBackEnd )
				)
				( attribute "TESTVIA_TO_TESTVIA_SPACING" "5.00,5.00,5.00,5.00,5.00,5.00,5.00,5.00,5.00,5.00,5.00,5.00,5.00,5.00"
					( Origin gBackEnd )
				)
				( attribute "BBV_TO_TESTVIA_SPACING" "5.00,5.00,5.00,5.00,5.00,5.00,5.00,5.00,5.00,5.00,5.00,5.00,5.00,5.00"
					( Origin gBackEnd )
				)
				( attribute "BONDPAD_TO_TESTVIA_SPACING" "5.00,5.00,5.00,5.00,5.00,5.00,5.00,5.00,5.00,5.00,5.00,5.00,5.00,5.00"
					( Origin gBackEnd )
				)
				( attribute "LINE_TO_TESTVIA_SPACING" "12.00,5.00,13.00,5.00,13.00,5.00,5.00,5.00,5.00,13.00,5.00,13.00,5.00,12.00"
					( Origin gBackEnd )
				)
				( attribute "SHAPE_TO_TESTVIA_SPACING" "4.50,4.00,4.00,4.00,4.00,4.00,4.00,4.00,4.00,4.00,4.00,4.00,4.00,4.00"
					( Origin gBackEnd )
				)
				( attribute "BBV_TO_BBV_SPACING" "5.00,5.00,5.00,5.00,5.00,5.00,5.00,5.00,5.00,5.00,5.00,5.00,5.00,5.00"
					( Origin gBackEnd )
				)
				( attribute "BONDPAD_TO_BBV_SPACING" "5.00,5.00,5.00,5.00,5.00,5.00,5.00,5.00,5.00,5.00,5.00,5.00,5.00,5.00"
					( Origin gBackEnd )
				)
				( attribute "BBV_TO_LINE_SPACING" "5.00,5.00,5.00,5.00,5.00,5.00,5.00,5.00,5.00,5.00,5.00,5.00,5.00,5.00"
					( Origin gBackEnd )
				)
				( attribute "BBV_TO_SHAPE_SPACING" "5.00,5.00,5.00,5.00,5.00,5.00,5.00,5.00,5.00,5.00,5.00,5.00,5.00,5.00"
					( Origin gBackEnd )
				)
				( attribute "BONDPAD_TO_BONDPAD_SPACING" "5.00,5.00,5.00,5.00,5.00,5.00,5.00,5.00,5.00,5.00,5.00,5.00,5.00,5.00"
					( Origin gBackEnd )
				)
				( attribute "BONDPAD_TO_LINE_SPACING" "5.00,5.00,5.00,5.00,5.00,5.00,5.00,5.00,5.00,5.00,5.00,5.00,5.00,5.00"
					( Origin gBackEnd )
				)
				( attribute "BONDPAD_TO_SHAPE_SPACING" "5.00,5.00,5.00,5.00,5.00,5.00,5.00,5.00,5.00,5.00,5.00,5.00,5.00,5.00"
					( Origin gBackEnd )
				)
				( attribute "LINE_TO_LINE_SPACING" "29.37,9.00,9.00,9.00,9.00,9.00,9.00,9.00,9.00,9.00,9.00,9.00,9.00,29.37"
					( Origin gBackEnd )
				)
				( attribute "LINE_TO_SHAPE_SPACING" "5.00,5.00,5.00,5.00,5.00,5.00,5.00,5.00,5.00,5.00,5.00,5.00,5.00,5.00"
					( Origin gBackEnd )
				)
				( attribute "SHAPE_TO_SHAPE_SPACING" "10.00,10.00,10.00,10.00,10.00,10.00,10.00,10.00,10.00,10.00,10.00,10.00,10.00,10.00"
					( Origin gBackEnd )
				)
				( attribute "HOLE_TO_PIN_SPACING" "8.00,8.00,8.00,8.00,8.00,8.00,8.00,8.00,8.00,8.00,8.00,8.00,8.00,8.00"
					( Origin gBackEnd )
				)
				( attribute "HOLE_TO_VIA_SPACING" "8.00,8.00,8.00,8.00,8.00,8.00,8.00,8.00,8.00,8.00,8.00,8.00,8.00,8.00"
					( Origin gBackEnd )
				)
				( attribute "HOLE_TO_LINE_SPACING" "8.00,8.00,8.00,8.00,8.00,8.00,8.00,8.00,8.00,8.00,8.00,8.00,8.00,8.00"
					( Origin gBackEnd )
				)
				( attribute "HOLE_TO_SHAPE_SPACING" "8.00,8.00,8.00,8.00,8.00,8.00,8.00,8.00,8.00,8.00,8.00,8.00,8.00,8.00"
					( Origin gBackEnd )
				)
				( attribute "HOLE_TO_HOLE_SPACING" "8.00,8.00,8.00,8.00,8.00,8.00,8.00,8.00,8.00,8.00,8.00,8.00,8.00,8.00"
					( Origin gBackEnd )
				)
				( attribute "MVIA_TO_MVIA_SPACING" "5.00,5.00,5.00,5.00,5.00,5.00,5.00,5.00,5.00,5.00,5.00,5.00,5.00,5.00"
					( Origin gBackEnd )
				)
				( attribute "MVIA_TO_THRUPIN_SPACING" "5.00,5.00,5.00,5.00,5.00,5.00,5.00,5.00,5.00,5.00,5.00,5.00,5.00,5.00"
					( Origin gBackEnd )
				)
				( attribute "MVIA_TO_SMDPIN_SPACING" "5.00,5.00,5.00,5.00,5.00,5.00,5.00,5.00,5.00,5.00,5.00,5.00,5.00,5.00"
					( Origin gBackEnd )
				)
				( attribute "MVIA_TO_THRUVIA_SPACING" "5.00,5.00,5.00,5.00,5.00,5.00,5.00,5.00,5.00,5.00,5.00,5.00,5.00,5.00"
					( Origin gBackEnd )
				)
				( attribute "MVIA_TO_BBV_SPACING" "5.00,5.00,5.00,5.00,5.00,5.00,5.00,5.00,5.00,5.00,5.00,5.00,5.00,5.00"
					( Origin gBackEnd )
				)
				( attribute "MVIA_TO_LINE_SPACING" "5.00,5.00,5.00,5.00,5.00,5.00,5.00,5.00,5.00,5.00,5.00,5.00,5.00,5.00"
					( Origin gBackEnd )
				)
				( attribute "MVIA_TO_SHAPE_SPACING" "5.00,5.00,5.00,5.00,5.00,5.00,5.00,5.00,5.00,5.00,5.00,5.00,5.00,5.00"
					( Origin gBackEnd )
				)
				( attribute "MVIA_TO_TESTPIN_SPACING" "5.00,5.00,5.00,5.00,5.00,5.00,5.00,5.00,5.00,5.00,5.00,5.00,5.00,5.00"
					( Origin gBackEnd )
				)
				( attribute "MVIA_TO_TESTVIA_SPACING" "5.00,5.00,5.00,5.00,5.00,5.00,5.00,5.00,5.00,5.00,5.00,5.00,5.00,5.00"
					( Origin gBackEnd )
				)
				( attribute "BONDPAD_TO_MVIA_SPACING" "5.00,5.00,5.00,5.00,5.00,5.00,5.00,5.00,5.00,5.00,5.00,5.00,5.00,5.00"
					( Origin gBackEnd )
				)
				( attribute "MIN_BVIA_GAP" "5.00"
					( Origin gBackEnd )
				)
				( attribute "BONDPAD_TO_BONDPAD_DIFFP_SPC" "5.00,5.00,5.00,5.00,5.00,5.00,5.00,5.00,5.00,5.00,5.00,5.00,5.00,5.00"
					( Origin gBackEnd )
				)
				( objectStatus "11H_US_&_3H_SL_VIA_3H+A" )
			)
			( spacingCSet "@crescent_city_bb_fab1_lib.crescent_city_bb_fab1(sch_1):\8P9_US_&_6H_SL\"
				( attribute "THRUPIN_TO_THRUPIN_SPACING" "5.00,5.00,5.00,5.00,5.00,5.00,5.00,5.00,5.00,5.00,5.00,5.00,5.00,5.00"
					( Origin gBackEnd )
				)
				( attribute "THRUPIN_TO_SMDPIN_SPACING" "5.00,5.00,5.00,5.00,5.00,5.00,5.00,5.00,5.00,5.00,5.00,5.00,5.00,5.00"
					( Origin gBackEnd )
				)
				( attribute "TESTPIN_TO_THRUPIN_SPACING" "5.00,5.00,5.00,5.00,5.00,5.00,5.00,5.00,5.00,5.00,5.00,5.00,5.00,5.00"
					( Origin gBackEnd )
				)
				( attribute "THRUPIN_TO_THRUVIA_SPACING" "5.00,5.00,5.00,5.00,5.00,5.00,5.00,5.00,5.00,5.00,5.00,5.00,5.00,5.00"
					( Origin gBackEnd )
				)
				( attribute "TESTVIA_TO_THRUPIN_SPACING" "5.00,5.00,5.00,5.00,5.00,5.00,5.00,5.00,5.00,5.00,5.00,5.00,5.00,5.00"
					( Origin gBackEnd )
				)
				( attribute "BBV_TO_THRUPIN_SPACING" "5.00,5.00,5.00,5.00,5.00,5.00,5.00,5.00,5.00,5.00,5.00,5.00,5.00,5.00"
					( Origin gBackEnd )
				)
				( attribute "THRUPIN_TO_BONDPAD_SPACING" "5.00,5.00,5.00,5.00,5.00,5.00,5.00,5.00,5.00,5.00,5.00,5.00,5.00,5.00"
					( Origin gBackEnd )
				)
				( attribute "LINE_TO_THRUPIN_SPACING" "4.50,4.00,4.00,4.00,4.00,4.00,4.00,4.00,4.00,4.00,4.00,4.00,4.00,4.50"
					( Origin gBackEnd )
				)
				( attribute "THRUPIN_TO_SHAPE_SPACING" "4.50,4.00,4.00,4.00,4.00,4.00,4.00,4.00,4.00,4.00,4.00,4.00,4.00,4.00"
					( Origin gBackEnd )
				)
				( attribute "SMDPIN_TO_SMDPIN_SPACING" "5.00,5.00,5.00,5.00,5.00,5.00,5.00,5.00,5.00,5.00,5.00,5.00,5.00,5.00"
					( Origin gBackEnd )
				)
				( attribute "SMDPIN_TO_TESTPIN_SPACING" "5.00,5.00,5.00,5.00,5.00,5.00,5.00,5.00,5.00,5.00,5.00,5.00,5.00,5.00"
					( Origin gBackEnd )
				)
				( attribute "SMDPIN_TO_THRUVIA_SPACING" "5.00,5.00,5.00,5.00,5.00,5.00,5.00,5.00,5.00,5.00,5.00,5.00,5.00,5.00"
					( Origin gBackEnd )
				)
				( attribute "SMDPIN_TO_TESTVIA_SPACING" "5.00,5.00,5.00,5.00,5.00,5.00,5.00,5.00,5.00,5.00,5.00,5.00,5.00,5.00"
					( Origin gBackEnd )
				)
				( attribute "BBV_TO_SMDPIN_SPACING" "5.00,5.00,5.00,5.00,5.00,5.00,5.00,5.00,5.00,5.00,5.00,5.00,5.00,5.00"
					( Origin gBackEnd )
				)
				( attribute "SMDPIN_TO_BONDPAD_SPACING" "5.00,5.00,5.00,5.00,5.00,5.00,5.00,5.00,5.00,5.00,5.00,5.00,5.00,5.00"
					( Origin gBackEnd )
				)
				( attribute "LINE_TO_SMDPIN_SPACING" "4.50,4.50,4.50,4.50,4.50,4.50,4.50,4.50,4.50,4.50,4.50,4.50,4.50,4.50"
					( Origin gBackEnd )
				)
				( attribute "SHAPE_TO_SMDPIN_SPACING" "5.00,5.00,5.00,5.00,5.00,5.00,5.00,5.00,5.00,5.00,5.00,5.00,5.00,5.00"
					( Origin gBackEnd )
				)
				( attribute "TESTPIN_TO_TESTPIN_SPACING" "5.00,5.00,5.00,5.00,5.00,5.00,5.00,5.00,5.00,5.00,5.00,5.00,5.00,5.00"
					( Origin gBackEnd )
				)
				( attribute "TESTPIN_TO_THRUVIA_SPACING" "5.00,5.00,5.00,5.00,5.00,5.00,5.00,5.00,5.00,5.00,5.00,5.00,5.00,5.00"
					( Origin gBackEnd )
				)
				( attribute "TESTPIN_TO_TESTVIA_SPACING" "5.00,5.00,5.00,5.00,5.00,5.00,5.00,5.00,5.00,5.00,5.00,5.00,5.00,5.00"
					( Origin gBackEnd )
				)
				( attribute "BBV_TO_TESTPIN_SPACING" "5.00,5.00,5.00,5.00,5.00,5.00,5.00,5.00,5.00,5.00,5.00,5.00,5.00,5.00"
					( Origin gBackEnd )
				)
				( attribute "BONDPAD_TO_TESTPIN_SPACING" "5.00,5.00,5.00,5.00,5.00,5.00,5.00,5.00,5.00,5.00,5.00,5.00,5.00,5.00"
					( Origin gBackEnd )
				)
				( attribute "LINE_TO_TESTPIN_SPACING" "4.50,5.00,5.00,5.00,5.00,5.00,5.00,5.00,5.00,5.00,5.00,5.00,5.00,5.00"
					( Origin gBackEnd )
				)
				( attribute "SHAPE_TO_TESTPIN_SPACING" "4.50,4.00,4.00,4.00,4.00,4.00,4.00,4.00,4.00,4.00,4.00,4.00,4.00,4.00"
					( Origin gBackEnd )
				)
				( attribute "THRUVIA_TO_THRUVIA_SPACING" "5.00,5.00,5.00,5.00,5.00,5.00,5.00,5.00,5.00,5.00,5.00,5.00,5.00,5.00"
					( Origin gBackEnd )
				)
				( attribute "TESTVIA_TO_THRUVIA_SPACING" "5.00,5.00,5.00,5.00,5.00,5.00,5.00,5.00,5.00,5.00,5.00,5.00,5.00,5.00"
					( Origin gBackEnd )
				)
				( attribute "BBV_TO_THRUVIA_SPACING" "5.00,5.00,5.00,5.00,5.00,5.00,5.00,5.00,5.00,5.00,5.00,5.00,5.00,5.00"
					( Origin gBackEnd )
				)
				( attribute "BONDPAD_TO_THRUVIA_SPACING" "5.00,5.00,5.00,5.00,5.00,5.00,5.00,5.00,5.00,5.00,5.00,5.00,5.00,5.00"
					( Origin gBackEnd )
				)
				( attribute "LINE_TO_THRUVIA_SPACING" "4.50,4.00,4.00,4.00,4.00,4.00,4.00,4.00,4.00,4.00,4.00,4.00,4.00,4.50"
					( Origin gBackEnd )
				)
				( attribute "SHAPE_TO_THRUVIA_SPACING" "4.50,4.00,4.00,4.00,4.00,4.00,4.00,4.00,4.00,4.00,4.00,4.00,4.00,4.00"
					( Origin gBackEnd )
				)
				( attribute "TESTVIA_TO_TESTVIA_SPACING" "5.00,5.00,5.00,5.00,5.00,5.00,5.00,5.00,5.00,5.00,5.00,5.00,5.00,5.00"
					( Origin gBackEnd )
				)
				( attribute "BBV_TO_TESTVIA_SPACING" "5.00,5.00,5.00,5.00,5.00,5.00,5.00,5.00,5.00,5.00,5.00,5.00,5.00,5.00"
					( Origin gBackEnd )
				)
				( attribute "BONDPAD_TO_TESTVIA_SPACING" "5.00,5.00,5.00,5.00,5.00,5.00,5.00,5.00,5.00,5.00,5.00,5.00,5.00,5.00"
					( Origin gBackEnd )
				)
				( attribute "LINE_TO_TESTVIA_SPACING" "4.50,5.00,4.00,5.00,4.00,5.00,5.00,5.00,5.00,4.00,5.00,4.00,5.00,4.50"
					( Origin gBackEnd )
				)
				( attribute "SHAPE_TO_TESTVIA_SPACING" "4.50,4.00,4.00,4.00,4.00,4.00,4.00,4.00,4.00,4.00,4.00,4.00,4.00,4.00"
					( Origin gBackEnd )
				)
				( attribute "BBV_TO_BBV_SPACING" "5.00,5.00,5.00,5.00,5.00,5.00,5.00,5.00,5.00,5.00,5.00,5.00,5.00,5.00"
					( Origin gBackEnd )
				)
				( attribute "BONDPAD_TO_BBV_SPACING" "5.00,5.00,5.00,5.00,5.00,5.00,5.00,5.00,5.00,5.00,5.00,5.00,5.00,5.00"
					( Origin gBackEnd )
				)
				( attribute "BBV_TO_LINE_SPACING" "5.00,5.00,5.00,5.00,5.00,5.00,5.00,5.00,5.00,5.00,5.00,5.00,5.00,5.00"
					( Origin gBackEnd )
				)
				( attribute "BBV_TO_SHAPE_SPACING" "5.00,5.00,5.00,5.00,5.00,5.00,5.00,5.00,5.00,5.00,5.00,5.00,5.00,5.00"
					( Origin gBackEnd )
				)
				( attribute "BONDPAD_TO_BONDPAD_SPACING" "5.00,5.00,5.00,5.00,5.00,5.00,5.00,5.00,5.00,5.00,5.00,5.00,5.00,5.00"
					( Origin gBackEnd )
				)
				( attribute "BONDPAD_TO_LINE_SPACING" "5.00,5.00,5.00,5.00,5.00,5.00,5.00,5.00,5.00,5.00,5.00,5.00,5.00,5.00"
					( Origin gBackEnd )
				)
				( attribute "BONDPAD_TO_SHAPE_SPACING" "5.00,5.00,5.00,5.00,5.00,5.00,5.00,5.00,5.00,5.00,5.00,5.00,5.00,5.00"
					( Origin gBackEnd )
				)
				( attribute "LINE_TO_LINE_SPACING" "25.00,18.00,18.00,18.00,18.00,18.00,18.00,18.00,18.00,18.00,18.00,18.00,18.00,25.00"
					( Origin gBackEnd )
				)
				( attribute "LINE_TO_SHAPE_SPACING" "5.00,5.00,5.00,5.00,5.00,5.00,5.00,5.00,5.00,5.00,5.00,5.00,5.00,5.00"
					( Origin gBackEnd )
				)
				( attribute "SHAPE_TO_SHAPE_SPACING" "10.00,10.00,10.00,10.00,10.00,10.00,10.00,10.00,10.00,10.00,10.00,10.00,10.00,10.00"
					( Origin gBackEnd )
				)
				( attribute "HOLE_TO_PIN_SPACING" "8.00,8.00,8.00,8.00,8.00,8.00,8.00,8.00,8.00,8.00,8.00,8.00,8.00,8.00"
					( Origin gBackEnd )
				)
				( attribute "HOLE_TO_VIA_SPACING" "8.00,8.00,8.00,8.00,8.00,8.00,8.00,8.00,8.00,8.00,8.00,8.00,8.00,8.00"
					( Origin gBackEnd )
				)
				( attribute "HOLE_TO_LINE_SPACING" "8.00,8.00,8.00,8.00,8.00,8.00,8.00,8.00,8.00,8.00,8.00,8.00,8.00,8.00"
					( Origin gBackEnd )
				)
				( attribute "HOLE_TO_SHAPE_SPACING" "8.00,8.00,8.00,8.00,8.00,8.00,8.00,8.00,8.00,8.00,8.00,8.00,8.00,8.00"
					( Origin gBackEnd )
				)
				( attribute "HOLE_TO_HOLE_SPACING" "8.00,8.00,8.00,8.00,8.00,8.00,8.00,8.00,8.00,8.00,8.00,8.00,8.00,8.00"
					( Origin gBackEnd )
				)
				( attribute "MVIA_TO_MVIA_SPACING" "5.00,5.00,5.00,5.00,5.00,5.00,5.00,5.00,5.00,5.00,5.00,5.00,5.00,5.00"
					( Origin gBackEnd )
				)
				( attribute "MVIA_TO_THRUPIN_SPACING" "5.00,5.00,5.00,5.00,5.00,5.00,5.00,5.00,5.00,5.00,5.00,5.00,5.00,5.00"
					( Origin gBackEnd )
				)
				( attribute "MVIA_TO_SMDPIN_SPACING" "5.00,5.00,5.00,5.00,5.00,5.00,5.00,5.00,5.00,5.00,5.00,5.00,5.00,5.00"
					( Origin gBackEnd )
				)
				( attribute "MVIA_TO_THRUVIA_SPACING" "5.00,5.00,5.00,5.00,5.00,5.00,5.00,5.00,5.00,5.00,5.00,5.00,5.00,5.00"
					( Origin gBackEnd )
				)
				( attribute "MVIA_TO_BBV_SPACING" "5.00,5.00,5.00,5.00,5.00,5.00,5.00,5.00,5.00,5.00,5.00,5.00,5.00,5.00"
					( Origin gBackEnd )
				)
				( attribute "MVIA_TO_LINE_SPACING" "5.00,5.00,5.00,5.00,5.00,5.00,5.00,5.00,5.00,5.00,5.00,5.00,5.00,5.00"
					( Origin gBackEnd )
				)
				( attribute "MVIA_TO_SHAPE_SPACING" "5.00,5.00,5.00,5.00,5.00,5.00,5.00,5.00,5.00,5.00,5.00,5.00,5.00,5.00"
					( Origin gBackEnd )
				)
				( attribute "MVIA_TO_TESTPIN_SPACING" "5.00,5.00,5.00,5.00,5.00,5.00,5.00,5.00,5.00,5.00,5.00,5.00,5.00,5.00"
					( Origin gBackEnd )
				)
				( attribute "MVIA_TO_TESTVIA_SPACING" "5.00,5.00,5.00,5.00,5.00,5.00,5.00,5.00,5.00,5.00,5.00,5.00,5.00,5.00"
					( Origin gBackEnd )
				)
				( attribute "BONDPAD_TO_MVIA_SPACING" "5.00,5.00,5.00,5.00,5.00,5.00,5.00,5.00,5.00,5.00,5.00,5.00,5.00,5.00"
					( Origin gBackEnd )
				)
				( attribute "MIN_BVIA_GAP" "5.00"
					( Origin gBackEnd )
				)
				( attribute "BONDPAD_TO_BONDPAD_DIFFP_SPC" "5.00,5.00,5.00,5.00,5.00,5.00,5.00,5.00,5.00,5.00,5.00,5.00,5.00,5.00"
					( Origin gBackEnd )
				)
				( objectStatus "8P9_US_&_6H_SL" )
			)
			( spacingCSet "@crescent_city_bb_fab1_lib.crescent_city_bb_fab1(sch_1):\13H_US_AND_7H_SL_VIA+3H_A\"
				( attribute "THRUPIN_TO_THRUPIN_SPACING" "5.00,5.00,5.00,5.00,5.00,5.00,5.00,5.00,5.00,5.00,5.00,5.00,5.00,5.00"
					( Origin gBackEnd )
				)
				( attribute "THRUPIN_TO_SMDPIN_SPACING" "5.00,5.00,5.00,5.00,5.00,5.00,5.00,5.00,5.00,5.00,5.00,5.00,5.00,5.00"
					( Origin gBackEnd )
				)
				( attribute "TESTPIN_TO_THRUPIN_SPACING" "5.00,5.00,5.00,5.00,5.00,5.00,5.00,5.00,5.00,5.00,5.00,5.00,5.00,5.00"
					( Origin gBackEnd )
				)
				( attribute "THRUPIN_TO_THRUVIA_SPACING" "5.00,5.00,5.00,5.00,5.00,5.00,5.00,5.00,5.00,5.00,5.00,5.00,5.00,5.00"
					( Origin gBackEnd )
				)
				( attribute "TESTVIA_TO_THRUPIN_SPACING" "5.00,5.00,5.00,5.00,5.00,5.00,5.00,5.00,5.00,5.00,5.00,5.00,5.00,5.00"
					( Origin gBackEnd )
				)
				( attribute "BBV_TO_THRUPIN_SPACING" "5.00,5.00,5.00,5.00,5.00,5.00,5.00,5.00,5.00,5.00,5.00,5.00,5.00,5.00"
					( Origin gBackEnd )
				)
				( attribute "THRUPIN_TO_BONDPAD_SPACING" "5.00,5.00,5.00,5.00,5.00,5.00,5.00,5.00,5.00,5.00,5.00,5.00,5.00,5.00"
					( Origin gBackEnd )
				)
				( attribute "LINE_TO_THRUPIN_SPACING" "4.50,4.00,4.00,4.00,4.00,4.00,4.00,4.00,4.00,4.00,4.00,4.00,4.00,4.50"
					( Origin gBackEnd )
				)
				( attribute "THRUPIN_TO_SHAPE_SPACING" "4.50,4.00,4.00,4.00,4.00,4.00,4.00,4.00,4.00,4.00,4.00,4.00,4.00,4.00"
					( Origin gBackEnd )
				)
				( attribute "SMDPIN_TO_SMDPIN_SPACING" "5.00,5.00,5.00,5.00,5.00,5.00,5.00,5.00,5.00,5.00,5.00,5.00,5.00,5.00"
					( Origin gBackEnd )
				)
				( attribute "SMDPIN_TO_TESTPIN_SPACING" "5.00,5.00,5.00,5.00,5.00,5.00,5.00,5.00,5.00,5.00,5.00,5.00,5.00,25.00"
					( Origin gBackEnd )
				)
				( attribute "SMDPIN_TO_THRUVIA_SPACING" "5.00,5.00,5.00,5.00,5.00,5.00,5.00,5.00,5.00,5.00,5.00,5.00,5.00,5.00"
					( Origin gBackEnd )
				)
				( attribute "SMDPIN_TO_TESTVIA_SPACING" "5.00,5.00,5.00,5.00,5.00,5.00,5.00,5.00,5.00,5.00,5.00,5.00,5.00,5.00"
					( Origin gBackEnd )
				)
				( attribute "BBV_TO_SMDPIN_SPACING" "5.00,5.00,5.00,5.00,5.00,5.00,5.00,5.00,5.00,5.00,5.00,5.00,5.00,5.00"
					( Origin gBackEnd )
				)
				( attribute "SMDPIN_TO_BONDPAD_SPACING" "5.00,5.00,5.00,5.00,5.00,5.00,5.00,5.00,5.00,5.00,5.00,5.00,5.00,5.00"
					( Origin gBackEnd )
				)
				( attribute "LINE_TO_SMDPIN_SPACING" "4.50,4.50,4.50,4.50,4.50,4.50,4.50,4.50,4.50,4.50,4.50,4.50,4.50,4.50"
					( Origin gBackEnd )
				)
				( attribute "SHAPE_TO_SMDPIN_SPACING" "5.00,5.00,5.00,5.00,5.00,5.00,5.00,5.00,5.00,5.00,5.00,5.00,5.00,5.00"
					( Origin gBackEnd )
				)
				( attribute "TESTPIN_TO_TESTPIN_SPACING" "5.00,5.00,5.00,5.00,5.00,5.00,5.00,5.00,5.00,5.00,5.00,5.00,5.00,5.00"
					( Origin gBackEnd )
				)
				( attribute "TESTPIN_TO_THRUVIA_SPACING" "5.00,5.00,5.00,5.00,5.00,5.00,5.00,5.00,5.00,5.00,5.00,5.00,5.00,5.00"
					( Origin gBackEnd )
				)
				( attribute "TESTPIN_TO_TESTVIA_SPACING" "5.00,5.00,5.00,5.00,5.00,5.00,5.00,5.00,5.00,5.00,5.00,5.00,5.00,5.00"
					( Origin gBackEnd )
				)
				( attribute "BBV_TO_TESTPIN_SPACING" "5.00,5.00,5.00,5.00,5.00,5.00,5.00,5.00,5.00,5.00,5.00,5.00,5.00,5.00"
					( Origin gBackEnd )
				)
				( attribute "BONDPAD_TO_TESTPIN_SPACING" "5.00,5.00,5.00,5.00,5.00,5.00,5.00,5.00,5.00,5.00,5.00,5.00,5.00,5.00"
					( Origin gBackEnd )
				)
				( attribute "LINE_TO_TESTPIN_SPACING" "4.50,5.00,5.00,5.00,5.00,5.00,5.00,5.00,5.00,5.00,5.00,5.00,5.00,5.00"
					( Origin gBackEnd )
				)
				( attribute "SHAPE_TO_TESTPIN_SPACING" "4.50,4.00,4.00,4.00,4.00,4.00,4.00,4.00,4.00,4.00,4.00,4.00,4.00,4.00"
					( Origin gBackEnd )
				)
				( attribute "THRUVIA_TO_THRUVIA_SPACING" "5.00,5.00,5.00,5.00,5.00,5.00,5.00,5.00,5.00,5.00,5.00,5.00,5.00,5.00"
					( Origin gBackEnd )
				)
				( attribute "TESTVIA_TO_THRUVIA_SPACING" "5.00,5.00,5.00,5.00,5.00,5.00,5.00,5.00,5.00,5.00,5.00,5.00,5.00,5.00"
					( Origin gBackEnd )
				)
				( attribute "BBV_TO_THRUVIA_SPACING" "5.00,5.00,5.00,5.00,5.00,5.00,5.00,5.00,5.00,5.00,5.00,5.00,5.00,5.00"
					( Origin gBackEnd )
				)
				( attribute "BONDPAD_TO_THRUVIA_SPACING" "5.00,5.00,5.00,5.00,5.00,5.00,5.00,5.00,5.00,5.00,5.00,5.00,5.00,5.00"
					( Origin gBackEnd )
				)
				( attribute "LINE_TO_THRUVIA_SPACING" "12.00,5.00,13.00,5.00,13.00,5.00,5.00,5.00,5.00,13.00,5.00,13.00,5.00,12.00"
					( Origin gBackEnd )
				)
				( attribute "SHAPE_TO_THRUVIA_SPACING" "4.50,4.00,4.00,4.00,4.00,4.00,4.00,4.00,4.00,4.00,4.00,4.00,4.00,4.00"
					( Origin gBackEnd )
				)
				( attribute "TESTVIA_TO_TESTVIA_SPACING" "5.00,5.00,5.00,5.00,5.00,5.00,5.00,5.00,5.00,5.00,5.00,5.00,5.00,5.00"
					( Origin gBackEnd )
				)
				( attribute "BBV_TO_TESTVIA_SPACING" "5.00,5.00,5.00,5.00,5.00,5.00,5.00,5.00,5.00,5.00,5.00,5.00,5.00,5.00"
					( Origin gBackEnd )
				)
				( attribute "BONDPAD_TO_TESTVIA_SPACING" "5.00,5.00,5.00,5.00,5.00,5.00,5.00,5.00,5.00,5.00,5.00,5.00,5.00,5.00"
					( Origin gBackEnd )
				)
				( attribute "LINE_TO_TESTVIA_SPACING" "12.00,5.00,13.00,5.00,13.00,5.00,5.00,5.00,5.00,13.00,5.00,13.00,5.00,12.00"
					( Origin gBackEnd )
				)
				( attribute "SHAPE_TO_TESTVIA_SPACING" "4.50,4.00,4.00,4.00,4.00,4.00,4.00,4.00,4.00,4.00,4.00,4.00,4.00,4.00"
					( Origin gBackEnd )
				)
				( attribute "BBV_TO_BBV_SPACING" "5.00,5.00,5.00,5.00,5.00,5.00,5.00,5.00,5.00,5.00,5.00,5.00,5.00,5.00"
					( Origin gBackEnd )
				)
				( attribute "BONDPAD_TO_BBV_SPACING" "5.00,5.00,5.00,5.00,5.00,5.00,5.00,5.00,5.00,5.00,5.00,5.00,5.00,5.00"
					( Origin gBackEnd )
				)
				( attribute "BBV_TO_LINE_SPACING" "5.00,5.00,5.00,5.00,5.00,5.00,5.00,5.00,5.00,5.00,5.00,5.00,5.00,5.00"
					( Origin gBackEnd )
				)
				( attribute "BBV_TO_SHAPE_SPACING" "5.00,5.00,5.00,5.00,5.00,5.00,5.00,5.00,5.00,5.00,5.00,5.00,5.00,5.00"
					( Origin gBackEnd )
				)
				( attribute "BONDPAD_TO_BONDPAD_SPACING" "5.00,5.00,5.00,5.00,5.00,5.00,5.00,5.00,5.00,5.00,5.00,5.00,5.00,5.00"
					( Origin gBackEnd )
				)
				( attribute "BONDPAD_TO_LINE_SPACING" "5.00,5.00,5.00,5.00,5.00,5.00,5.00,5.00,5.00,5.00,5.00,5.00,5.00,5.00"
					( Origin gBackEnd )
				)
				( attribute "BONDPAD_TO_SHAPE_SPACING" "5.00,5.00,5.00,5.00,5.00,5.00,5.00,5.00,5.00,5.00,5.00,5.00,5.00,5.00"
					( Origin gBackEnd )
				)
				( attribute "LINE_TO_LINE_SPACING" "35.10,21.00,21.00,21.00,21.00,21.00,21.00,21.00,21.00,21.00,21.00,21.00,21.00,35.10"
					( Origin gBackEnd )
				)
				( attribute "LINE_TO_SHAPE_SPACING" "5.00,5.00,5.00,5.00,5.00,5.00,5.00,5.00,5.00,5.00,5.00,5.00,5.00,5.00"
					( Origin gBackEnd )
				)
				( attribute "SHAPE_TO_SHAPE_SPACING" "10.00,10.00,10.00,10.00,10.00,10.00,10.00,10.00,10.00,10.00,10.00,10.00,10.00,10.00"
					( Origin gBackEnd )
				)
				( attribute "HOLE_TO_PIN_SPACING" "8.00,8.00,8.00,8.00,8.00,8.00,8.00,8.00,8.00,8.00,8.00,8.00,8.00,8.00"
					( Origin gBackEnd )
				)
				( attribute "HOLE_TO_VIA_SPACING" "8.00,8.00,8.00,8.00,8.00,8.00,8.00,8.00,8.00,8.00,8.00,8.00,8.00,8.00"
					( Origin gBackEnd )
				)
				( attribute "HOLE_TO_LINE_SPACING" "8.00,8.00,8.00,8.00,8.00,8.00,8.00,8.00,8.00,8.00,8.00,8.00,8.00,8.00"
					( Origin gBackEnd )
				)
				( attribute "HOLE_TO_SHAPE_SPACING" "8.00,8.00,8.00,8.00,8.00,8.00,8.00,8.00,8.00,8.00,8.00,8.00,8.00,8.00"
					( Origin gBackEnd )
				)
				( attribute "HOLE_TO_HOLE_SPACING" "8.00,8.00,8.00,8.00,8.00,8.00,8.00,8.00,8.00,8.00,8.00,8.00,8.00,8.00"
					( Origin gBackEnd )
				)
				( attribute "MVIA_TO_MVIA_SPACING" "5.00,5.00,5.00,5.00,5.00,5.00,5.00,5.00,5.00,5.00,5.00,5.00,5.00,5.00"
					( Origin gBackEnd )
				)
				( attribute "MVIA_TO_THRUPIN_SPACING" "5.00,5.00,5.00,5.00,5.00,5.00,5.00,5.00,5.00,5.00,5.00,5.00,5.00,5.00"
					( Origin gBackEnd )
				)
				( attribute "MVIA_TO_SMDPIN_SPACING" "5.00,5.00,5.00,5.00,5.00,5.00,5.00,5.00,5.00,5.00,5.00,5.00,5.00,5.00"
					( Origin gBackEnd )
				)
				( attribute "MVIA_TO_THRUVIA_SPACING" "5.00,5.00,5.00,5.00,5.00,5.00,5.00,5.00,5.00,5.00,5.00,5.00,5.00,5.00"
					( Origin gBackEnd )
				)
				( attribute "MVIA_TO_BBV_SPACING" "5.00,5.00,5.00,5.00,5.00,5.00,5.00,5.00,5.00,5.00,5.00,5.00,5.00,5.00"
					( Origin gBackEnd )
				)
				( attribute "MVIA_TO_LINE_SPACING" "5.00,5.00,5.00,5.00,5.00,5.00,5.00,5.00,5.00,5.00,5.00,5.00,5.00,5.00"
					( Origin gBackEnd )
				)
				( attribute "MVIA_TO_SHAPE_SPACING" "5.00,5.00,5.00,5.00,5.00,5.00,5.00,5.00,5.00,5.00,5.00,5.00,5.00,5.00"
					( Origin gBackEnd )
				)
				( attribute "MVIA_TO_TESTPIN_SPACING" "5.00,5.00,5.00,5.00,5.00,5.00,5.00,5.00,5.00,5.00,5.00,5.00,5.00,5.00"
					( Origin gBackEnd )
				)
				( attribute "MVIA_TO_TESTVIA_SPACING" "5.00,5.00,5.00,5.00,5.00,5.00,5.00,5.00,5.00,5.00,5.00,5.00,5.00,5.00"
					( Origin gBackEnd )
				)
				( attribute "BONDPAD_TO_MVIA_SPACING" "5.00,5.00,5.00,5.00,5.00,5.00,5.00,5.00,5.00,5.00,5.00,5.00,5.00,5.00"
					( Origin gBackEnd )
				)
				( attribute "MIN_BVIA_GAP" "5.00"
					( Origin gBackEnd )
				)
				( attribute "BONDPAD_TO_BONDPAD_DIFFP_SPC" "5.00,5.00,5.00,5.00,5.00,5.00,5.00,5.00,5.00,5.00,5.00,5.00,5.00,5.00"
					( Origin gBackEnd )
				)
				( objectStatus "13H_US_&_7H_SL_VIA_3H+A" )
			)
			( spacingCSet "@sapphirecity_baseboard_lib.sapphirecity_baseboard(sch_1):\FET_NODES\"
				( attribute "THRUPIN_TO_THRUPIN_SPACING" "5.00,5.00,5.00,5.00,5.00,5.00,5.00,5.00,5.00,5.00,5.00,5.00,5.00,5.00"
					( Origin gBackEnd )
				)
				( attribute "THRUPIN_TO_SMDPIN_SPACING" "5.00,5.00,5.00,5.00,5.00,5.00,5.00,5.00,5.00,5.00,5.00,5.00,5.00,5.00"
					( Origin gBackEnd )
				)
				( attribute "TESTPIN_TO_THRUPIN_SPACING" "5.00,5.00,5.00,5.00,5.00,5.00,5.00,5.00,5.00,5.00,5.00,5.00,5.00,5.00"
					( Origin gBackEnd )
				)
				( attribute "THRUPIN_TO_THRUVIA_SPACING" "5.00,5.00,5.00,5.00,5.00,5.00,5.00,5.00,5.00,5.00,5.00,5.00,5.00,5.00"
					( Origin gBackEnd )
				)
				( attribute "TESTVIA_TO_THRUPIN_SPACING" "5.00,5.00,5.00,5.00,5.00,5.00,5.00,5.00,5.00,5.00,5.00,5.00,5.00,5.00"
					( Origin gBackEnd )
				)
				( attribute "BBV_TO_THRUPIN_SPACING" "5.00,5.00,5.00,5.00,5.00,5.00,5.00,5.00,5.00,5.00,5.00,5.00,5.00,5.00"
					( Origin gBackEnd )
				)
				( attribute "THRUPIN_TO_BONDPAD_SPACING" "5.00,5.00,5.00,5.00,5.00,5.00,5.00,5.00,5.00,5.00,5.00,5.00,5.00,5.00"
					( Origin gBackEnd )
				)
				( attribute "LINE_TO_THRUPIN_SPACING" "5.00,5.00,5.00,5.00,5.00,5.00,5.00,5.00,5.00,5.00,5.00,5.00,5.00,5.00"
					( Origin gBackEnd )
				)
				( attribute "THRUPIN_TO_SHAPE_SPACING" "5.00,5.00,5.00,5.00,5.00,5.00,5.00,5.00,5.00,5.00,5.00,5.00,5.00,5.00"
					( Origin gBackEnd )
				)
				( attribute "SMDPIN_TO_SMDPIN_SPACING" "5.00,5.00,5.00,5.00,5.00,5.00,5.00,5.00,5.00,5.00,5.00,5.00,5.00,5.00"
					( Origin gBackEnd )
				)
				( attribute "SMDPIN_TO_TESTPIN_SPACING" "5.00,5.00,5.00,5.00,5.00,5.00,5.00,5.00,5.00,5.00,5.00,5.00,5.00,5.00"
					( Origin gBackEnd )
				)
				( attribute "SMDPIN_TO_THRUVIA_SPACING" "5.00,5.00,5.00,5.00,5.00,5.00,5.00,5.00,5.00,5.00,5.00,5.00,5.00,5.00"
					( Origin gBackEnd )
				)
				( attribute "SMDPIN_TO_TESTVIA_SPACING" "5.00,5.00,5.00,5.00,5.00,5.00,5.00,5.00,5.00,5.00,5.00,5.00,5.00,5.00"
					( Origin gBackEnd )
				)
				( attribute "BBV_TO_SMDPIN_SPACING" "5.00,5.00,5.00,5.00,5.00,5.00,5.00,5.00,5.00,5.00,5.00,5.00,5.00,5.00"
					( Origin gBackEnd )
				)
				( attribute "SMDPIN_TO_BONDPAD_SPACING" "5.00,5.00,5.00,5.00,5.00,5.00,5.00,5.00,5.00,5.00,5.00,5.00,5.00,5.00"
					( Origin gBackEnd )
				)
				( attribute "LINE_TO_SMDPIN_SPACING" "4.50,4.50,4.50,4.50,4.50,4.50,4.50,4.50,4.50,4.50,4.50,4.50,4.50,4.50"
					( Origin gBackEnd )
				)
				( attribute "SHAPE_TO_SMDPIN_SPACING" "5.00,5.00,5.00,5.00,5.00,5.00,5.00,5.00,5.00,5.00,5.00,5.00,5.00,5.00"
					( Origin gBackEnd )
				)
				( attribute "TESTPIN_TO_TESTPIN_SPACING" "5.00,5.00,5.00,5.00,5.00,5.00,5.00,5.00,5.00,5.00,5.00,5.00,5.00,5.00"
					( Origin gBackEnd )
				)
				( attribute "TESTPIN_TO_THRUVIA_SPACING" "5.00,5.00,5.00,5.00,5.00,5.00,5.00,5.00,5.00,5.00,5.00,5.00,5.00,5.00"
					( Origin gBackEnd )
				)
				( attribute "TESTPIN_TO_TESTVIA_SPACING" "5.00,5.00,5.00,5.00,5.00,5.00,5.00,5.00,5.00,5.00,5.00,5.00,5.00,5.00"
					( Origin gBackEnd )
				)
				( attribute "BBV_TO_TESTPIN_SPACING" "5.00,5.00,5.00,5.00,5.00,5.00,5.00,5.00,5.00,5.00,5.00,5.00,5.00,5.00"
					( Origin gBackEnd )
				)
				( attribute "BONDPAD_TO_TESTPIN_SPACING" "5.00,5.00,5.00,5.00,5.00,5.00,5.00,5.00,5.00,5.00,5.00,5.00,5.00,5.00"
					( Origin gBackEnd )
				)
				( attribute "LINE_TO_TESTPIN_SPACING" "4.50,5.00,5.00,5.00,5.00,5.00,5.00,5.00,5.00,5.00,5.00,5.00,5.00,5.00"
					( Origin gBackEnd )
				)
				( attribute "SHAPE_TO_TESTPIN_SPACING" "5.00,5.00,5.00,5.00,5.00,5.00,5.00,5.00,5.00,5.00,5.00,5.00,5.00,5.00"
					( Origin gBackEnd )
				)
				( attribute "THRUVIA_TO_THRUVIA_SPACING" "5.00,5.00,5.00,5.00,5.00,5.00,5.00,5.00,5.00,5.00,5.00,5.00,5.00,5.00"
					( Origin gBackEnd )
				)
				( attribute "TESTVIA_TO_THRUVIA_SPACING" "5.00,5.00,5.00,5.00,5.00,5.00,5.00,5.00,5.00,5.00,5.00,5.00,5.00,5.00"
					( Origin gBackEnd )
				)
				( attribute "BBV_TO_THRUVIA_SPACING" "5.00,5.00,5.00,5.00,5.00,5.00,5.00,5.00,5.00,5.00,5.00,5.00,5.00,5.00"
					( Origin gBackEnd )
				)
				( attribute "BONDPAD_TO_THRUVIA_SPACING" "5.00,5.00,5.00,5.00,5.00,5.00,5.00,5.00,5.00,5.00,5.00,5.00,5.00,5.00"
					( Origin gBackEnd )
				)
				( attribute "LINE_TO_THRUVIA_SPACING" "4.50,4.00,4.00,4.00,4.00,4.00,4.00,4.00,4.00,4.00,4.00,4.00,4.00,4.50"
					( Origin gBackEnd )
				)
				( attribute "SHAPE_TO_THRUVIA_SPACING" "5.00,5.00,5.00,5.00,5.00,5.00,5.00,5.00,5.00,5.00,5.00,5.00,5.00,5.00"
					( Origin gBackEnd )
				)
				( attribute "TESTVIA_TO_TESTVIA_SPACING" "5.00,5.00,5.00,5.00,5.00,5.00,5.00,5.00,5.00,5.00,5.00,5.00,5.00,5.00"
					( Origin gBackEnd )
				)
				( attribute "BBV_TO_TESTVIA_SPACING" "5.00,5.00,5.00,5.00,5.00,5.00,5.00,5.00,5.00,5.00,5.00,5.00,5.00,5.00"
					( Origin gBackEnd )
				)
				( attribute "BONDPAD_TO_TESTVIA_SPACING" "5.00,5.00,5.00,5.00,5.00,5.00,5.00,5.00,5.00,5.00,5.00,5.00,5.00,5.00"
					( Origin gBackEnd )
				)
				( attribute "LINE_TO_TESTVIA_SPACING" "4.50,5.00,5.00,5.00,5.00,5.00,5.00,5.00,5.00,5.00,5.00,5.00,5.00,4.50"
					( Origin gBackEnd )
				)
				( attribute "SHAPE_TO_TESTVIA_SPACING" "5.00,5.00,5.00,5.00,5.00,5.00,5.00,5.00,5.00,5.00,5.00,5.00,5.00,5.00"
					( Origin gBackEnd )
				)
				( attribute "BBV_TO_BBV_SPACING" "5.00,5.00,5.00,5.00,5.00,5.00,5.00,5.00,5.00,5.00,5.00,5.00,5.00,5.00"
					( Origin gBackEnd )
				)
				( attribute "BONDPAD_TO_BBV_SPACING" "5.00,5.00,5.00,5.00,5.00,5.00,5.00,5.00,5.00,5.00,5.00,5.00,5.00,5.00"
					( Origin gBackEnd )
				)
				( attribute "BBV_TO_LINE_SPACING" "5.00,5.00,5.00,5.00,5.00,5.00,5.00,5.00,5.00,5.00,5.00,5.00,5.00,5.00"
					( Origin gBackEnd )
				)
				( attribute "BBV_TO_SHAPE_SPACING" "5.00,5.00,5.00,5.00,5.00,5.00,5.00,5.00,5.00,5.00,5.00,5.00,5.00,5.00"
					( Origin gBackEnd )
				)
				( attribute "BONDPAD_TO_BONDPAD_SPACING" "5.00,5.00,5.00,5.00,5.00,5.00,5.00,5.00,5.00,5.00,5.00,5.00,5.00,5.00"
					( Origin gBackEnd )
				)
				( attribute "BONDPAD_TO_LINE_SPACING" "5.00,5.00,5.00,5.00,5.00,5.00,5.00,5.00,5.00,5.00,5.00,5.00,5.00,5.00"
					( Origin gBackEnd )
				)
				( attribute "BONDPAD_TO_SHAPE_SPACING" "5.00,5.00,5.00,5.00,5.00,5.00,5.00,5.00,5.00,5.00,5.00,5.00,5.00,5.00"
					( Origin gBackEnd )
				)
				( attribute "LINE_TO_LINE_SPACING" "5.00,5.00,5.00,5.00,5.00,5.00,5.00,5.00,5.00,5.00,5.00,5.00,5.00,5.00"
					( Origin gBackEnd )
				)
				( attribute "LINE_TO_SHAPE_SPACING" "5.00,5.00,5.00,5.00,5.00,5.00,5.00,5.00,5.00,5.00,5.00,5.00,5.00,5.00"
					( Origin gBackEnd )
				)
				( attribute "SHAPE_TO_SHAPE_SPACING" "10.00,10.00,10.00,10.00,10.00,10.00,10.00,10.00,10.00,10.00,10.00,10.00,10.00,10.00"
					( Origin gBackEnd )
				)
				( attribute "HOLE_TO_PIN_SPACING" "8.00,8.00,8.00,8.00,8.00,8.00,8.00,8.00,8.00,8.00,8.00,8.00,8.00,8.00"
					( Origin gBackEnd )
				)
				( attribute "HOLE_TO_VIA_SPACING" "8.00,8.00,8.00,8.00,8.00,8.00,8.00,8.00,8.00,8.00,8.00,8.00,8.00,8.00"
					( Origin gBackEnd )
				)
				( attribute "HOLE_TO_LINE_SPACING" "8.00,8.00,8.00,8.00,8.00,8.00,8.00,8.00,8.00,8.00,8.00,8.00,8.00,8.00"
					( Origin gBackEnd )
				)
				( attribute "HOLE_TO_SHAPE_SPACING" "8.00,8.00,8.00,8.00,8.00,8.00,8.00,8.00,8.00,8.00,8.00,8.00,8.00,8.00"
					( Origin gBackEnd )
				)
				( attribute "HOLE_TO_HOLE_SPACING" "8.00,8.00,8.00,8.00,8.00,8.00,8.00,8.00,8.00,8.00,8.00,8.00,8.00,8.00"
					( Origin gBackEnd )
				)
				( attribute "MVIA_TO_MVIA_SPACING" "5.00,5.00,5.00,5.00,5.00,5.00,5.00,5.00,5.00,5.00,5.00,5.00,5.00,5.00"
					( Origin gBackEnd )
				)
				( attribute "MVIA_TO_THRUPIN_SPACING" "5.00,5.00,5.00,5.00,5.00,5.00,5.00,5.00,5.00,5.00,5.00,5.00,5.00,5.00"
					( Origin gBackEnd )
				)
				( attribute "MVIA_TO_SMDPIN_SPACING" "5.00,5.00,5.00,5.00,5.00,5.00,5.00,5.00,5.00,5.00,5.00,5.00,5.00,5.00"
					( Origin gBackEnd )
				)
				( attribute "MVIA_TO_THRUVIA_SPACING" "5.00,5.00,5.00,5.00,5.00,5.00,5.00,5.00,5.00,5.00,5.00,5.00,5.00,5.00"
					( Origin gBackEnd )
				)
				( attribute "MVIA_TO_BBV_SPACING" "5.00,5.00,5.00,5.00,5.00,5.00,5.00,5.00,5.00,5.00,5.00,5.00,5.00,5.00"
					( Origin gBackEnd )
				)
				( attribute "MVIA_TO_LINE_SPACING" "5.00,5.00,5.00,5.00,5.00,5.00,5.00,5.00,5.00,5.00,5.00,5.00,5.00,5.00"
					( Origin gBackEnd )
				)
				( attribute "MVIA_TO_SHAPE_SPACING" "5.00,5.00,5.00,5.00,5.00,5.00,5.00,5.00,5.00,5.00,5.00,5.00,5.00,5.00"
					( Origin gBackEnd )
				)
				( attribute "MVIA_TO_TESTPIN_SPACING" "5.00,5.00,5.00,5.00,5.00,5.00,5.00,5.00,5.00,5.00,5.00,5.00,5.00,5.00"
					( Origin gBackEnd )
				)
				( attribute "MVIA_TO_TESTVIA_SPACING" "5.00,5.00,5.00,5.00,5.00,5.00,5.00,5.00,5.00,5.00,5.00,5.00,5.00,5.00"
					( Origin gBackEnd )
				)
				( attribute "BONDPAD_TO_MVIA_SPACING" "5.00,5.00,5.00,5.00,5.00,5.00,5.00,5.00,5.00,5.00,5.00,5.00,5.00,5.00"
					( Origin gBackEnd )
				)
				( attribute "MIN_BVIA_GAP" "5.00"
					( Origin gBackEnd )
				)
				( attribute "BONDPAD_TO_BONDPAD_DIFFP_SPC" "5.00,5.00,5.00,5.00,5.00,5.00,5.00,5.00,5.00,5.00,5.00,5.00,5.00,5.00"
					( Origin gBackEnd )
				)
				( objectStatus "FET_NODES" )
			)
			( spacingCSet "@sapphirecity_baseboard_lib.sapphirecity_baseboard(sch_1):\FET_GATE_TRACES\"
				( attribute "THRUPIN_TO_THRUPIN_SPACING" "5.00,5.00,5.00,5.00,5.00,5.00,5.00,5.00,5.00,5.00,5.00,5.00,5.00,5.00"
					( Origin gBackEnd )
				)
				( attribute "THRUPIN_TO_SMDPIN_SPACING" "5.00,5.00,5.00,5.00,5.00,5.00,5.00,5.00,5.00,5.00,5.00,5.00,5.00,5.00"
					( Origin gBackEnd )
				)
				( attribute "TESTPIN_TO_THRUPIN_SPACING" "5.00,5.00,5.00,5.00,5.00,5.00,5.00,5.00,5.00,5.00,5.00,5.00,5.00,5.00"
					( Origin gBackEnd )
				)
				( attribute "THRUPIN_TO_THRUVIA_SPACING" "5.00,5.00,5.00,5.00,5.00,5.00,5.00,5.00,5.00,5.00,5.00,5.00,5.00,5.00"
					( Origin gBackEnd )
				)
				( attribute "TESTVIA_TO_THRUPIN_SPACING" "5.00,5.00,5.00,5.00,5.00,5.00,5.00,5.00,5.00,5.00,5.00,5.00,5.00,5.00"
					( Origin gBackEnd )
				)
				( attribute "BBV_TO_THRUPIN_SPACING" "5.00,5.00,5.00,5.00,5.00,5.00,5.00,5.00,5.00,5.00,5.00,5.00,5.00,5.00"
					( Origin gBackEnd )
				)
				( attribute "THRUPIN_TO_BONDPAD_SPACING" "5.00,5.00,5.00,5.00,5.00,5.00,5.00,5.00,5.00,5.00,5.00,5.00,5.00,5.00"
					( Origin gBackEnd )
				)
				( attribute "LINE_TO_THRUPIN_SPACING" "5.00,5.00,5.00,5.00,5.00,5.00,5.00,5.00,5.00,5.00,5.00,5.00,5.00,5.00"
					( Origin gBackEnd )
				)
				( attribute "THRUPIN_TO_SHAPE_SPACING" "5.00,5.00,5.00,5.00,5.00,5.00,5.00,5.00,5.00,5.00,5.00,5.00,5.00,5.00"
					( Origin gBackEnd )
				)
				( attribute "SMDPIN_TO_SMDPIN_SPACING" "5.00,5.00,5.00,5.00,5.00,5.00,5.00,5.00,5.00,5.00,5.00,5.00,5.00,5.00"
					( Origin gBackEnd )
				)
				( attribute "SMDPIN_TO_TESTPIN_SPACING" "5.00,5.00,5.00,5.00,5.00,5.00,5.00,5.00,5.00,5.00,5.00,5.00,5.00,5.00"
					( Origin gBackEnd )
				)
				( attribute "SMDPIN_TO_THRUVIA_SPACING" "5.00,5.00,5.00,5.00,5.00,5.00,5.00,5.00,5.00,5.00,5.00,5.00,5.00,5.00"
					( Origin gBackEnd )
				)
				( attribute "SMDPIN_TO_TESTVIA_SPACING" "5.00,5.00,5.00,5.00,5.00,5.00,5.00,5.00,5.00,5.00,5.00,5.00,5.00,5.00"
					( Origin gBackEnd )
				)
				( attribute "BBV_TO_SMDPIN_SPACING" "5.00,5.00,5.00,5.00,5.00,5.00,5.00,5.00,5.00,5.00,5.00,5.00,5.00,5.00"
					( Origin gBackEnd )
				)
				( attribute "SMDPIN_TO_BONDPAD_SPACING" "5.00,5.00,5.00,5.00,5.00,5.00,5.00,5.00,5.00,5.00,5.00,5.00,5.00,5.00"
					( Origin gBackEnd )
				)
				( attribute "LINE_TO_SMDPIN_SPACING" "4.50,4.50,4.50,4.50,4.50,4.50,4.50,4.50,4.50,4.50,4.50,4.50,4.50,4.50"
					( Origin gBackEnd )
				)
				( attribute "SHAPE_TO_SMDPIN_SPACING" "5.00,5.00,5.00,5.00,5.00,5.00,5.00,5.00,5.00,5.00,5.00,5.00,5.00,5.00"
					( Origin gBackEnd )
				)
				( attribute "TESTPIN_TO_TESTPIN_SPACING" "5.00,5.00,5.00,5.00,5.00,5.00,5.00,5.00,5.00,5.00,5.00,5.00,5.00,5.00"
					( Origin gBackEnd )
				)
				( attribute "TESTPIN_TO_THRUVIA_SPACING" "5.00,5.00,5.00,5.00,5.00,5.00,5.00,5.00,5.00,5.00,5.00,5.00,5.00,5.00"
					( Origin gBackEnd )
				)
				( attribute "TESTPIN_TO_TESTVIA_SPACING" "5.00,5.00,5.00,5.00,5.00,5.00,5.00,5.00,5.00,5.00,5.00,5.00,5.00,5.00"
					( Origin gBackEnd )
				)
				( attribute "BBV_TO_TESTPIN_SPACING" "5.00,5.00,5.00,5.00,5.00,5.00,5.00,5.00,5.00,5.00,5.00,5.00,5.00,5.00"
					( Origin gBackEnd )
				)
				( attribute "BONDPAD_TO_TESTPIN_SPACING" "5.00,5.00,5.00,5.00,5.00,5.00,5.00,5.00,5.00,5.00,5.00,5.00,5.00,5.00"
					( Origin gBackEnd )
				)
				( attribute "LINE_TO_TESTPIN_SPACING" "4.50,5.00,5.00,5.00,5.00,5.00,5.00,5.00,5.00,5.00,5.00,5.00,5.00,5.00"
					( Origin gBackEnd )
				)
				( attribute "SHAPE_TO_TESTPIN_SPACING" "5.00,5.00,5.00,5.00,5.00,5.00,5.00,5.00,5.00,5.00,5.00,5.00,5.00,5.00"
					( Origin gBackEnd )
				)
				( attribute "THRUVIA_TO_THRUVIA_SPACING" "5.00,5.00,5.00,5.00,5.00,5.00,5.00,5.00,5.00,5.00,5.00,5.00,5.00,5.00"
					( Origin gBackEnd )
				)
				( attribute "TESTVIA_TO_THRUVIA_SPACING" "5.00,5.00,5.00,5.00,5.00,5.00,5.00,5.00,5.00,5.00,5.00,5.00,5.00,5.00"
					( Origin gBackEnd )
				)
				( attribute "BBV_TO_THRUVIA_SPACING" "5.00,5.00,5.00,5.00,5.00,5.00,5.00,5.00,5.00,5.00,5.00,5.00,5.00,5.00"
					( Origin gBackEnd )
				)
				( attribute "BONDPAD_TO_THRUVIA_SPACING" "5.00,5.00,5.00,5.00,5.00,5.00,5.00,5.00,5.00,5.00,5.00,5.00,5.00,5.00"
					( Origin gBackEnd )
				)
				( attribute "LINE_TO_THRUVIA_SPACING" "4.50,4.00,4.00,4.00,4.00,4.00,4.00,4.00,4.00,4.00,4.00,4.00,4.00,4.50"
					( Origin gBackEnd )
				)
				( attribute "SHAPE_TO_THRUVIA_SPACING" "5.00,5.00,5.00,5.00,5.00,5.00,5.00,5.00,5.00,5.00,5.00,5.00,5.00,5.00"
					( Origin gBackEnd )
				)
				( attribute "TESTVIA_TO_TESTVIA_SPACING" "5.00,5.00,5.00,5.00,5.00,5.00,5.00,5.00,5.00,5.00,5.00,5.00,5.00,5.00"
					( Origin gBackEnd )
				)
				( attribute "BBV_TO_TESTVIA_SPACING" "5.00,5.00,5.00,5.00,5.00,5.00,5.00,5.00,5.00,5.00,5.00,5.00,5.00,5.00"
					( Origin gBackEnd )
				)
				( attribute "BONDPAD_TO_TESTVIA_SPACING" "5.00,5.00,5.00,5.00,5.00,5.00,5.00,5.00,5.00,5.00,5.00,5.00,5.00,5.00"
					( Origin gBackEnd )
				)
				( attribute "LINE_TO_TESTVIA_SPACING" "4.50,5.00,5.00,5.00,5.00,5.00,5.00,5.00,5.00,5.00,5.00,5.00,5.00,4.50"
					( Origin gBackEnd )
				)
				( attribute "SHAPE_TO_TESTVIA_SPACING" "5.00,5.00,5.00,5.00,5.00,5.00,5.00,5.00,5.00,5.00,5.00,5.00,5.00,5.00"
					( Origin gBackEnd )
				)
				( attribute "BBV_TO_BBV_SPACING" "5.00,5.00,5.00,5.00,5.00,5.00,5.00,5.00,5.00,5.00,5.00,5.00,5.00,5.00"
					( Origin gBackEnd )
				)
				( attribute "BONDPAD_TO_BBV_SPACING" "5.00,5.00,5.00,5.00,5.00,5.00,5.00,5.00,5.00,5.00,5.00,5.00,5.00,5.00"
					( Origin gBackEnd )
				)
				( attribute "BBV_TO_LINE_SPACING" "5.00,5.00,5.00,5.00,5.00,5.00,5.00,5.00,5.00,5.00,5.00,5.00,5.00,5.00"
					( Origin gBackEnd )
				)
				( attribute "BBV_TO_SHAPE_SPACING" "5.00,5.00,5.00,5.00,5.00,5.00,5.00,5.00,5.00,5.00,5.00,5.00,5.00,5.00"
					( Origin gBackEnd )
				)
				( attribute "BONDPAD_TO_BONDPAD_SPACING" "5.00,5.00,5.00,5.00,5.00,5.00,5.00,5.00,5.00,5.00,5.00,5.00,5.00,5.00"
					( Origin gBackEnd )
				)
				( attribute "BONDPAD_TO_LINE_SPACING" "5.00,5.00,5.00,5.00,5.00,5.00,5.00,5.00,5.00,5.00,5.00,5.00,5.00,5.00"
					( Origin gBackEnd )
				)
				( attribute "BONDPAD_TO_SHAPE_SPACING" "5.00,5.00,5.00,5.00,5.00,5.00,5.00,5.00,5.00,5.00,5.00,5.00,5.00,5.00"
					( Origin gBackEnd )
				)
				( attribute "LINE_TO_LINE_SPACING" "5.00,5.00,5.00,5.00,5.00,5.00,5.00,5.00,5.00,5.00,5.00,5.00,5.00,5.00"
					( Origin gBackEnd )
				)
				( attribute "LINE_TO_SHAPE_SPACING" "5.00,5.00,5.00,5.00,5.00,5.00,5.00,5.00,5.00,5.00,5.00,5.00,5.00,5.00"
					( Origin gBackEnd )
				)
				( attribute "SHAPE_TO_SHAPE_SPACING" "10.00,10.00,10.00,10.00,10.00,10.00,10.00,10.00,10.00,10.00,10.00,10.00,10.00,10.00"
					( Origin gBackEnd )
				)
				( attribute "HOLE_TO_PIN_SPACING" "8.00,8.00,8.00,8.00,8.00,8.00,8.00,8.00,8.00,8.00,8.00,8.00,8.00,8.00"
					( Origin gBackEnd )
				)
				( attribute "HOLE_TO_VIA_SPACING" "8.00,8.00,8.00,8.00,8.00,8.00,8.00,8.00,8.00,8.00,8.00,8.00,8.00,8.00"
					( Origin gBackEnd )
				)
				( attribute "HOLE_TO_LINE_SPACING" "8.00,8.00,8.00,8.00,8.00,8.00,8.00,8.00,8.00,8.00,8.00,8.00,8.00,8.00"
					( Origin gBackEnd )
				)
				( attribute "HOLE_TO_SHAPE_SPACING" "8.00,8.00,8.00,8.00,8.00,8.00,8.00,8.00,8.00,8.00,8.00,8.00,8.00,8.00"
					( Origin gBackEnd )
				)
				( attribute "HOLE_TO_HOLE_SPACING" "8.00,8.00,8.00,8.00,8.00,8.00,8.00,8.00,8.00,8.00,8.00,8.00,8.00,8.00"
					( Origin gBackEnd )
				)
				( attribute "MVIA_TO_MVIA_SPACING" "5.00,5.00,5.00,5.00,5.00,5.00,5.00,5.00,5.00,5.00,5.00,5.00,5.00,5.00"
					( Origin gBackEnd )
				)
				( attribute "MVIA_TO_THRUPIN_SPACING" "5.00,5.00,5.00,5.00,5.00,5.00,5.00,5.00,5.00,5.00,5.00,5.00,5.00,5.00"
					( Origin gBackEnd )
				)
				( attribute "MVIA_TO_SMDPIN_SPACING" "5.00,5.00,5.00,5.00,5.00,5.00,5.00,5.00,5.00,5.00,5.00,5.00,5.00,5.00"
					( Origin gBackEnd )
				)
				( attribute "MVIA_TO_THRUVIA_SPACING" "5.00,5.00,5.00,5.00,5.00,5.00,5.00,5.00,5.00,5.00,5.00,5.00,5.00,5.00"
					( Origin gBackEnd )
				)
				( attribute "MVIA_TO_BBV_SPACING" "5.00,5.00,5.00,5.00,5.00,5.00,5.00,5.00,5.00,5.00,5.00,5.00,5.00,5.00"
					( Origin gBackEnd )
				)
				( attribute "MVIA_TO_LINE_SPACING" "5.00,5.00,5.00,5.00,5.00,5.00,5.00,5.00,5.00,5.00,5.00,5.00,5.00,5.00"
					( Origin gBackEnd )
				)
				( attribute "MVIA_TO_SHAPE_SPACING" "5.00,5.00,5.00,5.00,5.00,5.00,5.00,5.00,5.00,5.00,5.00,5.00,5.00,5.00"
					( Origin gBackEnd )
				)
				( attribute "MVIA_TO_TESTPIN_SPACING" "5.00,5.00,5.00,5.00,5.00,5.00,5.00,5.00,5.00,5.00,5.00,5.00,5.00,5.00"
					( Origin gBackEnd )
				)
				( attribute "MVIA_TO_TESTVIA_SPACING" "5.00,5.00,5.00,5.00,5.00,5.00,5.00,5.00,5.00,5.00,5.00,5.00,5.00,5.00"
					( Origin gBackEnd )
				)
				( attribute "BONDPAD_TO_MVIA_SPACING" "5.00,5.00,5.00,5.00,5.00,5.00,5.00,5.00,5.00,5.00,5.00,5.00,5.00,5.00"
					( Origin gBackEnd )
				)
				( attribute "MIN_BVIA_GAP" "5.00"
					( Origin gBackEnd )
				)
				( attribute "BONDPAD_TO_BONDPAD_DIFFP_SPC" "5.00,5.00,5.00,5.00,5.00,5.00,5.00,5.00,5.00,5.00,5.00,5.00,5.00,5.00"
					( Origin gBackEnd )
				)
				( objectStatus "FET_GATE_TRACES" )
			)
			( spacingCSet "@sapphirecity_baseboard_lib.sapphirecity_baseboard(sch_1):\GND\"
				( attribute "THRUPIN_TO_THRUPIN_SPACING" "5.00,5.00,5.00,5.00,5.00,5.00,5.00,5.00,5.00,5.00,5.00,5.00,5.00,5.00"
					( Origin gBackEnd )
				)
				( attribute "THRUPIN_TO_SMDPIN_SPACING" "5.00,5.00,5.00,5.00,5.00,5.00,5.00,5.00,5.00,5.00,5.00,5.00,5.00,5.00"
					( Origin gBackEnd )
				)
				( attribute "TESTPIN_TO_THRUPIN_SPACING" "5.00,5.00,5.00,5.00,5.00,5.00,5.00,5.00,5.00,5.00,5.00,5.00,5.00,5.00"
					( Origin gBackEnd )
				)
				( attribute "THRUPIN_TO_THRUVIA_SPACING" "5.00,5.00,5.00,5.00,5.00,5.00,5.00,5.00,5.00,5.00,5.00,5.00,5.00,5.00"
					( Origin gBackEnd )
				)
				( attribute "TESTVIA_TO_THRUPIN_SPACING" "5.00,5.00,5.00,5.00,5.00,5.00,5.00,5.00,5.00,5.00,5.00,5.00,5.00,5.00"
					( Origin gBackEnd )
				)
				( attribute "BBV_TO_THRUPIN_SPACING" "5.00,5.00,5.00,5.00,5.00,5.00,5.00,5.00,5.00,5.00,5.00,5.00,5.00,5.00"
					( Origin gBackEnd )
				)
				( attribute "THRUPIN_TO_BONDPAD_SPACING" "5.00,5.00,5.00,5.00,5.00,5.00,5.00,5.00,5.00,5.00,5.00,5.00,5.00,5.00"
					( Origin gBackEnd )
				)
				( attribute "LINE_TO_THRUPIN_SPACING" "5.00,5.00,5.00,5.00,5.00,5.00,5.00,5.00,5.00,5.00,5.00,5.00,5.00,5.00"
					( Origin gBackEnd )
				)
				( attribute "THRUPIN_TO_SHAPE_SPACING" "4.50,4.00,4.00,4.00,4.00,4.00,4.00,4.00,4.00,4.00,4.00,4.00,4.00,4.00"
					( Origin gBackEnd )
				)
				( attribute "SMDPIN_TO_SMDPIN_SPACING" "5.00,5.00,5.00,5.00,5.00,5.00,5.00,5.00,5.00,5.00,5.00,5.00,5.00,5.00"
					( Origin gBackEnd )
				)
				( attribute "SMDPIN_TO_TESTPIN_SPACING" "5.00,5.00,5.00,5.00,5.00,5.00,5.00,5.00,5.00,5.00,5.00,5.00,5.00,5.00"
					( Origin gBackEnd )
				)
				( attribute "SMDPIN_TO_THRUVIA_SPACING" "5.00,5.00,5.00,5.00,5.00,5.00,5.00,5.00,5.00,5.00,5.00,5.00,5.00,5.00"
					( Origin gBackEnd )
				)
				( attribute "SMDPIN_TO_TESTVIA_SPACING" "5.00,5.00,5.00,5.00,5.00,5.00,5.00,5.00,5.00,5.00,5.00,5.00,5.00,5.00"
					( Origin gBackEnd )
				)
				( attribute "BBV_TO_SMDPIN_SPACING" "5.00,5.00,5.00,5.00,5.00,5.00,5.00,5.00,5.00,5.00,5.00,5.00,5.00,5.00"
					( Origin gBackEnd )
				)
				( attribute "SMDPIN_TO_BONDPAD_SPACING" "5.00,5.00,5.00,5.00,5.00,5.00,5.00,5.00,5.00,5.00,5.00,5.00,5.00,5.00"
					( Origin gBackEnd )
				)
				( attribute "LINE_TO_SMDPIN_SPACING" "4.50,4.50,4.50,4.50,4.50,4.50,4.50,4.50,4.50,4.50,4.50,4.50,4.50,4.50"
					( Origin gBackEnd )
				)
				( attribute "SHAPE_TO_SMDPIN_SPACING" "5.00,5.00,5.00,5.00,5.00,5.00,5.00,5.00,5.00,5.00,5.00,5.00,5.00,5.00"
					( Origin gBackEnd )
				)
				( attribute "TESTPIN_TO_TESTPIN_SPACING" "5.00,5.00,5.00,5.00,5.00,5.00,5.00,5.00,5.00,5.00,5.00,5.00,5.00,5.00"
					( Origin gBackEnd )
				)
				( attribute "TESTPIN_TO_THRUVIA_SPACING" "5.00,5.00,5.00,5.00,5.00,5.00,5.00,5.00,5.00,5.00,5.00,5.00,5.00,5.00"
					( Origin gBackEnd )
				)
				( attribute "TESTPIN_TO_TESTVIA_SPACING" "5.00,5.00,5.00,5.00,5.00,5.00,5.00,5.00,5.00,5.00,5.00,5.00,5.00,5.00"
					( Origin gBackEnd )
				)
				( attribute "BBV_TO_TESTPIN_SPACING" "5.00,5.00,5.00,5.00,5.00,5.00,5.00,5.00,5.00,5.00,5.00,5.00,5.00,5.00"
					( Origin gBackEnd )
				)
				( attribute "BONDPAD_TO_TESTPIN_SPACING" "5.00,5.00,5.00,5.00,5.00,5.00,5.00,5.00,5.00,5.00,5.00,5.00,5.00,5.00"
					( Origin gBackEnd )
				)
				( attribute "LINE_TO_TESTPIN_SPACING" "4.50,5.00,5.00,5.00,5.00,5.00,5.00,5.00,5.00,5.00,5.00,5.00,5.00,5.00"
					( Origin gBackEnd )
				)
				( attribute "SHAPE_TO_TESTPIN_SPACING" "4.50,4.00,4.00,4.00,4.00,4.00,4.00,4.00,4.00,4.00,4.00,4.00,4.00,4.00"
					( Origin gBackEnd )
				)
				( attribute "THRUVIA_TO_THRUVIA_SPACING" "5.00,5.00,5.00,5.00,5.00,5.00,5.00,5.00,5.00,5.00,5.00,5.00,5.00,5.00"
					( Origin gBackEnd )
				)
				( attribute "TESTVIA_TO_THRUVIA_SPACING" "5.00,5.00,5.00,5.00,5.00,5.00,5.00,5.00,5.00,5.00,5.00,5.00,5.00,5.00"
					( Origin gBackEnd )
				)
				( attribute "BBV_TO_THRUVIA_SPACING" "5.00,5.00,5.00,5.00,5.00,5.00,5.00,5.00,5.00,5.00,5.00,5.00,5.00,5.00"
					( Origin gBackEnd )
				)
				( attribute "BONDPAD_TO_THRUVIA_SPACING" "5.00,5.00,5.00,5.00,5.00,5.00,5.00,5.00,5.00,5.00,5.00,5.00,5.00,5.00"
					( Origin gBackEnd )
				)
				( attribute "LINE_TO_THRUVIA_SPACING" "4.50,4.00,4.00,4.00,4.00,4.00,4.00,4.00,4.00,4.00,4.00,4.00,4.00,4.50"
					( Origin gBackEnd )
				)
				( attribute "SHAPE_TO_THRUVIA_SPACING" "4.50,4.00,4.00,4.00,4.00,4.00,4.00,4.00,4.00,4.00,4.00,4.00,4.00,4.00"
					( Origin gBackEnd )
				)
				( attribute "TESTVIA_TO_TESTVIA_SPACING" "5.00,5.00,5.00,5.00,5.00,5.00,5.00,5.00,5.00,5.00,5.00,5.00,5.00,5.00"
					( Origin gBackEnd )
				)
				( attribute "BBV_TO_TESTVIA_SPACING" "5.00,5.00,5.00,5.00,5.00,5.00,5.00,5.00,5.00,5.00,5.00,5.00,5.00,5.00"
					( Origin gBackEnd )
				)
				( attribute "BONDPAD_TO_TESTVIA_SPACING" "5.00,5.00,5.00,5.00,5.00,5.00,5.00,5.00,5.00,5.00,5.00,5.00,5.00,5.00"
					( Origin gBackEnd )
				)
				( attribute "LINE_TO_TESTVIA_SPACING" "4.50,5.00,4.00,5.00,4.00,5.00,5.00,5.00,5.00,4.00,5.00,4.00,5.00,4.00"
					( Origin gBackEnd )
				)
				( attribute "SHAPE_TO_TESTVIA_SPACING" "4.50,4.00,4.00,4.00,4.00,4.00,4.00,4.00,4.00,4.00,4.00,4.00,4.00,4.00"
					( Origin gBackEnd )
				)
				( attribute "BBV_TO_BBV_SPACING" "5.00,5.00,5.00,5.00,5.00,5.00,5.00,5.00,5.00,5.00,5.00,5.00,5.00,5.00"
					( Origin gBackEnd )
				)
				( attribute "BONDPAD_TO_BBV_SPACING" "5.00,5.00,5.00,5.00,5.00,5.00,5.00,5.00,5.00,5.00,5.00,5.00,5.00,5.00"
					( Origin gBackEnd )
				)
				( attribute "BBV_TO_LINE_SPACING" "5.00,5.00,5.00,5.00,5.00,5.00,5.00,5.00,5.00,5.00,5.00,5.00,5.00,5.00"
					( Origin gBackEnd )
				)
				( attribute "BBV_TO_SHAPE_SPACING" "5.00,5.00,5.00,5.00,5.00,5.00,5.00,5.00,5.00,5.00,5.00,5.00,5.00,5.00"
					( Origin gBackEnd )
				)
				( attribute "BONDPAD_TO_BONDPAD_SPACING" "5.00,5.00,5.00,5.00,5.00,5.00,5.00,5.00,5.00,5.00,5.00,5.00,5.00,5.00"
					( Origin gBackEnd )
				)
				( attribute "BONDPAD_TO_LINE_SPACING" "5.00,5.00,5.00,5.00,5.00,5.00,5.00,5.00,5.00,5.00,5.00,5.00,5.00,5.00"
					( Origin gBackEnd )
				)
				( attribute "BONDPAD_TO_SHAPE_SPACING" "5.00,5.00,5.00,5.00,5.00,5.00,5.00,5.00,5.00,5.00,5.00,5.00,5.00,5.00"
					( Origin gBackEnd )
				)
				( attribute "LINE_TO_LINE_SPACING" "5.00,5.00,5.00,5.00,5.00,5.00,5.00,5.00,5.00,5.00,5.00,5.00,5.00,5.00"
					( Origin gBackEnd )
				)
				( attribute "LINE_TO_SHAPE_SPACING" "5.00,5.00,5.00,5.00,5.00,5.00,5.00,5.00,5.00,5.00,5.00,5.00,5.00,5.00"
					( Origin gBackEnd )
				)
				( attribute "SHAPE_TO_SHAPE_SPACING" "10.00,10.00,10.00,10.00,10.00,10.00,10.00,10.00,10.00,10.00,10.00,10.00,10.00,10.00"
					( Origin gBackEnd )
				)
				( attribute "HOLE_TO_PIN_SPACING" "8.00,8.00,8.00,8.00,8.00,8.00,8.00,8.00,8.00,8.00,8.00,8.00,8.00,8.00"
					( Origin gBackEnd )
				)
				( attribute "HOLE_TO_VIA_SPACING" "8.00,8.00,8.00,8.00,8.00,8.00,8.00,8.00,8.00,8.00,8.00,8.00,8.00,8.00"
					( Origin gBackEnd )
				)
				( attribute "HOLE_TO_LINE_SPACING" "8.00,8.00,8.00,8.00,8.00,8.00,8.00,8.00,8.00,8.00,8.00,8.00,8.00,8.00"
					( Origin gBackEnd )
				)
				( attribute "HOLE_TO_SHAPE_SPACING" "8.00,8.00,8.00,8.00,8.00,8.00,8.00,8.00,8.00,8.00,8.00,8.00,8.00,8.00"
					( Origin gBackEnd )
				)
				( attribute "HOLE_TO_HOLE_SPACING" "8.00,8.00,8.00,8.00,8.00,8.00,8.00,8.00,8.00,8.00,8.00,8.00,8.00,8.00"
					( Origin gBackEnd )
				)
				( attribute "MVIA_TO_MVIA_SPACING" "5.00,5.00,5.00,5.00,5.00,5.00,5.00,5.00,5.00,5.00,5.00,5.00,5.00,5.00"
					( Origin gBackEnd )
				)
				( attribute "MVIA_TO_THRUPIN_SPACING" "5.00,5.00,5.00,5.00,5.00,5.00,5.00,5.00,5.00,5.00,5.00,5.00,5.00,5.00"
					( Origin gBackEnd )
				)
				( attribute "MVIA_TO_SMDPIN_SPACING" "5.00,5.00,5.00,5.00,5.00,5.00,5.00,5.00,5.00,5.00,5.00,5.00,5.00,5.00"
					( Origin gBackEnd )
				)
				( attribute "MVIA_TO_THRUVIA_SPACING" "5.00,5.00,5.00,5.00,5.00,5.00,5.00,5.00,5.00,5.00,5.00,5.00,5.00,5.00"
					( Origin gBackEnd )
				)
				( attribute "MVIA_TO_BBV_SPACING" "5.00,5.00,5.00,5.00,5.00,5.00,5.00,5.00,5.00,5.00,5.00,5.00,5.00,5.00"
					( Origin gBackEnd )
				)
				( attribute "MVIA_TO_LINE_SPACING" "5.00,5.00,5.00,5.00,5.00,5.00,5.00,5.00,5.00,5.00,5.00,5.00,5.00,5.00"
					( Origin gBackEnd )
				)
				( attribute "MVIA_TO_SHAPE_SPACING" "5.00,5.00,5.00,5.00,5.00,5.00,5.00,5.00,5.00,5.00,5.00,5.00,5.00,5.00"
					( Origin gBackEnd )
				)
				( attribute "MVIA_TO_TESTPIN_SPACING" "5.00,5.00,5.00,5.00,5.00,5.00,5.00,5.00,5.00,5.00,5.00,5.00,5.00,5.00"
					( Origin gBackEnd )
				)
				( attribute "MVIA_TO_TESTVIA_SPACING" "5.00,5.00,5.00,5.00,5.00,5.00,5.00,5.00,5.00,5.00,5.00,5.00,5.00,5.00"
					( Origin gBackEnd )
				)
				( attribute "BONDPAD_TO_MVIA_SPACING" "5.00,5.00,5.00,5.00,5.00,5.00,5.00,5.00,5.00,5.00,5.00,5.00,5.00,5.00"
					( Origin gBackEnd )
				)
				( attribute "MIN_BVIA_GAP" "5.00"
					( Origin gBackEnd )
				)
				( attribute "BONDPAD_TO_BONDPAD_DIFFP_SPC" "5.00,5.00,5.00,5.00,5.00,5.00,5.00,5.00,5.00,5.00,5.00,5.00,5.00,5.00"
					( Origin gBackEnd )
				)
				( objectStatus "GND" )
			)
			( spacingCSet "@sapphirecity_baseboard_lib.sapphirecity_baseboard(sch_1):\7H_VIA+3H\"
				( attribute "THRUPIN_TO_THRUPIN_SPACING" "5.00,5.00,5.00,5.00,5.00,5.00,5.00,5.00,5.00,5.00,5.00,5.00,5.00,5.00"
					( Origin gBackEnd )
				)
				( attribute "THRUPIN_TO_SMDPIN_SPACING" "5.00,5.00,5.00,5.00,5.00,5.00,5.00,5.00,5.00,5.00,5.00,5.00,5.00,5.00"
					( Origin gBackEnd )
				)
				( attribute "TESTPIN_TO_THRUPIN_SPACING" "5.00,5.00,5.00,5.00,5.00,5.00,5.00,5.00,5.00,5.00,5.00,5.00,5.00,5.00"
					( Origin gBackEnd )
				)
				( attribute "THRUPIN_TO_THRUVIA_SPACING" "5.00,5.00,5.00,5.00,5.00,5.00,5.00,5.00,5.00,5.00,5.00,5.00,5.00,5.00"
					( Origin gBackEnd )
				)
				( attribute "TESTVIA_TO_THRUPIN_SPACING" "5.00,5.00,5.00,5.00,5.00,5.00,5.00,5.00,5.00,5.00,5.00,5.00,5.00,5.00"
					( Origin gBackEnd )
				)
				( attribute "BBV_TO_THRUPIN_SPACING" "5.00,5.00,5.00,5.00,5.00,5.00,5.00,5.00,5.00,5.00,5.00,5.00,5.00,5.00"
					( Origin gBackEnd )
				)
				( attribute "THRUPIN_TO_BONDPAD_SPACING" "5.00,5.00,5.00,5.00,5.00,5.00,5.00,5.00,5.00,5.00,5.00,5.00,5.00,5.00"
					( Origin gBackEnd )
				)
				( attribute "LINE_TO_THRUPIN_SPACING" "4.50,4.00,4.00,4.00,4.00,4.00,4.00,4.00,4.00,4.00,4.00,4.00,4.00,4.50"
					( Origin gBackEnd )
				)
				( attribute "THRUPIN_TO_SHAPE_SPACING" "4.50,4.00,4.00,4.00,4.00,4.00,4.00,4.00,4.00,4.00,4.00,4.00,4.00,4.00"
					( Origin gBackEnd )
				)
				( attribute "SMDPIN_TO_SMDPIN_SPACING" "5.00,5.00,5.00,5.00,5.00,5.00,5.00,5.00,5.00,5.00,5.00,5.00,5.00,5.00"
					( Origin gBackEnd )
				)
				( attribute "SMDPIN_TO_TESTPIN_SPACING" "5.00,5.00,5.00,5.00,5.00,5.00,5.00,5.00,5.00,5.00,5.00,5.00,5.00,5.00"
					( Origin gBackEnd )
				)
				( attribute "SMDPIN_TO_THRUVIA_SPACING" "5.00,5.00,5.00,5.00,5.00,5.00,5.00,5.00,5.00,5.00,5.00,5.00,5.00,5.00"
					( Origin gBackEnd )
				)
				( attribute "SMDPIN_TO_TESTVIA_SPACING" "5.00,5.00,5.00,5.00,5.00,5.00,5.00,5.00,5.00,5.00,5.00,5.00,5.00,5.00"
					( Origin gBackEnd )
				)
				( attribute "BBV_TO_SMDPIN_SPACING" "5.00,5.00,5.00,5.00,5.00,5.00,5.00,5.00,5.00,5.00,5.00,5.00,5.00,5.00"
					( Origin gBackEnd )
				)
				( attribute "SMDPIN_TO_BONDPAD_SPACING" "5.00,5.00,5.00,5.00,5.00,5.00,5.00,5.00,5.00,5.00,5.00,5.00,5.00,5.00"
					( Origin gBackEnd )
				)
				( attribute "LINE_TO_SMDPIN_SPACING" "4.50,4.50,4.50,4.50,4.50,4.50,4.50,4.50,4.50,4.50,4.50,4.50,4.50,4.50"
					( Origin gBackEnd )
				)
				( attribute "SHAPE_TO_SMDPIN_SPACING" "5.00,5.00,5.00,5.00,5.00,5.00,5.00,5.00,5.00,5.00,5.00,5.00,5.00,5.00"
					( Origin gBackEnd )
				)
				( attribute "TESTPIN_TO_TESTPIN_SPACING" "5.00,5.00,5.00,5.00,5.00,5.00,5.00,5.00,5.00,5.00,5.00,5.00,5.00,5.00"
					( Origin gBackEnd )
				)
				( attribute "TESTPIN_TO_THRUVIA_SPACING" "5.00,5.00,5.00,5.00,5.00,5.00,5.00,5.00,5.00,5.00,5.00,5.00,5.00,5.00"
					( Origin gBackEnd )
				)
				( attribute "TESTPIN_TO_TESTVIA_SPACING" "5.00,5.00,5.00,5.00,5.00,5.00,5.00,5.00,5.00,5.00,5.00,5.00,5.00,5.00"
					( Origin gBackEnd )
				)
				( attribute "BBV_TO_TESTPIN_SPACING" "5.00,5.00,5.00,5.00,5.00,5.00,5.00,5.00,5.00,5.00,5.00,5.00,5.00,5.00"
					( Origin gBackEnd )
				)
				( attribute "BONDPAD_TO_TESTPIN_SPACING" "5.00,5.00,5.00,5.00,5.00,5.00,5.00,5.00,5.00,5.00,5.00,5.00,5.00,5.00"
					( Origin gBackEnd )
				)
				( attribute "LINE_TO_TESTPIN_SPACING" "4.50,5.00,5.00,5.00,5.00,5.00,5.00,5.00,5.00,5.00,5.00,5.00,5.00,5.00"
					( Origin gBackEnd )
				)
				( attribute "SHAPE_TO_TESTPIN_SPACING" "4.50,4.00,4.00,4.00,4.00,4.00,4.00,4.00,4.00,4.00,4.00,4.00,4.00,4.00"
					( Origin gBackEnd )
				)
				( attribute "THRUVIA_TO_THRUVIA_SPACING" "5.00,5.00,5.00,5.00,5.00,5.00,5.00,5.00,5.00,5.00,5.00,5.00,5.00,5.00"
					( Origin gBackEnd )
				)
				( attribute "TESTVIA_TO_THRUVIA_SPACING" "5.00,5.00,5.00,5.00,5.00,5.00,5.00,5.00,5.00,5.00,5.00,5.00,5.00,5.00"
					( Origin gBackEnd )
				)
				( attribute "BBV_TO_THRUVIA_SPACING" "5.00,5.00,5.00,5.00,5.00,5.00,5.00,5.00,5.00,5.00,5.00,5.00,5.00,5.00"
					( Origin gBackEnd )
				)
				( attribute "BONDPAD_TO_THRUVIA_SPACING" "5.00,5.00,5.00,5.00,5.00,5.00,5.00,5.00,5.00,5.00,5.00,5.00,5.00,5.00"
					( Origin gBackEnd )
				)
				( attribute "LINE_TO_THRUVIA_SPACING" "9.40,5.00,12.00,5.00,12.00,5.00,5.00,5.00,5.00,12.00,5.00,12.00,5.00,9.40"
					( Origin gBackEnd )
				)
				( attribute "SHAPE_TO_THRUVIA_SPACING" "4.50,4.00,4.00,4.00,4.00,4.00,4.00,4.00,4.00,4.00,4.00,4.00,4.00,4.00"
					( Origin gBackEnd )
				)
				( attribute "TESTVIA_TO_TESTVIA_SPACING" "5.00,5.00,5.00,5.00,5.00,5.00,5.00,5.00,5.00,5.00,5.00,5.00,5.00,5.00"
					( Origin gBackEnd )
				)
				( attribute "BBV_TO_TESTVIA_SPACING" "5.00,5.00,5.00,5.00,5.00,5.00,5.00,5.00,5.00,5.00,5.00,5.00,5.00,5.00"
					( Origin gBackEnd )
				)
				( attribute "BONDPAD_TO_TESTVIA_SPACING" "5.00,5.00,5.00,5.00,5.00,5.00,5.00,5.00,5.00,5.00,5.00,5.00,5.00,5.00"
					( Origin gBackEnd )
				)
				( attribute "LINE_TO_TESTVIA_SPACING" "13.10,5.00,17.00,5.00,17.00,5.00,5.00,5.00,5.00,17.00,5.00,17.00,5.00,17.00"
					( Origin gBackEnd )
				)
				( attribute "SHAPE_TO_TESTVIA_SPACING" "4.50,4.00,4.00,4.00,4.00,4.00,4.00,4.00,4.00,4.00,4.00,4.00,4.00,4.00"
					( Origin gBackEnd )
				)
				( attribute "BBV_TO_BBV_SPACING" "5.00,5.00,5.00,5.00,5.00,5.00,5.00,5.00,5.00,5.00,5.00,5.00,5.00,5.00"
					( Origin gBackEnd )
				)
				( attribute "BONDPAD_TO_BBV_SPACING" "5.00,5.00,5.00,5.00,5.00,5.00,5.00,5.00,5.00,5.00,5.00,5.00,5.00,5.00"
					( Origin gBackEnd )
				)
				( attribute "BBV_TO_LINE_SPACING" "5.00,5.00,5.00,5.00,5.00,5.00,5.00,5.00,5.00,5.00,5.00,5.00,5.00,5.00"
					( Origin gBackEnd )
				)
				( attribute "BBV_TO_SHAPE_SPACING" "5.00,5.00,5.00,5.00,5.00,5.00,5.00,5.00,5.00,5.00,5.00,5.00,5.00,5.00"
					( Origin gBackEnd )
				)
				( attribute "BONDPAD_TO_BONDPAD_SPACING" "5.00,5.00,5.00,5.00,5.00,5.00,5.00,5.00,5.00,5.00,5.00,5.00,5.00,5.00"
					( Origin gBackEnd )
				)
				( attribute "BONDPAD_TO_LINE_SPACING" "5.00,5.00,5.00,5.00,5.00,5.00,5.00,5.00,5.00,5.00,5.00,5.00,5.00,5.00"
					( Origin gBackEnd )
				)
				( attribute "BONDPAD_TO_SHAPE_SPACING" "5.00,5.00,5.00,5.00,5.00,5.00,5.00,5.00,5.00,5.00,5.00,5.00,5.00,5.00"
					( Origin gBackEnd )
				)
				( attribute "LINE_TO_LINE_SPACING" "18.69,21.00,21.00,21.00,21.00,21.00,21.00,21.00,21.00,21.00,21.00,21.00,21.00,18.69"
					( Origin gBackEnd )
				)
				( attribute "LINE_TO_SHAPE_SPACING" "5.00,5.00,5.00,5.00,5.00,5.00,5.00,5.00,5.00,5.00,5.00,5.00,5.00,5.00"
					( Origin gBackEnd )
				)
				( attribute "SHAPE_TO_SHAPE_SPACING" "10.00,10.00,10.00,10.00,10.00,10.00,10.00,10.00,10.00,10.00,10.00,10.00,10.00,10.00"
					( Origin gBackEnd )
				)
				( attribute "HOLE_TO_PIN_SPACING" "8.00,8.00,8.00,8.00,8.00,8.00,8.00,8.00,8.00,8.00,8.00,8.00,8.00,8.00"
					( Origin gBackEnd )
				)
				( attribute "HOLE_TO_VIA_SPACING" "8.00,8.00,8.00,8.00,8.00,8.00,8.00,8.00,8.00,8.00,8.00,8.00,8.00,8.00"
					( Origin gBackEnd )
				)
				( attribute "HOLE_TO_LINE_SPACING" "8.00,8.00,8.00,8.00,8.00,8.00,8.00,8.00,8.00,8.00,8.00,8.00,8.00,8.00"
					( Origin gBackEnd )
				)
				( attribute "HOLE_TO_SHAPE_SPACING" "8.00,8.00,8.00,8.00,8.00,8.00,8.00,8.00,8.00,8.00,8.00,8.00,8.00,8.00"
					( Origin gBackEnd )
				)
				( attribute "HOLE_TO_HOLE_SPACING" "8.00,8.00,8.00,8.00,8.00,8.00,8.00,8.00,8.00,8.00,8.00,8.00,8.00,8.00"
					( Origin gBackEnd )
				)
				( attribute "MVIA_TO_MVIA_SPACING" "5.00,5.00,5.00,5.00,5.00,5.00,5.00,5.00,5.00,5.00,5.00,5.00,5.00,5.00"
					( Origin gBackEnd )
				)
				( attribute "MVIA_TO_THRUPIN_SPACING" "5.00,5.00,5.00,5.00,5.00,5.00,5.00,5.00,5.00,5.00,5.00,5.00,5.00,5.00"
					( Origin gBackEnd )
				)
				( attribute "MVIA_TO_SMDPIN_SPACING" "5.00,5.00,5.00,5.00,5.00,5.00,5.00,5.00,5.00,5.00,5.00,5.00,5.00,5.00"
					( Origin gBackEnd )
				)
				( attribute "MVIA_TO_THRUVIA_SPACING" "5.00,5.00,5.00,5.00,5.00,5.00,5.00,5.00,5.00,5.00,5.00,5.00,5.00,5.00"
					( Origin gBackEnd )
				)
				( attribute "MVIA_TO_BBV_SPACING" "5.00,5.00,5.00,5.00,5.00,5.00,5.00,5.00,5.00,5.00,5.00,5.00,5.00,5.00"
					( Origin gBackEnd )
				)
				( attribute "MVIA_TO_LINE_SPACING" "5.00,5.00,5.00,5.00,5.00,5.00,5.00,5.00,5.00,5.00,5.00,5.00,5.00,5.00"
					( Origin gBackEnd )
				)
				( attribute "MVIA_TO_SHAPE_SPACING" "5.00,5.00,5.00,5.00,5.00,5.00,5.00,5.00,5.00,5.00,5.00,5.00,5.00,5.00"
					( Origin gBackEnd )
				)
				( attribute "MVIA_TO_TESTPIN_SPACING" "5.00,5.00,5.00,5.00,5.00,5.00,5.00,5.00,5.00,5.00,5.00,5.00,5.00,5.00"
					( Origin gBackEnd )
				)
				( attribute "MVIA_TO_TESTVIA_SPACING" "5.00,5.00,5.00,5.00,5.00,5.00,5.00,5.00,5.00,5.00,5.00,5.00,5.00,5.00"
					( Origin gBackEnd )
				)
				( attribute "BONDPAD_TO_MVIA_SPACING" "5.00,5.00,5.00,5.00,5.00,5.00,5.00,5.00,5.00,5.00,5.00,5.00,5.00,5.00"
					( Origin gBackEnd )
				)
				( attribute "MIN_BVIA_GAP" "5.00"
					( Origin gBackEnd )
				)
				( attribute "BONDPAD_TO_BONDPAD_DIFFP_SPC" "5.00,5.00,5.00,5.00,5.00,5.00,5.00,5.00,5.00,5.00,5.00,5.00,5.00,5.00"
					( Origin gBackEnd )
				)
				( objectStatus "7H_VIA+3H" )
			)
			( spacingCSet "@sapphirecity_baseboard_lib.sapphirecity_baseboard(sch_1):\11H_US_AND_9H_SL_VIA+3H_A\"
				( attribute "THRUPIN_TO_THRUPIN_SPACING" "5.00,5.00,5.00,5.00,5.00,5.00,5.00,5.00,5.00,5.00,5.00,5.00,5.00,5.00"
					( Origin gBackEnd )
				)
				( attribute "THRUPIN_TO_SMDPIN_SPACING" "5.00,5.00,5.00,5.00,5.00,5.00,5.00,5.00,5.00,5.00,5.00,5.00,5.00,5.00"
					( Origin gBackEnd )
				)
				( attribute "TESTPIN_TO_THRUPIN_SPACING" "5.00,5.00,5.00,5.00,5.00,5.00,5.00,5.00,5.00,5.00,5.00,5.00,5.00,5.00"
					( Origin gBackEnd )
				)
				( attribute "THRUPIN_TO_THRUVIA_SPACING" "5.00,5.00,5.00,5.00,5.00,5.00,5.00,5.00,5.00,5.00,5.00,5.00,5.00,5.00"
					( Origin gBackEnd )
				)
				( attribute "TESTVIA_TO_THRUPIN_SPACING" "5.00,5.00,5.00,5.00,5.00,5.00,5.00,5.00,5.00,5.00,5.00,5.00,5.00,5.00"
					( Origin gBackEnd )
				)
				( attribute "BBV_TO_THRUPIN_SPACING" "5.00,5.00,5.00,5.00,5.00,5.00,5.00,5.00,5.00,5.00,5.00,5.00,5.00,5.00"
					( Origin gBackEnd )
				)
				( attribute "THRUPIN_TO_BONDPAD_SPACING" "5.00,5.00,5.00,5.00,5.00,5.00,5.00,5.00,5.00,5.00,5.00,5.00,5.00,5.00"
					( Origin gBackEnd )
				)
				( attribute "LINE_TO_THRUPIN_SPACING" "4.50,4.00,4.00,4.00,4.00,4.00,4.00,4.00,4.00,4.00,4.00,4.00,4.00,4.50"
					( Origin gBackEnd )
				)
				( attribute "THRUPIN_TO_SHAPE_SPACING" "4.50,4.00,4.00,4.00,4.00,4.00,4.00,4.00,4.00,4.00,4.00,4.00,4.00,4.00"
					( Origin gBackEnd )
				)
				( attribute "SMDPIN_TO_SMDPIN_SPACING" "5.00,5.00,5.00,5.00,5.00,5.00,5.00,5.00,5.00,5.00,5.00,5.00,5.00,5.00"
					( Origin gBackEnd )
				)
				( attribute "SMDPIN_TO_TESTPIN_SPACING" "5.00,5.00,5.00,5.00,5.00,5.00,5.00,5.00,5.00,5.00,5.00,5.00,5.00,5.00"
					( Origin gBackEnd )
				)
				( attribute "SMDPIN_TO_THRUVIA_SPACING" "5.00,5.00,5.00,5.00,5.00,5.00,5.00,5.00,5.00,5.00,5.00,5.00,5.00,5.00"
					( Origin gBackEnd )
				)
				( attribute "SMDPIN_TO_TESTVIA_SPACING" "5.00,5.00,5.00,5.00,5.00,5.00,5.00,5.00,5.00,5.00,5.00,5.00,5.00,5.00"
					( Origin gBackEnd )
				)
				( attribute "BBV_TO_SMDPIN_SPACING" "5.00,5.00,5.00,5.00,5.00,5.00,5.00,5.00,5.00,5.00,5.00,5.00,5.00,5.00"
					( Origin gBackEnd )
				)
				( attribute "SMDPIN_TO_BONDPAD_SPACING" "5.00,5.00,5.00,5.00,5.00,5.00,5.00,5.00,5.00,5.00,5.00,5.00,5.00,5.00"
					( Origin gBackEnd )
				)
				( attribute "LINE_TO_SMDPIN_SPACING" "4.50,4.50,4.50,4.50,4.50,4.50,4.50,4.50,4.50,4.50,4.50,4.50,4.50,4.50"
					( Origin gBackEnd )
				)
				( attribute "SHAPE_TO_SMDPIN_SPACING" "5.00,5.00,5.00,5.00,5.00,5.00,5.00,5.00,5.00,5.00,5.00,5.00,5.00,5.00"
					( Origin gBackEnd )
				)
				( attribute "TESTPIN_TO_TESTPIN_SPACING" "5.00,5.00,5.00,5.00,5.00,5.00,5.00,5.00,5.00,5.00,5.00,5.00,5.00,5.00"
					( Origin gBackEnd )
				)
				( attribute "TESTPIN_TO_THRUVIA_SPACING" "5.00,5.00,5.00,5.00,5.00,5.00,5.00,5.00,5.00,5.00,5.00,5.00,5.00,5.00"
					( Origin gBackEnd )
				)
				( attribute "TESTPIN_TO_TESTVIA_SPACING" "5.00,5.00,5.00,5.00,5.00,5.00,5.00,5.00,5.00,5.00,5.00,5.00,5.00,5.00"
					( Origin gBackEnd )
				)
				( attribute "BBV_TO_TESTPIN_SPACING" "5.00,5.00,5.00,5.00,5.00,5.00,5.00,5.00,5.00,5.00,5.00,5.00,5.00,5.00"
					( Origin gBackEnd )
				)
				( attribute "BONDPAD_TO_TESTPIN_SPACING" "5.00,5.00,5.00,5.00,5.00,5.00,5.00,5.00,5.00,5.00,5.00,5.00,5.00,5.00"
					( Origin gBackEnd )
				)
				( attribute "LINE_TO_TESTPIN_SPACING" "4.50,5.00,5.00,5.00,5.00,5.00,5.00,5.00,5.00,5.00,5.00,5.00,5.00,5.00"
					( Origin gBackEnd )
				)
				( attribute "SHAPE_TO_TESTPIN_SPACING" "4.50,4.00,4.00,4.00,4.00,4.00,4.00,4.00,4.00,4.00,4.00,4.00,4.00,4.00"
					( Origin gBackEnd )
				)
				( attribute "THRUVIA_TO_THRUVIA_SPACING" "5.00,5.00,5.00,5.00,5.00,5.00,5.00,5.00,5.00,5.00,5.00,5.00,5.00,5.00"
					( Origin gBackEnd )
				)
				( attribute "TESTVIA_TO_THRUVIA_SPACING" "5.00,5.00,5.00,5.00,5.00,5.00,5.00,5.00,5.00,5.00,5.00,5.00,5.00,5.00"
					( Origin gBackEnd )
				)
				( attribute "BBV_TO_THRUVIA_SPACING" "5.00,5.00,5.00,5.00,5.00,5.00,5.00,5.00,5.00,5.00,5.00,5.00,5.00,5.00"
					( Origin gBackEnd )
				)
				( attribute "BONDPAD_TO_THRUVIA_SPACING" "5.00,5.00,5.00,5.00,5.00,5.00,5.00,5.00,5.00,5.00,5.00,5.00,5.00,5.00"
					( Origin gBackEnd )
				)
				( attribute "LINE_TO_THRUVIA_SPACING" "12.00,5.00,13.00,5.00,13.00,5.00,5.00,5.00,5.00,13.00,5.00,13.00,5.00,12.00"
					( Origin gBackEnd )
				)
				( attribute "SHAPE_TO_THRUVIA_SPACING" "4.50,4.00,4.00,4.00,4.00,4.00,4.00,4.00,4.00,4.00,4.00,4.00,4.00,4.00"
					( Origin gBackEnd )
				)
				( attribute "TESTVIA_TO_TESTVIA_SPACING" "5.00,5.00,5.00,5.00,5.00,5.00,5.00,5.00,5.00,5.00,5.00,5.00,5.00,5.00"
					( Origin gBackEnd )
				)
				( attribute "BBV_TO_TESTVIA_SPACING" "5.00,5.00,5.00,5.00,5.00,5.00,5.00,5.00,5.00,5.00,5.00,5.00,5.00,5.00"
					( Origin gBackEnd )
				)
				( attribute "BONDPAD_TO_TESTVIA_SPACING" "5.00,5.00,5.00,5.00,5.00,5.00,5.00,5.00,5.00,5.00,5.00,5.00,5.00,5.00"
					( Origin gBackEnd )
				)
				( attribute "LINE_TO_TESTVIA_SPACING" "12.00,5.00,13.00,5.00,13.00,5.00,5.00,5.00,5.00,13.00,5.00,13.00,5.00,12.00"
					( Origin gBackEnd )
				)
				( attribute "SHAPE_TO_TESTVIA_SPACING" "4.50,4.00,4.00,4.00,4.00,4.00,4.00,4.00,4.00,4.00,4.00,4.00,4.00,4.00"
					( Origin gBackEnd )
				)
				( attribute "BBV_TO_BBV_SPACING" "5.00,5.00,5.00,5.00,5.00,5.00,5.00,5.00,5.00,5.00,5.00,5.00,5.00,5.00"
					( Origin gBackEnd )
				)
				( attribute "BONDPAD_TO_BBV_SPACING" "5.00,5.00,5.00,5.00,5.00,5.00,5.00,5.00,5.00,5.00,5.00,5.00,5.00,5.00"
					( Origin gBackEnd )
				)
				( attribute "BBV_TO_LINE_SPACING" "5.00,5.00,5.00,5.00,5.00,5.00,5.00,5.00,5.00,5.00,5.00,5.00,5.00,5.00"
					( Origin gBackEnd )
				)
				( attribute "BBV_TO_SHAPE_SPACING" "5.00,5.00,5.00,5.00,5.00,5.00,5.00,5.00,5.00,5.00,5.00,5.00,5.00,5.00"
					( Origin gBackEnd )
				)
				( attribute "BONDPAD_TO_BONDPAD_SPACING" "5.00,5.00,5.00,5.00,5.00,5.00,5.00,5.00,5.00,5.00,5.00,5.00,5.00,5.00"
					( Origin gBackEnd )
				)
				( attribute "BONDPAD_TO_LINE_SPACING" "5.00,5.00,5.00,5.00,5.00,5.00,5.00,5.00,5.00,5.00,5.00,5.00,5.00,5.00"
					( Origin gBackEnd )
				)
				( attribute "BONDPAD_TO_SHAPE_SPACING" "5.00,5.00,5.00,5.00,5.00,5.00,5.00,5.00,5.00,5.00,5.00,5.00,5.00,5.00"
					( Origin gBackEnd )
				)
				( attribute "LINE_TO_LINE_SPACING" "29.37,27.00,27.00,27.00,27.00,27.00,27.00,27.00,27.00,27.00,27.00,27.00,27.00,29.37"
					( Origin gBackEnd )
				)
				( attribute "LINE_TO_SHAPE_SPACING" "5.00,5.00,5.00,5.00,5.00,5.00,5.00,5.00,5.00,5.00,5.00,5.00,5.00,5.00"
					( Origin gBackEnd )
				)
				( attribute "SHAPE_TO_SHAPE_SPACING" "10.00,10.00,10.00,10.00,10.00,10.00,10.00,10.00,10.00,10.00,10.00,10.00,10.00,10.00"
					( Origin gBackEnd )
				)
				( attribute "HOLE_TO_PIN_SPACING" "8.00,8.00,8.00,8.00,8.00,8.00,8.00,8.00,8.00,8.00,8.00,8.00,8.00,8.00"
					( Origin gBackEnd )
				)
				( attribute "HOLE_TO_VIA_SPACING" "8.00,8.00,8.00,8.00,8.00,8.00,8.00,8.00,8.00,8.00,8.00,8.00,8.00,8.00"
					( Origin gBackEnd )
				)
				( attribute "HOLE_TO_LINE_SPACING" "8.00,8.00,8.00,8.00,8.00,8.00,8.00,8.00,8.00,8.00,8.00,8.00,8.00,8.00"
					( Origin gBackEnd )
				)
				( attribute "HOLE_TO_SHAPE_SPACING" "8.00,8.00,8.00,8.00,8.00,8.00,8.00,8.00,8.00,8.00,8.00,8.00,8.00,8.00"
					( Origin gBackEnd )
				)
				( attribute "HOLE_TO_HOLE_SPACING" "8.00,8.00,8.00,8.00,8.00,8.00,8.00,8.00,8.00,8.00,8.00,8.00,8.00,8.00"
					( Origin gBackEnd )
				)
				( attribute "MVIA_TO_MVIA_SPACING" "5.00,5.00,5.00,5.00,5.00,5.00,5.00,5.00,5.00,5.00,5.00,5.00,5.00,5.00"
					( Origin gBackEnd )
				)
				( attribute "MVIA_TO_THRUPIN_SPACING" "5.00,5.00,5.00,5.00,5.00,5.00,5.00,5.00,5.00,5.00,5.00,5.00,5.00,5.00"
					( Origin gBackEnd )
				)
				( attribute "MVIA_TO_SMDPIN_SPACING" "5.00,5.00,5.00,5.00,5.00,5.00,5.00,5.00,5.00,5.00,5.00,5.00,5.00,5.00"
					( Origin gBackEnd )
				)
				( attribute "MVIA_TO_THRUVIA_SPACING" "5.00,5.00,5.00,5.00,5.00,5.00,5.00,5.00,5.00,5.00,5.00,5.00,5.00,5.00"
					( Origin gBackEnd )
				)
				( attribute "MVIA_TO_BBV_SPACING" "5.00,5.00,5.00,5.00,5.00,5.00,5.00,5.00,5.00,5.00,5.00,5.00,5.00,5.00"
					( Origin gBackEnd )
				)
				( attribute "MVIA_TO_LINE_SPACING" "5.00,5.00,5.00,5.00,5.00,5.00,5.00,5.00,5.00,5.00,5.00,5.00,5.00,5.00"
					( Origin gBackEnd )
				)
				( attribute "MVIA_TO_SHAPE_SPACING" "5.00,5.00,5.00,5.00,5.00,5.00,5.00,5.00,5.00,5.00,5.00,5.00,5.00,5.00"
					( Origin gBackEnd )
				)
				( attribute "MVIA_TO_TESTPIN_SPACING" "5.00,5.00,5.00,5.00,5.00,5.00,5.00,5.00,5.00,5.00,5.00,5.00,5.00,5.00"
					( Origin gBackEnd )
				)
				( attribute "MVIA_TO_TESTVIA_SPACING" "5.00,5.00,5.00,5.00,5.00,5.00,5.00,5.00,5.00,5.00,5.00,5.00,5.00,5.00"
					( Origin gBackEnd )
				)
				( attribute "BONDPAD_TO_MVIA_SPACING" "5.00,5.00,5.00,5.00,5.00,5.00,5.00,5.00,5.00,5.00,5.00,5.00,5.00,5.00"
					( Origin gBackEnd )
				)
				( attribute "MIN_BVIA_GAP" "5.00"
					( Origin gBackEnd )
				)
				( attribute "BONDPAD_TO_BONDPAD_DIFFP_SPC" "5.00,5.00,5.00,5.00,5.00,5.00,5.00,5.00,5.00,5.00,5.00,5.00,5.00,5.00"
					( Origin gBackEnd )
				)
				( objectStatus "11H_US_&_9H_SL_VIA_3H+A" )
			)
			( spacingCSet "@sapphirecity_baseboard_lib.sapphirecity_baseboard(sch_1):\12_US_AND_11H_SL_VIA+3H_A\"
				( attribute "THRUPIN_TO_THRUPIN_SPACING" "5.00,5.00,5.00,5.00,5.00,5.00,5.00,5.00,5.00,5.00,5.00,5.00,5.00,5.00"
					( Origin gBackEnd )
				)
				( attribute "THRUPIN_TO_SMDPIN_SPACING" "5.00,5.00,5.00,5.00,5.00,5.00,5.00,5.00,5.00,5.00,5.00,5.00,5.00,5.00"
					( Origin gBackEnd )
				)
				( attribute "TESTPIN_TO_THRUPIN_SPACING" "5.00,5.00,5.00,5.00,5.00,5.00,5.00,5.00,5.00,5.00,5.00,5.00,5.00,5.00"
					( Origin gBackEnd )
				)
				( attribute "THRUPIN_TO_THRUVIA_SPACING" "5.00,5.00,5.00,5.00,5.00,5.00,5.00,5.00,5.00,5.00,5.00,5.00,5.00,5.00"
					( Origin gBackEnd )
				)
				( attribute "TESTVIA_TO_THRUPIN_SPACING" "5.00,5.00,5.00,5.00,5.00,5.00,5.00,5.00,5.00,5.00,5.00,5.00,5.00,5.00"
					( Origin gBackEnd )
				)
				( attribute "BBV_TO_THRUPIN_SPACING" "5.00,5.00,5.00,5.00,5.00,5.00,5.00,5.00,5.00,5.00,5.00,5.00,5.00,5.00"
					( Origin gBackEnd )
				)
				( attribute "THRUPIN_TO_BONDPAD_SPACING" "5.00,5.00,5.00,5.00,5.00,5.00,5.00,5.00,5.00,5.00,5.00,5.00,5.00,5.00"
					( Origin gBackEnd )
				)
				( attribute "LINE_TO_THRUPIN_SPACING" "4.50,4.00,4.00,4.00,4.00,4.00,4.00,4.00,4.00,4.00,4.00,4.00,4.00,4.50"
					( Origin gBackEnd )
				)
				( attribute "THRUPIN_TO_SHAPE_SPACING" "4.50,4.00,4.00,4.00,4.00,4.00,4.00,4.00,4.00,4.00,4.00,4.00,4.00,4.00"
					( Origin gBackEnd )
				)
				( attribute "SMDPIN_TO_SMDPIN_SPACING" "5.00,5.00,5.00,5.00,5.00,5.00,5.00,5.00,5.00,5.00,5.00,5.00,5.00,5.00"
					( Origin gBackEnd )
				)
				( attribute "SMDPIN_TO_TESTPIN_SPACING" "5.00,5.00,5.00,5.00,5.00,5.00,5.00,5.00,5.00,5.00,5.00,5.00,5.00,25.00"
					( Origin gBackEnd )
				)
				( attribute "SMDPIN_TO_THRUVIA_SPACING" "5.00,5.00,5.00,5.00,5.00,5.00,5.00,5.00,5.00,5.00,5.00,5.00,5.00,5.00"
					( Origin gBackEnd )
				)
				( attribute "SMDPIN_TO_TESTVIA_SPACING" "5.00,5.00,5.00,5.00,5.00,5.00,5.00,5.00,5.00,5.00,5.00,5.00,5.00,5.00"
					( Origin gBackEnd )
				)
				( attribute "BBV_TO_SMDPIN_SPACING" "5.00,5.00,5.00,5.00,5.00,5.00,5.00,5.00,5.00,5.00,5.00,5.00,5.00,5.00"
					( Origin gBackEnd )
				)
				( attribute "SMDPIN_TO_BONDPAD_SPACING" "5.00,5.00,5.00,5.00,5.00,5.00,5.00,5.00,5.00,5.00,5.00,5.00,5.00,5.00"
					( Origin gBackEnd )
				)
				( attribute "LINE_TO_SMDPIN_SPACING" "4.50,4.50,4.50,4.50,4.50,4.50,4.50,4.50,4.50,4.50,4.50,4.50,4.50,4.50"
					( Origin gBackEnd )
				)
				( attribute "SHAPE_TO_SMDPIN_SPACING" "5.00,5.00,5.00,5.00,5.00,5.00,5.00,5.00,5.00,5.00,5.00,5.00,5.00,5.00"
					( Origin gBackEnd )
				)
				( attribute "TESTPIN_TO_TESTPIN_SPACING" "5.00,5.00,5.00,5.00,5.00,5.00,5.00,5.00,5.00,5.00,5.00,5.00,5.00,5.00"
					( Origin gBackEnd )
				)
				( attribute "TESTPIN_TO_THRUVIA_SPACING" "5.00,5.00,5.00,5.00,5.00,5.00,5.00,5.00,5.00,5.00,5.00,5.00,5.00,5.00"
					( Origin gBackEnd )
				)
				( attribute "TESTPIN_TO_TESTVIA_SPACING" "5.00,5.00,5.00,5.00,5.00,5.00,5.00,5.00,5.00,5.00,5.00,5.00,5.00,5.00"
					( Origin gBackEnd )
				)
				( attribute "BBV_TO_TESTPIN_SPACING" "5.00,5.00,5.00,5.00,5.00,5.00,5.00,5.00,5.00,5.00,5.00,5.00,5.00,5.00"
					( Origin gBackEnd )
				)
				( attribute "BONDPAD_TO_TESTPIN_SPACING" "5.00,5.00,5.00,5.00,5.00,5.00,5.00,5.00,5.00,5.00,5.00,5.00,5.00,5.00"
					( Origin gBackEnd )
				)
				( attribute "LINE_TO_TESTPIN_SPACING" "4.50,5.00,5.00,5.00,5.00,5.00,5.00,5.00,5.00,5.00,5.00,5.00,5.00,5.00"
					( Origin gBackEnd )
				)
				( attribute "SHAPE_TO_TESTPIN_SPACING" "4.50,4.00,4.00,4.00,4.00,4.00,4.00,4.00,4.00,4.00,4.00,4.00,4.00,4.00"
					( Origin gBackEnd )
				)
				( attribute "THRUVIA_TO_THRUVIA_SPACING" "5.00,5.00,5.00,5.00,5.00,5.00,5.00,5.00,5.00,5.00,5.00,5.00,5.00,5.00"
					( Origin gBackEnd )
				)
				( attribute "TESTVIA_TO_THRUVIA_SPACING" "5.00,5.00,5.00,5.00,5.00,5.00,5.00,5.00,5.00,5.00,5.00,5.00,5.00,5.00"
					( Origin gBackEnd )
				)
				( attribute "BBV_TO_THRUVIA_SPACING" "5.00,5.00,5.00,5.00,5.00,5.00,5.00,5.00,5.00,5.00,5.00,5.00,5.00,5.00"
					( Origin gBackEnd )
				)
				( attribute "BONDPAD_TO_THRUVIA_SPACING" "5.00,5.00,5.00,5.00,5.00,5.00,5.00,5.00,5.00,5.00,5.00,5.00,5.00,5.00"
					( Origin gBackEnd )
				)
				( attribute "LINE_TO_THRUVIA_SPACING" "12.00,5.00,13.00,5.00,13.00,5.00,5.00,5.00,5.00,13.00,5.00,13.00,5.00,12.00"
					( Origin gBackEnd )
				)
				( attribute "SHAPE_TO_THRUVIA_SPACING" "4.50,4.00,4.00,4.00,4.00,4.00,4.00,4.00,4.00,4.00,4.00,4.00,4.00,4.00"
					( Origin gBackEnd )
				)
				( attribute "TESTVIA_TO_TESTVIA_SPACING" "5.00,5.00,5.00,5.00,5.00,5.00,5.00,5.00,5.00,5.00,5.00,5.00,5.00,5.00"
					( Origin gBackEnd )
				)
				( attribute "BBV_TO_TESTVIA_SPACING" "5.00,5.00,5.00,5.00,5.00,5.00,5.00,5.00,5.00,5.00,5.00,5.00,5.00,5.00"
					( Origin gBackEnd )
				)
				( attribute "BONDPAD_TO_TESTVIA_SPACING" "5.00,5.00,5.00,5.00,5.00,5.00,5.00,5.00,5.00,5.00,5.00,5.00,5.00,5.00"
					( Origin gBackEnd )
				)
				( attribute "LINE_TO_TESTVIA_SPACING" "12.00,5.00,13.00,5.00,13.00,5.00,5.00,5.00,5.00,13.00,5.00,13.00,5.00,12.00"
					( Origin gBackEnd )
				)
				( attribute "SHAPE_TO_TESTVIA_SPACING" "4.50,4.00,4.00,4.00,4.00,4.00,4.00,4.00,4.00,4.00,4.00,4.00,4.00,4.00"
					( Origin gBackEnd )
				)
				( attribute "BBV_TO_BBV_SPACING" "5.00,5.00,5.00,5.00,5.00,5.00,5.00,5.00,5.00,5.00,5.00,5.00,5.00,5.00"
					( Origin gBackEnd )
				)
				( attribute "BONDPAD_TO_BBV_SPACING" "5.00,5.00,5.00,5.00,5.00,5.00,5.00,5.00,5.00,5.00,5.00,5.00,5.00,5.00"
					( Origin gBackEnd )
				)
				( attribute "BBV_TO_LINE_SPACING" "5.00,5.00,5.00,5.00,5.00,5.00,5.00,5.00,5.00,5.00,5.00,5.00,5.00,5.00"
					( Origin gBackEnd )
				)
				( attribute "BBV_TO_SHAPE_SPACING" "5.00,5.00,5.00,5.00,5.00,5.00,5.00,5.00,5.00,5.00,5.00,5.00,5.00,5.00"
					( Origin gBackEnd )
				)
				( attribute "BONDPAD_TO_BONDPAD_SPACING" "5.00,5.00,5.00,5.00,5.00,5.00,5.00,5.00,5.00,5.00,5.00,5.00,5.00,5.00"
					( Origin gBackEnd )
				)
				( attribute "BONDPAD_TO_LINE_SPACING" "5.00,5.00,5.00,5.00,5.00,5.00,5.00,5.00,5.00,5.00,5.00,5.00,5.00,5.00"
					( Origin gBackEnd )
				)
				( attribute "BONDPAD_TO_SHAPE_SPACING" "5.00,5.00,5.00,5.00,5.00,5.00,5.00,5.00,5.00,5.00,5.00,5.00,5.00,5.00"
					( Origin gBackEnd )
				)
				( attribute "LINE_TO_LINE_SPACING" "32.40,33.00,33.00,33.00,33.00,33.00,33.00,33.00,33.00,33.00,33.00,33.00,33.00,32.40"
					( Origin gBackEnd )
				)
				( attribute "LINE_TO_SHAPE_SPACING" "5.00,5.00,5.00,5.00,5.00,5.00,5.00,5.00,5.00,5.00,5.00,5.00,5.00,5.00"
					( Origin gBackEnd )
				)
				( attribute "SHAPE_TO_SHAPE_SPACING" "10.00,10.00,10.00,10.00,10.00,10.00,10.00,10.00,10.00,10.00,10.00,10.00,10.00,10.00"
					( Origin gBackEnd )
				)
				( attribute "HOLE_TO_PIN_SPACING" "8.00,8.00,8.00,8.00,8.00,8.00,8.00,8.00,8.00,8.00,8.00,8.00,8.00,8.00"
					( Origin gBackEnd )
				)
				( attribute "HOLE_TO_VIA_SPACING" "8.00,8.00,8.00,8.00,8.00,8.00,8.00,8.00,8.00,8.00,8.00,8.00,8.00,8.00"
					( Origin gBackEnd )
				)
				( attribute "HOLE_TO_LINE_SPACING" "8.00,8.00,8.00,8.00,8.00,8.00,8.00,8.00,8.00,8.00,8.00,8.00,8.00,8.00"
					( Origin gBackEnd )
				)
				( attribute "HOLE_TO_SHAPE_SPACING" "8.00,8.00,8.00,8.00,8.00,8.00,8.00,8.00,8.00,8.00,8.00,8.00,8.00,8.00"
					( Origin gBackEnd )
				)
				( attribute "HOLE_TO_HOLE_SPACING" "8.00,8.00,8.00,8.00,8.00,8.00,8.00,8.00,8.00,8.00,8.00,8.00,8.00,8.00"
					( Origin gBackEnd )
				)
				( attribute "MVIA_TO_MVIA_SPACING" "5.00,5.00,5.00,5.00,5.00,5.00,5.00,5.00,5.00,5.00,5.00,5.00,5.00,5.00"
					( Origin gBackEnd )
				)
				( attribute "MVIA_TO_THRUPIN_SPACING" "5.00,5.00,5.00,5.00,5.00,5.00,5.00,5.00,5.00,5.00,5.00,5.00,5.00,5.00"
					( Origin gBackEnd )
				)
				( attribute "MVIA_TO_SMDPIN_SPACING" "5.00,5.00,5.00,5.00,5.00,5.00,5.00,5.00,5.00,5.00,5.00,5.00,5.00,5.00"
					( Origin gBackEnd )
				)
				( attribute "MVIA_TO_THRUVIA_SPACING" "5.00,5.00,5.00,5.00,5.00,5.00,5.00,5.00,5.00,5.00,5.00,5.00,5.00,5.00"
					( Origin gBackEnd )
				)
				( attribute "MVIA_TO_BBV_SPACING" "5.00,5.00,5.00,5.00,5.00,5.00,5.00,5.00,5.00,5.00,5.00,5.00,5.00,5.00"
					( Origin gBackEnd )
				)
				( attribute "MVIA_TO_LINE_SPACING" "5.00,5.00,5.00,5.00,5.00,5.00,5.00,5.00,5.00,5.00,5.00,5.00,5.00,5.00"
					( Origin gBackEnd )
				)
				( attribute "MVIA_TO_SHAPE_SPACING" "5.00,5.00,5.00,5.00,5.00,5.00,5.00,5.00,5.00,5.00,5.00,5.00,5.00,5.00"
					( Origin gBackEnd )
				)
				( attribute "MVIA_TO_TESTPIN_SPACING" "5.00,5.00,5.00,5.00,5.00,5.00,5.00,5.00,5.00,5.00,5.00,5.00,5.00,5.00"
					( Origin gBackEnd )
				)
				( attribute "MVIA_TO_TESTVIA_SPACING" "5.00,5.00,5.00,5.00,5.00,5.00,5.00,5.00,5.00,5.00,5.00,5.00,5.00,5.00"
					( Origin gBackEnd )
				)
				( attribute "BONDPAD_TO_MVIA_SPACING" "5.00,5.00,5.00,5.00,5.00,5.00,5.00,5.00,5.00,5.00,5.00,5.00,5.00,5.00"
					( Origin gBackEnd )
				)
				( attribute "MIN_BVIA_GAP" "5.00"
					( Origin gBackEnd )
				)
				( attribute "BONDPAD_TO_BONDPAD_DIFFP_SPC" "5.00,5.00,5.00,5.00,5.00,5.00,5.00,5.00,5.00,5.00,5.00,5.00,5.00,5.00"
					( Origin gBackEnd )
				)
				( objectStatus "12H_US_&_11H_SL_VIA_3H+A" )
			)
			( spacingCSet "@sapphirecity_baseboard_lib.sapphirecity_baseboard(sch_1):\35MIL\"
				( attribute "THRUPIN_TO_THRUPIN_SPACING" "5.00,5.00,5.00,5.00,5.00,5.00,5.00,5.00,5.00,5.00,5.00,5.00,5.00,5.00"
					( Origin gBackEnd )
				)
				( attribute "THRUPIN_TO_SMDPIN_SPACING" "5.00,5.00,5.00,5.00,5.00,5.00,5.00,5.00,5.00,5.00,5.00,5.00,5.00,5.00"
					( Origin gBackEnd )
				)
				( attribute "TESTPIN_TO_THRUPIN_SPACING" "5.00,5.00,5.00,5.00,5.00,5.00,5.00,5.00,5.00,5.00,5.00,5.00,5.00,5.00"
					( Origin gBackEnd )
				)
				( attribute "THRUPIN_TO_THRUVIA_SPACING" "5.00,5.00,5.00,5.00,5.00,5.00,5.00,5.00,5.00,5.00,5.00,5.00,5.00,5.00"
					( Origin gBackEnd )
				)
				( attribute "TESTVIA_TO_THRUPIN_SPACING" "5.00,5.00,5.00,5.00,5.00,5.00,5.00,5.00,5.00,5.00,5.00,5.00,5.00,5.00"
					( Origin gBackEnd )
				)
				( attribute "BBV_TO_THRUPIN_SPACING" "5.00,5.00,5.00,5.00,5.00,5.00,5.00,5.00,5.00,5.00,5.00,5.00,5.00,5.00"
					( Origin gBackEnd )
				)
				( attribute "THRUPIN_TO_BONDPAD_SPACING" "5.00,5.00,5.00,5.00,5.00,5.00,5.00,5.00,5.00,5.00,5.00,5.00,5.00,5.00"
					( Origin gBackEnd )
				)
				( attribute "LINE_TO_THRUPIN_SPACING" "4.50,4.00,4.00,4.00,4.00,4.00,4.00,4.00,4.00,4.00,4.00,4.00,4.00,4.50"
					( Origin gBackEnd )
				)
				( attribute "THRUPIN_TO_SHAPE_SPACING" "5.00,5.00,5.00,5.00,5.00,5.00,5.00,5.00,5.00,5.00,5.00,5.00,5.00,5.00"
					( Origin gBackEnd )
				)
				( attribute "SMDPIN_TO_SMDPIN_SPACING" "5.00,5.00,5.00,5.00,5.00,5.00,5.00,5.00,5.00,5.00,5.00,5.00,5.00,5.00"
					( Origin gBackEnd )
				)
				( attribute "SMDPIN_TO_TESTPIN_SPACING" "5.00,5.00,5.00,5.00,5.00,5.00,5.00,5.00,5.00,5.00,5.00,5.00,5.00,25.00"
					( Origin gBackEnd )
				)
				( attribute "SMDPIN_TO_THRUVIA_SPACING" "5.00,5.00,5.00,5.00,5.00,5.00,5.00,5.00,5.00,5.00,5.00,5.00,5.00,5.00"
					( Origin gBackEnd )
				)
				( attribute "SMDPIN_TO_TESTVIA_SPACING" "5.00,5.00,5.00,5.00,5.00,5.00,5.00,5.00,5.00,5.00,5.00,5.00,5.00,5.00"
					( Origin gBackEnd )
				)
				( attribute "BBV_TO_SMDPIN_SPACING" "5.00,5.00,5.00,5.00,5.00,5.00,5.00,5.00,5.00,5.00,5.00,5.00,5.00,5.00"
					( Origin gBackEnd )
				)
				( attribute "SMDPIN_TO_BONDPAD_SPACING" "5.00,5.00,5.00,5.00,5.00,5.00,5.00,5.00,5.00,5.00,5.00,5.00,5.00,5.00"
					( Origin gBackEnd )
				)
				( attribute "LINE_TO_SMDPIN_SPACING" "4.50,4.50,4.50,4.50,4.50,4.50,4.50,4.50,4.50,4.50,4.50,4.50,4.50,4.50"
					( Origin gBackEnd )
				)
				( attribute "SHAPE_TO_SMDPIN_SPACING" "5.00,5.00,5.00,5.00,5.00,5.00,5.00,5.00,5.00,5.00,5.00,5.00,5.00,5.00"
					( Origin gBackEnd )
				)
				( attribute "TESTPIN_TO_TESTPIN_SPACING" "5.00,5.00,5.00,5.00,5.00,5.00,5.00,5.00,5.00,5.00,5.00,5.00,5.00,5.00"
					( Origin gBackEnd )
				)
				( attribute "TESTPIN_TO_THRUVIA_SPACING" "5.00,5.00,5.00,5.00,5.00,5.00,5.00,5.00,5.00,5.00,5.00,5.00,5.00,5.00"
					( Origin gBackEnd )
				)
				( attribute "TESTPIN_TO_TESTVIA_SPACING" "5.00,5.00,5.00,5.00,5.00,5.00,5.00,5.00,5.00,5.00,5.00,5.00,5.00,5.00"
					( Origin gBackEnd )
				)
				( attribute "BBV_TO_TESTPIN_SPACING" "5.00,5.00,5.00,5.00,5.00,5.00,5.00,5.00,5.00,5.00,5.00,5.00,5.00,5.00"
					( Origin gBackEnd )
				)
				( attribute "BONDPAD_TO_TESTPIN_SPACING" "5.00,5.00,5.00,5.00,5.00,5.00,5.00,5.00,5.00,5.00,5.00,5.00,5.00,5.00"
					( Origin gBackEnd )
				)
				( attribute "LINE_TO_TESTPIN_SPACING" "5.00,4.00,4.00,4.00,4.00,4.00,4.00,4.00,4.00,4.00,4.00,4.00,4.00,5.00"
					( Origin gBackEnd )
				)
				( attribute "SHAPE_TO_TESTPIN_SPACING" "5.00,5.00,5.00,5.00,5.00,5.00,5.00,5.00,5.00,5.00,5.00,5.00,5.00,5.00"
					( Origin gBackEnd )
				)
				( attribute "THRUVIA_TO_THRUVIA_SPACING" "5.00,5.00,5.00,5.00,5.00,5.00,5.00,5.00,5.00,5.00,5.00,5.00,5.00,5.00"
					( Origin gBackEnd )
				)
				( attribute "TESTVIA_TO_THRUVIA_SPACING" "6.00,6.00,6.00,6.00,6.00,6.00,6.00,6.00,6.00,6.00,6.00,6.00,6.00,6.00"
					( Origin gBackEnd )
				)
				( attribute "BBV_TO_THRUVIA_SPACING" "5.00,5.00,5.00,5.00,5.00,5.00,5.00,5.00,5.00,5.00,5.00,5.00,5.00,5.00"
					( Origin gBackEnd )
				)
				( attribute "BONDPAD_TO_THRUVIA_SPACING" "5.00,5.00,5.00,5.00,5.00,5.00,5.00,5.00,5.00,5.00,5.00,5.00,5.00,5.00"
					( Origin gBackEnd )
				)
				( attribute "LINE_TO_THRUVIA_SPACING" "4.50,4.00,4.00,4.00,4.00,4.00,4.00,4.00,4.00,4.00,4.00,4.00,4.00,4.50"
					( Origin gBackEnd )
				)
				( attribute "SHAPE_TO_THRUVIA_SPACING" "5.00,5.00,5.00,5.00,5.00,5.00,5.00,5.00,5.00,5.00,5.00,5.00,5.00,5.00"
					( Origin gBackEnd )
				)
				( attribute "TESTVIA_TO_TESTVIA_SPACING" "6.00,6.00,6.00,6.00,6.00,6.00,6.00,6.00,6.00,6.00,6.00,6.00,6.00,6.00"
					( Origin gBackEnd )
				)
				( attribute "BBV_TO_TESTVIA_SPACING" "5.00,5.00,5.00,5.00,5.00,5.00,5.00,5.00,5.00,5.00,5.00,5.00,5.00,5.00"
					( Origin gBackEnd )
				)
				( attribute "BONDPAD_TO_TESTVIA_SPACING" "5.00,5.00,5.00,5.00,5.00,5.00,5.00,5.00,5.00,5.00,5.00,5.00,5.00,5.00"
					( Origin gBackEnd )
				)
				( attribute "LINE_TO_TESTVIA_SPACING" "4.50,4.00,4.00,4.00,4.00,4.00,4.00,4.00,4.00,4.00,4.00,4.00,4.00,4.50"
					( Origin gBackEnd )
				)
				( attribute "SHAPE_TO_TESTVIA_SPACING" "5.00,5.00,5.00,5.00,5.00,5.00,5.00,5.00,5.00,5.00,5.00,5.00,5.00,5.00"
					( Origin gBackEnd )
				)
				( attribute "BBV_TO_BBV_SPACING" "5.00,5.00,5.00,5.00,5.00,5.00,5.00,5.00,5.00,5.00,5.00,5.00,5.00,5.00"
					( Origin gBackEnd )
				)
				( attribute "BONDPAD_TO_BBV_SPACING" "5.00,5.00,5.00,5.00,5.00,5.00,5.00,5.00,5.00,5.00,5.00,5.00,5.00,5.00"
					( Origin gBackEnd )
				)
				( attribute "BBV_TO_LINE_SPACING" "5.00,5.00,5.00,5.00,5.00,5.00,5.00,5.00,5.00,5.00,5.00,5.00,5.00,5.00"
					( Origin gBackEnd )
				)
				( attribute "BBV_TO_SHAPE_SPACING" "5.00,5.00,5.00,5.00,5.00,5.00,5.00,5.00,5.00,5.00,5.00,5.00,5.00,5.00"
					( Origin gBackEnd )
				)
				( attribute "BONDPAD_TO_BONDPAD_SPACING" "5.00,5.00,5.00,5.00,5.00,5.00,5.00,5.00,5.00,5.00,5.00,5.00,5.00,5.00"
					( Origin gBackEnd )
				)
				( attribute "BONDPAD_TO_LINE_SPACING" "5.00,5.00,5.00,5.00,5.00,5.00,5.00,5.00,5.00,5.00,5.00,5.00,5.00,5.00"
					( Origin gBackEnd )
				)
				( attribute "BONDPAD_TO_SHAPE_SPACING" "5.00,5.00,5.00,5.00,5.00,5.00,5.00,5.00,5.00,5.00,5.00,5.00,5.00,5.00"
					( Origin gBackEnd )
				)
				( attribute "LINE_TO_LINE_SPACING" "50.00,50.00,50.00,50.00,50.00,50.00,50.00,50.00,50.00,50.00,50.00,50.00,50.00,50.00"
					( Origin gBackEnd )
				)
				( attribute "LINE_TO_SHAPE_SPACING" "10.00,10.00,10.00,10.00,10.00,10.00,10.00,10.00,10.00,10.00,10.00,10.00,10.00,10.00"
					( Origin gBackEnd )
				)
				( attribute "SHAPE_TO_SHAPE_SPACING" "10.00,10.00,10.00,10.00,10.00,10.00,10.00,10.00,10.00,10.00,10.00,10.00,10.00,10.00"
					( Origin gBackEnd )
				)
				( attribute "HOLE_TO_PIN_SPACING" "8.00,8.00,8.00,8.00,8.00,8.00,8.00,8.00,8.00,8.00,8.00,8.00,8.00,8.00"
					( Origin gBackEnd )
				)
				( attribute "HOLE_TO_VIA_SPACING" "8.00,8.00,8.00,8.00,8.00,8.00,8.00,8.00,8.00,8.00,8.00,8.00,8.00,8.00"
					( Origin gBackEnd )
				)
				( attribute "HOLE_TO_LINE_SPACING" "8.00,8.00,8.00,8.00,8.00,8.00,8.00,8.00,8.00,8.00,8.00,8.00,8.00,8.00"
					( Origin gBackEnd )
				)
				( attribute "HOLE_TO_SHAPE_SPACING" "8.00,8.00,8.00,8.00,8.00,8.00,8.00,8.00,8.00,8.00,8.00,8.00,8.00,8.00"
					( Origin gBackEnd )
				)
				( attribute "HOLE_TO_HOLE_SPACING" "8.00,8.00,8.00,8.00,8.00,8.00,8.00,8.00,8.00,8.00,8.00,8.00,8.00,8.00"
					( Origin gBackEnd )
				)
				( attribute "MVIA_TO_MVIA_SPACING" "5.00,5.00,5.00,5.00,5.00,5.00,5.00,5.00,5.00,5.00,5.00,5.00,5.00,5.00"
					( Origin gBackEnd )
				)
				( attribute "MVIA_TO_THRUPIN_SPACING" "5.00,5.00,5.00,5.00,5.00,5.00,5.00,5.00,5.00,5.00,5.00,5.00,5.00,5.00"
					( Origin gBackEnd )
				)
				( attribute "MVIA_TO_SMDPIN_SPACING" "5.00,5.00,5.00,5.00,5.00,5.00,5.00,5.00,5.00,5.00,5.00,5.00,5.00,5.00"
					( Origin gBackEnd )
				)
				( attribute "MVIA_TO_THRUVIA_SPACING" "5.00,5.00,5.00,5.00,5.00,5.00,5.00,5.00,5.00,5.00,5.00,5.00,5.00,5.00"
					( Origin gBackEnd )
				)
				( attribute "MVIA_TO_BBV_SPACING" "5.00,5.00,5.00,5.00,5.00,5.00,5.00,5.00,5.00,5.00,5.00,5.00,5.00,5.00"
					( Origin gBackEnd )
				)
				( attribute "MVIA_TO_LINE_SPACING" "5.00,5.00,5.00,5.00,5.00,5.00,5.00,5.00,5.00,5.00,5.00,5.00,5.00,5.00"
					( Origin gBackEnd )
				)
				( attribute "MVIA_TO_SHAPE_SPACING" "5.00,5.00,5.00,5.00,5.00,5.00,5.00,5.00,5.00,5.00,5.00,5.00,5.00,5.00"
					( Origin gBackEnd )
				)
				( attribute "MVIA_TO_TESTPIN_SPACING" "5.00,5.00,5.00,5.00,5.00,5.00,5.00,5.00,5.00,5.00,5.00,5.00,5.00,5.00"
					( Origin gBackEnd )
				)
				( attribute "MVIA_TO_TESTVIA_SPACING" "5.00,5.00,5.00,5.00,5.00,5.00,5.00,5.00,5.00,5.00,5.00,5.00,5.00,5.00"
					( Origin gBackEnd )
				)
				( attribute "BONDPAD_TO_MVIA_SPACING" "5.00,5.00,5.00,5.00,5.00,5.00,5.00,5.00,5.00,5.00,5.00,5.00,5.00,5.00"
					( Origin gBackEnd )
				)
				( attribute "MIN_BVIA_GAP" "5.00"
					( Origin gBackEnd )
				)
				( attribute "BONDPAD_TO_BONDPAD_DIFFP_SPC" "5.00,5.00,5.00,5.00,5.00,5.00,5.00,5.00,5.00,5.00,5.00,5.00,5.00,5.00"
					( Origin gBackEnd )
				)
				( objectStatus "50_MILS" )
			)
			( spacingCSet "@sapphirecity_baseboard_lib.sapphirecity_baseboard(sch_1):\BGA_WBG\"
				( attribute "THRUPIN_TO_THRUPIN_SPACING" "5.00,5.00,5.00,5.00,5.00,5.00,5.00,5.00,5.00,5.00,5.00,5.00,5.00,5.00"
					( Origin gBackEnd )
				)
				( attribute "THRUPIN_TO_SMDPIN_SPACING" "5.00,5.00,5.00,5.00,5.00,5.00,5.00,5.00,5.00,5.00,5.00,5.00,5.00,5.00"
					( Origin gBackEnd )
				)
				( attribute "TESTPIN_TO_THRUPIN_SPACING" "5.00,5.00,5.00,5.00,5.00,5.00,5.00,5.00,5.00,5.00,5.00,5.00,5.00,5.00"
					( Origin gBackEnd )
				)
				( attribute "THRUPIN_TO_THRUVIA_SPACING" "5.00,5.00,5.00,5.00,5.00,5.00,5.00,5.00,5.00,5.00,5.00,5.00,5.00,5.00"
					( Origin gBackEnd )
				)
				( attribute "TESTVIA_TO_THRUPIN_SPACING" "5.00,5.00,5.00,5.00,5.00,5.00,5.00,5.00,5.00,5.00,5.00,5.00,5.00,5.00"
					( Origin gBackEnd )
				)
				( attribute "BBV_TO_THRUPIN_SPACING" "5.00,5.00,5.00,5.00,5.00,5.00,5.00,5.00,5.00,5.00,5.00,5.00,5.00,5.00"
					( Origin gBackEnd )
				)
				( attribute "THRUPIN_TO_BONDPAD_SPACING" "5.00,5.00,5.00,5.00,5.00,5.00,5.00,5.00,5.00,5.00,5.00,5.00,5.00,5.00"
					( Origin gBackEnd )
				)
				( attribute "LINE_TO_THRUPIN_SPACING" "4.50,4.00,4.00,4.00,4.00,4.00,4.00,4.00,4.00,4.00,4.00,4.00,4.00,4.50"
					( Origin gBackEnd )
				)
				( attribute "THRUPIN_TO_SHAPE_SPACING" "5.00,5.00,5.00,5.00,5.00,5.00,5.00,5.00,5.00,5.00,5.00,5.00,5.00,5.00"
					( Origin gBackEnd )
				)
				( attribute "SMDPIN_TO_SMDPIN_SPACING" "5.00,5.00,5.00,5.00,5.00,5.00,5.00,5.00,5.00,5.00,5.00,5.00,5.00,5.00"
					( Origin gBackEnd )
				)
				( attribute "SMDPIN_TO_TESTPIN_SPACING" "5.00,5.00,5.00,5.00,5.00,5.00,5.00,5.00,5.00,5.00,5.00,5.00,5.00,5.00"
					( Origin gBackEnd )
				)
				( attribute "SMDPIN_TO_THRUVIA_SPACING" "4.38,4.38,4.38,4.38,4.38,4.38,4.38,4.38,4.38,4.38,4.38,4.38,4.38,4.38"
					( Origin gBackEnd )
				)
				( attribute "SMDPIN_TO_TESTVIA_SPACING" "4.38,4.38,4.38,4.38,4.38,4.38,4.38,4.38,4.38,4.38,4.38,4.38,4.38,4.38"
					( Origin gBackEnd )
				)
				( attribute "BBV_TO_SMDPIN_SPACING" "5.00,5.00,5.00,5.00,5.00,5.00,5.00,5.00,5.00,5.00,5.00,5.00,5.00,5.00"
					( Origin gBackEnd )
				)
				( attribute "SMDPIN_TO_BONDPAD_SPACING" "5.00,5.00,5.00,5.00,5.00,5.00,5.00,5.00,5.00,5.00,5.00,5.00,5.00,5.00"
					( Origin gBackEnd )
				)
				( attribute "LINE_TO_SMDPIN_SPACING" "4.50,4.50,4.50,4.50,4.50,4.50,4.50,4.50,4.50,4.50,4.50,4.50,4.50,4.50"
					( Origin gBackEnd )
				)
				( attribute "SHAPE_TO_SMDPIN_SPACING" "4.00,4.00,4.00,4.00,4.00,4.00,4.00,4.00,4.00,4.00,4.00,4.00,4.00,4.00"
					( Origin gBackEnd )
				)
				( attribute "TESTPIN_TO_TESTPIN_SPACING" "5.00,5.00,5.00,5.00,5.00,5.00,5.00,5.00,5.00,5.00,5.00,5.00,5.00,5.00"
					( Origin gBackEnd )
				)
				( attribute "TESTPIN_TO_THRUVIA_SPACING" "5.00,5.00,5.00,5.00,5.00,5.00,5.00,5.00,5.00,5.00,5.00,5.00,5.00,5.00"
					( Origin gBackEnd )
				)
				( attribute "TESTPIN_TO_TESTVIA_SPACING" "5.00,5.00,5.00,5.00,5.00,5.00,5.00,5.00,5.00,5.00,5.00,5.00,5.00,5.00"
					( Origin gBackEnd )
				)
				( attribute "BBV_TO_TESTPIN_SPACING" "5.00,5.00,5.00,5.00,5.00,5.00,5.00,5.00,5.00,5.00,5.00,5.00,5.00,5.00"
					( Origin gBackEnd )
				)
				( attribute "BONDPAD_TO_TESTPIN_SPACING" "5.00,5.00,5.00,5.00,5.00,5.00,5.00,5.00,5.00,5.00,5.00,5.00,5.00,5.00"
					( Origin gBackEnd )
				)
				( attribute "LINE_TO_TESTPIN_SPACING" "4.50,4.50,4.50,4.50,4.50,4.50,4.50,4.50,4.50,4.50,4.50,4.50,4.50,4.50"
					( Origin gBackEnd )
				)
				( attribute "SHAPE_TO_TESTPIN_SPACING" "5.00,5.00,5.00,5.00,5.00,5.00,5.00,5.00,5.00,5.00,5.00,5.00,5.00,5.00"
					( Origin gBackEnd )
				)
				( attribute "THRUVIA_TO_THRUVIA_SPACING" "5.00,5.00,5.00,5.00,5.00,5.00,5.00,5.00,5.00,5.00,5.00,5.00,5.00,5.00"
					( Origin gBackEnd )
				)
				( attribute "TESTVIA_TO_THRUVIA_SPACING" "6.00,6.00,6.00,6.00,6.00,6.00,6.00,6.00,6.00,6.00,6.00,6.00,6.00,6.00"
					( Origin gBackEnd )
				)
				( attribute "BBV_TO_THRUVIA_SPACING" "5.00,5.00,5.00,5.00,5.00,5.00,5.00,5.00,5.00,5.00,5.00,5.00,5.00,5.00"
					( Origin gBackEnd )
				)
				( attribute "BONDPAD_TO_THRUVIA_SPACING" "5.00,5.00,5.00,5.00,5.00,5.00,5.00,5.00,5.00,5.00,5.00,5.00,5.00,5.00"
					( Origin gBackEnd )
				)
				( attribute "LINE_TO_THRUVIA_SPACING" "4.00,4.00,4.00,4.00,4.00,4.00,4.00,4.00,4.00,4.00,4.00,4.00,4.00,4.00"
					( Origin gBackEnd )
				)
				( attribute "SHAPE_TO_THRUVIA_SPACING" "4.50,4.00,4.00,4.00,4.00,4.00,4.00,4.00,4.00,4.00,4.00,4.00,4.00,4.50"
					( Origin gBackEnd )
				)
				( attribute "TESTVIA_TO_TESTVIA_SPACING" "6.00,6.00,6.00,6.00,6.00,6.00,6.00,6.00,6.00,6.00,6.00,6.00,6.00,6.00"
					( Origin gBackEnd )
				)
				( attribute "BBV_TO_TESTVIA_SPACING" "5.00,5.00,5.00,5.00,5.00,5.00,5.00,5.00,5.00,5.00,5.00,5.00,5.00,5.00"
					( Origin gBackEnd )
				)
				( attribute "BONDPAD_TO_TESTVIA_SPACING" "5.00,5.00,5.00,5.00,5.00,5.00,5.00,5.00,5.00,5.00,5.00,5.00,5.00,5.00"
					( Origin gBackEnd )
				)
				( attribute "LINE_TO_TESTVIA_SPACING" "4.50,4.00,4.00,4.00,4.00,4.00,4.00,4.00,4.00,4.00,4.00,4.00,4.00,4.50"
					( Origin gBackEnd )
				)
				( attribute "SHAPE_TO_TESTVIA_SPACING" "5.00,4.00,4.00,4.00,4.00,4.00,4.00,4.00,4.00,4.00,4.00,4.00,4.00,5.00"
					( Origin gBackEnd )
				)
				( attribute "BBV_TO_BBV_SPACING" "5.00,5.00,5.00,5.00,5.00,5.00,5.00,5.00,5.00,5.00,5.00,5.00,5.00,5.00"
					( Origin gBackEnd )
				)
				( attribute "BONDPAD_TO_BBV_SPACING" "5.00,5.00,5.00,5.00,5.00,5.00,5.00,5.00,5.00,5.00,5.00,5.00,5.00,5.00"
					( Origin gBackEnd )
				)
				( attribute "BBV_TO_LINE_SPACING" "5.00,5.00,5.00,5.00,5.00,5.00,5.00,5.00,5.00,5.00,5.00,5.00,5.00,5.00"
					( Origin gBackEnd )
				)
				( attribute "BBV_TO_SHAPE_SPACING" "5.00,5.00,5.00,5.00,5.00,5.00,5.00,5.00,5.00,5.00,5.00,5.00,5.00,5.00"
					( Origin gBackEnd )
				)
				( attribute "BONDPAD_TO_BONDPAD_SPACING" "5.00,5.00,5.00,5.00,5.00,5.00,5.00,5.00,5.00,5.00,5.00,5.00,5.00,5.00"
					( Origin gBackEnd )
				)
				( attribute "BONDPAD_TO_LINE_SPACING" "5.00,5.00,5.00,5.00,5.00,5.00,5.00,5.00,5.00,5.00,5.00,5.00,5.00,5.00"
					( Origin gBackEnd )
				)
				( attribute "BONDPAD_TO_SHAPE_SPACING" "5.00,5.00,5.00,5.00,5.00,5.00,5.00,5.00,5.00,5.00,5.00,5.00,5.00,5.00"
					( Origin gBackEnd )
				)
				( attribute "LINE_TO_LINE_SPACING" "4.00,4.00,4.00,4.00,4.00,4.00,4.00,4.00,4.00,4.00,4.00,4.00,4.00,4.00"
					( Origin gBackEnd )
				)
				( attribute "LINE_TO_SHAPE_SPACING" "10.00,10.00,10.00,10.00,10.00,10.00,10.00,10.00,10.00,10.00,10.00,10.00,10.00,10.00"
					( Origin gBackEnd )
				)
				( attribute "SHAPE_TO_SHAPE_SPACING" "10.00,10.00,10.00,10.00,10.00,10.00,10.00,10.00,10.00,10.00,10.00,10.00,10.00,10.00"
					( Origin gBackEnd )
				)
				( attribute "HOLE_TO_PIN_SPACING" "8.00,8.00,8.00,8.00,8.00,8.00,8.00,8.00,8.00,8.00,8.00,8.00,8.00,8.00"
					( Origin gBackEnd )
				)
				( attribute "HOLE_TO_VIA_SPACING" "8.00,8.00,8.00,8.00,8.00,8.00,8.00,8.00,8.00,8.00,8.00,8.00,8.00,8.00"
					( Origin gBackEnd )
				)
				( attribute "HOLE_TO_LINE_SPACING" "8.00,8.00,8.00,8.00,8.00,8.00,8.00,8.00,8.00,8.00,8.00,8.00,8.00,8.00"
					( Origin gBackEnd )
				)
				( attribute "HOLE_TO_SHAPE_SPACING" "8.00,8.00,8.00,8.00,8.00,8.00,8.00,8.00,8.00,8.00,8.00,8.00,8.00,8.00"
					( Origin gBackEnd )
				)
				( attribute "HOLE_TO_HOLE_SPACING" "8.00,8.00,8.00,8.00,8.00,8.00,8.00,8.00,8.00,8.00,8.00,8.00,8.00,8.00"
					( Origin gBackEnd )
				)
				( attribute "MVIA_TO_MVIA_SPACING" "5.00,5.00,5.00,5.00,5.00,5.00,5.00,5.00,5.00,5.00,5.00,5.00,5.00,5.00"
					( Origin gBackEnd )
				)
				( attribute "MVIA_TO_THRUPIN_SPACING" "5.00,5.00,5.00,5.00,5.00,5.00,5.00,5.00,5.00,5.00,5.00,5.00,5.00,5.00"
					( Origin gBackEnd )
				)
				( attribute "MVIA_TO_SMDPIN_SPACING" "5.00,5.00,5.00,5.00,5.00,5.00,5.00,5.00,5.00,5.00,5.00,5.00,5.00,5.00"
					( Origin gBackEnd )
				)
				( attribute "MVIA_TO_THRUVIA_SPACING" "5.00,5.00,5.00,5.00,5.00,5.00,5.00,5.00,5.00,5.00,5.00,5.00,5.00,5.00"
					( Origin gBackEnd )
				)
				( attribute "MVIA_TO_BBV_SPACING" "5.00,5.00,5.00,5.00,5.00,5.00,5.00,5.00,5.00,5.00,5.00,5.00,5.00,5.00"
					( Origin gBackEnd )
				)
				( attribute "MVIA_TO_LINE_SPACING" "5.00,5.00,5.00,5.00,5.00,5.00,5.00,5.00,5.00,5.00,5.00,5.00,5.00,5.00"
					( Origin gBackEnd )
				)
				( attribute "MVIA_TO_SHAPE_SPACING" "5.00,5.00,5.00,5.00,5.00,5.00,5.00,5.00,5.00,5.00,5.00,5.00,5.00,5.00"
					( Origin gBackEnd )
				)
				( attribute "MVIA_TO_TESTPIN_SPACING" "5.00,5.00,5.00,5.00,5.00,5.00,5.00,5.00,5.00,5.00,5.00,5.00,5.00,5.00"
					( Origin gBackEnd )
				)
				( attribute "MVIA_TO_TESTVIA_SPACING" "5.00,5.00,5.00,5.00,5.00,5.00,5.00,5.00,5.00,5.00,5.00,5.00,5.00,5.00"
					( Origin gBackEnd )
				)
				( attribute "BONDPAD_TO_MVIA_SPACING" "5.00,5.00,5.00,5.00,5.00,5.00,5.00,5.00,5.00,5.00,5.00,5.00,5.00,5.00"
					( Origin gBackEnd )
				)
				( attribute "MIN_BVIA_GAP" "5.00"
					( Origin gBackEnd )
				)
				( attribute "BONDPAD_TO_BONDPAD_DIFFP_SPC" "5.00,5.00,5.00,5.00,5.00,5.00,5.00,5.00,5.00,5.00,5.00,5.00,5.00,5.00"
					( Origin gBackEnd )
				)
				( objectStatus "BGA_WBG" )
			)
			( spacingCSet "@sapphirecity_baseboard_lib.sapphirecity_baseboard(sch_1):\XDP_CPU_MBP\"
				( attribute "THRUPIN_TO_THRUPIN_SPACING" "5.00,5.00,5.00,5.00,5.00,5.00,5.00,5.00,5.00,5.00,5.00,5.00,5.00,5.00"
					( Origin gBackEnd )
				)
				( attribute "THRUPIN_TO_SMDPIN_SPACING" "5.00,5.00,5.00,5.00,5.00,5.00,5.00,5.00,5.00,5.00,5.00,5.00,5.00,5.00"
					( Origin gBackEnd )
				)
				( attribute "TESTPIN_TO_THRUPIN_SPACING" "5.00,5.00,5.00,5.00,5.00,5.00,5.00,5.00,5.00,5.00,5.00,5.00,5.00,5.00"
					( Origin gBackEnd )
				)
				( attribute "THRUPIN_TO_THRUVIA_SPACING" "5.00,5.00,5.00,5.00,5.00,5.00,5.00,5.00,5.00,5.00,5.00,5.00,5.00,5.00"
					( Origin gBackEnd )
				)
				( attribute "TESTVIA_TO_THRUPIN_SPACING" "5.00,5.00,5.00,5.00,5.00,5.00,5.00,5.00,5.00,5.00,5.00,5.00,5.00,5.00"
					( Origin gBackEnd )
				)
				( attribute "BBV_TO_THRUPIN_SPACING" "5.00,5.00,5.00,5.00,5.00,5.00,5.00,5.00,5.00,5.00,5.00,5.00,5.00,5.00"
					( Origin gBackEnd )
				)
				( attribute "THRUPIN_TO_BONDPAD_SPACING" "5.00,5.00,5.00,5.00,5.00,5.00,5.00,5.00,5.00,5.00,5.00,5.00,5.00,5.00"
					( Origin gBackEnd )
				)
				( attribute "LINE_TO_THRUPIN_SPACING" "5.00,4.00,4.00,4.00,4.00,4.00,4.00,4.00,4.00,4.00,4.00,4.00,4.00,5.00"
					( Origin gBackEnd )
				)
				( attribute "THRUPIN_TO_SHAPE_SPACING" "5.00,5.00,5.00,5.00,5.00,5.00,5.00,5.00,5.00,5.00,5.00,5.00,5.00,5.00"
					( Origin gBackEnd )
				)
				( attribute "SMDPIN_TO_SMDPIN_SPACING" "5.00,5.00,5.00,5.00,5.00,5.00,5.00,5.00,5.00,5.00,5.00,5.00,5.00,5.00"
					( Origin gBackEnd )
				)
				( attribute "SMDPIN_TO_TESTPIN_SPACING" "5.00,5.00,5.00,5.00,5.00,5.00,5.00,5.00,5.00,5.00,5.00,5.00,5.00,25.00"
					( Origin gBackEnd )
				)
				( attribute "SMDPIN_TO_THRUVIA_SPACING" "5.00,5.00,5.00,5.00,5.00,5.00,5.00,5.00,5.00,5.00,5.00,5.00,5.00,5.00"
					( Origin gBackEnd )
				)
				( attribute "SMDPIN_TO_TESTVIA_SPACING" "5.00,5.00,5.00,5.00,5.00,5.00,5.00,5.00,5.00,5.00,5.00,5.00,5.00,5.00"
					( Origin gBackEnd )
				)
				( attribute "BBV_TO_SMDPIN_SPACING" "5.00,5.00,5.00,5.00,5.00,5.00,5.00,5.00,5.00,5.00,5.00,5.00,5.00,5.00"
					( Origin gBackEnd )
				)
				( attribute "SMDPIN_TO_BONDPAD_SPACING" "5.00,5.00,5.00,5.00,5.00,5.00,5.00,5.00,5.00,5.00,5.00,5.00,5.00,5.00"
					( Origin gBackEnd )
				)
				( attribute "LINE_TO_SMDPIN_SPACING" "4.50,4.50,4.50,4.50,4.50,4.50,4.50,4.50,4.50,4.50,4.50,4.50,4.50,4.50"
					( Origin gBackEnd )
				)
				( attribute "SHAPE_TO_SMDPIN_SPACING" "5.00,5.00,5.00,5.00,5.00,5.00,5.00,5.00,5.00,5.00,5.00,5.00,5.00,5.00"
					( Origin gBackEnd )
				)
				( attribute "TESTPIN_TO_TESTPIN_SPACING" "5.00,5.00,5.00,5.00,5.00,5.00,5.00,5.00,5.00,5.00,5.00,5.00,5.00,5.00"
					( Origin gBackEnd )
				)
				( attribute "TESTPIN_TO_THRUVIA_SPACING" "5.00,5.00,5.00,5.00,5.00,5.00,5.00,5.00,5.00,5.00,5.00,5.00,5.00,5.00"
					( Origin gBackEnd )
				)
				( attribute "TESTPIN_TO_TESTVIA_SPACING" "5.00,5.00,5.00,5.00,5.00,5.00,5.00,5.00,5.00,5.00,5.00,5.00,5.00,5.00"
					( Origin gBackEnd )
				)
				( attribute "BBV_TO_TESTPIN_SPACING" "5.00,5.00,5.00,5.00,5.00,5.00,5.00,5.00,5.00,5.00,5.00,5.00,5.00,5.00"
					( Origin gBackEnd )
				)
				( attribute "BONDPAD_TO_TESTPIN_SPACING" "5.00,5.00,5.00,5.00,5.00,5.00,5.00,5.00,5.00,5.00,5.00,5.00,5.00,5.00"
					( Origin gBackEnd )
				)
				( attribute "LINE_TO_TESTPIN_SPACING" "5.00,4.00,4.00,4.00,4.00,4.00,4.00,4.00,4.00,4.00,4.00,4.00,4.00,5.00"
					( Origin gBackEnd )
				)
				( attribute "SHAPE_TO_TESTPIN_SPACING" "5.00,5.00,5.00,5.00,5.00,5.00,5.00,5.00,5.00,5.00,5.00,5.00,5.00,5.00"
					( Origin gBackEnd )
				)
				( attribute "THRUVIA_TO_THRUVIA_SPACING" "6.00,6.00,6.00,6.00,6.00,6.00,6.00,6.00,6.00,6.00,6.00,6.00,6.00,6.00"
					( Origin gBackEnd )
				)
				( attribute "TESTVIA_TO_THRUVIA_SPACING" "6.00,6.00,6.00,6.00,6.00,6.00,6.00,6.00,6.00,6.00,6.00,6.00,6.00,6.00"
					( Origin gBackEnd )
				)
				( attribute "BBV_TO_THRUVIA_SPACING" "5.00,5.00,5.00,5.00,5.00,5.00,5.00,5.00,5.00,5.00,5.00,5.00,5.00,5.00"
					( Origin gBackEnd )
				)
				( attribute "BONDPAD_TO_THRUVIA_SPACING" "5.00,5.00,5.00,5.00,5.00,5.00,5.00,5.00,5.00,5.00,5.00,5.00,5.00,5.00"
					( Origin gBackEnd )
				)
				( attribute "LINE_TO_THRUVIA_SPACING" "4.50,4.00,4.00,4.00,4.00,4.00,4.00,4.00,4.00,4.00,4.00,4.00,4.00,4.50"
					( Origin gBackEnd )
				)
				( attribute "SHAPE_TO_THRUVIA_SPACING" "5.00,5.00,5.00,5.00,5.00,5.00,5.00,5.00,5.00,5.00,5.00,5.00,5.00,5.00"
					( Origin gBackEnd )
				)
				( attribute "TESTVIA_TO_TESTVIA_SPACING" "6.00,6.00,6.00,6.00,6.00,6.00,6.00,6.00,6.00,6.00,6.00,6.00,6.00,6.00"
					( Origin gBackEnd )
				)
				( attribute "BBV_TO_TESTVIA_SPACING" "5.00,5.00,5.00,5.00,5.00,5.00,5.00,5.00,5.00,5.00,5.00,5.00,5.00,5.00"
					( Origin gBackEnd )
				)
				( attribute "BONDPAD_TO_TESTVIA_SPACING" "5.00,5.00,5.00,5.00,5.00,5.00,5.00,5.00,5.00,5.00,5.00,5.00,5.00,5.00"
					( Origin gBackEnd )
				)
				( attribute "LINE_TO_TESTVIA_SPACING" "4.50,4.00,4.00,4.00,4.00,4.00,4.00,4.00,4.00,4.00,4.00,4.00,4.00,5.00"
					( Origin gBackEnd )
				)
				( attribute "SHAPE_TO_TESTVIA_SPACING" "5.00,5.00,5.00,5.00,5.00,5.00,5.00,5.00,5.00,5.00,5.00,5.00,5.00,5.00"
					( Origin gBackEnd )
				)
				( attribute "BBV_TO_BBV_SPACING" "5.00,5.00,5.00,5.00,5.00,5.00,5.00,5.00,5.00,5.00,5.00,5.00,5.00,5.00"
					( Origin gBackEnd )
				)
				( attribute "BONDPAD_TO_BBV_SPACING" "5.00,5.00,5.00,5.00,5.00,5.00,5.00,5.00,5.00,5.00,5.00,5.00,5.00,5.00"
					( Origin gBackEnd )
				)
				( attribute "BBV_TO_LINE_SPACING" "5.00,5.00,5.00,5.00,5.00,5.00,5.00,5.00,5.00,5.00,5.00,5.00,5.00,5.00"
					( Origin gBackEnd )
				)
				( attribute "BBV_TO_SHAPE_SPACING" "5.00,5.00,5.00,5.00,5.00,5.00,5.00,5.00,5.00,5.00,5.00,5.00,5.00,5.00"
					( Origin gBackEnd )
				)
				( attribute "BONDPAD_TO_BONDPAD_SPACING" "5.00,5.00,5.00,5.00,5.00,5.00,5.00,5.00,5.00,5.00,5.00,5.00,5.00,5.00"
					( Origin gBackEnd )
				)
				( attribute "BONDPAD_TO_LINE_SPACING" "5.00,5.00,5.00,5.00,5.00,5.00,5.00,5.00,5.00,5.00,5.00,5.00,5.00,5.00"
					( Origin gBackEnd )
				)
				( attribute "BONDPAD_TO_SHAPE_SPACING" "5.00,5.00,5.00,5.00,5.00,5.00,5.00,5.00,5.00,5.00,5.00,5.00,5.00,5.00"
					( Origin gBackEnd )
				)
				( attribute "LINE_TO_LINE_SPACING" "8.10,10.00,10.00,10.00,10.00,10.00,10.00,10.00,10.00,10.00,10.00,10.00,10.00,8.10"
					( Origin gBackEnd )
				)
				( attribute "LINE_TO_SHAPE_SPACING" "10.00,10.00,10.00,10.00,10.00,10.00,10.00,10.00,10.00,10.00,10.00,10.00,10.00,10.00"
					( Origin gBackEnd )
				)
				( attribute "SHAPE_TO_SHAPE_SPACING" "10.00,10.00,10.00,10.00,10.00,10.00,10.00,10.00,10.00,10.00,10.00,10.00,10.00,10.00"
					( Origin gBackEnd )
				)
				( attribute "HOLE_TO_PIN_SPACING" "8.00,8.00,8.00,8.00,8.00,8.00,8.00,8.00,8.00,8.00,8.00,8.00,8.00,8.00"
					( Origin gBackEnd )
				)
				( attribute "HOLE_TO_VIA_SPACING" "8.00,8.00,8.00,8.00,8.00,8.00,8.00,8.00,8.00,8.00,8.00,8.00,8.00,8.00"
					( Origin gBackEnd )
				)
				( attribute "HOLE_TO_LINE_SPACING" "8.00,8.00,8.00,8.00,8.00,8.00,8.00,8.00,8.00,8.00,8.00,8.00,8.00,8.00"
					( Origin gBackEnd )
				)
				( attribute "HOLE_TO_SHAPE_SPACING" "8.00,8.00,8.00,8.00,8.00,8.00,8.00,8.00,8.00,8.00,8.00,8.00,8.00,8.00"
					( Origin gBackEnd )
				)
				( attribute "HOLE_TO_HOLE_SPACING" "8.00,8.00,8.00,8.00,8.00,8.00,8.00,8.00,8.00,8.00,8.00,8.00,8.00,8.00"
					( Origin gBackEnd )
				)
				( attribute "MVIA_TO_MVIA_SPACING" "5.00,5.00,5.00,5.00,5.00,5.00,5.00,5.00,5.00,5.00,5.00,5.00,5.00,5.00"
					( Origin gBackEnd )
				)
				( attribute "MVIA_TO_THRUPIN_SPACING" "5.00,5.00,5.00,5.00,5.00,5.00,5.00,5.00,5.00,5.00,5.00,5.00,5.00,5.00"
					( Origin gBackEnd )
				)
				( attribute "MVIA_TO_SMDPIN_SPACING" "5.00,5.00,5.00,5.00,5.00,5.00,5.00,5.00,5.00,5.00,5.00,5.00,5.00,5.00"
					( Origin gBackEnd )
				)
				( attribute "MVIA_TO_THRUVIA_SPACING" "5.00,5.00,5.00,5.00,5.00,5.00,5.00,5.00,5.00,5.00,5.00,5.00,5.00,5.00"
					( Origin gBackEnd )
				)
				( attribute "MVIA_TO_BBV_SPACING" "5.00,5.00,5.00,5.00,5.00,5.00,5.00,5.00,5.00,5.00,5.00,5.00,5.00,5.00"
					( Origin gBackEnd )
				)
				( attribute "MVIA_TO_LINE_SPACING" "5.00,5.00,5.00,5.00,5.00,5.00,5.00,5.00,5.00,5.00,5.00,5.00,5.00,5.00"
					( Origin gBackEnd )
				)
				( attribute "MVIA_TO_SHAPE_SPACING" "5.00,5.00,5.00,5.00,5.00,5.00,5.00,5.00,5.00,5.00,5.00,5.00,5.00,5.00"
					( Origin gBackEnd )
				)
				( attribute "MVIA_TO_TESTPIN_SPACING" "5.00,5.00,5.00,5.00,5.00,5.00,5.00,5.00,5.00,5.00,5.00,5.00,5.00,5.00"
					( Origin gBackEnd )
				)
				( attribute "MVIA_TO_TESTVIA_SPACING" "5.00,5.00,5.00,5.00,5.00,5.00,5.00,5.00,5.00,5.00,5.00,5.00,5.00,5.00"
					( Origin gBackEnd )
				)
				( attribute "BONDPAD_TO_MVIA_SPACING" "5.00,5.00,5.00,5.00,5.00,5.00,5.00,5.00,5.00,5.00,5.00,5.00,5.00,5.00"
					( Origin gBackEnd )
				)
				( attribute "MIN_BVIA_GAP" "5.00"
					( Origin gBackEnd )
				)
				( attribute "BONDPAD_TO_BONDPAD_DIFFP_SPC" "5.00,5.00,5.00,5.00,5.00,5.00,5.00,5.00,5.00,5.00,5.00,5.00,5.00,5.00"
					( Origin gBackEnd )
				)
				( objectStatus "XDP_CPU_MBP" )
			)
			( spacingCSet "@sapphirecity_baseboard_lib.sapphirecity_baseboard(sch_1):\25MIL\"
				( attribute "THRUPIN_TO_THRUPIN_SPACING" "5.00,5.00,5.00,5.00,5.00,5.00,5.00,5.00,5.00,5.00,5.00,5.00,5.00,5.00"
					( Origin gBackEnd )
				)
				( attribute "THRUPIN_TO_SMDPIN_SPACING" "5.00,5.00,5.00,5.00,5.00,5.00,5.00,5.00,5.00,5.00,5.00,5.00,5.00,5.00"
					( Origin gBackEnd )
				)
				( attribute "TESTPIN_TO_THRUPIN_SPACING" "5.00,5.00,5.00,5.00,5.00,5.00,5.00,5.00,5.00,5.00,5.00,5.00,5.00,5.00"
					( Origin gBackEnd )
				)
				( attribute "THRUPIN_TO_THRUVIA_SPACING" "5.00,5.00,5.00,5.00,5.00,5.00,5.00,5.00,5.00,5.00,5.00,5.00,5.00,5.00"
					( Origin gBackEnd )
				)
				( attribute "TESTVIA_TO_THRUPIN_SPACING" "5.00,5.00,5.00,5.00,5.00,5.00,5.00,5.00,5.00,5.00,5.00,5.00,5.00,5.00"
					( Origin gBackEnd )
				)
				( attribute "BBV_TO_THRUPIN_SPACING" "5.00,5.00,5.00,5.00,5.00,5.00,5.00,5.00,5.00,5.00,5.00,5.00,5.00,5.00"
					( Origin gBackEnd )
				)
				( attribute "THRUPIN_TO_BONDPAD_SPACING" "5.00,5.00,5.00,5.00,5.00,5.00,5.00,5.00,5.00,5.00,5.00,5.00,5.00,5.00"
					( Origin gBackEnd )
				)
				( attribute "LINE_TO_THRUPIN_SPACING" "4.50,4.00,4.00,4.00,4.00,4.00,4.00,4.00,4.00,4.00,4.00,4.00,4.00,4.50"
					( Origin gBackEnd )
				)
				( attribute "THRUPIN_TO_SHAPE_SPACING" "5.00,5.00,5.00,5.00,5.00,5.00,5.00,5.00,5.00,5.00,5.00,5.00,5.00,5.00"
					( Origin gBackEnd )
				)
				( attribute "SMDPIN_TO_SMDPIN_SPACING" "5.00,5.00,5.00,5.00,5.00,5.00,5.00,5.00,5.00,5.00,5.00,5.00,5.00,5.00"
					( Origin gBackEnd )
				)
				( attribute "SMDPIN_TO_TESTPIN_SPACING" "5.00,5.00,5.00,5.00,5.00,5.00,5.00,5.00,5.00,5.00,5.00,5.00,5.00,25.00"
					( Origin gBackEnd )
				)
				( attribute "SMDPIN_TO_THRUVIA_SPACING" "5.00,5.00,5.00,5.00,5.00,5.00,5.00,5.00,5.00,5.00,5.00,5.00,5.00,5.00"
					( Origin gBackEnd )
				)
				( attribute "SMDPIN_TO_TESTVIA_SPACING" "5.00,5.00,5.00,5.00,5.00,5.00,5.00,5.00,5.00,5.00,5.00,5.00,5.00,5.00"
					( Origin gBackEnd )
				)
				( attribute "BBV_TO_SMDPIN_SPACING" "5.00,5.00,5.00,5.00,5.00,5.00,5.00,5.00,5.00,5.00,5.00,5.00,5.00,5.00"
					( Origin gBackEnd )
				)
				( attribute "SMDPIN_TO_BONDPAD_SPACING" "5.00,5.00,5.00,5.00,5.00,5.00,5.00,5.00,5.00,5.00,5.00,5.00,5.00,5.00"
					( Origin gBackEnd )
				)
				( attribute "LINE_TO_SMDPIN_SPACING" "4.50,4.50,4.50,4.50,4.50,4.50,4.50,4.50,4.50,4.50,4.50,4.50,4.50,4.50"
					( Origin gBackEnd )
				)
				( attribute "SHAPE_TO_SMDPIN_SPACING" "5.00,5.00,5.00,5.00,5.00,5.00,5.00,5.00,5.00,5.00,5.00,5.00,5.00,5.00"
					( Origin gBackEnd )
				)
				( attribute "TESTPIN_TO_TESTPIN_SPACING" "5.00,5.00,5.00,5.00,5.00,5.00,5.00,5.00,5.00,5.00,5.00,5.00,5.00,5.00"
					( Origin gBackEnd )
				)
				( attribute "TESTPIN_TO_THRUVIA_SPACING" "5.00,5.00,5.00,5.00,5.00,5.00,5.00,5.00,5.00,5.00,5.00,5.00,5.00,5.00"
					( Origin gBackEnd )
				)
				( attribute "TESTPIN_TO_TESTVIA_SPACING" "5.00,5.00,5.00,5.00,5.00,5.00,5.00,5.00,5.00,5.00,5.00,5.00,5.00,5.00"
					( Origin gBackEnd )
				)
				( attribute "BBV_TO_TESTPIN_SPACING" "5.00,5.00,5.00,5.00,5.00,5.00,5.00,5.00,5.00,5.00,5.00,5.00,5.00,5.00"
					( Origin gBackEnd )
				)
				( attribute "BONDPAD_TO_TESTPIN_SPACING" "5.00,5.00,5.00,5.00,5.00,5.00,5.00,5.00,5.00,5.00,5.00,5.00,5.00,5.00"
					( Origin gBackEnd )
				)
				( attribute "LINE_TO_TESTPIN_SPACING" "5.00,4.00,4.00,4.00,4.00,4.00,4.00,4.00,4.00,4.00,4.00,4.00,4.00,5.00"
					( Origin gBackEnd )
				)
				( attribute "SHAPE_TO_TESTPIN_SPACING" "5.00,5.00,5.00,5.00,5.00,5.00,5.00,5.00,5.00,5.00,5.00,5.00,5.00,5.00"
					( Origin gBackEnd )
				)
				( attribute "THRUVIA_TO_THRUVIA_SPACING" "6.00,6.00,6.00,6.00,6.00,6.00,6.00,6.00,6.00,6.00,6.00,6.00,6.00,6.00"
					( Origin gBackEnd )
				)
				( attribute "TESTVIA_TO_THRUVIA_SPACING" "6.00,6.00,6.00,6.00,6.00,6.00,6.00,6.00,6.00,6.00,6.00,6.00,6.00,6.00"
					( Origin gBackEnd )
				)
				( attribute "BBV_TO_THRUVIA_SPACING" "5.00,5.00,5.00,5.00,5.00,5.00,5.00,5.00,5.00,5.00,5.00,5.00,5.00,5.00"
					( Origin gBackEnd )
				)
				( attribute "BONDPAD_TO_THRUVIA_SPACING" "5.00,5.00,5.00,5.00,5.00,5.00,5.00,5.00,5.00,5.00,5.00,5.00,5.00,5.00"
					( Origin gBackEnd )
				)
				( attribute "LINE_TO_THRUVIA_SPACING" "4.50,4.00,4.00,4.00,4.00,4.00,4.00,4.00,4.00,4.00,4.00,4.00,4.00,4.50"
					( Origin gBackEnd )
				)
				( attribute "SHAPE_TO_THRUVIA_SPACING" "5.00,5.00,5.00,5.00,5.00,5.00,5.00,5.00,5.00,5.00,5.00,5.00,5.00,5.00"
					( Origin gBackEnd )
				)
				( attribute "TESTVIA_TO_TESTVIA_SPACING" "6.00,6.00,6.00,6.00,6.00,6.00,6.00,6.00,6.00,6.00,6.00,6.00,6.00,6.00"
					( Origin gBackEnd )
				)
				( attribute "BBV_TO_TESTVIA_SPACING" "5.00,5.00,5.00,5.00,5.00,5.00,5.00,5.00,5.00,5.00,5.00,5.00,5.00,5.00"
					( Origin gBackEnd )
				)
				( attribute "BONDPAD_TO_TESTVIA_SPACING" "5.00,5.00,5.00,5.00,5.00,5.00,5.00,5.00,5.00,5.00,5.00,5.00,5.00,5.00"
					( Origin gBackEnd )
				)
				( attribute "LINE_TO_TESTVIA_SPACING" "4.50,4.00,4.00,4.00,4.00,4.00,4.00,4.00,4.00,4.00,4.00,4.00,4.00,4.50"
					( Origin gBackEnd )
				)
				( attribute "SHAPE_TO_TESTVIA_SPACING" "5.00,5.00,5.00,5.00,5.00,5.00,5.00,5.00,5.00,5.00,5.00,5.00,5.00,5.00"
					( Origin gBackEnd )
				)
				( attribute "BBV_TO_BBV_SPACING" "5.00,5.00,5.00,5.00,5.00,5.00,5.00,5.00,5.00,5.00,5.00,5.00,5.00,5.00"
					( Origin gBackEnd )
				)
				( attribute "BONDPAD_TO_BBV_SPACING" "5.00,5.00,5.00,5.00,5.00,5.00,5.00,5.00,5.00,5.00,5.00,5.00,5.00,5.00"
					( Origin gBackEnd )
				)
				( attribute "BBV_TO_LINE_SPACING" "5.00,5.00,5.00,5.00,5.00,5.00,5.00,5.00,5.00,5.00,5.00,5.00,5.00,5.00"
					( Origin gBackEnd )
				)
				( attribute "BBV_TO_SHAPE_SPACING" "5.00,5.00,5.00,5.00,5.00,5.00,5.00,5.00,5.00,5.00,5.00,5.00,5.00,5.00"
					( Origin gBackEnd )
				)
				( attribute "BONDPAD_TO_BONDPAD_SPACING" "5.00,5.00,5.00,5.00,5.00,5.00,5.00,5.00,5.00,5.00,5.00,5.00,5.00,5.00"
					( Origin gBackEnd )
				)
				( attribute "BONDPAD_TO_LINE_SPACING" "5.00,5.00,5.00,5.00,5.00,5.00,5.00,5.00,5.00,5.00,5.00,5.00,5.00,5.00"
					( Origin gBackEnd )
				)
				( attribute "BONDPAD_TO_SHAPE_SPACING" "5.00,5.00,5.00,5.00,5.00,5.00,5.00,5.00,5.00,5.00,5.00,5.00,5.00,5.00"
					( Origin gBackEnd )
				)
				( attribute "LINE_TO_LINE_SPACING" "25.00,25.00,25.00,25.00,25.00,25.00,25.00,25.00,25.00,25.00,25.00,25.00,25.00,25.00"
					( Origin gBackEnd )
				)
				( attribute "LINE_TO_SHAPE_SPACING" "10.00,10.00,10.00,10.00,10.00,10.00,10.00,10.00,10.00,10.00,10.00,10.00,10.00,10.00"
					( Origin gBackEnd )
				)
				( attribute "SHAPE_TO_SHAPE_SPACING" "10.00,10.00,10.00,10.00,10.00,10.00,10.00,10.00,10.00,10.00,10.00,10.00,10.00,10.00"
					( Origin gBackEnd )
				)
				( attribute "HOLE_TO_PIN_SPACING" "8.00,8.00,8.00,8.00,8.00,8.00,8.00,8.00,8.00,8.00,8.00,8.00,8.00,8.00"
					( Origin gBackEnd )
				)
				( attribute "HOLE_TO_VIA_SPACING" "8.00,8.00,8.00,8.00,8.00,8.00,8.00,8.00,8.00,8.00,8.00,8.00,8.00,8.00"
					( Origin gBackEnd )
				)
				( attribute "HOLE_TO_LINE_SPACING" "8.00,8.00,8.00,8.00,8.00,8.00,8.00,8.00,8.00,8.00,8.00,8.00,8.00,8.00"
					( Origin gBackEnd )
				)
				( attribute "HOLE_TO_SHAPE_SPACING" "8.00,8.00,8.00,8.00,8.00,8.00,8.00,8.00,8.00,8.00,8.00,8.00,8.00,8.00"
					( Origin gBackEnd )
				)
				( attribute "HOLE_TO_HOLE_SPACING" "8.00,8.00,8.00,8.00,8.00,8.00,8.00,8.00,8.00,8.00,8.00,8.00,8.00,8.00"
					( Origin gBackEnd )
				)
				( attribute "MVIA_TO_MVIA_SPACING" "5.00,5.00,5.00,5.00,5.00,5.00,5.00,5.00,5.00,5.00,5.00,5.00,5.00,5.00"
					( Origin gBackEnd )
				)
				( attribute "MVIA_TO_THRUPIN_SPACING" "5.00,5.00,5.00,5.00,5.00,5.00,5.00,5.00,5.00,5.00,5.00,5.00,5.00,5.00"
					( Origin gBackEnd )
				)
				( attribute "MVIA_TO_SMDPIN_SPACING" "5.00,5.00,5.00,5.00,5.00,5.00,5.00,5.00,5.00,5.00,5.00,5.00,5.00,5.00"
					( Origin gBackEnd )
				)
				( attribute "MVIA_TO_THRUVIA_SPACING" "5.00,5.00,5.00,5.00,5.00,5.00,5.00,5.00,5.00,5.00,5.00,5.00,5.00,5.00"
					( Origin gBackEnd )
				)
				( attribute "MVIA_TO_BBV_SPACING" "5.00,5.00,5.00,5.00,5.00,5.00,5.00,5.00,5.00,5.00,5.00,5.00,5.00,5.00"
					( Origin gBackEnd )
				)
				( attribute "MVIA_TO_LINE_SPACING" "5.00,5.00,5.00,5.00,5.00,5.00,5.00,5.00,5.00,5.00,5.00,5.00,5.00,5.00"
					( Origin gBackEnd )
				)
				( attribute "MVIA_TO_SHAPE_SPACING" "5.00,5.00,5.00,5.00,5.00,5.00,5.00,5.00,5.00,5.00,5.00,5.00,5.00,5.00"
					( Origin gBackEnd )
				)
				( attribute "MVIA_TO_TESTPIN_SPACING" "5.00,5.00,5.00,5.00,5.00,5.00,5.00,5.00,5.00,5.00,5.00,5.00,5.00,5.00"
					( Origin gBackEnd )
				)
				( attribute "MVIA_TO_TESTVIA_SPACING" "5.00,5.00,5.00,5.00,5.00,5.00,5.00,5.00,5.00,5.00,5.00,5.00,5.00,5.00"
					( Origin gBackEnd )
				)
				( attribute "BONDPAD_TO_MVIA_SPACING" "5.00,5.00,5.00,5.00,5.00,5.00,5.00,5.00,5.00,5.00,5.00,5.00,5.00,5.00"
					( Origin gBackEnd )
				)
				( attribute "MIN_BVIA_GAP" "5.00"
					( Origin gBackEnd )
				)
				( attribute "BONDPAD_TO_BONDPAD_DIFFP_SPC" "5.00,5.00,5.00,5.00,5.00,5.00,5.00,5.00,5.00,5.00,5.00,5.00,5.00,5.00"
					( Origin gBackEnd )
				)
				( objectStatus "25MIL" )
			)
			( spacingCSet "@sapphirecity_baseboard_lib.sapphirecity_baseboard(sch_1):\8_MIL_SL_12_MIL_MS\"
				( attribute "THRUPIN_TO_THRUPIN_SPACING" "5.00,5.00,5.00,5.00,5.00,5.00,5.00,5.00,5.00,5.00,5.00,5.00,5.00,5.00"
					( Origin gBackEnd )
				)
				( attribute "THRUPIN_TO_SMDPIN_SPACING" "5.00,5.00,5.00,5.00,5.00,5.00,5.00,5.00,5.00,5.00,5.00,5.00,5.00,5.00"
					( Origin gBackEnd )
				)
				( attribute "TESTPIN_TO_THRUPIN_SPACING" "5.00,5.00,5.00,5.00,5.00,5.00,5.00,5.00,5.00,5.00,5.00,5.00,5.00,5.00"
					( Origin gBackEnd )
				)
				( attribute "THRUPIN_TO_THRUVIA_SPACING" "4.00,4.00,4.00,4.00,4.00,4.00,4.00,4.00,4.00,4.00,4.00,4.00,4.00,5.00"
					( Origin gBackEnd )
				)
				( attribute "TESTVIA_TO_THRUPIN_SPACING" "5.00,5.00,5.00,5.00,5.00,5.00,5.00,5.00,5.00,5.00,5.00,5.00,5.00,5.00"
					( Origin gBackEnd )
				)
				( attribute "BBV_TO_THRUPIN_SPACING" "5.00,5.00,5.00,5.00,5.00,5.00,5.00,5.00,5.00,5.00,5.00,5.00,5.00,5.00"
					( Origin gBackEnd )
				)
				( attribute "THRUPIN_TO_BONDPAD_SPACING" "5.00,5.00,5.00,5.00,5.00,5.00,5.00,5.00,5.00,5.00,5.00,5.00,5.00,5.00"
					( Origin gBackEnd )
				)
				( attribute "LINE_TO_THRUPIN_SPACING" "4.50,4.00,4.00,4.00,4.00,4.00,4.00,4.00,4.00,4.00,4.00,4.00,4.00,4.50"
					( Origin gBackEnd )
				)
				( attribute "THRUPIN_TO_SHAPE_SPACING" "4.50,4.00,4.00,4.00,4.00,4.00,4.00,4.00,4.00,4.00,4.00,4.00,4.00,5.00"
					( Origin gBackEnd )
				)
				( attribute "SMDPIN_TO_SMDPIN_SPACING" "5.00,5.00,5.00,5.00,5.00,5.00,5.00,5.00,5.00,5.00,5.00,5.00,5.00,5.00"
					( Origin gBackEnd )
				)
				( attribute "SMDPIN_TO_TESTPIN_SPACING" "5.00,5.00,5.00,5.00,5.00,5.00,5.00,5.00,5.00,5.00,5.00,5.00,5.00,25.00"
					( Origin gBackEnd )
				)
				( attribute "SMDPIN_TO_THRUVIA_SPACING" "4.00,4.00,4.00,4.00,4.00,4.00,4.00,4.00,4.00,4.00,4.00,4.00,4.00,5.00"
					( Origin gBackEnd )
				)
				( attribute "SMDPIN_TO_TESTVIA_SPACING" "4.50,4.50,4.50,4.50,4.50,4.50,4.50,4.50,4.50,4.50,4.50,4.50,4.50,5.00"
					( Origin gBackEnd )
				)
				( attribute "BBV_TO_SMDPIN_SPACING" "5.00,5.00,5.00,5.00,5.00,5.00,5.00,5.00,5.00,5.00,5.00,5.00,5.00,5.00"
					( Origin gBackEnd )
				)
				( attribute "SMDPIN_TO_BONDPAD_SPACING" "5.00,5.00,5.00,5.00,5.00,5.00,5.00,5.00,5.00,5.00,5.00,5.00,5.00,5.00"
					( Origin gBackEnd )
				)
				( attribute "LINE_TO_SMDPIN_SPACING" "4.50,4.50,4.50,4.50,4.50,4.50,4.50,4.50,4.50,4.50,4.50,4.50,4.50,4.50"
					( Origin gBackEnd )
				)
				( attribute "SHAPE_TO_SMDPIN_SPACING" "5.00,5.00,5.00,5.00,5.00,5.00,5.00,5.00,5.00,5.00,5.00,5.00,5.00,5.00"
					( Origin gBackEnd )
				)
				( attribute "TESTPIN_TO_TESTPIN_SPACING" "5.00,5.00,5.00,5.00,5.00,5.00,5.00,5.00,5.00,5.00,5.00,5.00,5.00,5.00"
					( Origin gBackEnd )
				)
				( attribute "TESTPIN_TO_THRUVIA_SPACING" "5.00,5.00,5.00,5.00,5.00,5.00,5.00,5.00,5.00,5.00,5.00,5.00,5.00,5.00"
					( Origin gBackEnd )
				)
				( attribute "TESTPIN_TO_TESTVIA_SPACING" "5.00,5.00,5.00,5.00,5.00,5.00,5.00,5.00,5.00,5.00,5.00,5.00,5.00,5.00"
					( Origin gBackEnd )
				)
				( attribute "BBV_TO_TESTPIN_SPACING" "5.00,5.00,5.00,5.00,5.00,5.00,5.00,5.00,5.00,5.00,5.00,5.00,5.00,5.00"
					( Origin gBackEnd )
				)
				( attribute "BONDPAD_TO_TESTPIN_SPACING" "5.00,5.00,5.00,5.00,5.00,5.00,5.00,5.00,5.00,5.00,5.00,5.00,5.00,5.00"
					( Origin gBackEnd )
				)
				( attribute "LINE_TO_TESTPIN_SPACING" "4.50,4.00,4.00,4.00,4.00,4.00,4.00,4.00,4.00,4.00,4.00,4.00,4.00,4.50"
					( Origin gBackEnd )
				)
				( attribute "SHAPE_TO_TESTPIN_SPACING" "4.50,4.00,4.00,4.00,4.00,4.00,4.00,4.00,4.00,4.00,4.00,4.00,4.00,5.00"
					( Origin gBackEnd )
				)
				( attribute "THRUVIA_TO_THRUVIA_SPACING" "5.00,5.00,5.00,5.00,5.00,5.00,5.00,5.00,5.00,5.00,5.00,5.00,5.00,5.00"
					( Origin gBackEnd )
				)
				( attribute "TESTVIA_TO_THRUVIA_SPACING" "5.00,5.00,5.00,5.00,5.00,5.00,5.00,5.00,5.00,5.00,5.00,5.00,5.00,6.00"
					( Origin gBackEnd )
				)
				( attribute "BBV_TO_THRUVIA_SPACING" "5.00,5.00,5.00,5.00,5.00,5.00,5.00,5.00,5.00,5.00,5.00,5.00,5.00,5.00"
					( Origin gBackEnd )
				)
				( attribute "BONDPAD_TO_THRUVIA_SPACING" "5.00,5.00,5.00,5.00,5.00,5.00,5.00,5.00,5.00,5.00,5.00,5.00,5.00,5.00"
					( Origin gBackEnd )
				)
				( attribute "LINE_TO_THRUVIA_SPACING" "4.50,4.00,4.00,4.00,4.00,4.00,4.00,4.00,4.00,4.00,4.00,4.00,4.00,4.50"
					( Origin gBackEnd )
				)
				( attribute "SHAPE_TO_THRUVIA_SPACING" "4.50,4.00,4.00,4.00,4.00,4.00,4.00,4.00,4.00,4.00,4.00,4.00,4.00,5.00"
					( Origin gBackEnd )
				)
				( attribute "TESTVIA_TO_TESTVIA_SPACING" "5.00,5.00,5.00,5.00,5.00,5.00,5.00,5.00,5.00,5.00,5.00,5.00,5.00,6.00"
					( Origin gBackEnd )
				)
				( attribute "BBV_TO_TESTVIA_SPACING" "5.00,5.00,5.00,5.00,5.00,5.00,5.00,5.00,5.00,5.00,5.00,5.00,5.00,5.00"
					( Origin gBackEnd )
				)
				( attribute "BONDPAD_TO_TESTVIA_SPACING" "5.00,5.00,5.00,5.00,5.00,5.00,5.00,5.00,5.00,5.00,5.00,5.00,5.00,5.00"
					( Origin gBackEnd )
				)
				( attribute "LINE_TO_TESTVIA_SPACING" "4.50,5.00,4.00,5.00,4.00,5.00,5.00,5.00,5.00,4.00,5.00,4.00,5.00,4.50"
					( Origin gBackEnd )
				)
				( attribute "SHAPE_TO_TESTVIA_SPACING" "4.50,4.00,4.00,4.00,4.00,4.00,4.00,4.00,4.00,4.00,4.00,4.00,4.00,5.00"
					( Origin gBackEnd )
				)
				( attribute "BBV_TO_BBV_SPACING" "5.00,5.00,5.00,5.00,5.00,5.00,5.00,5.00,5.00,5.00,5.00,5.00,5.00,5.00"
					( Origin gBackEnd )
				)
				( attribute "BONDPAD_TO_BBV_SPACING" "5.00,5.00,5.00,5.00,5.00,5.00,5.00,5.00,5.00,5.00,5.00,5.00,5.00,5.00"
					( Origin gBackEnd )
				)
				( attribute "BBV_TO_LINE_SPACING" "5.00,5.00,5.00,5.00,5.00,5.00,5.00,5.00,5.00,5.00,5.00,5.00,5.00,5.00"
					( Origin gBackEnd )
				)
				( attribute "BBV_TO_SHAPE_SPACING" "5.00,5.00,5.00,5.00,5.00,5.00,5.00,5.00,5.00,5.00,5.00,5.00,5.00,5.00"
					( Origin gBackEnd )
				)
				( attribute "BONDPAD_TO_BONDPAD_SPACING" "5.00,5.00,5.00,5.00,5.00,5.00,5.00,5.00,5.00,5.00,5.00,5.00,5.00,5.00"
					( Origin gBackEnd )
				)
				( attribute "BONDPAD_TO_LINE_SPACING" "5.00,5.00,5.00,5.00,5.00,5.00,5.00,5.00,5.00,5.00,5.00,5.00,5.00,5.00"
					( Origin gBackEnd )
				)
				( attribute "BONDPAD_TO_SHAPE_SPACING" "5.00,5.00,5.00,5.00,5.00,5.00,5.00,5.00,5.00,5.00,5.00,5.00,5.00,5.00"
					( Origin gBackEnd )
				)
				( attribute "LINE_TO_LINE_SPACING" "12.00,8.00,8.00,8.00,8.00,8.00,8.00,8.00,8.00,8.00,8.00,8.00,8.00,12.00"
					( Origin gBackEnd )
				)
				( attribute "LINE_TO_SHAPE_SPACING" "5.00,5.00,5.00,5.00,5.00,5.00,5.00,5.00,5.00,5.00,5.00,5.00,5.00,10.00"
					( Origin gBackEnd )
				)
				( attribute "SHAPE_TO_SHAPE_SPACING" "10.00,10.00,10.00,10.00,10.00,10.00,10.00,10.00,10.00,10.00,10.00,10.00,10.00,10.00"
					( Origin gBackEnd )
				)
				( attribute "HOLE_TO_PIN_SPACING" "8.00,8.00,8.00,8.00,8.00,8.00,8.00,8.00,8.00,8.00,8.00,8.00,8.00,8.00"
					( Origin gBackEnd )
				)
				( attribute "HOLE_TO_VIA_SPACING" "8.00,8.00,8.00,8.00,8.00,8.00,8.00,8.00,8.00,8.00,8.00,8.00,8.00,8.00"
					( Origin gBackEnd )
				)
				( attribute "HOLE_TO_LINE_SPACING" "8.00,8.00,8.00,8.00,8.00,8.00,8.00,8.00,8.00,8.00,8.00,8.00,8.00,8.00"
					( Origin gBackEnd )
				)
				( attribute "HOLE_TO_SHAPE_SPACING" "8.00,8.00,8.00,8.00,8.00,8.00,8.00,8.00,8.00,8.00,8.00,8.00,8.00,8.00"
					( Origin gBackEnd )
				)
				( attribute "HOLE_TO_HOLE_SPACING" "8.00,8.00,8.00,8.00,8.00,8.00,8.00,8.00,8.00,8.00,8.00,8.00,8.00,8.00"
					( Origin gBackEnd )
				)
				( attribute "MVIA_TO_MVIA_SPACING" "5.00,5.00,5.00,5.00,5.00,5.00,5.00,5.00,5.00,5.00,5.00,5.00,5.00,5.00"
					( Origin gBackEnd )
				)
				( attribute "MVIA_TO_THRUPIN_SPACING" "5.00,5.00,5.00,5.00,5.00,5.00,5.00,5.00,5.00,5.00,5.00,5.00,5.00,5.00"
					( Origin gBackEnd )
				)
				( attribute "MVIA_TO_SMDPIN_SPACING" "5.00,5.00,5.00,5.00,5.00,5.00,5.00,5.00,5.00,5.00,5.00,5.00,5.00,5.00"
					( Origin gBackEnd )
				)
				( attribute "MVIA_TO_THRUVIA_SPACING" "5.00,5.00,5.00,5.00,5.00,5.00,5.00,5.00,5.00,5.00,5.00,5.00,5.00,5.00"
					( Origin gBackEnd )
				)
				( attribute "MVIA_TO_BBV_SPACING" "5.00,5.00,5.00,5.00,5.00,5.00,5.00,5.00,5.00,5.00,5.00,5.00,5.00,5.00"
					( Origin gBackEnd )
				)
				( attribute "MVIA_TO_LINE_SPACING" "5.00,5.00,5.00,5.00,5.00,5.00,5.00,5.00,5.00,5.00,5.00,5.00,5.00,5.00"
					( Origin gBackEnd )
				)
				( attribute "MVIA_TO_SHAPE_SPACING" "5.00,5.00,5.00,5.00,5.00,5.00,5.00,5.00,5.00,5.00,5.00,5.00,5.00,5.00"
					( Origin gBackEnd )
				)
				( attribute "MVIA_TO_TESTPIN_SPACING" "5.00,5.00,5.00,5.00,5.00,5.00,5.00,5.00,5.00,5.00,5.00,5.00,5.00,5.00"
					( Origin gBackEnd )
				)
				( attribute "MVIA_TO_TESTVIA_SPACING" "5.00,5.00,5.00,5.00,5.00,5.00,5.00,5.00,5.00,5.00,5.00,5.00,5.00,5.00"
					( Origin gBackEnd )
				)
				( attribute "BONDPAD_TO_MVIA_SPACING" "5.00,5.00,5.00,5.00,5.00,5.00,5.00,5.00,5.00,5.00,5.00,5.00,5.00,5.00"
					( Origin gBackEnd )
				)
				( attribute "MIN_BVIA_GAP" "5.00"
					( Origin gBackEnd )
				)
				( attribute "BONDPAD_TO_BONDPAD_DIFFP_SPC" "5.00,5.00,5.00,5.00,5.00,5.00,5.00,5.00,5.00,5.00,5.00,5.00,5.00,5.00"
					( Origin gBackEnd )
				)
				( objectStatus "12_MIL_MS_&_8_MIL_SL" )
			)
			( spacingCSet "@sapphirecity_baseboard_lib.sapphirecity_baseboard(sch_1):\12_MIL_MS_17_MIL_SL\"
				( attribute "THRUPIN_TO_THRUPIN_SPACING" "5.00,5.00,5.00,5.00,5.00,5.00,5.00,5.00,5.00,5.00,5.00,5.00,5.00,5.00"
					( Origin gBackEnd )
				)
				( attribute "THRUPIN_TO_SMDPIN_SPACING" "5.00,5.00,5.00,5.00,5.00,5.00,5.00,5.00,5.00,5.00,5.00,5.00,5.00,5.00"
					( Origin gBackEnd )
				)
				( attribute "TESTPIN_TO_THRUPIN_SPACING" "5.00,5.00,5.00,5.00,5.00,5.00,5.00,5.00,5.00,5.00,5.00,5.00,5.00,5.00"
					( Origin gBackEnd )
				)
				( attribute "THRUPIN_TO_THRUVIA_SPACING" "4.00,4.00,4.00,4.00,4.00,4.00,4.00,4.00,4.00,4.00,4.00,4.00,4.00,5.00"
					( Origin gBackEnd )
				)
				( attribute "TESTVIA_TO_THRUPIN_SPACING" "5.00,5.00,5.00,5.00,5.00,5.00,5.00,5.00,5.00,5.00,5.00,5.00,5.00,5.00"
					( Origin gBackEnd )
				)
				( attribute "BBV_TO_THRUPIN_SPACING" "5.00,5.00,5.00,5.00,5.00,5.00,5.00,5.00,5.00,5.00,5.00,5.00,5.00,5.00"
					( Origin gBackEnd )
				)
				( attribute "THRUPIN_TO_BONDPAD_SPACING" "5.00,5.00,5.00,5.00,5.00,5.00,5.00,5.00,5.00,5.00,5.00,5.00,5.00,5.00"
					( Origin gBackEnd )
				)
				( attribute "LINE_TO_THRUPIN_SPACING" "4.50,4.00,4.00,4.00,4.00,4.00,4.00,4.00,4.00,4.00,4.00,4.00,4.00,4.50"
					( Origin gBackEnd )
				)
				( attribute "THRUPIN_TO_SHAPE_SPACING" "4.50,4.00,4.00,4.00,4.00,4.00,4.00,4.00,4.00,4.00,4.00,4.00,4.00,5.00"
					( Origin gBackEnd )
				)
				( attribute "SMDPIN_TO_SMDPIN_SPACING" "5.00,5.00,5.00,5.00,5.00,5.00,5.00,5.00,5.00,5.00,5.00,5.00,5.00,5.00"
					( Origin gBackEnd )
				)
				( attribute "SMDPIN_TO_TESTPIN_SPACING" "5.00,5.00,5.00,5.00,5.00,5.00,5.00,5.00,5.00,5.00,5.00,5.00,5.00,25.00"
					( Origin gBackEnd )
				)
				( attribute "SMDPIN_TO_THRUVIA_SPACING" "4.00,4.00,4.00,4.00,4.00,4.00,4.00,4.00,4.00,4.00,4.00,4.00,4.00,5.00"
					( Origin gBackEnd )
				)
				( attribute "SMDPIN_TO_TESTVIA_SPACING" "4.50,4.50,4.50,4.50,4.50,4.50,4.50,4.50,4.50,4.50,4.50,4.50,4.50,5.00"
					( Origin gBackEnd )
				)
				( attribute "BBV_TO_SMDPIN_SPACING" "5.00,5.00,5.00,5.00,5.00,5.00,5.00,5.00,5.00,5.00,5.00,5.00,5.00,5.00"
					( Origin gBackEnd )
				)
				( attribute "SMDPIN_TO_BONDPAD_SPACING" "5.00,5.00,5.00,5.00,5.00,5.00,5.00,5.00,5.00,5.00,5.00,5.00,5.00,5.00"
					( Origin gBackEnd )
				)
				( attribute "LINE_TO_SMDPIN_SPACING" "4.50,4.50,4.50,4.50,4.50,4.50,4.50,4.50,4.50,4.50,4.50,4.50,4.50,4.50"
					( Origin gBackEnd )
				)
				( attribute "SHAPE_TO_SMDPIN_SPACING" "5.00,5.00,5.00,5.00,5.00,5.00,5.00,5.00,5.00,5.00,5.00,5.00,5.00,5.00"
					( Origin gBackEnd )
				)
				( attribute "TESTPIN_TO_TESTPIN_SPACING" "5.00,5.00,5.00,5.00,5.00,5.00,5.00,5.00,5.00,5.00,5.00,5.00,5.00,5.00"
					( Origin gBackEnd )
				)
				( attribute "TESTPIN_TO_THRUVIA_SPACING" "5.00,5.00,5.00,5.00,5.00,5.00,5.00,5.00,5.00,5.00,5.00,5.00,5.00,5.00"
					( Origin gBackEnd )
				)
				( attribute "TESTPIN_TO_TESTVIA_SPACING" "5.00,5.00,5.00,5.00,5.00,5.00,5.00,5.00,5.00,5.00,5.00,5.00,5.00,5.00"
					( Origin gBackEnd )
				)
				( attribute "BBV_TO_TESTPIN_SPACING" "5.00,5.00,5.00,5.00,5.00,5.00,5.00,5.00,5.00,5.00,5.00,5.00,5.00,5.00"
					( Origin gBackEnd )
				)
				( attribute "BONDPAD_TO_TESTPIN_SPACING" "5.00,5.00,5.00,5.00,5.00,5.00,5.00,5.00,5.00,5.00,5.00,5.00,5.00,5.00"
					( Origin gBackEnd )
				)
				( attribute "LINE_TO_TESTPIN_SPACING" "4.50,5.00,5.00,5.00,5.00,5.00,5.00,5.00,5.00,5.00,5.00,5.00,5.00,5.00"
					( Origin gBackEnd )
				)
				( attribute "SHAPE_TO_TESTPIN_SPACING" "4.50,4.00,4.00,4.00,4.00,4.00,4.00,4.00,4.00,4.00,4.00,4.00,4.00,5.00"
					( Origin gBackEnd )
				)
				( attribute "THRUVIA_TO_THRUVIA_SPACING" "5.00,5.00,5.00,5.00,5.00,5.00,5.00,5.00,5.00,5.00,5.00,5.00,5.00,5.00"
					( Origin gBackEnd )
				)
				( attribute "TESTVIA_TO_THRUVIA_SPACING" "5.00,5.00,5.00,5.00,5.00,5.00,5.00,5.00,5.00,5.00,5.00,5.00,5.00,6.00"
					( Origin gBackEnd )
				)
				( attribute "BBV_TO_THRUVIA_SPACING" "5.00,5.00,5.00,5.00,5.00,5.00,5.00,5.00,5.00,5.00,5.00,5.00,5.00,5.00"
					( Origin gBackEnd )
				)
				( attribute "BONDPAD_TO_THRUVIA_SPACING" "5.00,5.00,5.00,5.00,5.00,5.00,5.00,5.00,5.00,5.00,5.00,5.00,5.00,5.00"
					( Origin gBackEnd )
				)
				( attribute "LINE_TO_THRUVIA_SPACING" "4.50,4.00,4.00,4.00,4.00,4.00,4.00,4.00,4.00,4.00,4.00,4.00,4.00,4.50"
					( Origin gBackEnd )
				)
				( attribute "SHAPE_TO_THRUVIA_SPACING" "4.50,4.00,4.00,4.00,4.00,4.00,4.00,4.00,4.00,4.00,4.00,4.00,4.00,5.00"
					( Origin gBackEnd )
				)
				( attribute "TESTVIA_TO_TESTVIA_SPACING" "5.00,5.00,5.00,5.00,5.00,5.00,5.00,5.00,5.00,5.00,5.00,5.00,5.00,6.00"
					( Origin gBackEnd )
				)
				( attribute "BBV_TO_TESTVIA_SPACING" "5.00,5.00,5.00,5.00,5.00,5.00,5.00,5.00,5.00,5.00,5.00,5.00,5.00,5.00"
					( Origin gBackEnd )
				)
				( attribute "BONDPAD_TO_TESTVIA_SPACING" "5.00,5.00,5.00,5.00,5.00,5.00,5.00,5.00,5.00,5.00,5.00,5.00,5.00,5.00"
					( Origin gBackEnd )
				)
				( attribute "LINE_TO_TESTVIA_SPACING" "4.50,5.00,4.00,5.00,4.00,5.00,5.00,5.00,5.00,4.00,5.00,4.00,5.00,4.50"
					( Origin gBackEnd )
				)
				( attribute "SHAPE_TO_TESTVIA_SPACING" "4.50,4.00,4.00,4.00,4.00,4.00,4.00,4.00,4.00,4.00,4.00,4.00,4.00,5.00"
					( Origin gBackEnd )
				)
				( attribute "BBV_TO_BBV_SPACING" "5.00,5.00,5.00,5.00,5.00,5.00,5.00,5.00,5.00,5.00,5.00,5.00,5.00,5.00"
					( Origin gBackEnd )
				)
				( attribute "BONDPAD_TO_BBV_SPACING" "5.00,5.00,5.00,5.00,5.00,5.00,5.00,5.00,5.00,5.00,5.00,5.00,5.00,5.00"
					( Origin gBackEnd )
				)
				( attribute "BBV_TO_LINE_SPACING" "5.00,5.00,5.00,5.00,5.00,5.00,5.00,5.00,5.00,5.00,5.00,5.00,5.00,5.00"
					( Origin gBackEnd )
				)
				( attribute "BBV_TO_SHAPE_SPACING" "5.00,5.00,5.00,5.00,5.00,5.00,5.00,5.00,5.00,5.00,5.00,5.00,5.00,5.00"
					( Origin gBackEnd )
				)
				( attribute "BONDPAD_TO_BONDPAD_SPACING" "5.00,5.00,5.00,5.00,5.00,5.00,5.00,5.00,5.00,5.00,5.00,5.00,5.00,5.00"
					( Origin gBackEnd )
				)
				( attribute "BONDPAD_TO_LINE_SPACING" "5.00,5.00,5.00,5.00,5.00,5.00,5.00,5.00,5.00,5.00,5.00,5.00,5.00,5.00"
					( Origin gBackEnd )
				)
				( attribute "BONDPAD_TO_SHAPE_SPACING" "5.00,5.00,5.00,5.00,5.00,5.00,5.00,5.00,5.00,5.00,5.00,5.00,5.00,5.00"
					( Origin gBackEnd )
				)
				( attribute "LINE_TO_LINE_SPACING" "12.00,17.00,17.00,17.00,17.00,17.00,17.00,17.00,17.00,17.00,17.00,17.00,17.00,12.00"
					( Origin gBackEnd )
				)
				( attribute "LINE_TO_SHAPE_SPACING" "5.00,5.00,5.00,5.00,5.00,5.00,5.00,5.00,5.00,5.00,5.00,5.00,5.00,10.00"
					( Origin gBackEnd )
				)
				( attribute "SHAPE_TO_SHAPE_SPACING" "10.00,10.00,10.00,10.00,10.00,10.00,10.00,10.00,10.00,10.00,10.00,10.00,10.00,10.00"
					( Origin gBackEnd )
				)
				( attribute "HOLE_TO_PIN_SPACING" "8.00,8.00,8.00,8.00,8.00,8.00,8.00,8.00,8.00,8.00,8.00,8.00,8.00,8.00"
					( Origin gBackEnd )
				)
				( attribute "HOLE_TO_VIA_SPACING" "8.00,8.00,8.00,8.00,8.00,8.00,8.00,8.00,8.00,8.00,8.00,8.00,8.00,8.00"
					( Origin gBackEnd )
				)
				( attribute "HOLE_TO_LINE_SPACING" "8.00,8.00,8.00,8.00,8.00,8.00,8.00,8.00,8.00,8.00,8.00,8.00,8.00,8.00"
					( Origin gBackEnd )
				)
				( attribute "HOLE_TO_SHAPE_SPACING" "8.00,8.00,8.00,8.00,8.00,8.00,8.00,8.00,8.00,8.00,8.00,8.00,8.00,8.00"
					( Origin gBackEnd )
				)
				( attribute "HOLE_TO_HOLE_SPACING" "8.00,8.00,8.00,8.00,8.00,8.00,8.00,8.00,8.00,8.00,8.00,8.00,8.00,8.00"
					( Origin gBackEnd )
				)
				( attribute "MVIA_TO_MVIA_SPACING" "5.00,5.00,5.00,5.00,5.00,5.00,5.00,5.00,5.00,5.00,5.00,5.00,5.00,5.00"
					( Origin gBackEnd )
				)
				( attribute "MVIA_TO_THRUPIN_SPACING" "5.00,5.00,5.00,5.00,5.00,5.00,5.00,5.00,5.00,5.00,5.00,5.00,5.00,5.00"
					( Origin gBackEnd )
				)
				( attribute "MVIA_TO_SMDPIN_SPACING" "5.00,5.00,5.00,5.00,5.00,5.00,5.00,5.00,5.00,5.00,5.00,5.00,5.00,5.00"
					( Origin gBackEnd )
				)
				( attribute "MVIA_TO_THRUVIA_SPACING" "5.00,5.00,5.00,5.00,5.00,5.00,5.00,5.00,5.00,5.00,5.00,5.00,5.00,5.00"
					( Origin gBackEnd )
				)
				( attribute "MVIA_TO_BBV_SPACING" "5.00,5.00,5.00,5.00,5.00,5.00,5.00,5.00,5.00,5.00,5.00,5.00,5.00,5.00"
					( Origin gBackEnd )
				)
				( attribute "MVIA_TO_LINE_SPACING" "5.00,5.00,5.00,5.00,5.00,5.00,5.00,5.00,5.00,5.00,5.00,5.00,5.00,5.00"
					( Origin gBackEnd )
				)
				( attribute "MVIA_TO_SHAPE_SPACING" "5.00,5.00,5.00,5.00,5.00,5.00,5.00,5.00,5.00,5.00,5.00,5.00,5.00,5.00"
					( Origin gBackEnd )
				)
				( attribute "MVIA_TO_TESTPIN_SPACING" "5.00,5.00,5.00,5.00,5.00,5.00,5.00,5.00,5.00,5.00,5.00,5.00,5.00,5.00"
					( Origin gBackEnd )
				)
				( attribute "MVIA_TO_TESTVIA_SPACING" "5.00,5.00,5.00,5.00,5.00,5.00,5.00,5.00,5.00,5.00,5.00,5.00,5.00,5.00"
					( Origin gBackEnd )
				)
				( attribute "BONDPAD_TO_MVIA_SPACING" "5.00,5.00,5.00,5.00,5.00,5.00,5.00,5.00,5.00,5.00,5.00,5.00,5.00,5.00"
					( Origin gBackEnd )
				)
				( attribute "MIN_BVIA_GAP" "5.00"
					( Origin gBackEnd )
				)
				( attribute "BONDPAD_TO_BONDPAD_DIFFP_SPC" "5.00,5.00,5.00,5.00,5.00,5.00,5.00,5.00,5.00,5.00,5.00,5.00,5.00,5.00"
					( Origin gBackEnd )
				)
				( objectStatus "12_MIL_US_&_17_MIL_SL" )
			)
			( spacingCSet "@sapphirecity_baseboard_lib.sapphirecity_baseboard(sch_1):\KPI\"
				( attribute "THRUPIN_TO_THRUPIN_SPACING" "5.00,5.00,5.00,5.00,5.00,5.00,5.00,5.00,5.00,5.00,5.00,5.00,5.00,5.00"
					( Origin gBackEnd )
				)
				( attribute "THRUPIN_TO_SMDPIN_SPACING" "5.00,5.00,5.00,5.00,5.00,5.00,5.00,5.00,5.00,5.00,5.00,5.00,5.00,5.00"
					( Origin gBackEnd )
				)
				( attribute "TESTPIN_TO_THRUPIN_SPACING" "5.00,5.00,5.00,5.00,5.00,5.00,5.00,5.00,5.00,5.00,5.00,5.00,5.00,5.00"
					( Origin gBackEnd )
				)
				( attribute "THRUPIN_TO_THRUVIA_SPACING" "4.00,4.00,4.00,4.00,4.00,4.00,4.00,4.00,4.00,4.00,4.00,4.00,4.00,5.00"
					( Origin gBackEnd )
				)
				( attribute "TESTVIA_TO_THRUPIN_SPACING" "5.00,5.00,5.00,5.00,5.00,5.00,5.00,5.00,5.00,5.00,5.00,5.00,5.00,5.00"
					( Origin gBackEnd )
				)
				( attribute "BBV_TO_THRUPIN_SPACING" "5.00,5.00,5.00,5.00,5.00,5.00,5.00,5.00,5.00,5.00,5.00,5.00,5.00,5.00"
					( Origin gBackEnd )
				)
				( attribute "THRUPIN_TO_BONDPAD_SPACING" "5.00,5.00,5.00,5.00,5.00,5.00,5.00,5.00,5.00,5.00,5.00,5.00,5.00,5.00"
					( Origin gBackEnd )
				)
				( attribute "LINE_TO_THRUPIN_SPACING" "5.00,5.00,5.00,5.00,5.00,5.00,5.00,5.00,5.00,5.00,5.00,5.00,5.00,5.00"
					( Origin gBackEnd )
				)
				( attribute "THRUPIN_TO_SHAPE_SPACING" "4.50,4.00,4.00,4.00,4.00,4.00,4.00,4.00,4.00,4.00,4.00,4.00,4.00,5.00"
					( Origin gBackEnd )
				)
				( attribute "SMDPIN_TO_SMDPIN_SPACING" "5.00,5.00,5.00,5.00,5.00,5.00,5.00,5.00,5.00,5.00,5.00,5.00,5.00,5.00"
					( Origin gBackEnd )
				)
				( attribute "SMDPIN_TO_TESTPIN_SPACING" "5.00,5.00,5.00,5.00,5.00,5.00,5.00,5.00,5.00,5.00,5.00,5.00,5.00,25.00"
					( Origin gBackEnd )
				)
				( attribute "SMDPIN_TO_THRUVIA_SPACING" "4.00,4.00,4.00,4.00,4.00,4.00,4.00,4.00,4.00,4.00,4.00,4.00,4.00,5.00"
					( Origin gBackEnd )
				)
				( attribute "SMDPIN_TO_TESTVIA_SPACING" "4.50,4.50,4.50,4.50,4.50,4.50,4.50,4.50,4.50,4.50,4.50,4.50,4.50,5.00"
					( Origin gBackEnd )
				)
				( attribute "BBV_TO_SMDPIN_SPACING" "5.00,5.00,5.00,5.00,5.00,5.00,5.00,5.00,5.00,5.00,5.00,5.00,5.00,5.00"
					( Origin gBackEnd )
				)
				( attribute "SMDPIN_TO_BONDPAD_SPACING" "5.00,5.00,5.00,5.00,5.00,5.00,5.00,5.00,5.00,5.00,5.00,5.00,5.00,5.00"
					( Origin gBackEnd )
				)
				( attribute "LINE_TO_SMDPIN_SPACING" "4.50,4.50,4.50,4.50,4.50,4.50,4.50,4.50,4.50,4.50,4.50,4.50,4.50,4.50"
					( Origin gBackEnd )
				)
				( attribute "SHAPE_TO_SMDPIN_SPACING" "5.00,5.00,5.00,5.00,5.00,5.00,5.00,5.00,5.00,5.00,5.00,5.00,5.00,5.00"
					( Origin gBackEnd )
				)
				( attribute "TESTPIN_TO_TESTPIN_SPACING" "5.00,5.00,5.00,5.00,5.00,5.00,5.00,5.00,5.00,5.00,5.00,5.00,5.00,5.00"
					( Origin gBackEnd )
				)
				( attribute "TESTPIN_TO_THRUVIA_SPACING" "5.00,5.00,5.00,5.00,5.00,5.00,5.00,5.00,5.00,5.00,5.00,5.00,5.00,5.00"
					( Origin gBackEnd )
				)
				( attribute "TESTPIN_TO_TESTVIA_SPACING" "5.00,5.00,5.00,5.00,5.00,5.00,5.00,5.00,5.00,5.00,5.00,5.00,5.00,5.00"
					( Origin gBackEnd )
				)
				( attribute "BBV_TO_TESTPIN_SPACING" "5.00,5.00,5.00,5.00,5.00,5.00,5.00,5.00,5.00,5.00,5.00,5.00,5.00,5.00"
					( Origin gBackEnd )
				)
				( attribute "BONDPAD_TO_TESTPIN_SPACING" "5.00,5.00,5.00,5.00,5.00,5.00,5.00,5.00,5.00,5.00,5.00,5.00,5.00,5.00"
					( Origin gBackEnd )
				)
				( attribute "LINE_TO_TESTPIN_SPACING" "4.50,5.00,5.00,5.00,5.00,5.00,5.00,5.00,5.00,5.00,5.00,5.00,5.00,5.00"
					( Origin gBackEnd )
				)
				( attribute "SHAPE_TO_TESTPIN_SPACING" "4.50,4.00,4.00,4.00,4.00,4.00,4.00,4.00,4.00,4.00,4.00,4.00,4.00,5.00"
					( Origin gBackEnd )
				)
				( attribute "THRUVIA_TO_THRUVIA_SPACING" "5.00,5.00,5.00,5.00,5.00,5.00,5.00,5.00,5.00,5.00,5.00,5.00,5.00,5.00"
					( Origin gBackEnd )
				)
				( attribute "TESTVIA_TO_THRUVIA_SPACING" "5.00,5.00,5.00,5.00,5.00,5.00,5.00,5.00,5.00,5.00,5.00,5.00,5.00,6.00"
					( Origin gBackEnd )
				)
				( attribute "BBV_TO_THRUVIA_SPACING" "5.00,5.00,5.00,5.00,5.00,5.00,5.00,5.00,5.00,5.00,5.00,5.00,5.00,5.00"
					( Origin gBackEnd )
				)
				( attribute "BONDPAD_TO_THRUVIA_SPACING" "5.00,5.00,5.00,5.00,5.00,5.00,5.00,5.00,5.00,5.00,5.00,5.00,5.00,5.00"
					( Origin gBackEnd )
				)
				( attribute "LINE_TO_THRUVIA_SPACING" "4.50,4.00,4.00,4.00,4.00,4.00,4.00,4.00,4.00,4.00,4.00,4.00,4.00,4.50"
					( Origin gBackEnd )
				)
				( attribute "SHAPE_TO_THRUVIA_SPACING" "4.50,4.00,4.00,4.00,4.00,4.00,4.00,4.00,4.00,4.00,4.00,4.00,4.00,5.00"
					( Origin gBackEnd )
				)
				( attribute "TESTVIA_TO_TESTVIA_SPACING" "5.00,5.00,5.00,5.00,5.00,5.00,5.00,5.00,5.00,5.00,5.00,5.00,5.00,6.00"
					( Origin gBackEnd )
				)
				( attribute "BBV_TO_TESTVIA_SPACING" "5.00,5.00,5.00,5.00,5.00,5.00,5.00,5.00,5.00,5.00,5.00,5.00,5.00,5.00"
					( Origin gBackEnd )
				)
				( attribute "BONDPAD_TO_TESTVIA_SPACING" "5.00,5.00,5.00,5.00,5.00,5.00,5.00,5.00,5.00,5.00,5.00,5.00,5.00,5.00"
					( Origin gBackEnd )
				)
				( attribute "LINE_TO_TESTVIA_SPACING" "4.50,5.00,4.00,5.00,4.00,5.00,5.00,5.00,5.00,4.00,5.00,4.00,5.00,4.50"
					( Origin gBackEnd )
				)
				( attribute "SHAPE_TO_TESTVIA_SPACING" "4.50,4.00,4.00,4.00,4.00,4.00,4.00,4.00,4.00,4.00,4.00,4.00,4.00,5.00"
					( Origin gBackEnd )
				)
				( attribute "BBV_TO_BBV_SPACING" "5.00,5.00,5.00,5.00,5.00,5.00,5.00,5.00,5.00,5.00,5.00,5.00,5.00,5.00"
					( Origin gBackEnd )
				)
				( attribute "BONDPAD_TO_BBV_SPACING" "5.00,5.00,5.00,5.00,5.00,5.00,5.00,5.00,5.00,5.00,5.00,5.00,5.00,5.00"
					( Origin gBackEnd )
				)
				( attribute "BBV_TO_LINE_SPACING" "5.00,5.00,5.00,5.00,5.00,5.00,5.00,5.00,5.00,5.00,5.00,5.00,5.00,5.00"
					( Origin gBackEnd )
				)
				( attribute "BBV_TO_SHAPE_SPACING" "5.00,5.00,5.00,5.00,5.00,5.00,5.00,5.00,5.00,5.00,5.00,5.00,5.00,5.00"
					( Origin gBackEnd )
				)
				( attribute "BONDPAD_TO_BONDPAD_SPACING" "5.00,5.00,5.00,5.00,5.00,5.00,5.00,5.00,5.00,5.00,5.00,5.00,5.00,5.00"
					( Origin gBackEnd )
				)
				( attribute "BONDPAD_TO_LINE_SPACING" "5.00,5.00,5.00,5.00,5.00,5.00,5.00,5.00,5.00,5.00,5.00,5.00,5.00,5.00"
					( Origin gBackEnd )
				)
				( attribute "BONDPAD_TO_SHAPE_SPACING" "5.00,5.00,5.00,5.00,5.00,5.00,5.00,5.00,5.00,5.00,5.00,5.00,5.00,5.00"
					( Origin gBackEnd )
				)
				( attribute "LINE_TO_LINE_SPACING" "7.00,4.10,4.10,4.10,4.10,4.10,4.10,4.10,4.10,4.10,4.10,4.10,4.10,4.10"
					( Origin gBackEnd )
				)
				( attribute "LINE_TO_SHAPE_SPACING" "5.00,5.00,5.00,5.00,5.00,5.00,5.00,5.00,5.00,5.00,5.00,5.00,5.00,10.00"
					( Origin gBackEnd )
				)
				( attribute "SHAPE_TO_SHAPE_SPACING" "10.00,10.00,10.00,10.00,10.00,10.00,10.00,10.00,10.00,10.00,10.00,10.00,10.00,10.00"
					( Origin gBackEnd )
				)
				( attribute "HOLE_TO_PIN_SPACING" "8.00,8.00,8.00,8.00,8.00,8.00,8.00,8.00,8.00,8.00,8.00,8.00,8.00,8.00"
					( Origin gBackEnd )
				)
				( attribute "HOLE_TO_VIA_SPACING" "8.00,8.00,8.00,8.00,8.00,8.00,8.00,8.00,8.00,8.00,8.00,8.00,8.00,8.00"
					( Origin gBackEnd )
				)
				( attribute "HOLE_TO_LINE_SPACING" "8.00,8.00,8.00,8.00,8.00,8.00,8.00,8.00,8.00,8.00,8.00,8.00,8.00,8.00"
					( Origin gBackEnd )
				)
				( attribute "HOLE_TO_SHAPE_SPACING" "8.00,8.00,8.00,8.00,8.00,8.00,8.00,8.00,8.00,8.00,8.00,8.00,8.00,8.00"
					( Origin gBackEnd )
				)
				( attribute "HOLE_TO_HOLE_SPACING" "8.00,8.00,8.00,8.00,8.00,8.00,8.00,8.00,8.00,8.00,8.00,8.00,8.00,8.00"
					( Origin gBackEnd )
				)
				( attribute "MVIA_TO_MVIA_SPACING" "5.00,5.00,5.00,5.00,5.00,5.00,5.00,5.00,5.00,5.00,5.00,5.00,5.00,5.00"
					( Origin gBackEnd )
				)
				( attribute "MVIA_TO_THRUPIN_SPACING" "5.00,5.00,5.00,5.00,5.00,5.00,5.00,5.00,5.00,5.00,5.00,5.00,5.00,5.00"
					( Origin gBackEnd )
				)
				( attribute "MVIA_TO_SMDPIN_SPACING" "5.00,5.00,5.00,5.00,5.00,5.00,5.00,5.00,5.00,5.00,5.00,5.00,5.00,5.00"
					( Origin gBackEnd )
				)
				( attribute "MVIA_TO_THRUVIA_SPACING" "5.00,5.00,5.00,5.00,5.00,5.00,5.00,5.00,5.00,5.00,5.00,5.00,5.00,5.00"
					( Origin gBackEnd )
				)
				( attribute "MVIA_TO_BBV_SPACING" "5.00,5.00,5.00,5.00,5.00,5.00,5.00,5.00,5.00,5.00,5.00,5.00,5.00,5.00"
					( Origin gBackEnd )
				)
				( attribute "MVIA_TO_LINE_SPACING" "5.00,5.00,5.00,5.00,5.00,5.00,5.00,5.00,5.00,5.00,5.00,5.00,5.00,5.00"
					( Origin gBackEnd )
				)
				( attribute "MVIA_TO_SHAPE_SPACING" "5.00,5.00,5.00,5.00,5.00,5.00,5.00,5.00,5.00,5.00,5.00,5.00,5.00,5.00"
					( Origin gBackEnd )
				)
				( attribute "MVIA_TO_TESTPIN_SPACING" "5.00,5.00,5.00,5.00,5.00,5.00,5.00,5.00,5.00,5.00,5.00,5.00,5.00,5.00"
					( Origin gBackEnd )
				)
				( attribute "MVIA_TO_TESTVIA_SPACING" "5.00,5.00,5.00,5.00,5.00,5.00,5.00,5.00,5.00,5.00,5.00,5.00,5.00,5.00"
					( Origin gBackEnd )
				)
				( attribute "BONDPAD_TO_MVIA_SPACING" "5.00,5.00,5.00,5.00,5.00,5.00,5.00,5.00,5.00,5.00,5.00,5.00,5.00,5.00"
					( Origin gBackEnd )
				)
				( attribute "MIN_BVIA_GAP" "5.00"
					( Origin gBackEnd )
				)
				( attribute "BONDPAD_TO_BONDPAD_DIFFP_SPC" "5.00,5.00,5.00,5.00,5.00,5.00,5.00,5.00,5.00,5.00,5.00,5.00,5.00,5.00"
					( Origin gBackEnd )
				)
				( objectStatus "KPI" )
			)
			( spacingCSet "@sapphirecity_baseboard_lib.sapphirecity_baseboard(sch_1):\DDR4_STUBBY_EXTERNAL\"
				( attribute "THRUPIN_TO_THRUPIN_SPACING" "5.00,5.00,5.00,5.00,5.00,5.00,5.00,5.00,5.00,5.00,5.00,5.00,5.00,5.00"
					( Origin gBackEnd )
				)
				( attribute "THRUPIN_TO_SMDPIN_SPACING" "5.00,5.00,5.00,5.00,5.00,5.00,5.00,5.00,5.00,5.00,5.00,5.00,5.00,5.00"
					( Origin gBackEnd )
				)
				( attribute "TESTPIN_TO_THRUPIN_SPACING" "5.00,5.00,5.00,5.00,5.00,5.00,5.00,5.00,5.00,5.00,5.00,5.00,5.00,5.00"
					( Origin gBackEnd )
				)
				( attribute "THRUPIN_TO_THRUVIA_SPACING" "6.00,6.00,6.00,6.00,6.00,6.00,6.00,6.00,6.00,6.00,6.00,6.00,6.00,6.00"
					( Origin gBackEnd )
				)
				( attribute "TESTVIA_TO_THRUPIN_SPACING" "5.00,5.00,5.00,5.00,5.00,5.00,5.00,5.00,5.00,5.00,5.00,5.00,5.00,5.00"
					( Origin gBackEnd )
				)
				( attribute "BBV_TO_THRUPIN_SPACING" "5.00,5.00,5.00,5.00,5.00,5.00,5.00,5.00,5.00,5.00,5.00,5.00,5.00,5.00"
					( Origin gBackEnd )
				)
				( attribute "THRUPIN_TO_BONDPAD_SPACING" "5.00,5.00,5.00,5.00,5.00,5.00,5.00,5.00,5.00,5.00,5.00,5.00,5.00,5.00"
					( Origin gBackEnd )
				)
				( attribute "LINE_TO_THRUPIN_SPACING" "5.00,5.00,5.00,5.00,5.00,5.00,5.00,5.00,5.00,5.00,5.00,5.00,5.00,5.00"
					( Origin gBackEnd )
				)
				( attribute "THRUPIN_TO_SHAPE_SPACING" "5.00,5.00,5.00,5.00,5.00,5.00,5.00,5.00,5.00,5.00,5.00,5.00,5.00,5.00"
					( Origin gBackEnd )
				)
				( attribute "SMDPIN_TO_SMDPIN_SPACING" "5.00,5.00,5.00,5.00,5.00,5.00,5.00,5.00,5.00,5.00,5.00,5.00,5.00,5.00"
					( Origin gBackEnd )
				)
				( attribute "SMDPIN_TO_TESTPIN_SPACING" "5.00,5.00,5.00,5.00,5.00,5.00,5.00,5.00,5.00,5.00,5.00,5.00,5.00,5.00"
					( Origin gBackEnd )
				)
				( attribute "SMDPIN_TO_THRUVIA_SPACING" "5.00,5.00,5.00,5.00,5.00,5.00,5.00,5.00,5.00,5.00,5.00,5.00,5.00,5.00"
					( Origin gBackEnd )
				)
				( attribute "SMDPIN_TO_TESTVIA_SPACING" "5.00,5.00,5.00,5.00,5.00,5.00,5.00,5.00,5.00,5.00,5.00,5.00,5.00,5.00"
					( Origin gBackEnd )
				)
				( attribute "BBV_TO_SMDPIN_SPACING" "5.00,5.00,5.00,5.00,5.00,5.00,5.00,5.00,5.00,5.00,5.00,5.00,5.00,5.00"
					( Origin gBackEnd )
				)
				( attribute "SMDPIN_TO_BONDPAD_SPACING" "5.00,5.00,5.00,5.00,5.00,5.00,5.00,5.00,5.00,5.00,5.00,5.00,5.00,5.00"
					( Origin gBackEnd )
				)
				( attribute "LINE_TO_SMDPIN_SPACING" "4.50,4.50,4.50,4.50,4.50,4.50,4.50,4.50,4.50,4.50,4.50,4.50,4.50,4.50"
					( Origin gBackEnd )
				)
				( attribute "SHAPE_TO_SMDPIN_SPACING" "4.50,4.00,4.00,4.00,4.00,4.00,4.00,4.00,4.00,4.00,4.00,4.00,4.00,4.50"
					( Origin gBackEnd )
				)
				( attribute "TESTPIN_TO_TESTPIN_SPACING" "5.00,5.00,5.00,5.00,5.00,5.00,5.00,5.00,5.00,5.00,5.00,5.00,5.00,5.00"
					( Origin gBackEnd )
				)
				( attribute "TESTPIN_TO_THRUVIA_SPACING" "6.00,6.00,6.00,6.00,6.00,6.00,6.00,6.00,6.00,6.00,6.00,6.00,6.00,6.00"
					( Origin gBackEnd )
				)
				( attribute "TESTPIN_TO_TESTVIA_SPACING" "5.00,5.00,5.00,5.00,5.00,5.00,5.00,5.00,5.00,5.00,5.00,5.00,5.00,5.00"
					( Origin gBackEnd )
				)
				( attribute "BBV_TO_TESTPIN_SPACING" "5.00,5.00,5.00,5.00,5.00,5.00,5.00,5.00,5.00,5.00,5.00,5.00,5.00,5.00"
					( Origin gBackEnd )
				)
				( attribute "BONDPAD_TO_TESTPIN_SPACING" "5.00,5.00,5.00,5.00,5.00,5.00,5.00,5.00,5.00,5.00,5.00,5.00,5.00,5.00"
					( Origin gBackEnd )
				)
				( attribute "LINE_TO_TESTPIN_SPACING" "5.00,4.00,4.00,4.00,4.00,4.00,4.00,4.00,4.00,4.00,4.00,4.00,4.00,5.00"
					( Origin gBackEnd )
				)
				( attribute "SHAPE_TO_TESTPIN_SPACING" "5.00,5.00,5.00,5.00,5.00,5.00,5.00,5.00,5.00,5.00,5.00,5.00,5.00,5.00"
					( Origin gBackEnd )
				)
				( attribute "THRUVIA_TO_THRUVIA_SPACING" "6.00,6.00,6.00,6.00,6.00,6.00,6.00,6.00,6.00,6.00,6.00,6.00,6.00,6.00"
					( Origin gBackEnd )
				)
				( attribute "TESTVIA_TO_THRUVIA_SPACING" "6.00,6.00,6.00,6.00,6.00,6.00,6.00,6.00,6.00,6.00,6.00,6.00,6.00,6.00"
					( Origin gBackEnd )
				)
				( attribute "BBV_TO_THRUVIA_SPACING" "5.00,5.00,5.00,5.00,5.00,5.00,5.00,5.00,5.00,5.00,5.00,5.00,5.00,5.00"
					( Origin gBackEnd )
				)
				( attribute "BONDPAD_TO_THRUVIA_SPACING" "5.00,5.00,5.00,5.00,5.00,5.00,5.00,5.00,5.00,5.00,5.00,5.00,5.00,5.00"
					( Origin gBackEnd )
				)
				( attribute "LINE_TO_THRUVIA_SPACING" "4.50,4.00,4.00,4.00,4.00,4.00,4.00,4.00,4.00,4.00,4.00,4.00,4.00,4.50"
					( Origin gBackEnd )
				)
				( attribute "SHAPE_TO_THRUVIA_SPACING" "4.50,4.00,4.00,4.00,4.00,4.00,4.00,4.00,4.00,4.00,4.00,4.00,4.00,4.50"
					( Origin gBackEnd )
				)
				( attribute "TESTVIA_TO_TESTVIA_SPACING" "6.00,6.00,6.00,6.00,6.00,6.00,6.00,6.00,6.00,6.00,6.00,6.00,6.00,6.00"
					( Origin gBackEnd )
				)
				( attribute "BBV_TO_TESTVIA_SPACING" "5.00,5.00,5.00,5.00,5.00,5.00,5.00,5.00,5.00,5.00,5.00,5.00,5.00,5.00"
					( Origin gBackEnd )
				)
				( attribute "BONDPAD_TO_TESTVIA_SPACING" "5.00,5.00,5.00,5.00,5.00,5.00,5.00,5.00,5.00,5.00,5.00,5.00,5.00,5.00"
					( Origin gBackEnd )
				)
				( attribute "LINE_TO_TESTVIA_SPACING" "4.50,4.00,4.00,4.00,4.00,4.00,4.00,4.00,4.00,4.00,4.00,4.00,4.00,4.50"
					( Origin gBackEnd )
				)
				( attribute "SHAPE_TO_TESTVIA_SPACING" "5.00,5.00,5.00,5.00,5.00,5.00,5.00,5.00,5.00,5.00,5.00,5.00,5.00,5.00"
					( Origin gBackEnd )
				)
				( attribute "BBV_TO_BBV_SPACING" "5.00,5.00,5.00,5.00,5.00,5.00,5.00,5.00,5.00,5.00,5.00,5.00,5.00,5.00"
					( Origin gBackEnd )
				)
				( attribute "BONDPAD_TO_BBV_SPACING" "5.00,5.00,5.00,5.00,5.00,5.00,5.00,5.00,5.00,5.00,5.00,5.00,5.00,5.00"
					( Origin gBackEnd )
				)
				( attribute "BBV_TO_LINE_SPACING" "5.00,5.00,5.00,5.00,5.00,5.00,5.00,5.00,5.00,5.00,5.00,5.00,5.00,5.00"
					( Origin gBackEnd )
				)
				( attribute "BBV_TO_SHAPE_SPACING" "5.00,5.00,5.00,5.00,5.00,5.00,5.00,5.00,5.00,5.00,5.00,5.00,5.00,5.00"
					( Origin gBackEnd )
				)
				( attribute "BONDPAD_TO_BONDPAD_SPACING" "5.00,5.00,5.00,5.00,5.00,5.00,5.00,5.00,5.00,5.00,5.00,5.00,5.00,5.00"
					( Origin gBackEnd )
				)
				( attribute "BONDPAD_TO_LINE_SPACING" "5.00,5.00,5.00,5.00,5.00,5.00,5.00,5.00,5.00,5.00,5.00,5.00,5.00,5.00"
					( Origin gBackEnd )
				)
				( attribute "BONDPAD_TO_SHAPE_SPACING" "5.00,5.00,5.00,5.00,5.00,5.00,5.00,5.00,5.00,5.00,5.00,5.00,5.00,5.00"
					( Origin gBackEnd )
				)
				( attribute "LINE_TO_LINE_SPACING" "11.49,11.50,11.50,11.50,11.50,11.50,11.50,11.50,11.50,11.50,11.50,11.50,11.50,11.50"
					( Origin gBackEnd )
				)
				( attribute "LINE_TO_SHAPE_SPACING" "3.98,5.00,3.99,5.00,3.99,5.00,10.00,10.00,5.00,3.99,5.00,3.99,10.00,3.98"
					( Origin gBackEnd )
				)
				( attribute "SHAPE_TO_SHAPE_SPACING" "4.00,4.00,4.00,4.00,4.00,4.00,5.00,5.00,4.00,4.00,4.00,4.00,4.00,4.00"
					( Origin gBackEnd )
				)
				( attribute "HOLE_TO_PIN_SPACING" "8.00,8.00,8.00,8.00,8.00,8.00,8.00,8.00,8.00,8.00,8.00,8.00,8.00,8.00"
					( Origin gBackEnd )
				)
				( attribute "HOLE_TO_VIA_SPACING" "8.00,8.00,8.00,8.00,8.00,8.00,8.00,8.00,8.00,8.00,8.00,8.00,8.00,8.00"
					( Origin gBackEnd )
				)
				( attribute "HOLE_TO_LINE_SPACING" "8.00,8.00,8.00,8.00,8.00,8.00,8.00,8.00,8.00,8.00,8.00,8.00,8.00,8.00"
					( Origin gBackEnd )
				)
				( attribute "HOLE_TO_SHAPE_SPACING" "8.00,8.00,8.00,8.00,8.00,8.00,8.00,8.00,8.00,8.00,8.00,8.00,8.00,8.00"
					( Origin gBackEnd )
				)
				( attribute "HOLE_TO_HOLE_SPACING" "8.00,8.00,8.00,8.00,8.00,8.00,8.00,8.00,8.00,8.00,8.00,8.00,8.00,8.00"
					( Origin gBackEnd )
				)
				( attribute "MVIA_TO_MVIA_SPACING" "5.00,5.00,5.00,5.00,5.00,5.00,5.00,5.00,5.00,5.00,5.00,5.00,5.00,5.00"
					( Origin gBackEnd )
				)
				( attribute "MVIA_TO_THRUPIN_SPACING" "5.00,5.00,5.00,5.00,5.00,5.00,5.00,5.00,5.00,5.00,5.00,5.00,5.00,5.00"
					( Origin gBackEnd )
				)
				( attribute "MVIA_TO_SMDPIN_SPACING" "5.00,5.00,5.00,5.00,5.00,5.00,5.00,5.00,5.00,5.00,5.00,5.00,5.00,5.00"
					( Origin gBackEnd )
				)
				( attribute "MVIA_TO_THRUVIA_SPACING" "5.00,5.00,5.00,5.00,5.00,5.00,5.00,5.00,5.00,5.00,5.00,5.00,5.00,5.00"
					( Origin gBackEnd )
				)
				( attribute "MVIA_TO_BBV_SPACING" "5.00,5.00,5.00,5.00,5.00,5.00,5.00,5.00,5.00,5.00,5.00,5.00,5.00,5.00"
					( Origin gBackEnd )
				)
				( attribute "MVIA_TO_LINE_SPACING" "5.00,5.00,5.00,5.00,5.00,5.00,5.00,5.00,5.00,5.00,5.00,5.00,5.00,5.00"
					( Origin gBackEnd )
				)
				( attribute "MVIA_TO_SHAPE_SPACING" "5.00,5.00,5.00,5.00,5.00,5.00,5.00,5.00,5.00,5.00,5.00,5.00,5.00,5.00"
					( Origin gBackEnd )
				)
				( attribute "MVIA_TO_TESTPIN_SPACING" "5.00,5.00,5.00,5.00,5.00,5.00,5.00,5.00,5.00,5.00,5.00,5.00,5.00,5.00"
					( Origin gBackEnd )
				)
				( attribute "MVIA_TO_TESTVIA_SPACING" "5.00,5.00,5.00,5.00,5.00,5.00,5.00,5.00,5.00,5.00,5.00,5.00,5.00,5.00"
					( Origin gBackEnd )
				)
				( attribute "BONDPAD_TO_MVIA_SPACING" "5.00,5.00,5.00,5.00,5.00,5.00,5.00,5.00,5.00,5.00,5.00,5.00,5.00,5.00"
					( Origin gBackEnd )
				)
				( attribute "MIN_BVIA_GAP" "5.00"
					( Origin gBackEnd )
				)
				( attribute "BONDPAD_TO_BONDPAD_DIFFP_SPC" "5.00,5.00,5.00,5.00,5.00,5.00,5.00,5.00,5.00,5.00,5.00,5.00,5.00,5.00"
					( Origin gBackEnd )
				)
				( objectStatus "PCS_TABBED_OPENFIELD" )
			)
			( spacingCSet "@sapphirecity_baseboard_lib.sapphirecity_baseboard(sch_1):\DDR4_STUBBY_TIGHT_EXT\"
				( attribute "THRUPIN_TO_THRUPIN_SPACING" "5.00,5.00,5.00,5.00,5.00,5.00,5.00,5.00,5.00,5.00,5.00,5.00,5.00,5.00"
					( Origin gBackEnd )
				)
				( attribute "THRUPIN_TO_SMDPIN_SPACING" "5.00,5.00,5.00,5.00,5.00,5.00,5.00,5.00,5.00,5.00,5.00,5.00,5.00,5.00"
					( Origin gBackEnd )
				)
				( attribute "TESTPIN_TO_THRUPIN_SPACING" "5.00,5.00,5.00,5.00,5.00,5.00,5.00,5.00,5.00,5.00,5.00,5.00,5.00,5.00"
					( Origin gBackEnd )
				)
				( attribute "THRUPIN_TO_THRUVIA_SPACING" "6.00,6.00,6.00,6.00,6.00,6.00,6.00,6.00,6.00,6.00,6.00,6.00,6.00,6.00"
					( Origin gBackEnd )
				)
				( attribute "TESTVIA_TO_THRUPIN_SPACING" "5.00,5.00,5.00,5.00,5.00,5.00,5.00,5.00,5.00,5.00,5.00,5.00,5.00,5.00"
					( Origin gBackEnd )
				)
				( attribute "BBV_TO_THRUPIN_SPACING" "5.00,5.00,5.00,5.00,5.00,5.00,5.00,5.00,5.00,5.00,5.00,5.00,5.00,5.00"
					( Origin gBackEnd )
				)
				( attribute "THRUPIN_TO_BONDPAD_SPACING" "5.00,5.00,5.00,5.00,5.00,5.00,5.00,5.00,5.00,5.00,5.00,5.00,5.00,5.00"
					( Origin gBackEnd )
				)
				( attribute "LINE_TO_THRUPIN_SPACING" "5.00,5.00,5.00,5.00,5.00,5.00,5.00,5.00,5.00,5.00,5.00,5.00,5.00,5.00"
					( Origin gBackEnd )
				)
				( attribute "THRUPIN_TO_SHAPE_SPACING" "5.00,5.00,5.00,5.00,5.00,5.00,5.00,5.00,5.00,5.00,5.00,5.00,5.00,5.00"
					( Origin gBackEnd )
				)
				( attribute "SMDPIN_TO_SMDPIN_SPACING" "5.00,5.00,5.00,5.00,5.00,5.00,5.00,5.00,5.00,5.00,5.00,5.00,5.00,5.00"
					( Origin gBackEnd )
				)
				( attribute "SMDPIN_TO_TESTPIN_SPACING" "5.00,5.00,5.00,5.00,5.00,5.00,5.00,5.00,5.00,5.00,5.00,5.00,5.00,5.00"
					( Origin gBackEnd )
				)
				( attribute "SMDPIN_TO_THRUVIA_SPACING" "5.00,5.00,5.00,5.00,5.00,5.00,5.00,5.00,5.00,5.00,5.00,5.00,5.00,5.00"
					( Origin gBackEnd )
				)
				( attribute "SMDPIN_TO_TESTVIA_SPACING" "5.00,5.00,5.00,5.00,5.00,5.00,5.00,5.00,5.00,5.00,5.00,5.00,5.00,5.00"
					( Origin gBackEnd )
				)
				( attribute "BBV_TO_SMDPIN_SPACING" "5.00,5.00,5.00,5.00,5.00,5.00,5.00,5.00,5.00,5.00,5.00,5.00,5.00,5.00"
					( Origin gBackEnd )
				)
				( attribute "SMDPIN_TO_BONDPAD_SPACING" "5.00,5.00,5.00,5.00,5.00,5.00,5.00,5.00,5.00,5.00,5.00,5.00,5.00,5.00"
					( Origin gBackEnd )
				)
				( attribute "LINE_TO_SMDPIN_SPACING" "4.50,4.50,4.50,4.50,4.50,4.50,4.50,4.50,4.50,4.50,4.50,4.50,4.50,4.50"
					( Origin gBackEnd )
				)
				( attribute "SHAPE_TO_SMDPIN_SPACING" "4.50,4.00,4.00,4.00,4.00,4.00,4.00,4.00,4.00,4.00,4.00,4.00,4.00,4.50"
					( Origin gBackEnd )
				)
				( attribute "TESTPIN_TO_TESTPIN_SPACING" "5.00,5.00,5.00,5.00,5.00,5.00,5.00,5.00,5.00,5.00,5.00,5.00,5.00,5.00"
					( Origin gBackEnd )
				)
				( attribute "TESTPIN_TO_THRUVIA_SPACING" "6.00,6.00,6.00,6.00,6.00,6.00,6.00,6.00,6.00,6.00,6.00,6.00,6.00,6.00"
					( Origin gBackEnd )
				)
				( attribute "TESTPIN_TO_TESTVIA_SPACING" "5.00,5.00,5.00,5.00,5.00,5.00,5.00,5.00,5.00,5.00,5.00,5.00,5.00,5.00"
					( Origin gBackEnd )
				)
				( attribute "BBV_TO_TESTPIN_SPACING" "5.00,5.00,5.00,5.00,5.00,5.00,5.00,5.00,5.00,5.00,5.00,5.00,5.00,5.00"
					( Origin gBackEnd )
				)
				( attribute "BONDPAD_TO_TESTPIN_SPACING" "5.00,5.00,5.00,5.00,5.00,5.00,5.00,5.00,5.00,5.00,5.00,5.00,5.00,5.00"
					( Origin gBackEnd )
				)
				( attribute "LINE_TO_TESTPIN_SPACING" "5.00,4.00,4.00,4.00,4.00,4.00,4.00,4.00,4.00,4.00,4.00,4.00,4.00,5.00"
					( Origin gBackEnd )
				)
				( attribute "SHAPE_TO_TESTPIN_SPACING" "5.00,5.00,5.00,5.00,5.00,5.00,5.00,5.00,5.00,5.00,5.00,5.00,5.00,5.00"
					( Origin gBackEnd )
				)
				( attribute "THRUVIA_TO_THRUVIA_SPACING" "6.00,6.00,6.00,6.00,6.00,6.00,6.00,6.00,6.00,6.00,6.00,6.00,6.00,6.00"
					( Origin gBackEnd )
				)
				( attribute "TESTVIA_TO_THRUVIA_SPACING" "6.00,6.00,6.00,6.00,6.00,6.00,6.00,6.00,6.00,6.00,6.00,6.00,6.00,6.00"
					( Origin gBackEnd )
				)
				( attribute "BBV_TO_THRUVIA_SPACING" "5.00,5.00,5.00,5.00,5.00,5.00,5.00,5.00,5.00,5.00,5.00,5.00,5.00,5.00"
					( Origin gBackEnd )
				)
				( attribute "BONDPAD_TO_THRUVIA_SPACING" "5.00,5.00,5.00,5.00,5.00,5.00,5.00,5.00,5.00,5.00,5.00,5.00,5.00,5.00"
					( Origin gBackEnd )
				)
				( attribute "LINE_TO_THRUVIA_SPACING" "4.50,4.00,4.00,4.00,4.00,4.00,4.00,4.00,4.00,4.00,4.00,4.00,4.00,4.50"
					( Origin gBackEnd )
				)
				( attribute "SHAPE_TO_THRUVIA_SPACING" "4.50,4.00,4.00,4.00,4.00,4.00,4.00,4.00,4.00,4.00,4.00,4.00,4.00,4.50"
					( Origin gBackEnd )
				)
				( attribute "TESTVIA_TO_TESTVIA_SPACING" "6.00,6.00,6.00,6.00,6.00,6.00,6.00,6.00,6.00,6.00,6.00,6.00,6.00,6.00"
					( Origin gBackEnd )
				)
				( attribute "BBV_TO_TESTVIA_SPACING" "5.00,5.00,5.00,5.00,5.00,5.00,5.00,5.00,5.00,5.00,5.00,5.00,5.00,5.00"
					( Origin gBackEnd )
				)
				( attribute "BONDPAD_TO_TESTVIA_SPACING" "5.00,5.00,5.00,5.00,5.00,5.00,5.00,5.00,5.00,5.00,5.00,5.00,5.00,5.00"
					( Origin gBackEnd )
				)
				( attribute "LINE_TO_TESTVIA_SPACING" "4.50,4.00,4.00,4.00,4.00,4.00,4.00,4.00,4.00,4.00,4.00,4.00,4.00,4.50"
					( Origin gBackEnd )
				)
				( attribute "SHAPE_TO_TESTVIA_SPACING" "5.00,5.00,5.00,5.00,5.00,5.00,5.00,5.00,5.00,5.00,5.00,5.00,5.00,5.00"
					( Origin gBackEnd )
				)
				( attribute "BBV_TO_BBV_SPACING" "5.00,5.00,5.00,5.00,5.00,5.00,5.00,5.00,5.00,5.00,5.00,5.00,5.00,5.00"
					( Origin gBackEnd )
				)
				( attribute "BONDPAD_TO_BBV_SPACING" "5.00,5.00,5.00,5.00,5.00,5.00,5.00,5.00,5.00,5.00,5.00,5.00,5.00,5.00"
					( Origin gBackEnd )
				)
				( attribute "BBV_TO_LINE_SPACING" "5.00,5.00,5.00,5.00,5.00,5.00,5.00,5.00,5.00,5.00,5.00,5.00,5.00,5.00"
					( Origin gBackEnd )
				)
				( attribute "BBV_TO_SHAPE_SPACING" "5.00,5.00,5.00,5.00,5.00,5.00,5.00,5.00,5.00,5.00,5.00,5.00,5.00,5.00"
					( Origin gBackEnd )
				)
				( attribute "BONDPAD_TO_BONDPAD_SPACING" "5.00,5.00,5.00,5.00,5.00,5.00,5.00,5.00,5.00,5.00,5.00,5.00,5.00,5.00"
					( Origin gBackEnd )
				)
				( attribute "BONDPAD_TO_LINE_SPACING" "5.00,5.00,5.00,5.00,5.00,5.00,5.00,5.00,5.00,5.00,5.00,5.00,5.00,5.00"
					( Origin gBackEnd )
				)
				( attribute "BONDPAD_TO_SHAPE_SPACING" "5.00,5.00,5.00,5.00,5.00,5.00,5.00,5.00,5.00,5.00,5.00,5.00,5.00,5.00"
					( Origin gBackEnd )
				)
				( attribute "LINE_TO_LINE_SPACING" "8.00,8.00,8.00,8.00,8.00,8.00,8.00,8.00,8.00,8.00,8.00,8.00,8.00,8.00"
					( Origin gBackEnd )
				)
				( attribute "LINE_TO_SHAPE_SPACING" "3.98,5.00,3.99,5.00,3.99,5.00,10.00,10.00,5.00,3.99,5.00,3.99,10.00,3.98"
					( Origin gBackEnd )
				)
				( attribute "SHAPE_TO_SHAPE_SPACING" "4.00,4.00,4.00,4.00,4.00,4.00,5.00,5.00,4.00,4.00,4.00,4.00,4.00,4.00"
					( Origin gBackEnd )
				)
				( attribute "HOLE_TO_PIN_SPACING" "8.00,8.00,8.00,8.00,8.00,8.00,8.00,8.00,8.00,8.00,8.00,8.00,8.00,8.00"
					( Origin gBackEnd )
				)
				( attribute "HOLE_TO_VIA_SPACING" "8.00,8.00,8.00,8.00,8.00,8.00,8.00,8.00,8.00,8.00,8.00,8.00,8.00,8.00"
					( Origin gBackEnd )
				)
				( attribute "HOLE_TO_LINE_SPACING" "8.00,8.00,8.00,8.00,8.00,8.00,8.00,8.00,8.00,8.00,8.00,8.00,8.00,8.00"
					( Origin gBackEnd )
				)
				( attribute "HOLE_TO_SHAPE_SPACING" "8.00,8.00,8.00,8.00,8.00,8.00,8.00,8.00,8.00,8.00,8.00,8.00,8.00,8.00"
					( Origin gBackEnd )
				)
				( attribute "HOLE_TO_HOLE_SPACING" "8.00,8.00,8.00,8.00,8.00,8.00,8.00,8.00,8.00,8.00,8.00,8.00,8.00,8.00"
					( Origin gBackEnd )
				)
				( attribute "MVIA_TO_MVIA_SPACING" "5.00,5.00,5.00,5.00,5.00,5.00,5.00,5.00,5.00,5.00,5.00,5.00,5.00,5.00"
					( Origin gBackEnd )
				)
				( attribute "MVIA_TO_THRUPIN_SPACING" "5.00,5.00,5.00,5.00,5.00,5.00,5.00,5.00,5.00,5.00,5.00,5.00,5.00,5.00"
					( Origin gBackEnd )
				)
				( attribute "MVIA_TO_SMDPIN_SPACING" "5.00,5.00,5.00,5.00,5.00,5.00,5.00,5.00,5.00,5.00,5.00,5.00,5.00,5.00"
					( Origin gBackEnd )
				)
				( attribute "MVIA_TO_THRUVIA_SPACING" "5.00,5.00,5.00,5.00,5.00,5.00,5.00,5.00,5.00,5.00,5.00,5.00,5.00,5.00"
					( Origin gBackEnd )
				)
				( attribute "MVIA_TO_BBV_SPACING" "5.00,5.00,5.00,5.00,5.00,5.00,5.00,5.00,5.00,5.00,5.00,5.00,5.00,5.00"
					( Origin gBackEnd )
				)
				( attribute "MVIA_TO_LINE_SPACING" "5.00,5.00,5.00,5.00,5.00,5.00,5.00,5.00,5.00,5.00,5.00,5.00,5.00,5.00"
					( Origin gBackEnd )
				)
				( attribute "MVIA_TO_SHAPE_SPACING" "5.00,5.00,5.00,5.00,5.00,5.00,5.00,5.00,5.00,5.00,5.00,5.00,5.00,5.00"
					( Origin gBackEnd )
				)
				( attribute "MVIA_TO_TESTPIN_SPACING" "5.00,5.00,5.00,5.00,5.00,5.00,5.00,5.00,5.00,5.00,5.00,5.00,5.00,5.00"
					( Origin gBackEnd )
				)
				( attribute "MVIA_TO_TESTVIA_SPACING" "5.00,5.00,5.00,5.00,5.00,5.00,5.00,5.00,5.00,5.00,5.00,5.00,5.00,5.00"
					( Origin gBackEnd )
				)
				( attribute "BONDPAD_TO_MVIA_SPACING" "5.00,5.00,5.00,5.00,5.00,5.00,5.00,5.00,5.00,5.00,5.00,5.00,5.00,5.00"
					( Origin gBackEnd )
				)
				( attribute "MIN_BVIA_GAP" "5.00"
					( Origin gBackEnd )
				)
				( attribute "BONDPAD_TO_BONDPAD_DIFFP_SPC" "5.00,5.00,5.00,5.00,5.00,5.00,5.00,5.00,5.00,5.00,5.00,5.00,5.00,5.00"
					( Origin gBackEnd )
				)
				( objectStatus "PCS_TABBED_BREAKOUT" )
			)
			( spacingCSet "@sapphirecity_baseboard_lib.sapphirecity_baseboard(sch_1):\TH_PIN_SMT_PIN\"
				( attribute "THRUPIN_TO_THRUPIN_SPACING" "5.00,5.00,5.00,5.00,5.00,5.00,5.00,5.00,5.00,5.00,5.00,5.00,5.00,5.00"
					( Origin gBackEnd )
				)
				( attribute "THRUPIN_TO_SMDPIN_SPACING" "5.00,5.00,5.00,5.00,5.00,5.00,5.00,5.00,5.00,5.00,5.00,5.00,5.00,5.00"
					( Origin gBackEnd )
				)
				( attribute "TESTPIN_TO_THRUPIN_SPACING" "5.00,5.00,5.00,5.00,5.00,5.00,5.00,5.00,5.00,5.00,5.00,5.00,5.00,5.00"
					( Origin gBackEnd )
				)
				( attribute "THRUPIN_TO_THRUVIA_SPACING" "6.00,6.00,6.00,6.00,6.00,6.00,6.00,6.00,6.00,6.00,6.00,6.00,6.00,6.00"
					( Origin gBackEnd )
				)
				( attribute "TESTVIA_TO_THRUPIN_SPACING" "5.00,5.00,5.00,5.00,5.00,5.00,5.00,5.00,5.00,5.00,5.00,5.00,5.00,5.00"
					( Origin gBackEnd )
				)
				( attribute "BBV_TO_THRUPIN_SPACING" "5.00,5.00,5.00,5.00,5.00,5.00,5.00,5.00,5.00,5.00,5.00,5.00,5.00,5.00"
					( Origin gBackEnd )
				)
				( attribute "THRUPIN_TO_BONDPAD_SPACING" "5.00,5.00,5.00,5.00,5.00,5.00,5.00,5.00,5.00,5.00,5.00,5.00,5.00,5.00"
					( Origin gBackEnd )
				)
				( attribute "LINE_TO_THRUPIN_SPACING" "5.00,5.00,5.00,5.00,5.00,5.00,5.00,5.00,5.00,5.00,5.00,5.00,5.00,5.00"
					( Origin gBackEnd )
				)
				( attribute "THRUPIN_TO_SHAPE_SPACING" "5.00,5.00,5.00,5.00,5.00,5.00,5.00,5.00,5.00,5.00,5.00,5.00,5.00,5.00"
					( Origin gBackEnd )
				)
				( attribute "SMDPIN_TO_SMDPIN_SPACING" "5.00,5.00,5.00,5.00,5.00,5.00,5.00,5.00,5.00,5.00,5.00,5.00,5.00,5.00"
					( Origin gBackEnd )
				)
				( attribute "SMDPIN_TO_TESTPIN_SPACING" "5.00,5.00,5.00,5.00,5.00,5.00,5.00,5.00,5.00,5.00,5.00,5.00,5.00,5.00"
					( Origin gBackEnd )
				)
				( attribute "SMDPIN_TO_THRUVIA_SPACING" "5.00,5.00,5.00,5.00,5.00,5.00,5.00,5.00,5.00,5.00,5.00,5.00,5.00,5.00"
					( Origin gBackEnd )
				)
				( attribute "SMDPIN_TO_TESTVIA_SPACING" "5.00,5.00,5.00,5.00,5.00,5.00,5.00,5.00,5.00,5.00,5.00,5.00,5.00,5.00"
					( Origin gBackEnd )
				)
				( attribute "BBV_TO_SMDPIN_SPACING" "5.00,5.00,5.00,5.00,5.00,5.00,5.00,5.00,5.00,5.00,5.00,5.00,5.00,5.00"
					( Origin gBackEnd )
				)
				( attribute "SMDPIN_TO_BONDPAD_SPACING" "5.00,5.00,5.00,5.00,5.00,5.00,5.00,5.00,5.00,5.00,5.00,5.00,5.00,5.00"
					( Origin gBackEnd )
				)
				( attribute "LINE_TO_SMDPIN_SPACING" "4.50,4.50,4.50,4.50,4.50,4.50,4.50,4.50,4.50,4.50,4.50,4.50,4.50,4.50"
					( Origin gBackEnd )
				)
				( attribute "SHAPE_TO_SMDPIN_SPACING" "5.00,5.00,5.00,5.00,5.00,5.00,5.00,5.00,5.00,5.00,5.00,5.00,5.00,5.00"
					( Origin gBackEnd )
				)
				( attribute "TESTPIN_TO_TESTPIN_SPACING" "5.00,5.00,5.00,5.00,5.00,5.00,5.00,5.00,5.00,5.00,5.00,5.00,5.00,5.00"
					( Origin gBackEnd )
				)
				( attribute "TESTPIN_TO_THRUVIA_SPACING" "6.00,6.00,6.00,6.00,6.00,6.00,6.00,6.00,6.00,6.00,6.00,6.00,6.00,6.00"
					( Origin gBackEnd )
				)
				( attribute "TESTPIN_TO_TESTVIA_SPACING" "5.00,5.00,5.00,5.00,5.00,5.00,5.00,5.00,5.00,5.00,5.00,5.00,5.00,5.00"
					( Origin gBackEnd )
				)
				( attribute "BBV_TO_TESTPIN_SPACING" "5.00,5.00,5.00,5.00,5.00,5.00,5.00,5.00,5.00,5.00,5.00,5.00,5.00,5.00"
					( Origin gBackEnd )
				)
				( attribute "BONDPAD_TO_TESTPIN_SPACING" "5.00,5.00,5.00,5.00,5.00,5.00,5.00,5.00,5.00,5.00,5.00,5.00,5.00,5.00"
					( Origin gBackEnd )
				)
				( attribute "LINE_TO_TESTPIN_SPACING" "5.00,4.00,4.00,4.00,4.00,4.00,4.00,4.00,4.00,4.00,4.00,4.00,4.00,5.00"
					( Origin gBackEnd )
				)
				( attribute "SHAPE_TO_TESTPIN_SPACING" "5.00,5.00,5.00,5.00,5.00,5.00,5.00,5.00,5.00,5.00,5.00,5.00,5.00,5.00"
					( Origin gBackEnd )
				)
				( attribute "THRUVIA_TO_THRUVIA_SPACING" "5.00,5.00,5.00,5.00,5.00,5.00,5.00,5.00,5.00,5.00,5.00,5.00,5.00,5.00"
					( Origin gBackEnd )
				)
				( attribute "TESTVIA_TO_THRUVIA_SPACING" "6.00,6.00,6.00,6.00,6.00,6.00,6.00,6.00,6.00,6.00,6.00,6.00,6.00,6.00"
					( Origin gBackEnd )
				)
				( attribute "BBV_TO_THRUVIA_SPACING" "5.00,5.00,5.00,5.00,5.00,5.00,5.00,5.00,5.00,5.00,5.00,5.00,5.00,5.00"
					( Origin gBackEnd )
				)
				( attribute "BONDPAD_TO_THRUVIA_SPACING" "5.00,5.00,5.00,5.00,5.00,5.00,5.00,5.00,5.00,5.00,5.00,5.00,5.00,5.00"
					( Origin gBackEnd )
				)
				( attribute "LINE_TO_THRUVIA_SPACING" "4.50,4.00,4.00,4.00,4.00,4.00,4.00,4.00,4.00,4.00,4.00,4.00,4.00,4.50"
					( Origin gBackEnd )
				)
				( attribute "SHAPE_TO_THRUVIA_SPACING" "5.00,5.00,5.00,5.00,5.00,5.00,5.00,5.00,5.00,5.00,5.00,5.00,5.00,5.00"
					( Origin gBackEnd )
				)
				( attribute "TESTVIA_TO_TESTVIA_SPACING" "6.00,6.00,6.00,6.00,6.00,6.00,6.00,6.00,6.00,6.00,6.00,6.00,6.00,6.00"
					( Origin gBackEnd )
				)
				( attribute "BBV_TO_TESTVIA_SPACING" "5.00,5.00,5.00,5.00,5.00,5.00,5.00,5.00,5.00,5.00,5.00,5.00,5.00,5.00"
					( Origin gBackEnd )
				)
				( attribute "BONDPAD_TO_TESTVIA_SPACING" "5.00,5.00,5.00,5.00,5.00,5.00,5.00,5.00,5.00,5.00,5.00,5.00,5.00,5.00"
					( Origin gBackEnd )
				)
				( attribute "LINE_TO_TESTVIA_SPACING" "4.50,4.00,4.00,4.00,4.00,4.00,4.00,4.00,4.00,4.00,4.00,4.00,4.00,4.50"
					( Origin gBackEnd )
				)
				( attribute "SHAPE_TO_TESTVIA_SPACING" "5.00,5.00,5.00,5.00,5.00,5.00,5.00,5.00,5.00,5.00,5.00,5.00,5.00,5.00"
					( Origin gBackEnd )
				)
				( attribute "BBV_TO_BBV_SPACING" "5.00,5.00,5.00,5.00,5.00,5.00,5.00,5.00,5.00,5.00,5.00,5.00,5.00,5.00"
					( Origin gBackEnd )
				)
				( attribute "BONDPAD_TO_BBV_SPACING" "5.00,5.00,5.00,5.00,5.00,5.00,5.00,5.00,5.00,5.00,5.00,5.00,5.00,5.00"
					( Origin gBackEnd )
				)
				( attribute "BBV_TO_LINE_SPACING" "5.00,5.00,5.00,5.00,5.00,5.00,5.00,5.00,5.00,5.00,5.00,5.00,5.00,5.00"
					( Origin gBackEnd )
				)
				( attribute "BBV_TO_SHAPE_SPACING" "5.00,5.00,5.00,5.00,5.00,5.00,5.00,5.00,5.00,5.00,5.00,5.00,5.00,5.00"
					( Origin gBackEnd )
				)
				( attribute "BONDPAD_TO_BONDPAD_SPACING" "5.00,5.00,5.00,5.00,5.00,5.00,5.00,5.00,5.00,5.00,5.00,5.00,5.00,5.00"
					( Origin gBackEnd )
				)
				( attribute "BONDPAD_TO_LINE_SPACING" "5.00,5.00,5.00,5.00,5.00,5.00,5.00,5.00,5.00,5.00,5.00,5.00,5.00,5.00"
					( Origin gBackEnd )
				)
				( attribute "BONDPAD_TO_SHAPE_SPACING" "5.00,5.00,5.00,5.00,5.00,5.00,5.00,5.00,5.00,5.00,5.00,5.00,5.00,5.00"
					( Origin gBackEnd )
				)
				( attribute "LINE_TO_LINE_SPACING" "5.00,5.00,5.00,5.00,5.00,5.00,5.00,5.00,5.00,5.00,5.00,5.00,5.00,5.00"
					( Origin gBackEnd )
				)
				( attribute "LINE_TO_SHAPE_SPACING" "10.00,10.00,10.00,10.00,10.00,10.00,10.00,10.00,10.00,10.00,10.00,10.00,10.00,10.00"
					( Origin gBackEnd )
				)
				( attribute "SHAPE_TO_SHAPE_SPACING" "10.00,10.00,10.00,10.00,10.00,10.00,10.00,10.00,10.00,10.00,10.00,10.00,10.00,10.00"
					( Origin gBackEnd )
				)
				( attribute "HOLE_TO_PIN_SPACING" "8.00,8.00,8.00,8.00,8.00,8.00,8.00,8.00,8.00,8.00,8.00,8.00,8.00,8.00"
					( Origin gBackEnd )
				)
				( attribute "HOLE_TO_VIA_SPACING" "8.00,8.00,8.00,8.00,8.00,8.00,8.00,8.00,8.00,8.00,8.00,8.00,8.00,8.00"
					( Origin gBackEnd )
				)
				( attribute "HOLE_TO_LINE_SPACING" "8.00,8.00,8.00,8.00,8.00,8.00,8.00,8.00,8.00,8.00,8.00,8.00,8.00,8.00"
					( Origin gBackEnd )
				)
				( attribute "HOLE_TO_SHAPE_SPACING" "8.00,8.00,8.00,8.00,8.00,8.00,8.00,8.00,8.00,8.00,8.00,8.00,8.00,8.00"
					( Origin gBackEnd )
				)
				( attribute "HOLE_TO_HOLE_SPACING" "8.00,8.00,8.00,8.00,8.00,8.00,8.00,8.00,8.00,8.00,8.00,8.00,8.00,8.00"
					( Origin gBackEnd )
				)
				( attribute "MVIA_TO_MVIA_SPACING" "5.00,5.00,5.00,5.00,5.00,5.00,5.00,5.00,5.00,5.00,5.00,5.00,5.00,5.00"
					( Origin gBackEnd )
				)
				( attribute "MVIA_TO_THRUPIN_SPACING" "5.00,5.00,5.00,5.00,5.00,5.00,5.00,5.00,5.00,5.00,5.00,5.00,5.00,5.00"
					( Origin gBackEnd )
				)
				( attribute "MVIA_TO_SMDPIN_SPACING" "5.00,5.00,5.00,5.00,5.00,5.00,5.00,5.00,5.00,5.00,5.00,5.00,5.00,5.00"
					( Origin gBackEnd )
				)
				( attribute "MVIA_TO_THRUVIA_SPACING" "5.00,5.00,5.00,5.00,5.00,5.00,5.00,5.00,5.00,5.00,5.00,5.00,5.00,5.00"
					( Origin gBackEnd )
				)
				( attribute "MVIA_TO_BBV_SPACING" "5.00,5.00,5.00,5.00,5.00,5.00,5.00,5.00,5.00,5.00,5.00,5.00,5.00,5.00"
					( Origin gBackEnd )
				)
				( attribute "MVIA_TO_LINE_SPACING" "5.00,5.00,5.00,5.00,5.00,5.00,5.00,5.00,5.00,5.00,5.00,5.00,5.00,5.00"
					( Origin gBackEnd )
				)
				( attribute "MVIA_TO_SHAPE_SPACING" "5.00,5.00,5.00,5.00,5.00,5.00,5.00,5.00,5.00,5.00,5.00,5.00,5.00,5.00"
					( Origin gBackEnd )
				)
				( attribute "MVIA_TO_TESTPIN_SPACING" "5.00,5.00,5.00,5.00,5.00,5.00,5.00,5.00,5.00,5.00,5.00,5.00,5.00,5.00"
					( Origin gBackEnd )
				)
				( attribute "MVIA_TO_TESTVIA_SPACING" "5.00,5.00,5.00,5.00,5.00,5.00,5.00,5.00,5.00,5.00,5.00,5.00,5.00,5.00"
					( Origin gBackEnd )
				)
				( attribute "BONDPAD_TO_MVIA_SPACING" "5.00,5.00,5.00,5.00,5.00,5.00,5.00,5.00,5.00,5.00,5.00,5.00,5.00,5.00"
					( Origin gBackEnd )
				)
				( attribute "MIN_BVIA_GAP" "5.00"
					( Origin gBackEnd )
				)
				( attribute "BONDPAD_TO_BONDPAD_DIFFP_SPC" "5.00,5.00,5.00,5.00,5.00,5.00,5.00,5.00,5.00,5.00,5.00,5.00,5.00,5.00"
					( Origin gBackEnd )
				)
				( objectStatus "TH_PIN_SMT_PIN" )
			)
			( spacingCSet "@sapphirecity_baseboard_lib.sapphirecity_baseboard(sch_1):\VIA_5H\"
				( attribute "THRUPIN_TO_THRUPIN_SPACING" "5.00,5.00,5.00,5.00,5.00,5.00,5.00,5.00,5.00,5.00,5.00,5.00,5.00,5.00"
					( Origin gBackEnd )
				)
				( attribute "THRUPIN_TO_SMDPIN_SPACING" "5.00,5.00,5.00,5.00,5.00,5.00,5.00,5.00,5.00,5.00,5.00,5.00,5.00,5.00"
					( Origin gBackEnd )
				)
				( attribute "TESTPIN_TO_THRUPIN_SPACING" "5.00,5.00,5.00,5.00,5.00,5.00,5.00,5.00,5.00,5.00,5.00,5.00,5.00,5.00"
					( Origin gBackEnd )
				)
				( attribute "THRUPIN_TO_THRUVIA_SPACING" "5.00,5.00,5.00,5.00,5.00,5.00,5.00,5.00,5.00,5.00,5.00,5.00,5.00,5.00"
					( Origin gBackEnd )
				)
				( attribute "TESTVIA_TO_THRUPIN_SPACING" "5.00,5.00,5.00,5.00,5.00,5.00,5.00,5.00,5.00,5.00,5.00,5.00,5.00,5.00"
					( Origin gBackEnd )
				)
				( attribute "BBV_TO_THRUPIN_SPACING" "5.00,5.00,5.00,5.00,5.00,5.00,5.00,5.00,5.00,5.00,5.00,5.00,5.00,5.00"
					( Origin gBackEnd )
				)
				( attribute "THRUPIN_TO_BONDPAD_SPACING" "5.00,5.00,5.00,5.00,5.00,5.00,5.00,5.00,5.00,5.00,5.00,5.00,5.00,5.00"
					( Origin gBackEnd )
				)
				( attribute "LINE_TO_THRUPIN_SPACING" "13.50,20.00,20.00,20.00,20.00,20.00,20.00,20.00,20.00,20.00,20.00,20.00,20.00,13.50"
					( Origin gBackEnd )
				)
				( attribute "THRUPIN_TO_SHAPE_SPACING" "5.00,5.00,5.00,5.00,5.00,5.00,5.00,5.00,5.00,5.00,5.00,5.00,5.00,5.00"
					( Origin gBackEnd )
				)
				( attribute "SMDPIN_TO_SMDPIN_SPACING" "5.00,5.00,5.00,5.00,5.00,5.00,5.00,5.00,5.00,5.00,5.00,5.00,5.00,5.00"
					( Origin gBackEnd )
				)
				( attribute "SMDPIN_TO_TESTPIN_SPACING" "5.00,5.00,5.00,5.00,5.00,5.00,5.00,5.00,5.00,5.00,5.00,5.00,5.00,25.00"
					( Origin gBackEnd )
				)
				( attribute "SMDPIN_TO_THRUVIA_SPACING" "5.00,5.00,5.00,5.00,5.00,5.00,5.00,5.00,5.00,5.00,5.00,5.00,5.00,5.00"
					( Origin gBackEnd )
				)
				( attribute "SMDPIN_TO_TESTVIA_SPACING" "5.00,5.00,5.00,5.00,5.00,5.00,5.00,5.00,5.00,5.00,5.00,5.00,5.00,5.00"
					( Origin gBackEnd )
				)
				( attribute "BBV_TO_SMDPIN_SPACING" "5.00,5.00,5.00,5.00,5.00,5.00,5.00,5.00,5.00,5.00,5.00,5.00,5.00,5.00"
					( Origin gBackEnd )
				)
				( attribute "SMDPIN_TO_BONDPAD_SPACING" "5.00,5.00,5.00,5.00,5.00,5.00,5.00,5.00,5.00,5.00,5.00,5.00,5.00,5.00"
					( Origin gBackEnd )
				)
				( attribute "LINE_TO_SMDPIN_SPACING" "4.50,4.50,4.50,4.50,4.50,4.50,4.50,4.50,4.50,4.50,4.50,4.50,4.50,4.50"
					( Origin gBackEnd )
				)
				( attribute "SHAPE_TO_SMDPIN_SPACING" "5.00,5.00,5.00,5.00,5.00,5.00,5.00,5.00,5.00,5.00,5.00,5.00,5.00,5.00"
					( Origin gBackEnd )
				)
				( attribute "TESTPIN_TO_TESTPIN_SPACING" "5.00,5.00,5.00,5.00,5.00,5.00,5.00,5.00,5.00,5.00,5.00,5.00,5.00,5.00"
					( Origin gBackEnd )
				)
				( attribute "TESTPIN_TO_THRUVIA_SPACING" "5.00,5.00,5.00,5.00,5.00,5.00,5.00,5.00,5.00,5.00,5.00,5.00,5.00,5.00"
					( Origin gBackEnd )
				)
				( attribute "TESTPIN_TO_TESTVIA_SPACING" "5.00,5.00,5.00,5.00,5.00,5.00,5.00,5.00,5.00,5.00,5.00,5.00,5.00,5.00"
					( Origin gBackEnd )
				)
				( attribute "BBV_TO_TESTPIN_SPACING" "5.00,5.00,5.00,5.00,5.00,5.00,5.00,5.00,5.00,5.00,5.00,5.00,5.00,5.00"
					( Origin gBackEnd )
				)
				( attribute "BONDPAD_TO_TESTPIN_SPACING" "5.00,5.00,5.00,5.00,5.00,5.00,5.00,5.00,5.00,5.00,5.00,5.00,5.00,5.00"
					( Origin gBackEnd )
				)
				( attribute "LINE_TO_TESTPIN_SPACING" "13.50,20.00,20.00,20.00,20.00,20.00,20.00,20.00,20.00,20.00,20.00,20.00,20.00,13.50"
					( Origin gBackEnd )
				)
				( attribute "SHAPE_TO_TESTPIN_SPACING" "5.00,5.00,5.00,5.00,5.00,5.00,5.00,5.00,5.00,5.00,5.00,5.00,5.00,5.00"
					( Origin gBackEnd )
				)
				( attribute "THRUVIA_TO_THRUVIA_SPACING" "5.00,5.00,5.00,5.00,5.00,5.00,5.00,5.00,5.00,5.00,5.00,5.00,5.00,5.00"
					( Origin gBackEnd )
				)
				( attribute "TESTVIA_TO_THRUVIA_SPACING" "6.00,6.00,6.00,6.00,6.00,6.00,6.00,6.00,6.00,6.00,6.00,6.00,6.00,6.00"
					( Origin gBackEnd )
				)
				( attribute "BBV_TO_THRUVIA_SPACING" "5.00,5.00,5.00,5.00,5.00,5.00,5.00,5.00,5.00,5.00,5.00,5.00,5.00,5.00"
					( Origin gBackEnd )
				)
				( attribute "BONDPAD_TO_THRUVIA_SPACING" "5.00,5.00,5.00,5.00,5.00,5.00,5.00,5.00,5.00,5.00,5.00,5.00,5.00,5.00"
					( Origin gBackEnd )
				)
				( attribute "LINE_TO_THRUVIA_SPACING" "13.50,20.00,20.00,20.00,20.00,20.00,20.00,20.00,20.00,20.00,20.00,20.00,20.00,13.50"
					( Origin gBackEnd )
				)
				( attribute "SHAPE_TO_THRUVIA_SPACING" "5.00,5.00,5.00,5.00,5.00,5.00,5.00,5.00,5.00,5.00,5.00,5.00,5.00,5.00"
					( Origin gBackEnd )
				)
				( attribute "TESTVIA_TO_TESTVIA_SPACING" "6.00,6.00,6.00,6.00,6.00,6.00,6.00,6.00,6.00,6.00,6.00,6.00,6.00,6.00"
					( Origin gBackEnd )
				)
				( attribute "BBV_TO_TESTVIA_SPACING" "5.00,5.00,5.00,5.00,5.00,5.00,5.00,5.00,5.00,5.00,5.00,5.00,5.00,5.00"
					( Origin gBackEnd )
				)
				( attribute "BONDPAD_TO_TESTVIA_SPACING" "5.00,5.00,5.00,5.00,5.00,5.00,5.00,5.00,5.00,5.00,5.00,5.00,5.00,5.00"
					( Origin gBackEnd )
				)
				( attribute "LINE_TO_TESTVIA_SPACING" "13.50,20.00,20.00,20.00,20.00,20.00,20.00,20.00,20.00,20.00,20.00,20.00,20.00,13.50"
					( Origin gBackEnd )
				)
				( attribute "SHAPE_TO_TESTVIA_SPACING" "5.00,5.00,5.00,5.00,5.00,5.00,5.00,5.00,5.00,5.00,5.00,5.00,5.00,5.00"
					( Origin gBackEnd )
				)
				( attribute "BBV_TO_BBV_SPACING" "5.00,5.00,5.00,5.00,5.00,5.00,5.00,5.00,5.00,5.00,5.00,5.00,5.00,5.00"
					( Origin gBackEnd )
				)
				( attribute "BONDPAD_TO_BBV_SPACING" "5.00,5.00,5.00,5.00,5.00,5.00,5.00,5.00,5.00,5.00,5.00,5.00,5.00,5.00"
					( Origin gBackEnd )
				)
				( attribute "BBV_TO_LINE_SPACING" "5.00,5.00,5.00,5.00,5.00,5.00,5.00,5.00,5.00,5.00,5.00,5.00,5.00,5.00"
					( Origin gBackEnd )
				)
				( attribute "BBV_TO_SHAPE_SPACING" "5.00,5.00,5.00,5.00,5.00,5.00,5.00,5.00,5.00,5.00,5.00,5.00,5.00,5.00"
					( Origin gBackEnd )
				)
				( attribute "BONDPAD_TO_BONDPAD_SPACING" "5.00,5.00,5.00,5.00,5.00,5.00,5.00,5.00,5.00,5.00,5.00,5.00,5.00,5.00"
					( Origin gBackEnd )
				)
				( attribute "BONDPAD_TO_LINE_SPACING" "5.00,5.00,5.00,5.00,5.00,5.00,5.00,5.00,5.00,5.00,5.00,5.00,5.00,5.00"
					( Origin gBackEnd )
				)
				( attribute "BONDPAD_TO_SHAPE_SPACING" "5.00,5.00,5.00,5.00,5.00,5.00,5.00,5.00,5.00,5.00,5.00,5.00,5.00,5.00"
					( Origin gBackEnd )
				)
				( attribute "LINE_TO_LINE_SPACING" "5.00,5.00,5.00,5.00,5.00,5.00,5.00,5.00,5.00,5.00,5.00,5.00,5.00,5.00"
					( Origin gBackEnd )
				)
				( attribute "LINE_TO_SHAPE_SPACING" "10.00,10.00,10.00,10.00,10.00,10.00,10.00,10.00,10.00,10.00,10.00,10.00,10.00,10.00"
					( Origin gBackEnd )
				)
				( attribute "SHAPE_TO_SHAPE_SPACING" "10.00,10.00,10.00,10.00,10.00,10.00,10.00,10.00,10.00,10.00,10.00,10.00,10.00,10.00"
					( Origin gBackEnd )
				)
				( attribute "HOLE_TO_PIN_SPACING" "8.00,8.00,8.00,8.00,8.00,8.00,8.00,8.00,8.00,8.00,8.00,8.00,8.00,8.00"
					( Origin gBackEnd )
				)
				( attribute "HOLE_TO_VIA_SPACING" "8.00,8.00,8.00,8.00,8.00,8.00,8.00,8.00,8.00,8.00,8.00,8.00,8.00,8.00"
					( Origin gBackEnd )
				)
				( attribute "HOLE_TO_LINE_SPACING" "8.00,8.00,8.00,8.00,8.00,8.00,8.00,8.00,8.00,8.00,8.00,8.00,8.00,8.00"
					( Origin gBackEnd )
				)
				( attribute "HOLE_TO_SHAPE_SPACING" "8.00,8.00,8.00,8.00,8.00,8.00,8.00,8.00,8.00,8.00,8.00,8.00,8.00,8.00"
					( Origin gBackEnd )
				)
				( attribute "HOLE_TO_HOLE_SPACING" "8.00,8.00,8.00,8.00,8.00,8.00,8.00,8.00,8.00,8.00,8.00,8.00,8.00,8.00"
					( Origin gBackEnd )
				)
				( attribute "MVIA_TO_MVIA_SPACING" "5.00,5.00,5.00,5.00,5.00,5.00,5.00,5.00,5.00,5.00,5.00,5.00,5.00,5.00"
					( Origin gBackEnd )
				)
				( attribute "MVIA_TO_THRUPIN_SPACING" "5.00,5.00,5.00,5.00,5.00,5.00,5.00,5.00,5.00,5.00,5.00,5.00,5.00,5.00"
					( Origin gBackEnd )
				)
				( attribute "MVIA_TO_SMDPIN_SPACING" "5.00,5.00,5.00,5.00,5.00,5.00,5.00,5.00,5.00,5.00,5.00,5.00,5.00,5.00"
					( Origin gBackEnd )
				)
				( attribute "MVIA_TO_THRUVIA_SPACING" "5.00,5.00,5.00,5.00,5.00,5.00,5.00,5.00,5.00,5.00,5.00,5.00,5.00,5.00"
					( Origin gBackEnd )
				)
				( attribute "MVIA_TO_BBV_SPACING" "5.00,5.00,5.00,5.00,5.00,5.00,5.00,5.00,5.00,5.00,5.00,5.00,5.00,5.00"
					( Origin gBackEnd )
				)
				( attribute "MVIA_TO_LINE_SPACING" "5.00,5.00,5.00,5.00,5.00,5.00,5.00,5.00,5.00,5.00,5.00,5.00,5.00,5.00"
					( Origin gBackEnd )
				)
				( attribute "MVIA_TO_SHAPE_SPACING" "5.00,5.00,5.00,5.00,5.00,5.00,5.00,5.00,5.00,5.00,5.00,5.00,5.00,5.00"
					( Origin gBackEnd )
				)
				( attribute "MVIA_TO_TESTPIN_SPACING" "5.00,5.00,5.00,5.00,5.00,5.00,5.00,5.00,5.00,5.00,5.00,5.00,5.00,5.00"
					( Origin gBackEnd )
				)
				( attribute "MVIA_TO_TESTVIA_SPACING" "5.00,5.00,5.00,5.00,5.00,5.00,5.00,5.00,5.00,5.00,5.00,5.00,5.00,5.00"
					( Origin gBackEnd )
				)
				( attribute "BONDPAD_TO_MVIA_SPACING" "5.00,5.00,5.00,5.00,5.00,5.00,5.00,5.00,5.00,5.00,5.00,5.00,5.00,5.00"
					( Origin gBackEnd )
				)
				( attribute "MIN_BVIA_GAP" "5.00"
					( Origin gBackEnd )
				)
				( attribute "BONDPAD_TO_BONDPAD_DIFFP_SPC" "5.00,5.00,5.00,5.00,5.00,5.00,5.00,5.00,5.00,5.00,5.00,5.00,5.00,5.00"
					( Origin gBackEnd )
				)
				( objectStatus "VIA_5H" )
			)
			( spacingCSet "@sapphirecity_baseboard_lib.sapphirecity_baseboard(sch_1):\VIA_10H\"
				( attribute "THRUPIN_TO_THRUPIN_SPACING" "5.00,5.00,5.00,5.00,5.00,5.00,5.00,5.00,5.00,5.00,5.00,5.00,5.00,5.00"
					( Origin gBackEnd )
				)
				( attribute "THRUPIN_TO_SMDPIN_SPACING" "5.00,5.00,5.00,5.00,5.00,5.00,5.00,5.00,5.00,5.00,5.00,5.00,5.00,5.00"
					( Origin gBackEnd )
				)
				( attribute "TESTPIN_TO_THRUPIN_SPACING" "5.00,5.00,5.00,5.00,5.00,5.00,5.00,5.00,5.00,5.00,5.00,5.00,5.00,5.00"
					( Origin gBackEnd )
				)
				( attribute "THRUPIN_TO_THRUVIA_SPACING" "5.00,5.00,5.00,5.00,5.00,5.00,5.00,5.00,5.00,5.00,5.00,5.00,5.00,5.00"
					( Origin gBackEnd )
				)
				( attribute "TESTVIA_TO_THRUPIN_SPACING" "5.00,5.00,5.00,5.00,5.00,5.00,5.00,5.00,5.00,5.00,5.00,5.00,5.00,5.00"
					( Origin gBackEnd )
				)
				( attribute "BBV_TO_THRUPIN_SPACING" "5.00,5.00,5.00,5.00,5.00,5.00,5.00,5.00,5.00,5.00,5.00,5.00,5.00,5.00"
					( Origin gBackEnd )
				)
				( attribute "THRUPIN_TO_BONDPAD_SPACING" "5.00,5.00,5.00,5.00,5.00,5.00,5.00,5.00,5.00,5.00,5.00,5.00,5.00,5.00"
					( Origin gBackEnd )
				)
				( attribute "LINE_TO_THRUPIN_SPACING" "27.00,40.00,40.00,40.00,40.00,40.00,40.00,40.00,40.00,40.00,40.00,40.00,40.00,27.00"
					( Origin gBackEnd )
				)
				( attribute "THRUPIN_TO_SHAPE_SPACING" "5.00,5.00,5.00,5.00,5.00,5.00,5.00,5.00,5.00,5.00,5.00,5.00,5.00,5.00"
					( Origin gBackEnd )
				)
				( attribute "SMDPIN_TO_SMDPIN_SPACING" "5.00,5.00,5.00,5.00,5.00,5.00,5.00,5.00,5.00,5.00,5.00,5.00,5.00,5.00"
					( Origin gBackEnd )
				)
				( attribute "SMDPIN_TO_TESTPIN_SPACING" "5.00,5.00,5.00,5.00,5.00,5.00,5.00,5.00,5.00,5.00,5.00,5.00,5.00,5.00"
					( Origin gBackEnd )
				)
				( attribute "SMDPIN_TO_THRUVIA_SPACING" "5.00,5.00,5.00,5.00,5.00,5.00,5.00,5.00,5.00,5.00,5.00,5.00,5.00,5.00"
					( Origin gBackEnd )
				)
				( attribute "SMDPIN_TO_TESTVIA_SPACING" "5.00,5.00,5.00,5.00,5.00,5.00,5.00,5.00,5.00,5.00,5.00,5.00,5.00,5.00"
					( Origin gBackEnd )
				)
				( attribute "BBV_TO_SMDPIN_SPACING" "5.00,5.00,5.00,5.00,5.00,5.00,5.00,5.00,5.00,5.00,5.00,5.00,5.00,5.00"
					( Origin gBackEnd )
				)
				( attribute "SMDPIN_TO_BONDPAD_SPACING" "5.00,5.00,5.00,5.00,5.00,5.00,5.00,5.00,5.00,5.00,5.00,5.00,5.00,5.00"
					( Origin gBackEnd )
				)
				( attribute "LINE_TO_SMDPIN_SPACING" "4.50,4.50,4.50,4.50,4.50,4.50,4.50,4.50,4.50,4.50,4.50,4.50,4.50,4.50"
					( Origin gBackEnd )
				)
				( attribute "SHAPE_TO_SMDPIN_SPACING" "5.00,5.00,5.00,5.00,5.00,5.00,5.00,5.00,5.00,5.00,5.00,5.00,5.00,5.00"
					( Origin gBackEnd )
				)
				( attribute "TESTPIN_TO_TESTPIN_SPACING" "5.00,5.00,5.00,5.00,5.00,5.00,5.00,5.00,5.00,5.00,5.00,5.00,5.00,5.00"
					( Origin gBackEnd )
				)
				( attribute "TESTPIN_TO_THRUVIA_SPACING" "5.00,5.00,5.00,5.00,5.00,5.00,5.00,5.00,5.00,5.00,5.00,5.00,5.00,5.00"
					( Origin gBackEnd )
				)
				( attribute "TESTPIN_TO_TESTVIA_SPACING" "5.00,5.00,5.00,5.00,5.00,5.00,5.00,5.00,5.00,5.00,5.00,5.00,5.00,5.00"
					( Origin gBackEnd )
				)
				( attribute "BBV_TO_TESTPIN_SPACING" "5.00,5.00,5.00,5.00,5.00,5.00,5.00,5.00,5.00,5.00,5.00,5.00,5.00,5.00"
					( Origin gBackEnd )
				)
				( attribute "BONDPAD_TO_TESTPIN_SPACING" "5.00,5.00,5.00,5.00,5.00,5.00,5.00,5.00,5.00,5.00,5.00,5.00,5.00,5.00"
					( Origin gBackEnd )
				)
				( attribute "LINE_TO_TESTPIN_SPACING" "27.00,40.00,40.00,40.00,40.00,40.00,40.00,40.00,40.00,40.00,40.00,40.00,40.00,27.00"
					( Origin gBackEnd )
				)
				( attribute "SHAPE_TO_TESTPIN_SPACING" "5.00,5.00,5.00,5.00,5.00,5.00,5.00,5.00,5.00,5.00,5.00,5.00,5.00,5.00"
					( Origin gBackEnd )
				)
				( attribute "THRUVIA_TO_THRUVIA_SPACING" "5.00,5.00,5.00,5.00,5.00,5.00,5.00,5.00,5.00,5.00,5.00,5.00,5.00,5.00"
					( Origin gBackEnd )
				)
				( attribute "TESTVIA_TO_THRUVIA_SPACING" "6.00,6.00,6.00,6.00,6.00,6.00,6.00,6.00,6.00,6.00,6.00,6.00,6.00,6.00"
					( Origin gBackEnd )
				)
				( attribute "BBV_TO_THRUVIA_SPACING" "5.00,5.00,5.00,5.00,5.00,5.00,5.00,5.00,5.00,5.00,5.00,5.00,5.00,5.00"
					( Origin gBackEnd )
				)
				( attribute "BONDPAD_TO_THRUVIA_SPACING" "5.00,5.00,5.00,5.00,5.00,5.00,5.00,5.00,5.00,5.00,5.00,5.00,5.00,5.00"
					( Origin gBackEnd )
				)
				( attribute "LINE_TO_THRUVIA_SPACING" "27.00,40.00,40.00,40.00,40.00,40.00,40.00,40.00,40.00,40.00,40.00,40.00,40.00,27.00"
					( Origin gBackEnd )
				)
				( attribute "SHAPE_TO_THRUVIA_SPACING" "5.00,5.00,5.00,5.00,5.00,5.00,5.00,5.00,5.00,5.00,5.00,5.00,5.00,5.00"
					( Origin gBackEnd )
				)
				( attribute "TESTVIA_TO_TESTVIA_SPACING" "6.00,6.00,6.00,6.00,6.00,6.00,6.00,6.00,6.00,6.00,6.00,6.00,6.00,6.00"
					( Origin gBackEnd )
				)
				( attribute "BBV_TO_TESTVIA_SPACING" "5.00,5.00,5.00,5.00,5.00,5.00,5.00,5.00,5.00,5.00,5.00,5.00,5.00,5.00"
					( Origin gBackEnd )
				)
				( attribute "BONDPAD_TO_TESTVIA_SPACING" "5.00,5.00,5.00,5.00,5.00,5.00,5.00,5.00,5.00,5.00,5.00,5.00,5.00,5.00"
					( Origin gBackEnd )
				)
				( attribute "LINE_TO_TESTVIA_SPACING" "27.00,40.00,40.00,40.00,40.00,40.00,40.00,40.00,40.00,40.00,40.00,40.00,40.00,27.00"
					( Origin gBackEnd )
				)
				( attribute "SHAPE_TO_TESTVIA_SPACING" "5.00,5.00,5.00,5.00,5.00,5.00,5.00,5.00,5.00,5.00,5.00,5.00,5.00,5.00"
					( Origin gBackEnd )
				)
				( attribute "BBV_TO_BBV_SPACING" "5.00,5.00,5.00,5.00,5.00,5.00,5.00,5.00,5.00,5.00,5.00,5.00,5.00,5.00"
					( Origin gBackEnd )
				)
				( attribute "BONDPAD_TO_BBV_SPACING" "5.00,5.00,5.00,5.00,5.00,5.00,5.00,5.00,5.00,5.00,5.00,5.00,5.00,5.00"
					( Origin gBackEnd )
				)
				( attribute "BBV_TO_LINE_SPACING" "5.00,5.00,5.00,5.00,5.00,5.00,5.00,5.00,5.00,5.00,5.00,5.00,5.00,5.00"
					( Origin gBackEnd )
				)
				( attribute "BBV_TO_SHAPE_SPACING" "5.00,5.00,5.00,5.00,5.00,5.00,5.00,5.00,5.00,5.00,5.00,5.00,5.00,5.00"
					( Origin gBackEnd )
				)
				( attribute "BONDPAD_TO_BONDPAD_SPACING" "5.00,5.00,5.00,5.00,5.00,5.00,5.00,5.00,5.00,5.00,5.00,5.00,5.00,5.00"
					( Origin gBackEnd )
				)
				( attribute "BONDPAD_TO_LINE_SPACING" "5.00,5.00,5.00,5.00,5.00,5.00,5.00,5.00,5.00,5.00,5.00,5.00,5.00,5.00"
					( Origin gBackEnd )
				)
				( attribute "BONDPAD_TO_SHAPE_SPACING" "5.00,5.00,5.00,5.00,5.00,5.00,5.00,5.00,5.00,5.00,5.00,5.00,5.00,5.00"
					( Origin gBackEnd )
				)
				( attribute "LINE_TO_LINE_SPACING" "5.00,5.00,5.00,5.00,5.00,5.00,5.00,5.00,5.00,5.00,5.00,5.00,5.00,5.00"
					( Origin gBackEnd )
				)
				( attribute "LINE_TO_SHAPE_SPACING" "10.00,10.00,10.00,10.00,10.00,10.00,10.00,10.00,10.00,10.00,10.00,10.00,10.00,10.00"
					( Origin gBackEnd )
				)
				( attribute "SHAPE_TO_SHAPE_SPACING" "10.00,10.00,10.00,10.00,10.00,10.00,10.00,10.00,10.00,10.00,10.00,10.00,10.00,10.00"
					( Origin gBackEnd )
				)
				( attribute "HOLE_TO_PIN_SPACING" "8.00,8.00,8.00,8.00,8.00,8.00,8.00,8.00,8.00,8.00,8.00,8.00,8.00,8.00"
					( Origin gBackEnd )
				)
				( attribute "HOLE_TO_VIA_SPACING" "8.00,8.00,8.00,8.00,8.00,8.00,8.00,8.00,8.00,8.00,8.00,8.00,8.00,8.00"
					( Origin gBackEnd )
				)
				( attribute "HOLE_TO_LINE_SPACING" "8.00,8.00,8.00,8.00,8.00,8.00,8.00,8.00,8.00,8.00,8.00,8.00,8.00,8.00"
					( Origin gBackEnd )
				)
				( attribute "HOLE_TO_SHAPE_SPACING" "8.00,8.00,8.00,8.00,8.00,8.00,8.00,8.00,8.00,8.00,8.00,8.00,8.00,8.00"
					( Origin gBackEnd )
				)
				( attribute "HOLE_TO_HOLE_SPACING" "8.00,8.00,8.00,8.00,8.00,8.00,8.00,8.00,8.00,8.00,8.00,8.00,8.00,8.00"
					( Origin gBackEnd )
				)
				( attribute "MVIA_TO_MVIA_SPACING" "5.00,5.00,5.00,5.00,5.00,5.00,5.00,5.00,5.00,5.00,5.00,5.00,5.00,5.00"
					( Origin gBackEnd )
				)
				( attribute "MVIA_TO_THRUPIN_SPACING" "5.00,5.00,5.00,5.00,5.00,5.00,5.00,5.00,5.00,5.00,5.00,5.00,5.00,5.00"
					( Origin gBackEnd )
				)
				( attribute "MVIA_TO_SMDPIN_SPACING" "5.00,5.00,5.00,5.00,5.00,5.00,5.00,5.00,5.00,5.00,5.00,5.00,5.00,5.00"
					( Origin gBackEnd )
				)
				( attribute "MVIA_TO_THRUVIA_SPACING" "5.00,5.00,5.00,5.00,5.00,5.00,5.00,5.00,5.00,5.00,5.00,5.00,5.00,5.00"
					( Origin gBackEnd )
				)
				( attribute "MVIA_TO_BBV_SPACING" "5.00,5.00,5.00,5.00,5.00,5.00,5.00,5.00,5.00,5.00,5.00,5.00,5.00,5.00"
					( Origin gBackEnd )
				)
				( attribute "MVIA_TO_LINE_SPACING" "5.00,5.00,5.00,5.00,5.00,5.00,5.00,5.00,5.00,5.00,5.00,5.00,5.00,5.00"
					( Origin gBackEnd )
				)
				( attribute "MVIA_TO_SHAPE_SPACING" "5.00,5.00,5.00,5.00,5.00,5.00,5.00,5.00,5.00,5.00,5.00,5.00,5.00,5.00"
					( Origin gBackEnd )
				)
				( attribute "MVIA_TO_TESTPIN_SPACING" "5.00,5.00,5.00,5.00,5.00,5.00,5.00,5.00,5.00,5.00,5.00,5.00,5.00,5.00"
					( Origin gBackEnd )
				)
				( attribute "MVIA_TO_TESTVIA_SPACING" "5.00,5.00,5.00,5.00,5.00,5.00,5.00,5.00,5.00,5.00,5.00,5.00,5.00,5.00"
					( Origin gBackEnd )
				)
				( attribute "BONDPAD_TO_MVIA_SPACING" "5.00,5.00,5.00,5.00,5.00,5.00,5.00,5.00,5.00,5.00,5.00,5.00,5.00,5.00"
					( Origin gBackEnd )
				)
				( attribute "MIN_BVIA_GAP" "5.00"
					( Origin gBackEnd )
				)
				( attribute "BONDPAD_TO_BONDPAD_DIFFP_SPC" "5.00,5.00,5.00,5.00,5.00,5.00,5.00,5.00,5.00,5.00,5.00,5.00,5.00,5.00"
					( Origin gBackEnd )
				)
				( objectStatus "VIA_10H" )
			)
			( spacingCSet "@sapphirecity_baseboard_lib.sapphirecity_baseboard(sch_1):\BMC_MEM\"
				( attribute "THRUPIN_TO_THRUPIN_SPACING" "5.00,5.00,5.00,5.00,5.00,5.00,5.00,5.00,5.00,5.00,5.00,5.00,5.00,5.00"
					( Origin gBackEnd )
				)
				( attribute "THRUPIN_TO_SMDPIN_SPACING" "5.00,5.00,5.00,5.00,5.00,5.00,5.00,5.00,5.00,5.00,5.00,5.00,5.00,5.00"
					( Origin gBackEnd )
				)
				( attribute "TESTPIN_TO_THRUPIN_SPACING" "5.00,5.00,5.00,5.00,5.00,5.00,5.00,5.00,5.00,5.00,5.00,5.00,5.00,5.00"
					( Origin gBackEnd )
				)
				( attribute "THRUPIN_TO_THRUVIA_SPACING" "5.00,5.00,5.00,5.00,5.00,5.00,5.00,5.00,5.00,5.00,5.00,5.00,5.00,5.00"
					( Origin gBackEnd )
				)
				( attribute "TESTVIA_TO_THRUPIN_SPACING" "5.00,5.00,5.00,5.00,5.00,5.00,5.00,5.00,5.00,5.00,5.00,5.00,5.00,5.00"
					( Origin gBackEnd )
				)
				( attribute "BBV_TO_THRUPIN_SPACING" "5.00,5.00,5.00,5.00,5.00,5.00,5.00,5.00,5.00,5.00,5.00,5.00,5.00,5.00"
					( Origin gBackEnd )
				)
				( attribute "THRUPIN_TO_BONDPAD_SPACING" "5.00,5.00,5.00,5.00,5.00,5.00,5.00,5.00,5.00,5.00,5.00,5.00,5.00,5.00"
					( Origin gBackEnd )
				)
				( attribute "LINE_TO_THRUPIN_SPACING" "4.50,4.00,4.00,4.00,4.00,4.00,4.00,4.00,4.00,4.00,4.00,4.00,4.00,4.50"
					( Origin gBackEnd )
				)
				( attribute "THRUPIN_TO_SHAPE_SPACING" "5.00,5.00,5.00,5.00,5.00,5.00,5.00,5.00,5.00,5.00,5.00,5.00,5.00,5.00"
					( Origin gBackEnd )
				)
				( attribute "SMDPIN_TO_SMDPIN_SPACING" "5.00,5.00,5.00,5.00,5.00,5.00,5.00,5.00,5.00,5.00,5.00,5.00,5.00,5.00"
					( Origin gBackEnd )
				)
				( attribute "SMDPIN_TO_TESTPIN_SPACING" "5.00,5.00,5.00,5.00,5.00,5.00,5.00,5.00,5.00,5.00,5.00,5.00,5.00,25.00"
					( Origin gBackEnd )
				)
				( attribute "SMDPIN_TO_THRUVIA_SPACING" "4.00,4.00,4.00,4.00,4.00,4.00,4.00,4.00,4.00,4.00,4.00,4.00,4.00,4.00"
					( Origin gBackEnd )
				)
				( attribute "SMDPIN_TO_TESTVIA_SPACING" "4.00,4.00,4.00,4.00,4.00,4.00,4.00,4.00,4.00,4.00,4.00,4.00,4.00,4.00"
					( Origin gBackEnd )
				)
				( attribute "BBV_TO_SMDPIN_SPACING" "5.00,5.00,5.00,5.00,5.00,5.00,5.00,5.00,5.00,5.00,5.00,5.00,5.00,5.00"
					( Origin gBackEnd )
				)
				( attribute "SMDPIN_TO_BONDPAD_SPACING" "5.00,5.00,5.00,5.00,5.00,5.00,5.00,5.00,5.00,5.00,5.00,5.00,5.00,5.00"
					( Origin gBackEnd )
				)
				( attribute "LINE_TO_SMDPIN_SPACING" "4.50,4.50,4.50,4.50,4.50,4.50,4.50,4.50,4.50,4.50,4.50,4.50,4.50,4.50"
					( Origin gBackEnd )
				)
				( attribute "SHAPE_TO_SMDPIN_SPACING" "5.00,5.00,5.00,5.00,5.00,5.00,5.00,5.00,5.00,5.00,5.00,5.00,5.00,5.00"
					( Origin gBackEnd )
				)
				( attribute "TESTPIN_TO_TESTPIN_SPACING" "5.00,5.00,5.00,5.00,5.00,5.00,5.00,5.00,5.00,5.00,5.00,5.00,5.00,5.00"
					( Origin gBackEnd )
				)
				( attribute "TESTPIN_TO_THRUVIA_SPACING" "5.00,5.00,5.00,5.00,5.00,5.00,5.00,5.00,5.00,5.00,5.00,5.00,5.00,5.00"
					( Origin gBackEnd )
				)
				( attribute "TESTPIN_TO_TESTVIA_SPACING" "5.00,5.00,5.00,5.00,5.00,5.00,5.00,5.00,5.00,5.00,5.00,5.00,5.00,5.00"
					( Origin gBackEnd )
				)
				( attribute "BBV_TO_TESTPIN_SPACING" "5.00,5.00,5.00,5.00,5.00,5.00,5.00,5.00,5.00,5.00,5.00,5.00,5.00,5.00"
					( Origin gBackEnd )
				)
				( attribute "BONDPAD_TO_TESTPIN_SPACING" "5.00,5.00,5.00,5.00,5.00,5.00,5.00,5.00,5.00,5.00,5.00,5.00,5.00,5.00"
					( Origin gBackEnd )
				)
				( attribute "LINE_TO_TESTPIN_SPACING" "4.50,4.50,4.50,4.50,4.50,4.50,4.50,4.50,4.50,4.50,4.50,4.50,4.50,4.50"
					( Origin gBackEnd )
				)
				( attribute "SHAPE_TO_TESTPIN_SPACING" "5.00,5.00,5.00,5.00,5.00,5.00,5.00,5.00,5.00,5.00,5.00,5.00,5.00,5.00"
					( Origin gBackEnd )
				)
				( attribute "THRUVIA_TO_THRUVIA_SPACING" "6.00,6.00,6.00,6.00,6.00,6.00,6.00,6.00,6.00,6.00,6.00,6.00,6.00,6.00"
					( Origin gBackEnd )
				)
				( attribute "TESTVIA_TO_THRUVIA_SPACING" "6.00,6.00,6.00,6.00,6.00,6.00,6.00,6.00,6.00,6.00,6.00,6.00,6.00,6.00"
					( Origin gBackEnd )
				)
				( attribute "BBV_TO_THRUVIA_SPACING" "5.00,5.00,5.00,5.00,5.00,5.00,5.00,5.00,5.00,5.00,5.00,5.00,5.00,5.00"
					( Origin gBackEnd )
				)
				( attribute "BONDPAD_TO_THRUVIA_SPACING" "5.00,5.00,5.00,5.00,5.00,5.00,5.00,5.00,5.00,5.00,5.00,5.00,5.00,5.00"
					( Origin gBackEnd )
				)
				( attribute "LINE_TO_THRUVIA_SPACING" "4.00,4.00,4.00,4.00,4.00,4.00,4.00,4.00,4.00,4.00,4.00,4.00,4.00,4.00"
					( Origin gBackEnd )
				)
				( attribute "SHAPE_TO_THRUVIA_SPACING" "5.00,5.00,5.00,5.00,5.00,5.00,5.00,5.00,5.00,5.00,5.00,5.00,5.00,5.00"
					( Origin gBackEnd )
				)
				( attribute "TESTVIA_TO_TESTVIA_SPACING" "6.00,6.00,6.00,6.00,6.00,6.00,6.00,6.00,6.00,6.00,6.00,6.00,6.00,6.00"
					( Origin gBackEnd )
				)
				( attribute "BBV_TO_TESTVIA_SPACING" "5.00,5.00,5.00,5.00,5.00,5.00,5.00,5.00,5.00,5.00,5.00,5.00,5.00,5.00"
					( Origin gBackEnd )
				)
				( attribute "BONDPAD_TO_TESTVIA_SPACING" "5.00,5.00,5.00,5.00,5.00,5.00,5.00,5.00,5.00,5.00,5.00,5.00,5.00,5.00"
					( Origin gBackEnd )
				)
				( attribute "LINE_TO_TESTVIA_SPACING" "4.00,4.00,4.00,4.00,4.00,4.00,4.00,4.00,4.00,4.00,4.00,4.00,4.00,4.50"
					( Origin gBackEnd )
				)
				( attribute "SHAPE_TO_TESTVIA_SPACING" "5.00,5.00,5.00,5.00,5.00,5.00,5.00,5.00,5.00,5.00,5.00,5.00,5.00,5.00"
					( Origin gBackEnd )
				)
				( attribute "BBV_TO_BBV_SPACING" "5.00,5.00,5.00,5.00,5.00,5.00,5.00,5.00,5.00,5.00,5.00,5.00,5.00,5.00"
					( Origin gBackEnd )
				)
				( attribute "BONDPAD_TO_BBV_SPACING" "5.00,5.00,5.00,5.00,5.00,5.00,5.00,5.00,5.00,5.00,5.00,5.00,5.00,5.00"
					( Origin gBackEnd )
				)
				( attribute "BBV_TO_LINE_SPACING" "5.00,5.00,5.00,5.00,5.00,5.00,5.00,5.00,5.00,5.00,5.00,5.00,5.00,5.00"
					( Origin gBackEnd )
				)
				( attribute "BBV_TO_SHAPE_SPACING" "5.00,5.00,5.00,5.00,5.00,5.00,5.00,5.00,5.00,5.00,5.00,5.00,5.00,5.00"
					( Origin gBackEnd )
				)
				( attribute "BONDPAD_TO_BONDPAD_SPACING" "5.00,5.00,5.00,5.00,5.00,5.00,5.00,5.00,5.00,5.00,5.00,5.00,5.00,5.00"
					( Origin gBackEnd )
				)
				( attribute "BONDPAD_TO_LINE_SPACING" "5.00,5.00,5.00,5.00,5.00,5.00,5.00,5.00,5.00,5.00,5.00,5.00,5.00,5.00"
					( Origin gBackEnd )
				)
				( attribute "BONDPAD_TO_SHAPE_SPACING" "5.00,5.00,5.00,5.00,5.00,5.00,5.00,5.00,5.00,5.00,5.00,5.00,5.00,5.00"
					( Origin gBackEnd )
				)
				( attribute "LINE_TO_LINE_SPACING" "4.00,4.00,4.00,4.00,4.00,4.00,4.00,4.00,4.00,4.00,4.00,4.00,4.00,4.00"
					( Origin gBackEnd )
				)
				( attribute "LINE_TO_SHAPE_SPACING" "10.00,10.00,10.00,10.00,10.00,10.00,10.00,10.00,10.00,10.00,10.00,10.00,10.00,10.00"
					( Origin gBackEnd )
				)
				( attribute "SHAPE_TO_SHAPE_SPACING" "10.00,10.00,10.00,10.00,10.00,10.00,10.00,10.00,10.00,10.00,10.00,10.00,10.00,10.00"
					( Origin gBackEnd )
				)
				( attribute "HOLE_TO_PIN_SPACING" "8.00,8.00,8.00,8.00,8.00,8.00,8.00,8.00,8.00,8.00,8.00,8.00,8.00,8.00"
					( Origin gBackEnd )
				)
				( attribute "HOLE_TO_VIA_SPACING" "8.00,8.00,8.00,8.00,8.00,8.00,8.00,8.00,8.00,8.00,8.00,8.00,8.00,8.00"
					( Origin gBackEnd )
				)
				( attribute "HOLE_TO_LINE_SPACING" "8.00,8.00,8.00,8.00,8.00,8.00,8.00,8.00,8.00,8.00,8.00,8.00,8.00,8.00"
					( Origin gBackEnd )
				)
				( attribute "HOLE_TO_SHAPE_SPACING" "8.00,8.00,8.00,8.00,8.00,8.00,8.00,8.00,8.00,8.00,8.00,8.00,8.00,8.00"
					( Origin gBackEnd )
				)
				( attribute "HOLE_TO_HOLE_SPACING" "8.00,8.00,8.00,8.00,8.00,8.00,8.00,8.00,8.00,8.00,8.00,8.00,8.00,8.00"
					( Origin gBackEnd )
				)
				( attribute "MVIA_TO_MVIA_SPACING" "5.00,5.00,5.00,5.00,5.00,5.00,5.00,5.00,5.00,5.00,5.00,5.00,5.00,5.00"
					( Origin gBackEnd )
				)
				( attribute "MVIA_TO_THRUPIN_SPACING" "5.00,5.00,5.00,5.00,5.00,5.00,5.00,5.00,5.00,5.00,5.00,5.00,5.00,5.00"
					( Origin gBackEnd )
				)
				( attribute "MVIA_TO_SMDPIN_SPACING" "5.00,5.00,5.00,5.00,5.00,5.00,5.00,5.00,5.00,5.00,5.00,5.00,5.00,5.00"
					( Origin gBackEnd )
				)
				( attribute "MVIA_TO_THRUVIA_SPACING" "5.00,5.00,5.00,5.00,5.00,5.00,5.00,5.00,5.00,5.00,5.00,5.00,5.00,5.00"
					( Origin gBackEnd )
				)
				( attribute "MVIA_TO_BBV_SPACING" "5.00,5.00,5.00,5.00,5.00,5.00,5.00,5.00,5.00,5.00,5.00,5.00,5.00,5.00"
					( Origin gBackEnd )
				)
				( attribute "MVIA_TO_LINE_SPACING" "5.00,5.00,5.00,5.00,5.00,5.00,5.00,5.00,5.00,5.00,5.00,5.00,5.00,5.00"
					( Origin gBackEnd )
				)
				( attribute "MVIA_TO_SHAPE_SPACING" "5.00,5.00,5.00,5.00,5.00,5.00,5.00,5.00,5.00,5.00,5.00,5.00,5.00,5.00"
					( Origin gBackEnd )
				)
				( attribute "MVIA_TO_TESTPIN_SPACING" "5.00,5.00,5.00,5.00,5.00,5.00,5.00,5.00,5.00,5.00,5.00,5.00,5.00,5.00"
					( Origin gBackEnd )
				)
				( attribute "MVIA_TO_TESTVIA_SPACING" "5.00,5.00,5.00,5.00,5.00,5.00,5.00,5.00,5.00,5.00,5.00,5.00,5.00,5.00"
					( Origin gBackEnd )
				)
				( attribute "BONDPAD_TO_MVIA_SPACING" "5.00,5.00,5.00,5.00,5.00,5.00,5.00,5.00,5.00,5.00,5.00,5.00,5.00,5.00"
					( Origin gBackEnd )
				)
				( attribute "MIN_BVIA_GAP" "5.00"
					( Origin gBackEnd )
				)
				( attribute "BONDPAD_TO_BONDPAD_DIFFP_SPC" "5.00,5.00,5.00,5.00,5.00,5.00,5.00,5.00,5.00,5.00,5.00,5.00,5.00,5.00"
					( Origin gBackEnd )
				)
				( objectStatus "BMC_MEM" )
			)
			( spacingCSet "@sapphirecity_baseboard_lib.sapphirecity_baseboard(sch_1):\2H_SL_5H_MS\"
				( attribute "THRUPIN_TO_THRUPIN_SPACING" "5.00,5.00,5.00,5.00,5.00,5.00,5.00,5.00,5.00,5.00,5.00,5.00,5.00,5.00"
					( Origin gBackEnd )
				)
				( attribute "THRUPIN_TO_SMDPIN_SPACING" "5.00,5.00,5.00,5.00,5.00,5.00,5.00,5.00,5.00,5.00,5.00,5.00,5.00,5.00"
					( Origin gBackEnd )
				)
				( attribute "TESTPIN_TO_THRUPIN_SPACING" "5.00,5.00,5.00,5.00,5.00,5.00,5.00,5.00,5.00,5.00,5.00,5.00,5.00,5.00"
					( Origin gBackEnd )
				)
				( attribute "THRUPIN_TO_THRUVIA_SPACING" "5.00,5.00,5.00,5.00,5.00,5.00,5.00,5.00,5.00,5.00,5.00,5.00,5.00,5.00"
					( Origin gBackEnd )
				)
				( attribute "TESTVIA_TO_THRUPIN_SPACING" "5.00,5.00,5.00,5.00,5.00,5.00,5.00,5.00,5.00,5.00,5.00,5.00,5.00,5.00"
					( Origin gBackEnd )
				)
				( attribute "BBV_TO_THRUPIN_SPACING" "5.00,5.00,5.00,5.00,5.00,5.00,5.00,5.00,5.00,5.00,5.00,5.00,5.00,5.00"
					( Origin gBackEnd )
				)
				( attribute "THRUPIN_TO_BONDPAD_SPACING" "5.00,5.00,5.00,5.00,5.00,5.00,5.00,5.00,5.00,5.00,5.00,5.00,5.00,5.00"
					( Origin gBackEnd )
				)
				( attribute "LINE_TO_THRUPIN_SPACING" "5.00,4.00,4.00,4.00,4.00,4.00,4.00,4.00,4.00,4.00,4.00,4.00,4.00,5.00"
					( Origin gBackEnd )
				)
				( attribute "THRUPIN_TO_SHAPE_SPACING" "5.00,5.00,5.00,5.00,5.00,5.00,5.00,5.00,5.00,5.00,5.00,5.00,5.00,5.00"
					( Origin gBackEnd )
				)
				( attribute "SMDPIN_TO_SMDPIN_SPACING" "5.00,5.00,5.00,5.00,5.00,5.00,5.00,5.00,5.00,5.00,5.00,5.00,5.00,5.00"
					( Origin gBackEnd )
				)
				( attribute "SMDPIN_TO_TESTPIN_SPACING" "5.00,5.00,5.00,5.00,5.00,5.00,5.00,5.00,5.00,5.00,5.00,5.00,5.00,25.00"
					( Origin gBackEnd )
				)
				( attribute "SMDPIN_TO_THRUVIA_SPACING" "5.00,5.00,5.00,5.00,5.00,5.00,5.00,5.00,5.00,5.00,5.00,5.00,5.00,5.00"
					( Origin gBackEnd )
				)
				( attribute "SMDPIN_TO_TESTVIA_SPACING" "5.00,5.00,5.00,5.00,5.00,5.00,5.00,5.00,5.00,5.00,5.00,5.00,5.00,5.00"
					( Origin gBackEnd )
				)
				( attribute "BBV_TO_SMDPIN_SPACING" "5.00,5.00,5.00,5.00,5.00,5.00,5.00,5.00,5.00,5.00,5.00,5.00,5.00,5.00"
					( Origin gBackEnd )
				)
				( attribute "SMDPIN_TO_BONDPAD_SPACING" "5.00,5.00,5.00,5.00,5.00,5.00,5.00,5.00,5.00,5.00,5.00,5.00,5.00,5.00"
					( Origin gBackEnd )
				)
				( attribute "LINE_TO_SMDPIN_SPACING" "4.50,4.50,4.50,4.50,4.50,4.50,4.50,4.50,4.50,4.50,4.50,4.50,4.50,4.50"
					( Origin gBackEnd )
				)
				( attribute "SHAPE_TO_SMDPIN_SPACING" "5.00,5.00,5.00,5.00,5.00,5.00,5.00,5.00,5.00,5.00,5.00,5.00,5.00,5.00"
					( Origin gBackEnd )
				)
				( attribute "TESTPIN_TO_TESTPIN_SPACING" "5.00,5.00,5.00,5.00,5.00,5.00,5.00,5.00,5.00,5.00,5.00,5.00,5.00,5.00"
					( Origin gBackEnd )
				)
				( attribute "TESTPIN_TO_THRUVIA_SPACING" "5.00,5.00,5.00,5.00,5.00,5.00,5.00,5.00,5.00,5.00,5.00,5.00,5.00,5.00"
					( Origin gBackEnd )
				)
				( attribute "TESTPIN_TO_TESTVIA_SPACING" "5.00,5.00,5.00,5.00,5.00,5.00,5.00,5.00,5.00,5.00,5.00,5.00,5.00,5.00"
					( Origin gBackEnd )
				)
				( attribute "BBV_TO_TESTPIN_SPACING" "5.00,5.00,5.00,5.00,5.00,5.00,5.00,5.00,5.00,5.00,5.00,5.00,5.00,5.00"
					( Origin gBackEnd )
				)
				( attribute "BONDPAD_TO_TESTPIN_SPACING" "5.00,5.00,5.00,5.00,5.00,5.00,5.00,5.00,5.00,5.00,5.00,5.00,5.00,5.00"
					( Origin gBackEnd )
				)
				( attribute "LINE_TO_TESTPIN_SPACING" "5.00,4.00,4.00,4.00,4.00,4.00,4.00,4.00,4.00,4.00,4.00,4.00,4.00,5.00"
					( Origin gBackEnd )
				)
				( attribute "SHAPE_TO_TESTPIN_SPACING" "5.00,5.00,5.00,5.00,5.00,5.00,5.00,5.00,5.00,5.00,5.00,5.00,5.00,5.00"
					( Origin gBackEnd )
				)
				( attribute "THRUVIA_TO_THRUVIA_SPACING" "6.00,6.00,6.00,6.00,6.00,6.00,6.00,6.00,6.00,6.00,6.00,6.00,6.00,6.00"
					( Origin gBackEnd )
				)
				( attribute "TESTVIA_TO_THRUVIA_SPACING" "6.00,6.00,6.00,6.00,6.00,6.00,6.00,6.00,6.00,6.00,6.00,6.00,6.00,6.00"
					( Origin gBackEnd )
				)
				( attribute "BBV_TO_THRUVIA_SPACING" "5.00,5.00,5.00,5.00,5.00,5.00,5.00,5.00,5.00,5.00,5.00,5.00,5.00,5.00"
					( Origin gBackEnd )
				)
				( attribute "BONDPAD_TO_THRUVIA_SPACING" "5.00,5.00,5.00,5.00,5.00,5.00,5.00,5.00,5.00,5.00,5.00,5.00,5.00,5.00"
					( Origin gBackEnd )
				)
				( attribute "LINE_TO_THRUVIA_SPACING" "4.50,4.00,4.00,4.00,4.00,4.00,4.00,4.00,4.00,4.00,4.00,4.00,4.00,4.50"
					( Origin gBackEnd )
				)
				( attribute "SHAPE_TO_THRUVIA_SPACING" "5.00,5.00,5.00,5.00,5.00,5.00,5.00,5.00,5.00,5.00,5.00,5.00,5.00,5.00"
					( Origin gBackEnd )
				)
				( attribute "TESTVIA_TO_TESTVIA_SPACING" "6.00,6.00,6.00,6.00,6.00,6.00,6.00,6.00,6.00,6.00,6.00,6.00,6.00,6.00"
					( Origin gBackEnd )
				)
				( attribute "BBV_TO_TESTVIA_SPACING" "5.00,5.00,5.00,5.00,5.00,5.00,5.00,5.00,5.00,5.00,5.00,5.00,5.00,5.00"
					( Origin gBackEnd )
				)
				( attribute "BONDPAD_TO_TESTVIA_SPACING" "5.00,5.00,5.00,5.00,5.00,5.00,5.00,5.00,5.00,5.00,5.00,5.00,5.00,5.00"
					( Origin gBackEnd )
				)
				( attribute "LINE_TO_TESTVIA_SPACING" "4.50,4.00,4.00,4.00,4.00,4.00,4.00,4.00,4.00,4.00,4.00,4.00,4.00,4.50"
					( Origin gBackEnd )
				)
				( attribute "SHAPE_TO_TESTVIA_SPACING" "5.00,5.00,5.00,5.00,5.00,5.00,5.00,5.00,5.00,5.00,5.00,5.00,5.00,5.00"
					( Origin gBackEnd )
				)
				( attribute "BBV_TO_BBV_SPACING" "5.00,5.00,5.00,5.00,5.00,5.00,5.00,5.00,5.00,5.00,5.00,5.00,5.00,5.00"
					( Origin gBackEnd )
				)
				( attribute "BONDPAD_TO_BBV_SPACING" "5.00,5.00,5.00,5.00,5.00,5.00,5.00,5.00,5.00,5.00,5.00,5.00,5.00,5.00"
					( Origin gBackEnd )
				)
				( attribute "BBV_TO_LINE_SPACING" "5.00,5.00,5.00,5.00,5.00,5.00,5.00,5.00,5.00,5.00,5.00,5.00,5.00,5.00"
					( Origin gBackEnd )
				)
				( attribute "BBV_TO_SHAPE_SPACING" "5.00,5.00,5.00,5.00,5.00,5.00,5.00,5.00,5.00,5.00,5.00,5.00,5.00,5.00"
					( Origin gBackEnd )
				)
				( attribute "BONDPAD_TO_BONDPAD_SPACING" "5.00,5.00,5.00,5.00,5.00,5.00,5.00,5.00,5.00,5.00,5.00,5.00,5.00,5.00"
					( Origin gBackEnd )
				)
				( attribute "BONDPAD_TO_LINE_SPACING" "5.00,5.00,5.00,5.00,5.00,5.00,5.00,5.00,5.00,5.00,5.00,5.00,5.00,5.00"
					( Origin gBackEnd )
				)
				( attribute "BONDPAD_TO_SHAPE_SPACING" "5.00,5.00,5.00,5.00,5.00,5.00,5.00,5.00,5.00,5.00,5.00,5.00,5.00,5.00"
					( Origin gBackEnd )
				)
				( attribute "LINE_TO_LINE_SPACING" "13.35,6.00,6.00,6.00,6.00,6.00,6.00,6.00,6.00,6.00,6.00,6.00,6.00,13.35"
					( Origin gBackEnd )
				)
				( attribute "LINE_TO_SHAPE_SPACING" "10.00,10.00,10.00,10.00,10.00,10.00,10.00,10.00,10.00,10.00,10.00,10.00,10.00,10.00"
					( Origin gBackEnd )
				)
				( attribute "SHAPE_TO_SHAPE_SPACING" "10.00,10.00,10.00,10.00,10.00,10.00,10.00,10.00,10.00,10.00,10.00,10.00,10.00,10.00"
					( Origin gBackEnd )
				)
				( attribute "HOLE_TO_PIN_SPACING" "8.00,8.00,8.00,8.00,8.00,8.00,8.00,8.00,8.00,8.00,8.00,8.00,8.00,8.00"
					( Origin gBackEnd )
				)
				( attribute "HOLE_TO_VIA_SPACING" "8.00,8.00,8.00,8.00,8.00,8.00,8.00,8.00,8.00,8.00,8.00,8.00,8.00,8.00"
					( Origin gBackEnd )
				)
				( attribute "HOLE_TO_LINE_SPACING" "8.00,8.00,8.00,8.00,8.00,8.00,8.00,8.00,8.00,8.00,8.00,8.00,8.00,8.00"
					( Origin gBackEnd )
				)
				( attribute "HOLE_TO_SHAPE_SPACING" "8.00,8.00,8.00,8.00,8.00,8.00,8.00,8.00,8.00,8.00,8.00,8.00,8.00,8.00"
					( Origin gBackEnd )
				)
				( attribute "HOLE_TO_HOLE_SPACING" "8.00,8.00,8.00,8.00,8.00,8.00,8.00,8.00,8.00,8.00,8.00,8.00,8.00,8.00"
					( Origin gBackEnd )
				)
				( attribute "MVIA_TO_MVIA_SPACING" "5.00,5.00,5.00,5.00,5.00,5.00,5.00,5.00,5.00,5.00,5.00,5.00,5.00,5.00"
					( Origin gBackEnd )
				)
				( attribute "MVIA_TO_THRUPIN_SPACING" "5.00,5.00,5.00,5.00,5.00,5.00,5.00,5.00,5.00,5.00,5.00,5.00,5.00,5.00"
					( Origin gBackEnd )
				)
				( attribute "MVIA_TO_SMDPIN_SPACING" "5.00,5.00,5.00,5.00,5.00,5.00,5.00,5.00,5.00,5.00,5.00,5.00,5.00,5.00"
					( Origin gBackEnd )
				)
				( attribute "MVIA_TO_THRUVIA_SPACING" "5.00,5.00,5.00,5.00,5.00,5.00,5.00,5.00,5.00,5.00,5.00,5.00,5.00,5.00"
					( Origin gBackEnd )
				)
				( attribute "MVIA_TO_BBV_SPACING" "5.00,5.00,5.00,5.00,5.00,5.00,5.00,5.00,5.00,5.00,5.00,5.00,5.00,5.00"
					( Origin gBackEnd )
				)
				( attribute "MVIA_TO_LINE_SPACING" "5.00,5.00,5.00,5.00,5.00,5.00,5.00,5.00,5.00,5.00,5.00,5.00,5.00,5.00"
					( Origin gBackEnd )
				)
				( attribute "MVIA_TO_SHAPE_SPACING" "5.00,5.00,5.00,5.00,5.00,5.00,5.00,5.00,5.00,5.00,5.00,5.00,5.00,5.00"
					( Origin gBackEnd )
				)
				( attribute "MVIA_TO_TESTPIN_SPACING" "5.00,5.00,5.00,5.00,5.00,5.00,5.00,5.00,5.00,5.00,5.00,5.00,5.00,5.00"
					( Origin gBackEnd )
				)
				( attribute "MVIA_TO_TESTVIA_SPACING" "5.00,5.00,5.00,5.00,5.00,5.00,5.00,5.00,5.00,5.00,5.00,5.00,5.00,5.00"
					( Origin gBackEnd )
				)
				( attribute "BONDPAD_TO_MVIA_SPACING" "5.00,5.00,5.00,5.00,5.00,5.00,5.00,5.00,5.00,5.00,5.00,5.00,5.00,5.00"
					( Origin gBackEnd )
				)
				( attribute "MIN_BVIA_GAP" "5.00"
					( Origin gBackEnd )
				)
				( attribute "BONDPAD_TO_BONDPAD_DIFFP_SPC" "5.00,5.00,5.00,5.00,5.00,5.00,5.00,5.00,5.00,5.00,5.00,5.00,5.00,5.00"
					( Origin gBackEnd )
				)
				( objectStatus "5H_US_&_2H_SL" )
			)
			( spacingCSet "@sapphirecity_baseboard_lib.sapphirecity_baseboard(sch_1):\DDR4_DIMM\"
				( attribute "THRUPIN_TO_THRUPIN_SPACING" "5.00,5.00,5.00,5.00,5.00,5.00,5.00,5.00,5.00,5.00,5.00,5.00,5.00,5.00"
					( Origin gBackEnd )
				)
				( attribute "THRUPIN_TO_SMDPIN_SPACING" "5.00,5.00,5.00,5.00,5.00,5.00,5.00,5.00,5.00,5.00,5.00,5.00,5.00,5.00"
					( Origin gBackEnd )
				)
				( attribute "TESTPIN_TO_THRUPIN_SPACING" "5.00,5.00,5.00,5.00,5.00,5.00,5.00,5.00,5.00,5.00,5.00,5.00,5.00,5.00"
					( Origin gBackEnd )
				)
				( attribute "THRUPIN_TO_THRUVIA_SPACING" "10.00,10.00,10.00,10.00,10.00,10.00,10.00,10.00,10.00,10.00,10.00,10.00,10.00,10.00"
					( Origin gBackEnd )
				)
				( attribute "TESTVIA_TO_THRUPIN_SPACING" "5.00,5.00,5.00,5.00,5.00,5.00,5.00,5.00,5.00,5.00,5.00,5.00,5.00,5.00"
					( Origin gBackEnd )
				)
				( attribute "BBV_TO_THRUPIN_SPACING" "5.00,5.00,5.00,5.00,5.00,5.00,5.00,5.00,5.00,5.00,5.00,5.00,5.00,5.00"
					( Origin gBackEnd )
				)
				( attribute "THRUPIN_TO_BONDPAD_SPACING" "5.00,5.00,5.00,5.00,5.00,5.00,5.00,5.00,5.00,5.00,5.00,5.00,5.00,5.00"
					( Origin gBackEnd )
				)
				( attribute "LINE_TO_THRUPIN_SPACING" "4.50,4.00,4.00,4.00,4.00,4.00,4.00,4.00,4.00,4.00,4.00,4.00,4.00,4.50"
					( Origin gBackEnd )
				)
				( attribute "THRUPIN_TO_SHAPE_SPACING" "5.00,4.00,4.00,4.00,4.00,4.00,4.00,4.00,4.00,4.00,4.00,4.00,4.00,5.00"
					( Origin gBackEnd )
				)
				( attribute "SMDPIN_TO_SMDPIN_SPACING" "5.00,5.00,5.00,5.00,5.00,5.00,5.00,5.00,5.00,5.00,5.00,5.00,5.00,5.00"
					( Origin gBackEnd )
				)
				( attribute "SMDPIN_TO_TESTPIN_SPACING" "5.00,5.00,5.00,5.00,5.00,5.00,5.00,5.00,5.00,5.00,5.00,5.00,5.00,25.00"
					( Origin gBackEnd )
				)
				( attribute "SMDPIN_TO_THRUVIA_SPACING" "5.00,5.00,5.00,5.00,5.00,5.00,5.00,5.00,5.00,5.00,5.00,5.00,5.00,5.00"
					( Origin gBackEnd )
				)
				( attribute "SMDPIN_TO_TESTVIA_SPACING" "5.00,5.00,5.00,5.00,5.00,5.00,5.00,5.00,5.00,5.00,5.00,5.00,5.00,5.00"
					( Origin gBackEnd )
				)
				( attribute "BBV_TO_SMDPIN_SPACING" "5.00,5.00,5.00,5.00,5.00,5.00,5.00,5.00,5.00,5.00,5.00,5.00,5.00,5.00"
					( Origin gBackEnd )
				)
				( attribute "SMDPIN_TO_BONDPAD_SPACING" "5.00,5.00,5.00,5.00,5.00,5.00,5.00,5.00,5.00,5.00,5.00,5.00,5.00,5.00"
					( Origin gBackEnd )
				)
				( attribute "LINE_TO_SMDPIN_SPACING" "4.50,4.50,4.50,4.50,4.50,4.50,4.50,4.50,4.50,4.50,4.50,4.50,4.50,4.50"
					( Origin gBackEnd )
				)
				( attribute "SHAPE_TO_SMDPIN_SPACING" "5.00,5.00,5.00,5.00,5.00,5.00,5.00,5.00,5.00,5.00,5.00,5.00,5.00,5.00"
					( Origin gBackEnd )
				)
				( attribute "TESTPIN_TO_TESTPIN_SPACING" "5.00,5.00,5.00,5.00,5.00,5.00,5.00,5.00,5.00,5.00,5.00,5.00,5.00,5.00"
					( Origin gBackEnd )
				)
				( attribute "TESTPIN_TO_THRUVIA_SPACING" "5.00,5.00,5.00,5.00,5.00,5.00,5.00,5.00,5.00,5.00,5.00,5.00,5.00,5.00"
					( Origin gBackEnd )
				)
				( attribute "TESTPIN_TO_TESTVIA_SPACING" "5.00,5.00,5.00,5.00,5.00,5.00,5.00,5.00,5.00,5.00,5.00,5.00,5.00,5.00"
					( Origin gBackEnd )
				)
				( attribute "BBV_TO_TESTPIN_SPACING" "5.00,5.00,5.00,5.00,5.00,5.00,5.00,5.00,5.00,5.00,5.00,5.00,5.00,5.00"
					( Origin gBackEnd )
				)
				( attribute "BONDPAD_TO_TESTPIN_SPACING" "5.00,5.00,5.00,5.00,5.00,5.00,5.00,5.00,5.00,5.00,5.00,5.00,5.00,5.00"
					( Origin gBackEnd )
				)
				( attribute "LINE_TO_TESTPIN_SPACING" "4.50,4.00,4.00,4.00,4.00,4.00,4.00,4.00,4.00,4.00,4.00,4.00,4.00,4.50"
					( Origin gBackEnd )
				)
				( attribute "SHAPE_TO_TESTPIN_SPACING" "5.00,4.00,4.00,4.00,4.00,4.00,4.00,4.00,4.00,4.00,4.00,4.00,4.00,5.00"
					( Origin gBackEnd )
				)
				( attribute "THRUVIA_TO_THRUVIA_SPACING" "6.00,6.00,6.00,6.00,6.00,6.00,6.00,6.00,6.00,6.00,6.00,6.00,6.00,6.00"
					( Origin gBackEnd )
				)
				( attribute "TESTVIA_TO_THRUVIA_SPACING" "6.00,6.00,6.00,6.00,6.00,6.00,6.00,6.00,6.00,6.00,6.00,6.00,6.00,6.00"
					( Origin gBackEnd )
				)
				( attribute "BBV_TO_THRUVIA_SPACING" "5.00,5.00,5.00,5.00,5.00,5.00,5.00,5.00,5.00,5.00,5.00,5.00,5.00,5.00"
					( Origin gBackEnd )
				)
				( attribute "BONDPAD_TO_THRUVIA_SPACING" "5.00,5.00,5.00,5.00,5.00,5.00,5.00,5.00,5.00,5.00,5.00,5.00,5.00,5.00"
					( Origin gBackEnd )
				)
				( attribute "LINE_TO_THRUVIA_SPACING" "4.50,4.00,4.00,4.00,4.00,4.00,4.00,4.00,4.00,4.00,4.00,4.00,4.00,4.50"
					( Origin gBackEnd )
				)
				( attribute "SHAPE_TO_THRUVIA_SPACING" "5.00,4.00,5.00,4.00,5.00,4.00,5.00,5.00,4.00,5.00,5.00,4.00,5.00,5.00"
					( Origin gBackEnd )
				)
				( attribute "TESTVIA_TO_TESTVIA_SPACING" "6.00,6.00,6.00,6.00,6.00,6.00,6.00,6.00,6.00,6.00,6.00,6.00,6.00,6.00"
					( Origin gBackEnd )
				)
				( attribute "BBV_TO_TESTVIA_SPACING" "5.00,5.00,5.00,5.00,5.00,5.00,5.00,5.00,5.00,5.00,5.00,5.00,5.00,5.00"
					( Origin gBackEnd )
				)
				( attribute "BONDPAD_TO_TESTVIA_SPACING" "5.00,5.00,5.00,5.00,5.00,5.00,5.00,5.00,5.00,5.00,5.00,5.00,5.00,5.00"
					( Origin gBackEnd )
				)
				( attribute "LINE_TO_TESTVIA_SPACING" "4.50,4.00,4.00,4.00,4.00,4.00,4.00,4.00,4.00,4.00,4.00,4.00,4.00,4.50"
					( Origin gBackEnd )
				)
				( attribute "SHAPE_TO_TESTVIA_SPACING" "5.00,4.00,5.00,4.00,5.00,4.00,5.00,5.00,4.00,5.00,4.00,5.00,4.00,5.00"
					( Origin gBackEnd )
				)
				( attribute "BBV_TO_BBV_SPACING" "5.00,5.00,5.00,5.00,5.00,5.00,5.00,5.00,5.00,5.00,5.00,5.00,5.00,5.00"
					( Origin gBackEnd )
				)
				( attribute "BONDPAD_TO_BBV_SPACING" "5.00,5.00,5.00,5.00,5.00,5.00,5.00,5.00,5.00,5.00,5.00,5.00,5.00,5.00"
					( Origin gBackEnd )
				)
				( attribute "BBV_TO_LINE_SPACING" "5.00,5.00,5.00,5.00,5.00,5.00,5.00,5.00,5.00,5.00,5.00,5.00,5.00,5.00"
					( Origin gBackEnd )
				)
				( attribute "BBV_TO_SHAPE_SPACING" "5.00,5.00,5.00,5.00,5.00,5.00,5.00,5.00,5.00,5.00,5.00,5.00,5.00,5.00"
					( Origin gBackEnd )
				)
				( attribute "BONDPAD_TO_BONDPAD_SPACING" "5.00,5.00,5.00,5.00,5.00,5.00,5.00,5.00,5.00,5.00,5.00,5.00,5.00,5.00"
					( Origin gBackEnd )
				)
				( attribute "BONDPAD_TO_LINE_SPACING" "5.00,5.00,5.00,5.00,5.00,5.00,5.00,5.00,5.00,5.00,5.00,5.00,5.00,5.00"
					( Origin gBackEnd )
				)
				( attribute "BONDPAD_TO_SHAPE_SPACING" "5.00,5.00,5.00,5.00,5.00,5.00,5.00,5.00,5.00,5.00,5.00,5.00,5.00,5.00"
					( Origin gBackEnd )
				)
				( attribute "LINE_TO_LINE_SPACING" "6.92,4.92,4.92,4.92,4.92,4.92,4.92,4.92,4.92,4.92,4.92,4.92,4.92,6.92"
					( Origin gBackEnd )
				)
				( attribute "LINE_TO_SHAPE_SPACING" "10.00,10.00,10.00,10.00,10.00,10.00,10.00,10.00,10.00,10.00,10.00,10.00,10.00,10.00"
					( Origin gBackEnd )
				)
				( attribute "SHAPE_TO_SHAPE_SPACING" "10.00,10.00,10.00,10.00,10.00,10.00,10.00,10.00,10.00,10.00,10.00,10.00,10.00,10.00"
					( Origin gBackEnd )
				)
				( attribute "HOLE_TO_PIN_SPACING" "8.00,8.00,8.00,8.00,8.00,8.00,8.00,8.00,8.00,8.00,8.00,8.00,8.00,8.00"
					( Origin gBackEnd )
				)
				( attribute "HOLE_TO_VIA_SPACING" "8.00,8.00,8.00,8.00,8.00,8.00,8.00,8.00,8.00,8.00,8.00,8.00,8.00,8.00"
					( Origin gBackEnd )
				)
				( attribute "HOLE_TO_LINE_SPACING" "8.00,8.00,8.00,8.00,8.00,8.00,8.00,8.00,8.00,8.00,8.00,8.00,8.00,8.00"
					( Origin gBackEnd )
				)
				( attribute "HOLE_TO_SHAPE_SPACING" "8.00,8.00,8.00,8.00,8.00,8.00,8.00,8.00,8.00,8.00,8.00,8.00,8.00,8.00"
					( Origin gBackEnd )
				)
				( attribute "HOLE_TO_HOLE_SPACING" "8.00,8.00,8.00,8.00,8.00,8.00,8.00,8.00,8.00,8.00,8.00,8.00,8.00,8.00"
					( Origin gBackEnd )
				)
				( attribute "MVIA_TO_MVIA_SPACING" "5.00,5.00,5.00,5.00,5.00,5.00,5.00,5.00,5.00,5.00,5.00,5.00,5.00,5.00"
					( Origin gBackEnd )
				)
				( attribute "MVIA_TO_THRUPIN_SPACING" "5.00,5.00,5.00,5.00,5.00,5.00,5.00,5.00,5.00,5.00,5.00,5.00,5.00,5.00"
					( Origin gBackEnd )
				)
				( attribute "MVIA_TO_SMDPIN_SPACING" "5.00,5.00,5.00,5.00,5.00,5.00,5.00,5.00,5.00,5.00,5.00,5.00,5.00,5.00"
					( Origin gBackEnd )
				)
				( attribute "MVIA_TO_THRUVIA_SPACING" "5.00,5.00,5.00,5.00,5.00,5.00,5.00,5.00,5.00,5.00,5.00,5.00,5.00,5.00"
					( Origin gBackEnd )
				)
				( attribute "MVIA_TO_BBV_SPACING" "5.00,5.00,5.00,5.00,5.00,5.00,5.00,5.00,5.00,5.00,5.00,5.00,5.00,5.00"
					( Origin gBackEnd )
				)
				( attribute "MVIA_TO_LINE_SPACING" "5.00,5.00,5.00,5.00,5.00,5.00,5.00,5.00,5.00,5.00,5.00,5.00,5.00,5.00"
					( Origin gBackEnd )
				)
				( attribute "MVIA_TO_SHAPE_SPACING" "5.00,5.00,5.00,5.00,5.00,5.00,5.00,5.00,5.00,5.00,5.00,5.00,5.00,5.00"
					( Origin gBackEnd )
				)
				( attribute "MVIA_TO_TESTPIN_SPACING" "5.00,5.00,5.00,5.00,5.00,5.00,5.00,5.00,5.00,5.00,5.00,5.00,5.00,5.00"
					( Origin gBackEnd )
				)
				( attribute "MVIA_TO_TESTVIA_SPACING" "5.00,5.00,5.00,5.00,5.00,5.00,5.00,5.00,5.00,5.00,5.00,5.00,5.00,5.00"
					( Origin gBackEnd )
				)
				( attribute "BONDPAD_TO_MVIA_SPACING" "5.00,5.00,5.00,5.00,5.00,5.00,5.00,5.00,5.00,5.00,5.00,5.00,5.00,5.00"
					( Origin gBackEnd )
				)
				( attribute "MIN_BVIA_GAP" "5.00"
					( Origin gBackEnd )
				)
				( attribute "BONDPAD_TO_BONDPAD_DIFFP_SPC" "5.00,5.00,5.00,5.00,5.00,5.00,5.00,5.00,5.00,5.00,5.00,5.00,5.00,5.00"
					( Origin gBackEnd )
				)
				( objectStatus "DDR4_DIMM" )
			)
			( spacingCSet "@sapphirecity_baseboard_lib.sapphirecity_baseboard(sch_1):\BGA\"
				( attribute "THRUPIN_TO_THRUPIN_SPACING" "5.00,5.00,5.00,5.00,5.00,5.00,5.00,5.00,5.00,5.00,5.00,5.00,5.00,5.00"
					( Origin gBackEnd )
				)
				( attribute "THRUPIN_TO_SMDPIN_SPACING" "5.00,5.00,5.00,5.00,5.00,5.00,5.00,5.00,5.00,5.00,5.00,5.00,5.00,5.00"
					( Origin gBackEnd )
				)
				( attribute "TESTPIN_TO_THRUPIN_SPACING" "5.00,5.00,5.00,5.00,5.00,5.00,5.00,5.00,5.00,5.00,5.00,5.00,5.00,5.00"
					( Origin gBackEnd )
				)
				( attribute "THRUPIN_TO_THRUVIA_SPACING" "6.00,6.00,6.00,6.00,6.00,6.00,6.00,6.00,6.00,6.00,6.00,6.00,6.00,6.00"
					( Origin gBackEnd )
				)
				( attribute "TESTVIA_TO_THRUPIN_SPACING" "6.00,6.00,6.00,6.00,6.00,6.00,6.00,6.00,6.00,6.00,6.00,6.00,6.00,6.00"
					( Origin gBackEnd )
				)
				( attribute "BBV_TO_THRUPIN_SPACING" "5.00,5.00,5.00,5.00,5.00,5.00,5.00,5.00,5.00,5.00,5.00,5.00,5.00,5.00"
					( Origin gBackEnd )
				)
				( attribute "THRUPIN_TO_BONDPAD_SPACING" "5.00,5.00,5.00,5.00,5.00,5.00,5.00,5.00,5.00,5.00,5.00,5.00,5.00,5.00"
					( Origin gBackEnd )
				)
				( attribute "LINE_TO_THRUPIN_SPACING" "4.50,4.00,4.00,4.00,4.00,4.00,4.00,4.00,4.00,4.00,4.00,4.00,4.00,4.50"
					( Origin gBackEnd )
				)
				( attribute "THRUPIN_TO_SHAPE_SPACING" "5.00,5.00,5.00,5.00,5.00,5.00,5.00,5.00,5.00,5.00,5.00,5.00,5.00,5.00"
					( Origin gBackEnd )
				)
				( attribute "SMDPIN_TO_SMDPIN_SPACING" "5.00,5.00,5.00,5.00,5.00,5.00,5.00,5.00,5.00,5.00,5.00,5.00,5.00,5.00"
					( Origin gBackEnd )
				)
				( attribute "SMDPIN_TO_TESTPIN_SPACING" "5.00,5.00,5.00,5.00,5.00,5.00,5.00,5.00,5.00,5.00,5.00,5.00,5.00,5.00"
					( Origin gBackEnd )
				)
				( attribute "SMDPIN_TO_THRUVIA_SPACING" "4.00,4.00,4.00,4.00,4.00,4.00,4.00,4.00,4.00,4.00,4.00,4.00,4.00,4.00"
					( Origin gBackEnd )
				)
				( attribute "SMDPIN_TO_TESTVIA_SPACING" "4.00,4.00,4.00,4.00,4.00,4.00,4.00,4.00,4.00,4.00,4.00,4.00,4.00,4.00"
					( Origin gBackEnd )
				)
				( attribute "BBV_TO_SMDPIN_SPACING" "5.00,5.00,5.00,5.00,5.00,5.00,5.00,5.00,5.00,5.00,5.00,5.00,5.00,5.00"
					( Origin gBackEnd )
				)
				( attribute "SMDPIN_TO_BONDPAD_SPACING" "5.00,5.00,5.00,5.00,5.00,5.00,5.00,5.00,5.00,5.00,5.00,5.00,5.00,5.00"
					( Origin gBackEnd )
				)
				( attribute "LINE_TO_SMDPIN_SPACING" "4.50,4.50,4.50,4.50,4.50,4.50,4.50,4.50,4.50,4.50,4.50,4.50,4.50,4.50"
					( Origin gBackEnd )
				)
				( attribute "SHAPE_TO_SMDPIN_SPACING" "5.00,5.00,5.00,5.00,5.00,5.00,5.00,5.00,5.00,5.00,5.00,5.00,5.00,5.00"
					( Origin gBackEnd )
				)
				( attribute "TESTPIN_TO_TESTPIN_SPACING" "5.00,5.00,5.00,5.00,5.00,5.00,5.00,5.00,5.00,5.00,5.00,5.00,5.00,5.00"
					( Origin gBackEnd )
				)
				( attribute "TESTPIN_TO_THRUVIA_SPACING" "6.00,6.00,6.00,6.00,6.00,6.00,6.00,6.00,6.00,6.00,6.00,6.00,6.00,6.00"
					( Origin gBackEnd )
				)
				( attribute "TESTPIN_TO_TESTVIA_SPACING" "6.00,6.00,6.00,6.00,6.00,6.00,6.00,6.00,6.00,6.00,6.00,6.00,6.00,6.00"
					( Origin gBackEnd )
				)
				( attribute "BBV_TO_TESTPIN_SPACING" "5.00,5.00,5.00,5.00,5.00,5.00,5.00,5.00,5.00,5.00,5.00,5.00,5.00,5.00"
					( Origin gBackEnd )
				)
				( attribute "BONDPAD_TO_TESTPIN_SPACING" "5.00,5.00,5.00,5.00,5.00,5.00,5.00,5.00,5.00,5.00,5.00,5.00,5.00,5.00"
					( Origin gBackEnd )
				)
				( attribute "LINE_TO_TESTPIN_SPACING" "4.50,4.50,4.50,4.50,4.50,4.50,4.50,4.50,4.50,4.50,4.50,4.50,4.50,4.50"
					( Origin gBackEnd )
				)
				( attribute "SHAPE_TO_TESTPIN_SPACING" "5.00,5.00,5.00,5.00,5.00,5.00,5.00,5.00,5.00,5.00,5.00,5.00,5.00,5.00"
					( Origin gBackEnd )
				)
				( attribute "THRUVIA_TO_THRUVIA_SPACING" "5.00,5.00,5.00,5.00,5.00,5.00,5.00,5.00,5.00,5.00,5.00,5.00,5.00,5.00"
					( Origin gBackEnd )
				)
				( attribute "TESTVIA_TO_THRUVIA_SPACING" "5.00,5.00,5.00,5.00,5.00,5.00,5.00,5.00,5.00,5.00,5.00,5.00,5.00,5.00"
					( Origin gBackEnd )
				)
				( attribute "BBV_TO_THRUVIA_SPACING" "5.00,5.00,5.00,5.00,5.00,5.00,5.00,5.00,5.00,5.00,5.00,5.00,5.00,5.00"
					( Origin gBackEnd )
				)
				( attribute "BONDPAD_TO_THRUVIA_SPACING" "5.00,5.00,5.00,5.00,5.00,5.00,5.00,5.00,5.00,5.00,5.00,5.00,5.00,5.00"
					( Origin gBackEnd )
				)
				( attribute "LINE_TO_THRUVIA_SPACING" "3.99,3.99,3.99,3.99,3.99,3.99,3.99,3.99,3.99,3.99,3.99,3.99,3.99,3.99"
					( Origin gBackEnd )
				)
				( attribute "SHAPE_TO_THRUVIA_SPACING" "4.50,4.00,4.00,4.00,4.00,4.00,4.00,4.00,4.00,4.00,4.00,4.00,4.00,4.50"
					( Origin gBackEnd )
				)
				( attribute "TESTVIA_TO_TESTVIA_SPACING" "6.00,6.00,6.00,6.00,6.00,6.00,6.00,6.00,6.00,6.00,6.00,6.00,6.00,6.00"
					( Origin gBackEnd )
				)
				( attribute "BBV_TO_TESTVIA_SPACING" "5.00,5.00,5.00,5.00,5.00,5.00,5.00,5.00,5.00,5.00,5.00,5.00,5.00,5.00"
					( Origin gBackEnd )
				)
				( attribute "BONDPAD_TO_TESTVIA_SPACING" "5.00,5.00,5.00,5.00,5.00,5.00,5.00,5.00,5.00,5.00,5.00,5.00,5.00,5.00"
					( Origin gBackEnd )
				)
				( attribute "LINE_TO_TESTVIA_SPACING" "4.49,4.49,4.49,4.49,4.49,4.49,4.49,4.49,4.49,4.49,4.49,4.49,4.49,4.49"
					( Origin gBackEnd )
				)
				( attribute "SHAPE_TO_TESTVIA_SPACING" "4.00,4.00,4.00,4.00,4.00,4.00,4.00,4.00,4.00,4.00,4.00,4.00,4.00,4.00"
					( Origin gBackEnd )
				)
				( attribute "BBV_TO_BBV_SPACING" "5.00,5.00,5.00,5.00,5.00,5.00,5.00,5.00,5.00,5.00,5.00,5.00,5.00,5.00"
					( Origin gBackEnd )
				)
				( attribute "BONDPAD_TO_BBV_SPACING" "5.00,5.00,5.00,5.00,5.00,5.00,5.00,5.00,5.00,5.00,5.00,5.00,5.00,5.00"
					( Origin gBackEnd )
				)
				( attribute "BBV_TO_LINE_SPACING" "5.00,5.00,5.00,5.00,5.00,5.00,5.00,5.00,5.00,5.00,5.00,5.00,5.00,5.00"
					( Origin gBackEnd )
				)
				( attribute "BBV_TO_SHAPE_SPACING" "5.00,5.00,5.00,5.00,5.00,5.00,5.00,5.00,5.00,5.00,5.00,5.00,5.00,5.00"
					( Origin gBackEnd )
				)
				( attribute "BONDPAD_TO_BONDPAD_SPACING" "5.00,5.00,5.00,5.00,5.00,5.00,5.00,5.00,5.00,5.00,5.00,5.00,5.00,5.00"
					( Origin gBackEnd )
				)
				( attribute "BONDPAD_TO_LINE_SPACING" "5.00,5.00,5.00,5.00,5.00,5.00,5.00,5.00,5.00,5.00,5.00,5.00,5.00,5.00"
					( Origin gBackEnd )
				)
				( attribute "BONDPAD_TO_SHAPE_SPACING" "5.00,5.00,5.00,5.00,5.00,5.00,5.00,5.00,5.00,5.00,5.00,5.00,5.00,5.00"
					( Origin gBackEnd )
				)
				( attribute "LINE_TO_LINE_SPACING" "3.99,4.00,3.99,4.00,3.99,4.00,4.00,4.00,4.00,3.99,4.00,3.99,4.00,3.99"
					( Origin gBackEnd )
				)
				( attribute "LINE_TO_SHAPE_SPACING" "4.50,5.00,5.00,5.00,5.00,5.00,5.00,5.00,5.00,5.00,5.00,5.00,5.00,4.50"
					( Origin gBackEnd )
				)
				( attribute "SHAPE_TO_SHAPE_SPACING" "10.00,10.00,10.00,10.00,10.00,10.00,10.00,10.00,10.00,10.00,10.00,10.00,10.00,10.00"
					( Origin gBackEnd )
				)
				( attribute "HOLE_TO_PIN_SPACING" "8.00,8.00,8.00,8.00,8.00,8.00,8.00,8.00,8.00,8.00,8.00,8.00,8.00,8.00"
					( Origin gBackEnd )
				)
				( attribute "HOLE_TO_VIA_SPACING" "8.00,8.00,8.00,8.00,8.00,8.00,8.00,8.00,8.00,8.00,8.00,8.00,8.00,8.00"
					( Origin gBackEnd )
				)
				( attribute "HOLE_TO_LINE_SPACING" "8.00,8.00,8.00,8.00,8.00,8.00,8.00,8.00,8.00,8.00,8.00,8.00,8.00,8.00"
					( Origin gBackEnd )
				)
				( attribute "HOLE_TO_SHAPE_SPACING" "8.00,8.00,8.00,8.00,8.00,8.00,8.00,8.00,8.00,8.00,8.00,8.00,8.00,8.00"
					( Origin gBackEnd )
				)
				( attribute "HOLE_TO_HOLE_SPACING" "8.00,8.00,8.00,8.00,8.00,8.00,8.00,8.00,8.00,8.00,8.00,8.00,8.00,8.00"
					( Origin gBackEnd )
				)
				( attribute "MVIA_TO_MVIA_SPACING" "5.00,5.00,5.00,5.00,5.00,5.00,5.00,5.00,5.00,5.00,5.00,5.00,5.00,5.00"
					( Origin gBackEnd )
				)
				( attribute "MVIA_TO_THRUPIN_SPACING" "5.00,5.00,5.00,5.00,5.00,5.00,5.00,5.00,5.00,5.00,5.00,5.00,5.00,5.00"
					( Origin gBackEnd )
				)
				( attribute "MVIA_TO_SMDPIN_SPACING" "5.00,5.00,5.00,5.00,5.00,5.00,5.00,5.00,5.00,5.00,5.00,5.00,5.00,5.00"
					( Origin gBackEnd )
				)
				( attribute "MVIA_TO_THRUVIA_SPACING" "5.00,5.00,5.00,5.00,5.00,5.00,5.00,5.00,5.00,5.00,5.00,5.00,5.00,5.00"
					( Origin gBackEnd )
				)
				( attribute "MVIA_TO_BBV_SPACING" "5.00,5.00,5.00,5.00,5.00,5.00,5.00,5.00,5.00,5.00,5.00,5.00,5.00,5.00"
					( Origin gBackEnd )
				)
				( attribute "MVIA_TO_LINE_SPACING" "5.00,5.00,5.00,5.00,5.00,5.00,5.00,5.00,5.00,5.00,5.00,5.00,5.00,5.00"
					( Origin gBackEnd )
				)
				( attribute "MVIA_TO_SHAPE_SPACING" "5.00,5.00,5.00,5.00,5.00,5.00,5.00,5.00,5.00,5.00,5.00,5.00,5.00,5.00"
					( Origin gBackEnd )
				)
				( attribute "MVIA_TO_TESTPIN_SPACING" "5.00,5.00,5.00,5.00,5.00,5.00,5.00,5.00,5.00,5.00,5.00,5.00,5.00,5.00"
					( Origin gBackEnd )
				)
				( attribute "MVIA_TO_TESTVIA_SPACING" "5.00,5.00,5.00,5.00,5.00,5.00,5.00,5.00,5.00,5.00,5.00,5.00,5.00,5.00"
					( Origin gBackEnd )
				)
				( attribute "BONDPAD_TO_MVIA_SPACING" "5.00,5.00,5.00,5.00,5.00,5.00,5.00,5.00,5.00,5.00,5.00,5.00,5.00,5.00"
					( Origin gBackEnd )
				)
				( attribute "MIN_BVIA_GAP" "5.00"
					( Origin gBackEnd )
				)
				( attribute "BONDPAD_TO_BONDPAD_DIFFP_SPC" "5.00,5.00,5.00,5.00,5.00,5.00,5.00,5.00,5.00,5.00,5.00,5.00,5.00,5.00"
					( Origin gBackEnd )
				)
				( objectStatus "BGA" )
			)
			( spacingCSet "@sapphirecity_baseboard_lib.sapphirecity_baseboard(sch_1):\DIMM\"
				( attribute "THRUPIN_TO_THRUPIN_SPACING" "5.00,5.00,5.00,5.00,5.00,5.00,5.00,5.00,5.00,5.00,5.00,5.00,5.00,5.00"
					( Origin gBackEnd )
				)
				( attribute "THRUPIN_TO_SMDPIN_SPACING" "5.00,5.00,5.00,5.00,5.00,5.00,5.00,5.00,5.00,5.00,5.00,5.00,5.00,5.00"
					( Origin gBackEnd )
				)
				( attribute "TESTPIN_TO_THRUPIN_SPACING" "5.00,5.00,5.00,5.00,5.00,5.00,5.00,5.00,5.00,5.00,5.00,5.00,5.00,5.00"
					( Origin gBackEnd )
				)
				( attribute "THRUPIN_TO_THRUVIA_SPACING" "5.00,5.00,5.00,5.00,5.00,5.00,5.00,5.00,5.00,5.00,5.00,5.00,5.00,5.00"
					( Origin gBackEnd )
				)
				( attribute "TESTVIA_TO_THRUPIN_SPACING" "5.00,5.00,5.00,5.00,5.00,5.00,5.00,5.00,5.00,5.00,5.00,5.00,5.00,5.00"
					( Origin gBackEnd )
				)
				( attribute "BBV_TO_THRUPIN_SPACING" "5.00,5.00,5.00,5.00,5.00,5.00,5.00,5.00,5.00,5.00,5.00,5.00,5.00,5.00"
					( Origin gBackEnd )
				)
				( attribute "THRUPIN_TO_BONDPAD_SPACING" "5.00,5.00,5.00,5.00,5.00,5.00,5.00,5.00,5.00,5.00,5.00,5.00,5.00,5.00"
					( Origin gBackEnd )
				)
				( attribute "LINE_TO_THRUPIN_SPACING" "4.50,4.00,4.00,4.00,4.00,4.00,4.00,4.00,4.00,4.00,4.00,4.00,4.00,4.50"
					( Origin gBackEnd )
				)
				( attribute "THRUPIN_TO_SHAPE_SPACING" "4.50,4.00,4.00,4.00,4.00,4.00,4.00,4.00,4.00,4.00,4.00,4.00,4.00,4.00"
					( Origin gBackEnd )
				)
				( attribute "SMDPIN_TO_SMDPIN_SPACING" "5.00,5.00,5.00,5.00,5.00,5.00,5.00,5.00,5.00,5.00,5.00,5.00,5.00,5.00"
					( Origin gBackEnd )
				)
				( attribute "SMDPIN_TO_TESTPIN_SPACING" "5.00,5.00,5.00,5.00,5.00,5.00,5.00,5.00,5.00,5.00,5.00,5.00,5.00,5.00"
					( Origin gBackEnd )
				)
				( attribute "SMDPIN_TO_THRUVIA_SPACING" "5.00,5.00,5.00,5.00,5.00,5.00,5.00,5.00,5.00,5.00,5.00,5.00,5.00,5.00"
					( Origin gBackEnd )
				)
				( attribute "SMDPIN_TO_TESTVIA_SPACING" "5.00,5.00,5.00,5.00,5.00,5.00,5.00,5.00,5.00,5.00,5.00,5.00,5.00,5.00"
					( Origin gBackEnd )
				)
				( attribute "BBV_TO_SMDPIN_SPACING" "5.00,5.00,5.00,5.00,5.00,5.00,5.00,5.00,5.00,5.00,5.00,5.00,5.00,5.00"
					( Origin gBackEnd )
				)
				( attribute "SMDPIN_TO_BONDPAD_SPACING" "5.00,5.00,5.00,5.00,5.00,5.00,5.00,5.00,5.00,5.00,5.00,5.00,5.00,5.00"
					( Origin gBackEnd )
				)
				( attribute "LINE_TO_SMDPIN_SPACING" "4.50,4.50,4.50,4.50,4.50,4.50,4.50,4.50,4.50,4.50,4.50,4.50,4.50,4.50"
					( Origin gBackEnd )
				)
				( attribute "SHAPE_TO_SMDPIN_SPACING" "5.00,5.00,5.00,5.00,5.00,5.00,5.00,5.00,5.00,5.00,5.00,5.00,5.00,5.00"
					( Origin gBackEnd )
				)
				( attribute "TESTPIN_TO_TESTPIN_SPACING" "5.00,5.00,5.00,5.00,5.00,5.00,5.00,5.00,5.00,5.00,5.00,5.00,5.00,5.00"
					( Origin gBackEnd )
				)
				( attribute "TESTPIN_TO_THRUVIA_SPACING" "5.00,5.00,5.00,5.00,5.00,5.00,5.00,5.00,5.00,5.00,5.00,5.00,5.00,5.00"
					( Origin gBackEnd )
				)
				( attribute "TESTPIN_TO_TESTVIA_SPACING" "5.00,5.00,5.00,5.00,5.00,5.00,5.00,5.00,5.00,5.00,5.00,5.00,5.00,5.00"
					( Origin gBackEnd )
				)
				( attribute "BBV_TO_TESTPIN_SPACING" "5.00,5.00,5.00,5.00,5.00,5.00,5.00,5.00,5.00,5.00,5.00,5.00,5.00,5.00"
					( Origin gBackEnd )
				)
				( attribute "BONDPAD_TO_TESTPIN_SPACING" "5.00,5.00,5.00,5.00,5.00,5.00,5.00,5.00,5.00,5.00,5.00,5.00,5.00,5.00"
					( Origin gBackEnd )
				)
				( attribute "LINE_TO_TESTPIN_SPACING" "4.50,5.00,5.00,5.00,5.00,5.00,5.00,5.00,5.00,5.00,5.00,5.00,5.00,4.50"
					( Origin gBackEnd )
				)
				( attribute "SHAPE_TO_TESTPIN_SPACING" "4.50,4.00,4.00,4.00,4.00,4.00,4.00,4.00,4.00,4.00,4.00,4.00,4.00,4.00"
					( Origin gBackEnd )
				)
				( attribute "THRUVIA_TO_THRUVIA_SPACING" "5.00,5.00,5.00,5.00,5.00,5.00,5.00,5.00,5.00,5.00,5.00,5.00,5.00,5.00"
					( Origin gBackEnd )
				)
				( attribute "TESTVIA_TO_THRUVIA_SPACING" "5.00,5.00,5.00,5.00,5.00,5.00,5.00,5.00,5.00,5.00,5.00,5.00,5.00,5.00"
					( Origin gBackEnd )
				)
				( attribute "BBV_TO_THRUVIA_SPACING" "5.00,5.00,5.00,5.00,5.00,5.00,5.00,5.00,5.00,5.00,5.00,5.00,5.00,5.00"
					( Origin gBackEnd )
				)
				( attribute "BONDPAD_TO_THRUVIA_SPACING" "5.00,5.00,5.00,5.00,5.00,5.00,5.00,5.00,5.00,5.00,5.00,5.00,5.00,5.00"
					( Origin gBackEnd )
				)
				( attribute "LINE_TO_THRUVIA_SPACING" "4.50,4.00,4.00,4.00,4.00,4.00,4.00,4.00,4.00,4.00,4.00,4.00,4.00,4.50"
					( Origin gBackEnd )
				)
				( attribute "SHAPE_TO_THRUVIA_SPACING" "4.50,4.00,4.00,4.00,4.00,4.00,4.00,4.00,4.00,4.00,4.00,4.00,4.00,4.00"
					( Origin gBackEnd )
				)
				( attribute "TESTVIA_TO_TESTVIA_SPACING" "5.00,5.00,5.00,5.00,5.00,5.00,5.00,5.00,5.00,5.00,5.00,5.00,5.00,5.00"
					( Origin gBackEnd )
				)
				( attribute "BBV_TO_TESTVIA_SPACING" "5.00,5.00,5.00,5.00,5.00,5.00,5.00,5.00,5.00,5.00,5.00,5.00,5.00,5.00"
					( Origin gBackEnd )
				)
				( attribute "BONDPAD_TO_TESTVIA_SPACING" "5.00,5.00,5.00,5.00,5.00,5.00,5.00,5.00,5.00,5.00,5.00,5.00,5.00,5.00"
					( Origin gBackEnd )
				)
				( attribute "LINE_TO_TESTVIA_SPACING" "4.50,5.00,5.00,5.00,5.00,5.00,5.00,5.00,5.00,5.00,5.00,5.00,5.00,4.50"
					( Origin gBackEnd )
				)
				( attribute "SHAPE_TO_TESTVIA_SPACING" "4.50,4.00,4.00,4.00,4.00,4.00,4.00,4.00,4.00,4.00,4.00,4.00,4.00,4.00"
					( Origin gBackEnd )
				)
				( attribute "BBV_TO_BBV_SPACING" "5.00,5.00,5.00,5.00,5.00,5.00,5.00,5.00,5.00,5.00,5.00,5.00,5.00,5.00"
					( Origin gBackEnd )
				)
				( attribute "BONDPAD_TO_BBV_SPACING" "5.00,5.00,5.00,5.00,5.00,5.00,5.00,5.00,5.00,5.00,5.00,5.00,5.00,5.00"
					( Origin gBackEnd )
				)
				( attribute "BBV_TO_LINE_SPACING" "5.00,5.00,5.00,5.00,5.00,5.00,5.00,5.00,5.00,5.00,5.00,5.00,5.00,5.00"
					( Origin gBackEnd )
				)
				( attribute "BBV_TO_SHAPE_SPACING" "5.00,5.00,5.00,5.00,5.00,5.00,5.00,5.00,5.00,5.00,5.00,5.00,5.00,5.00"
					( Origin gBackEnd )
				)
				( attribute "BONDPAD_TO_BONDPAD_SPACING" "5.00,5.00,5.00,5.00,5.00,5.00,5.00,5.00,5.00,5.00,5.00,5.00,5.00,5.00"
					( Origin gBackEnd )
				)
				( attribute "BONDPAD_TO_LINE_SPACING" "5.00,5.00,5.00,5.00,5.00,5.00,5.00,5.00,5.00,5.00,5.00,5.00,5.00,5.00"
					( Origin gBackEnd )
				)
				( attribute "BONDPAD_TO_SHAPE_SPACING" "5.00,5.00,5.00,5.00,5.00,5.00,5.00,5.00,5.00,5.00,5.00,5.00,5.00,5.00"
					( Origin gBackEnd )
				)
				( attribute "LINE_TO_LINE_SPACING" "6.92,4.92,4.92,4.92,4.92,4.92,4.92,4.92,4.92,4.92,4.92,4.92,4.92,6.92"
					( Origin gBackEnd )
				)
				( attribute "LINE_TO_SHAPE_SPACING" "5.00,5.00,5.00,5.00,5.00,5.00,5.00,5.00,5.00,5.00,5.00,5.00,5.00,5.00"
					( Origin gBackEnd )
				)
				( attribute "SHAPE_TO_SHAPE_SPACING" "10.00,10.00,10.00,10.00,10.00,10.00,10.00,10.00,10.00,10.00,10.00,10.00,10.00,10.00"
					( Origin gBackEnd )
				)
				( attribute "HOLE_TO_PIN_SPACING" "8.00,8.00,8.00,8.00,8.00,8.00,8.00,8.00,8.00,8.00,8.00,8.00,8.00,8.00"
					( Origin gBackEnd )
				)
				( attribute "HOLE_TO_VIA_SPACING" "8.00,8.00,8.00,8.00,8.00,8.00,8.00,8.00,8.00,8.00,8.00,8.00,8.00,8.00"
					( Origin gBackEnd )
				)
				( attribute "HOLE_TO_LINE_SPACING" "8.00,8.00,8.00,8.00,8.00,8.00,8.00,8.00,8.00,8.00,8.00,8.00,8.00,8.00"
					( Origin gBackEnd )
				)
				( attribute "HOLE_TO_SHAPE_SPACING" "8.00,8.00,8.00,8.00,8.00,8.00,8.00,8.00,8.00,8.00,8.00,8.00,8.00,8.00"
					( Origin gBackEnd )
				)
				( attribute "HOLE_TO_HOLE_SPACING" "8.00,8.00,8.00,8.00,8.00,8.00,8.00,8.00,8.00,8.00,8.00,8.00,8.00,8.00"
					( Origin gBackEnd )
				)
				( attribute "MVIA_TO_MVIA_SPACING" "5.00,5.00,5.00,5.00,5.00,5.00,5.00,5.00,5.00,5.00,5.00,5.00,5.00,5.00"
					( Origin gBackEnd )
				)
				( attribute "MVIA_TO_THRUPIN_SPACING" "5.00,5.00,5.00,5.00,5.00,5.00,5.00,5.00,5.00,5.00,5.00,5.00,5.00,5.00"
					( Origin gBackEnd )
				)
				( attribute "MVIA_TO_SMDPIN_SPACING" "5.00,5.00,5.00,5.00,5.00,5.00,5.00,5.00,5.00,5.00,5.00,5.00,5.00,5.00"
					( Origin gBackEnd )
				)
				( attribute "MVIA_TO_THRUVIA_SPACING" "5.00,5.00,5.00,5.00,5.00,5.00,5.00,5.00,5.00,5.00,5.00,5.00,5.00,5.00"
					( Origin gBackEnd )
				)
				( attribute "MVIA_TO_BBV_SPACING" "5.00,5.00,5.00,5.00,5.00,5.00,5.00,5.00,5.00,5.00,5.00,5.00,5.00,5.00"
					( Origin gBackEnd )
				)
				( attribute "MVIA_TO_LINE_SPACING" "5.00,5.00,5.00,5.00,5.00,5.00,5.00,5.00,5.00,5.00,5.00,5.00,5.00,5.00"
					( Origin gBackEnd )
				)
				( attribute "MVIA_TO_SHAPE_SPACING" "5.00,5.00,5.00,5.00,5.00,5.00,5.00,5.00,5.00,5.00,5.00,5.00,5.00,5.00"
					( Origin gBackEnd )
				)
				( attribute "MVIA_TO_TESTPIN_SPACING" "5.00,5.00,5.00,5.00,5.00,5.00,5.00,5.00,5.00,5.00,5.00,5.00,5.00,5.00"
					( Origin gBackEnd )
				)
				( attribute "MVIA_TO_TESTVIA_SPACING" "5.00,5.00,5.00,5.00,5.00,5.00,5.00,5.00,5.00,5.00,5.00,5.00,5.00,5.00"
					( Origin gBackEnd )
				)
				( attribute "BONDPAD_TO_MVIA_SPACING" "5.00,5.00,5.00,5.00,5.00,5.00,5.00,5.00,5.00,5.00,5.00,5.00,5.00,5.00"
					( Origin gBackEnd )
				)
				( attribute "MIN_BVIA_GAP" "5.00"
					( Origin gBackEnd )
				)
				( attribute "BONDPAD_TO_BONDPAD_DIFFP_SPC" "5.00,5.00,5.00,5.00,5.00,5.00,5.00,5.00,5.00,5.00,5.00,5.00,5.00,5.00"
					( Origin gBackEnd )
				)
				( objectStatus "DIMM" )
			)
			( spacingCSet "@sapphirecity_baseboard_lib.sapphirecity_baseboard(sch_1):\10H_SL_12H_MS\"
				( attribute "THRUPIN_TO_THRUPIN_SPACING" "5.00,5.00,5.00,5.00,5.00,5.00,5.00,5.00,5.00,5.00,5.00,5.00,5.00,5.00"
					( Origin gBackEnd )
				)
				( attribute "THRUPIN_TO_SMDPIN_SPACING" "5.00,5.00,5.00,5.00,5.00,5.00,5.00,5.00,5.00,5.00,5.00,5.00,5.00,5.00"
					( Origin gBackEnd )
				)
				( attribute "TESTPIN_TO_THRUPIN_SPACING" "5.00,5.00,5.00,5.00,5.00,5.00,5.00,5.00,5.00,5.00,5.00,5.00,5.00,5.00"
					( Origin gBackEnd )
				)
				( attribute "THRUPIN_TO_THRUVIA_SPACING" "5.00,5.00,5.00,5.00,5.00,5.00,5.00,5.00,5.00,5.00,5.00,5.00,5.00,5.00"
					( Origin gBackEnd )
				)
				( attribute "TESTVIA_TO_THRUPIN_SPACING" "5.00,5.00,5.00,5.00,5.00,5.00,5.00,5.00,5.00,5.00,5.00,5.00,5.00,5.00"
					( Origin gBackEnd )
				)
				( attribute "BBV_TO_THRUPIN_SPACING" "5.00,5.00,5.00,5.00,5.00,5.00,5.00,5.00,5.00,5.00,5.00,5.00,5.00,5.00"
					( Origin gBackEnd )
				)
				( attribute "THRUPIN_TO_BONDPAD_SPACING" "5.00,5.00,5.00,5.00,5.00,5.00,5.00,5.00,5.00,5.00,5.00,5.00,5.00,5.00"
					( Origin gBackEnd )
				)
				( attribute "LINE_TO_THRUPIN_SPACING" "4.50,4.00,4.00,4.00,4.00,4.00,4.00,4.00,4.00,4.00,4.00,4.00,4.00,4.50"
					( Origin gBackEnd )
				)
				( attribute "THRUPIN_TO_SHAPE_SPACING" "5.00,5.00,5.00,5.00,5.00,5.00,5.00,5.00,5.00,5.00,5.00,5.00,5.00,5.00"
					( Origin gBackEnd )
				)
				( attribute "SMDPIN_TO_SMDPIN_SPACING" "5.00,5.00,5.00,5.00,5.00,5.00,5.00,5.00,5.00,5.00,5.00,5.00,5.00,5.00"
					( Origin gBackEnd )
				)
				( attribute "SMDPIN_TO_TESTPIN_SPACING" "5.00,5.00,5.00,5.00,5.00,5.00,5.00,5.00,5.00,5.00,5.00,5.00,5.00,25.00"
					( Origin gBackEnd )
				)
				( attribute "SMDPIN_TO_THRUVIA_SPACING" "5.00,5.00,5.00,5.00,5.00,5.00,5.00,5.00,5.00,5.00,5.00,5.00,5.00,5.00"
					( Origin gBackEnd )
				)
				( attribute "SMDPIN_TO_TESTVIA_SPACING" "5.00,5.00,5.00,5.00,5.00,5.00,5.00,5.00,5.00,5.00,5.00,5.00,5.00,5.00"
					( Origin gBackEnd )
				)
				( attribute "BBV_TO_SMDPIN_SPACING" "5.00,5.00,5.00,5.00,5.00,5.00,5.00,5.00,5.00,5.00,5.00,5.00,5.00,5.00"
					( Origin gBackEnd )
				)
				( attribute "SMDPIN_TO_BONDPAD_SPACING" "5.00,5.00,5.00,5.00,5.00,5.00,5.00,5.00,5.00,5.00,5.00,5.00,5.00,5.00"
					( Origin gBackEnd )
				)
				( attribute "LINE_TO_SMDPIN_SPACING" "4.50,4.50,4.50,4.50,4.50,4.50,4.50,4.50,4.50,4.50,4.50,4.50,4.50,4.50"
					( Origin gBackEnd )
				)
				( attribute "SHAPE_TO_SMDPIN_SPACING" "5.00,5.00,5.00,5.00,5.00,5.00,5.00,5.00,5.00,5.00,5.00,5.00,5.00,5.00"
					( Origin gBackEnd )
				)
				( attribute "TESTPIN_TO_TESTPIN_SPACING" "5.00,5.00,5.00,5.00,5.00,5.00,5.00,5.00,5.00,5.00,5.00,5.00,5.00,5.00"
					( Origin gBackEnd )
				)
				( attribute "TESTPIN_TO_THRUVIA_SPACING" "5.00,5.00,5.00,5.00,5.00,5.00,5.00,5.00,5.00,5.00,5.00,5.00,5.00,5.00"
					( Origin gBackEnd )
				)
				( attribute "TESTPIN_TO_TESTVIA_SPACING" "5.00,5.00,5.00,5.00,5.00,5.00,5.00,5.00,5.00,5.00,5.00,5.00,5.00,5.00"
					( Origin gBackEnd )
				)
				( attribute "BBV_TO_TESTPIN_SPACING" "5.00,5.00,5.00,5.00,5.00,5.00,5.00,5.00,5.00,5.00,5.00,5.00,5.00,5.00"
					( Origin gBackEnd )
				)
				( attribute "BONDPAD_TO_TESTPIN_SPACING" "5.00,5.00,5.00,5.00,5.00,5.00,5.00,5.00,5.00,5.00,5.00,5.00,5.00,5.00"
					( Origin gBackEnd )
				)
				( attribute "LINE_TO_TESTPIN_SPACING" "5.00,4.00,4.00,4.00,4.00,4.00,4.00,4.00,4.00,4.00,4.00,4.00,4.00,5.00"
					( Origin gBackEnd )
				)
				( attribute "SHAPE_TO_TESTPIN_SPACING" "5.00,5.00,5.00,5.00,5.00,5.00,5.00,5.00,5.00,5.00,5.00,5.00,5.00,5.00"
					( Origin gBackEnd )
				)
				( attribute "THRUVIA_TO_THRUVIA_SPACING" "5.00,5.00,5.00,5.00,5.00,5.00,5.00,5.00,5.00,5.00,5.00,5.00,5.00,5.00"
					( Origin gBackEnd )
				)
				( attribute "TESTVIA_TO_THRUVIA_SPACING" "6.00,6.00,6.00,6.00,6.00,6.00,6.00,6.00,6.00,6.00,6.00,6.00,6.00,6.00"
					( Origin gBackEnd )
				)
				( attribute "BBV_TO_THRUVIA_SPACING" "5.00,5.00,5.00,5.00,5.00,5.00,5.00,5.00,5.00,5.00,5.00,5.00,5.00,5.00"
					( Origin gBackEnd )
				)
				( attribute "BONDPAD_TO_THRUVIA_SPACING" "5.00,5.00,5.00,5.00,5.00,5.00,5.00,5.00,5.00,5.00,5.00,5.00,5.00,5.00"
					( Origin gBackEnd )
				)
				( attribute "LINE_TO_THRUVIA_SPACING" "4.50,4.00,4.00,4.00,4.00,4.00,4.00,4.00,4.00,4.00,4.00,4.00,4.00,4.50"
					( Origin gBackEnd )
				)
				( attribute "SHAPE_TO_THRUVIA_SPACING" "5.00,5.00,5.00,5.00,5.00,5.00,5.00,5.00,5.00,5.00,5.00,5.00,5.00,5.00"
					( Origin gBackEnd )
				)
				( attribute "TESTVIA_TO_TESTVIA_SPACING" "6.00,6.00,6.00,6.00,6.00,6.00,6.00,6.00,6.00,6.00,6.00,6.00,6.00,6.00"
					( Origin gBackEnd )
				)
				( attribute "BBV_TO_TESTVIA_SPACING" "5.00,5.00,5.00,5.00,5.00,5.00,5.00,5.00,5.00,5.00,5.00,5.00,5.00,5.00"
					( Origin gBackEnd )
				)
				( attribute "BONDPAD_TO_TESTVIA_SPACING" "5.00,5.00,5.00,5.00,5.00,5.00,5.00,5.00,5.00,5.00,5.00,5.00,5.00,5.00"
					( Origin gBackEnd )
				)
				( attribute "LINE_TO_TESTVIA_SPACING" "4.50,4.00,4.00,4.00,4.00,4.00,4.00,4.00,4.00,4.00,4.00,4.00,4.00,4.50"
					( Origin gBackEnd )
				)
				( attribute "SHAPE_TO_TESTVIA_SPACING" "5.00,5.00,5.00,5.00,5.00,5.00,5.00,5.00,5.00,5.00,5.00,5.00,5.00,5.00"
					( Origin gBackEnd )
				)
				( attribute "BBV_TO_BBV_SPACING" "5.00,5.00,5.00,5.00,5.00,5.00,5.00,5.00,5.00,5.00,5.00,5.00,5.00,5.00"
					( Origin gBackEnd )
				)
				( attribute "BONDPAD_TO_BBV_SPACING" "5.00,5.00,5.00,5.00,5.00,5.00,5.00,5.00,5.00,5.00,5.00,5.00,5.00,5.00"
					( Origin gBackEnd )
				)
				( attribute "BBV_TO_LINE_SPACING" "5.00,5.00,5.00,5.00,5.00,5.00,5.00,5.00,5.00,5.00,5.00,5.00,5.00,5.00"
					( Origin gBackEnd )
				)
				( attribute "BBV_TO_SHAPE_SPACING" "5.00,5.00,5.00,5.00,5.00,5.00,5.00,5.00,5.00,5.00,5.00,5.00,5.00,5.00"
					( Origin gBackEnd )
				)
				( attribute "BONDPAD_TO_BONDPAD_SPACING" "5.00,5.00,5.00,5.00,5.00,5.00,5.00,5.00,5.00,5.00,5.00,5.00,5.00,5.00"
					( Origin gBackEnd )
				)
				( attribute "BONDPAD_TO_LINE_SPACING" "5.00,5.00,5.00,5.00,5.00,5.00,5.00,5.00,5.00,5.00,5.00,5.00,5.00,5.00"
					( Origin gBackEnd )
				)
				( attribute "BONDPAD_TO_SHAPE_SPACING" "5.00,5.00,5.00,5.00,5.00,5.00,5.00,5.00,5.00,5.00,5.00,5.00,5.00,5.00"
					( Origin gBackEnd )
				)
				( attribute "LINE_TO_LINE_SPACING" "32.40,30.00,30.00,30.00,30.00,30.00,30.00,30.00,30.00,30.00,30.00,30.00,30.00,32.40"
					( Origin gBackEnd )
				)
				( attribute "LINE_TO_SHAPE_SPACING" "10.00,10.00,10.00,10.00,10.00,10.00,10.00,10.00,10.00,10.00,10.00,10.00,10.00,10.00"
					( Origin gBackEnd )
				)
				( attribute "SHAPE_TO_SHAPE_SPACING" "10.00,10.00,10.00,10.00,10.00,10.00,10.00,10.00,10.00,10.00,10.00,10.00,10.00,10.00"
					( Origin gBackEnd )
				)
				( attribute "HOLE_TO_PIN_SPACING" "8.00,8.00,8.00,8.00,8.00,8.00,8.00,8.00,8.00,8.00,8.00,8.00,8.00,8.00"
					( Origin gBackEnd )
				)
				( attribute "HOLE_TO_VIA_SPACING" "8.00,8.00,8.00,8.00,8.00,8.00,8.00,8.00,8.00,8.00,8.00,8.00,8.00,8.00"
					( Origin gBackEnd )
				)
				( attribute "HOLE_TO_LINE_SPACING" "8.00,8.00,8.00,8.00,8.00,8.00,8.00,8.00,8.00,8.00,8.00,8.00,8.00,8.00"
					( Origin gBackEnd )
				)
				( attribute "HOLE_TO_SHAPE_SPACING" "8.00,8.00,8.00,8.00,8.00,8.00,8.00,8.00,8.00,8.00,8.00,8.00,8.00,8.00"
					( Origin gBackEnd )
				)
				( attribute "HOLE_TO_HOLE_SPACING" "8.00,8.00,8.00,8.00,8.00,8.00,8.00,8.00,8.00,8.00,8.00,8.00,8.00,8.00"
					( Origin gBackEnd )
				)
				( attribute "MVIA_TO_MVIA_SPACING" "5.00,5.00,5.00,5.00,5.00,5.00,5.00,5.00,5.00,5.00,5.00,5.00,5.00,5.00"
					( Origin gBackEnd )
				)
				( attribute "MVIA_TO_THRUPIN_SPACING" "5.00,5.00,5.00,5.00,5.00,5.00,5.00,5.00,5.00,5.00,5.00,5.00,5.00,5.00"
					( Origin gBackEnd )
				)
				( attribute "MVIA_TO_SMDPIN_SPACING" "5.00,5.00,5.00,5.00,5.00,5.00,5.00,5.00,5.00,5.00,5.00,5.00,5.00,5.00"
					( Origin gBackEnd )
				)
				( attribute "MVIA_TO_THRUVIA_SPACING" "5.00,5.00,5.00,5.00,5.00,5.00,5.00,5.00,5.00,5.00,5.00,5.00,5.00,5.00"
					( Origin gBackEnd )
				)
				( attribute "MVIA_TO_BBV_SPACING" "5.00,5.00,5.00,5.00,5.00,5.00,5.00,5.00,5.00,5.00,5.00,5.00,5.00,5.00"
					( Origin gBackEnd )
				)
				( attribute "MVIA_TO_LINE_SPACING" "5.00,5.00,5.00,5.00,5.00,5.00,5.00,5.00,5.00,5.00,5.00,5.00,5.00,5.00"
					( Origin gBackEnd )
				)
				( attribute "MVIA_TO_SHAPE_SPACING" "5.00,5.00,5.00,5.00,5.00,5.00,5.00,5.00,5.00,5.00,5.00,5.00,5.00,5.00"
					( Origin gBackEnd )
				)
				( attribute "MVIA_TO_TESTPIN_SPACING" "5.00,5.00,5.00,5.00,5.00,5.00,5.00,5.00,5.00,5.00,5.00,5.00,5.00,5.00"
					( Origin gBackEnd )
				)
				( attribute "MVIA_TO_TESTVIA_SPACING" "5.00,5.00,5.00,5.00,5.00,5.00,5.00,5.00,5.00,5.00,5.00,5.00,5.00,5.00"
					( Origin gBackEnd )
				)
				( attribute "BONDPAD_TO_MVIA_SPACING" "5.00,5.00,5.00,5.00,5.00,5.00,5.00,5.00,5.00,5.00,5.00,5.00,5.00,5.00"
					( Origin gBackEnd )
				)
				( attribute "MIN_BVIA_GAP" "5.00"
					( Origin gBackEnd )
				)
				( attribute "BONDPAD_TO_BONDPAD_DIFFP_SPC" "5.00,5.00,5.00,5.00,5.00,5.00,5.00,5.00,5.00,5.00,5.00,5.00,5.00,5.00"
					( Origin gBackEnd )
				)
				( objectStatus "12H_US_&_10H_SL" )
			)
			( spacingCSet "@sapphirecity_baseboard_lib.sapphirecity_baseboard(sch_1):\13.5MIL_SL_12MIL_MS\"
				( attribute "THRUPIN_TO_THRUPIN_SPACING" "5.00,5.00,5.00,5.00,5.00,5.00,5.00,5.00,5.00,5.00,5.00,5.00,5.00,5.00"
					( Origin gBackEnd )
				)
				( attribute "THRUPIN_TO_SMDPIN_SPACING" "5.00,5.00,5.00,5.00,5.00,5.00,5.00,5.00,5.00,5.00,5.00,5.00,5.00,5.00"
					( Origin gBackEnd )
				)
				( attribute "TESTPIN_TO_THRUPIN_SPACING" "5.00,5.00,5.00,5.00,5.00,5.00,5.00,5.00,5.00,5.00,5.00,5.00,5.00,5.00"
					( Origin gBackEnd )
				)
				( attribute "THRUPIN_TO_THRUVIA_SPACING" "5.00,5.00,5.00,5.00,5.00,5.00,5.00,5.00,5.00,5.00,5.00,5.00,5.00,5.00"
					( Origin gBackEnd )
				)
				( attribute "TESTVIA_TO_THRUPIN_SPACING" "5.00,5.00,5.00,5.00,5.00,5.00,5.00,5.00,5.00,5.00,5.00,5.00,5.00,5.00"
					( Origin gBackEnd )
				)
				( attribute "BBV_TO_THRUPIN_SPACING" "5.00,5.00,5.00,5.00,5.00,5.00,5.00,5.00,5.00,5.00,5.00,5.00,5.00,5.00"
					( Origin gBackEnd )
				)
				( attribute "THRUPIN_TO_BONDPAD_SPACING" "5.00,5.00,5.00,5.00,5.00,5.00,5.00,5.00,5.00,5.00,5.00,5.00,5.00,5.00"
					( Origin gBackEnd )
				)
				( attribute "LINE_TO_THRUPIN_SPACING" "4.50,4.00,4.00,4.00,4.00,4.00,4.00,4.00,4.00,4.00,4.00,4.00,4.00,4.50"
					( Origin gBackEnd )
				)
				( attribute "THRUPIN_TO_SHAPE_SPACING" "4.50,4.00,4.00,4.00,4.00,4.00,4.00,4.00,4.00,4.00,4.00,4.00,4.00,4.00"
					( Origin gBackEnd )
				)
				( attribute "SMDPIN_TO_SMDPIN_SPACING" "5.00,5.00,5.00,5.00,5.00,5.00,5.00,5.00,5.00,5.00,5.00,5.00,5.00,5.00"
					( Origin gBackEnd )
				)
				( attribute "SMDPIN_TO_TESTPIN_SPACING" "5.00,5.00,5.00,5.00,5.00,5.00,5.00,5.00,5.00,5.00,5.00,5.00,5.00,25.00"
					( Origin gBackEnd )
				)
				( attribute "SMDPIN_TO_THRUVIA_SPACING" "5.00,5.00,5.00,5.00,5.00,5.00,5.00,5.00,5.00,5.00,5.00,5.00,5.00,5.00"
					( Origin gBackEnd )
				)
				( attribute "SMDPIN_TO_TESTVIA_SPACING" "5.00,5.00,5.00,5.00,5.00,5.00,5.00,5.00,5.00,5.00,5.00,5.00,5.00,5.00"
					( Origin gBackEnd )
				)
				( attribute "BBV_TO_SMDPIN_SPACING" "5.00,5.00,5.00,5.00,5.00,5.00,5.00,5.00,5.00,5.00,5.00,5.00,5.00,5.00"
					( Origin gBackEnd )
				)
				( attribute "SMDPIN_TO_BONDPAD_SPACING" "5.00,5.00,5.00,5.00,5.00,5.00,5.00,5.00,5.00,5.00,5.00,5.00,5.00,5.00"
					( Origin gBackEnd )
				)
				( attribute "LINE_TO_SMDPIN_SPACING" "4.50,4.50,4.50,4.50,4.50,4.50,4.50,4.50,4.50,4.50,4.50,4.50,4.50,4.50"
					( Origin gBackEnd )
				)
				( attribute "SHAPE_TO_SMDPIN_SPACING" "5.00,5.00,5.00,5.00,5.00,5.00,5.00,5.00,5.00,5.00,5.00,5.00,5.00,5.00"
					( Origin gBackEnd )
				)
				( attribute "TESTPIN_TO_TESTPIN_SPACING" "5.00,5.00,5.00,5.00,5.00,5.00,5.00,5.00,5.00,5.00,5.00,5.00,5.00,5.00"
					( Origin gBackEnd )
				)
				( attribute "TESTPIN_TO_THRUVIA_SPACING" "5.00,5.00,5.00,5.00,5.00,5.00,5.00,5.00,5.00,5.00,5.00,5.00,5.00,5.00"
					( Origin gBackEnd )
				)
				( attribute "TESTPIN_TO_TESTVIA_SPACING" "5.00,5.00,5.00,5.00,5.00,5.00,5.00,5.00,5.00,5.00,5.00,5.00,5.00,5.00"
					( Origin gBackEnd )
				)
				( attribute "BBV_TO_TESTPIN_SPACING" "5.00,5.00,5.00,5.00,5.00,5.00,5.00,5.00,5.00,5.00,5.00,5.00,5.00,5.00"
					( Origin gBackEnd )
				)
				( attribute "BONDPAD_TO_TESTPIN_SPACING" "5.00,5.00,5.00,5.00,5.00,5.00,5.00,5.00,5.00,5.00,5.00,5.00,5.00,5.00"
					( Origin gBackEnd )
				)
				( attribute "LINE_TO_TESTPIN_SPACING" "4.50,5.00,5.00,5.00,5.00,5.00,5.00,5.00,5.00,5.00,5.00,5.00,5.00,5.00"
					( Origin gBackEnd )
				)
				( attribute "SHAPE_TO_TESTPIN_SPACING" "4.50,4.00,4.00,4.00,4.00,4.00,4.00,4.00,4.00,4.00,4.00,4.00,4.00,4.00"
					( Origin gBackEnd )
				)
				( attribute "THRUVIA_TO_THRUVIA_SPACING" "5.00,5.00,5.00,5.00,5.00,5.00,5.00,5.00,5.00,5.00,5.00,5.00,5.00,5.00"
					( Origin gBackEnd )
				)
				( attribute "TESTVIA_TO_THRUVIA_SPACING" "5.00,5.00,5.00,5.00,5.00,5.00,5.00,5.00,5.00,5.00,5.00,5.00,5.00,5.00"
					( Origin gBackEnd )
				)
				( attribute "BBV_TO_THRUVIA_SPACING" "5.00,5.00,5.00,5.00,5.00,5.00,5.00,5.00,5.00,5.00,5.00,5.00,5.00,5.00"
					( Origin gBackEnd )
				)
				( attribute "BONDPAD_TO_THRUVIA_SPACING" "5.00,5.00,5.00,5.00,5.00,5.00,5.00,5.00,5.00,5.00,5.00,5.00,5.00,5.00"
					( Origin gBackEnd )
				)
				( attribute "LINE_TO_THRUVIA_SPACING" "4.50,4.00,4.00,4.00,4.00,4.00,4.00,4.00,4.00,4.00,4.00,4.00,4.00,4.50"
					( Origin gBackEnd )
				)
				( attribute "SHAPE_TO_THRUVIA_SPACING" "4.50,4.00,4.00,4.00,4.00,4.00,4.00,4.00,4.00,4.00,4.00,4.00,4.00,4.00"
					( Origin gBackEnd )
				)
				( attribute "TESTVIA_TO_TESTVIA_SPACING" "5.00,5.00,5.00,5.00,5.00,5.00,5.00,5.00,5.00,5.00,5.00,5.00,5.00,5.00"
					( Origin gBackEnd )
				)
				( attribute "BBV_TO_TESTVIA_SPACING" "5.00,5.00,5.00,5.00,5.00,5.00,5.00,5.00,5.00,5.00,5.00,5.00,5.00,5.00"
					( Origin gBackEnd )
				)
				( attribute "BONDPAD_TO_TESTVIA_SPACING" "5.00,5.00,5.00,5.00,5.00,5.00,5.00,5.00,5.00,5.00,5.00,5.00,5.00,5.00"
					( Origin gBackEnd )
				)
				( attribute "LINE_TO_TESTVIA_SPACING" "4.50,5.00,4.00,5.00,4.00,5.00,5.00,5.00,5.00,4.00,5.00,4.00,5.00,4.50"
					( Origin gBackEnd )
				)
				( attribute "SHAPE_TO_TESTVIA_SPACING" "4.50,4.00,4.00,4.00,4.00,4.00,4.00,4.00,4.00,4.00,4.00,4.00,4.00,4.00"
					( Origin gBackEnd )
				)
				( attribute "BBV_TO_BBV_SPACING" "5.00,5.00,5.00,5.00,5.00,5.00,5.00,5.00,5.00,5.00,5.00,5.00,5.00,5.00"
					( Origin gBackEnd )
				)
				( attribute "BONDPAD_TO_BBV_SPACING" "5.00,5.00,5.00,5.00,5.00,5.00,5.00,5.00,5.00,5.00,5.00,5.00,5.00,5.00"
					( Origin gBackEnd )
				)
				( attribute "BBV_TO_LINE_SPACING" "5.00,5.00,5.00,5.00,5.00,5.00,5.00,5.00,5.00,5.00,5.00,5.00,5.00,5.00"
					( Origin gBackEnd )
				)
				( attribute "BBV_TO_SHAPE_SPACING" "5.00,5.00,5.00,5.00,5.00,5.00,5.00,5.00,5.00,5.00,5.00,5.00,5.00,5.00"
					( Origin gBackEnd )
				)
				( attribute "BONDPAD_TO_BONDPAD_SPACING" "5.00,5.00,5.00,5.00,5.00,5.00,5.00,5.00,5.00,5.00,5.00,5.00,5.00,5.00"
					( Origin gBackEnd )
				)
				( attribute "BONDPAD_TO_LINE_SPACING" "5.00,5.00,5.00,5.00,5.00,5.00,5.00,5.00,5.00,5.00,5.00,5.00,5.00,5.00"
					( Origin gBackEnd )
				)
				( attribute "BONDPAD_TO_SHAPE_SPACING" "5.00,5.00,5.00,5.00,5.00,5.00,5.00,5.00,5.00,5.00,5.00,5.00,5.00,5.00"
					( Origin gBackEnd )
				)
				( attribute "LINE_TO_LINE_SPACING" "12.00,13.50,13.50,13.50,13.50,13.50,13.50,13.50,13.50,13.50,13.50,13.50,13.50,13.50"
					( Origin gBackEnd )
				)
				( attribute "LINE_TO_SHAPE_SPACING" "5.00,5.00,5.00,5.00,5.00,5.00,5.00,5.00,5.00,5.00,5.00,5.00,5.00,5.00"
					( Origin gBackEnd )
				)
				( attribute "SHAPE_TO_SHAPE_SPACING" "10.00,10.00,10.00,10.00,10.00,10.00,10.00,10.00,10.00,10.00,10.00,10.00,10.00,10.00"
					( Origin gBackEnd )
				)
				( attribute "HOLE_TO_PIN_SPACING" "8.00,8.00,8.00,8.00,8.00,8.00,8.00,8.00,8.00,8.00,8.00,8.00,8.00,8.00"
					( Origin gBackEnd )
				)
				( attribute "HOLE_TO_VIA_SPACING" "8.00,8.00,8.00,8.00,8.00,8.00,8.00,8.00,8.00,8.00,8.00,8.00,8.00,8.00"
					( Origin gBackEnd )
				)
				( attribute "HOLE_TO_LINE_SPACING" "8.00,8.00,8.00,8.00,8.00,8.00,8.00,8.00,8.00,8.00,8.00,8.00,8.00,8.00"
					( Origin gBackEnd )
				)
				( attribute "HOLE_TO_SHAPE_SPACING" "8.00,8.00,8.00,8.00,8.00,8.00,8.00,8.00,8.00,8.00,8.00,8.00,8.00,8.00"
					( Origin gBackEnd )
				)
				( attribute "HOLE_TO_HOLE_SPACING" "8.00,8.00,8.00,8.00,8.00,8.00,8.00,8.00,8.00,8.00,8.00,8.00,8.00,8.00"
					( Origin gBackEnd )
				)
				( attribute "MVIA_TO_MVIA_SPACING" "5.00,5.00,5.00,5.00,5.00,5.00,5.00,5.00,5.00,5.00,5.00,5.00,5.00,5.00"
					( Origin gBackEnd )
				)
				( attribute "MVIA_TO_THRUPIN_SPACING" "5.00,5.00,5.00,5.00,5.00,5.00,5.00,5.00,5.00,5.00,5.00,5.00,5.00,5.00"
					( Origin gBackEnd )
				)
				( attribute "MVIA_TO_SMDPIN_SPACING" "5.00,5.00,5.00,5.00,5.00,5.00,5.00,5.00,5.00,5.00,5.00,5.00,5.00,5.00"
					( Origin gBackEnd )
				)
				( attribute "MVIA_TO_THRUVIA_SPACING" "5.00,5.00,5.00,5.00,5.00,5.00,5.00,5.00,5.00,5.00,5.00,5.00,5.00,5.00"
					( Origin gBackEnd )
				)
				( attribute "MVIA_TO_BBV_SPACING" "5.00,5.00,5.00,5.00,5.00,5.00,5.00,5.00,5.00,5.00,5.00,5.00,5.00,5.00"
					( Origin gBackEnd )
				)
				( attribute "MVIA_TO_LINE_SPACING" "5.00,5.00,5.00,5.00,5.00,5.00,5.00,5.00,5.00,5.00,5.00,5.00,5.00,5.00"
					( Origin gBackEnd )
				)
				( attribute "MVIA_TO_SHAPE_SPACING" "5.00,5.00,5.00,5.00,5.00,5.00,5.00,5.00,5.00,5.00,5.00,5.00,5.00,5.00"
					( Origin gBackEnd )
				)
				( attribute "MVIA_TO_TESTPIN_SPACING" "5.00,5.00,5.00,5.00,5.00,5.00,5.00,5.00,5.00,5.00,5.00,5.00,5.00,5.00"
					( Origin gBackEnd )
				)
				( attribute "MVIA_TO_TESTVIA_SPACING" "5.00,5.00,5.00,5.00,5.00,5.00,5.00,5.00,5.00,5.00,5.00,5.00,5.00,5.00"
					( Origin gBackEnd )
				)
				( attribute "BONDPAD_TO_MVIA_SPACING" "5.00,5.00,5.00,5.00,5.00,5.00,5.00,5.00,5.00,5.00,5.00,5.00,5.00,5.00"
					( Origin gBackEnd )
				)
				( attribute "MIN_BVIA_GAP" "5.00"
					( Origin gBackEnd )
				)
				( attribute "BONDPAD_TO_BONDPAD_DIFFP_SPC" "5.00,5.00,5.00,5.00,5.00,5.00,5.00,5.00,5.00,5.00,5.00,5.00,5.00,5.00"
					( Origin gBackEnd )
				)
				( objectStatus "12MIL_US_&_13.5MIL_SL" )
			)
			( spacingCSet "@sapphirecity_baseboard_lib.sapphirecity_baseboard(sch_1):\3H_SL_9H_MS_VIA_3H+A\"
				( attribute "THRUPIN_TO_THRUPIN_SPACING" "5.00,5.00,5.00,5.00,5.00,5.00,5.00,5.00,5.00,5.00,5.00,5.00,5.00,5.00"
					( Origin gBackEnd )
				)
				( attribute "THRUPIN_TO_SMDPIN_SPACING" "5.00,5.00,5.00,5.00,5.00,5.00,5.00,5.00,5.00,5.00,5.00,5.00,5.00,5.00"
					( Origin gBackEnd )
				)
				( attribute "TESTPIN_TO_THRUPIN_SPACING" "5.00,5.00,5.00,5.00,5.00,5.00,5.00,5.00,5.00,5.00,5.00,5.00,5.00,5.00"
					( Origin gBackEnd )
				)
				( attribute "THRUPIN_TO_THRUVIA_SPACING" "5.00,5.00,5.00,5.00,5.00,5.00,5.00,5.00,5.00,5.00,5.00,5.00,5.00,5.00"
					( Origin gBackEnd )
				)
				( attribute "TESTVIA_TO_THRUPIN_SPACING" "5.00,5.00,5.00,5.00,5.00,5.00,5.00,5.00,5.00,5.00,5.00,5.00,5.00,5.00"
					( Origin gBackEnd )
				)
				( attribute "BBV_TO_THRUPIN_SPACING" "5.00,5.00,5.00,5.00,5.00,5.00,5.00,5.00,5.00,5.00,5.00,5.00,5.00,5.00"
					( Origin gBackEnd )
				)
				( attribute "THRUPIN_TO_BONDPAD_SPACING" "5.00,5.00,5.00,5.00,5.00,5.00,5.00,5.00,5.00,5.00,5.00,5.00,5.00,5.00"
					( Origin gBackEnd )
				)
				( attribute "LINE_TO_THRUPIN_SPACING" "13.10,17.00,17.00,17.00,17.00,17.00,17.00,17.00,17.00,17.00,17.00,17.00,17.00,13.10"
					( Origin gBackEnd )
				)
				( attribute "THRUPIN_TO_SHAPE_SPACING" "5.00,5.00,5.00,5.00,5.00,5.00,5.00,5.00,5.00,5.00,5.00,5.00,5.00,5.00"
					( Origin gBackEnd )
				)
				( attribute "SMDPIN_TO_SMDPIN_SPACING" "5.00,5.00,5.00,5.00,5.00,5.00,5.00,5.00,5.00,5.00,5.00,5.00,5.00,5.00"
					( Origin gBackEnd )
				)
				( attribute "SMDPIN_TO_TESTPIN_SPACING" "5.00,5.00,5.00,5.00,5.00,5.00,5.00,5.00,5.00,5.00,5.00,5.00,5.00,25.00"
					( Origin gBackEnd )
				)
				( attribute "SMDPIN_TO_THRUVIA_SPACING" "5.00,5.00,5.00,5.00,5.00,5.00,5.00,5.00,5.00,5.00,5.00,5.00,5.00,5.00"
					( Origin gBackEnd )
				)
				( attribute "SMDPIN_TO_TESTVIA_SPACING" "5.00,5.00,5.00,5.00,5.00,5.00,5.00,5.00,5.00,5.00,5.00,5.00,5.00,5.00"
					( Origin gBackEnd )
				)
				( attribute "BBV_TO_SMDPIN_SPACING" "5.00,5.00,5.00,5.00,5.00,5.00,5.00,5.00,5.00,5.00,5.00,5.00,5.00,5.00"
					( Origin gBackEnd )
				)
				( attribute "SMDPIN_TO_BONDPAD_SPACING" "5.00,5.00,5.00,5.00,5.00,5.00,5.00,5.00,5.00,5.00,5.00,5.00,5.00,5.00"
					( Origin gBackEnd )
				)
				( attribute "LINE_TO_SMDPIN_SPACING" "4.50,4.50,4.50,4.50,4.50,4.50,4.50,4.50,4.50,4.50,4.50,4.50,4.50,4.50"
					( Origin gBackEnd )
				)
				( attribute "SHAPE_TO_SMDPIN_SPACING" "5.00,5.00,5.00,5.00,5.00,5.00,5.00,5.00,5.00,5.00,5.00,5.00,5.00,5.00"
					( Origin gBackEnd )
				)
				( attribute "TESTPIN_TO_TESTPIN_SPACING" "5.00,5.00,5.00,5.00,5.00,5.00,5.00,5.00,5.00,5.00,5.00,5.00,5.00,5.00"
					( Origin gBackEnd )
				)
				( attribute "TESTPIN_TO_THRUVIA_SPACING" "5.00,5.00,5.00,5.00,5.00,5.00,5.00,5.00,5.00,5.00,5.00,5.00,5.00,5.00"
					( Origin gBackEnd )
				)
				( attribute "TESTPIN_TO_TESTVIA_SPACING" "5.00,5.00,5.00,5.00,5.00,5.00,5.00,5.00,5.00,5.00,5.00,5.00,5.00,5.00"
					( Origin gBackEnd )
				)
				( attribute "BBV_TO_TESTPIN_SPACING" "5.00,5.00,5.00,5.00,5.00,5.00,5.00,5.00,5.00,5.00,5.00,5.00,5.00,5.00"
					( Origin gBackEnd )
				)
				( attribute "BONDPAD_TO_TESTPIN_SPACING" "5.00,5.00,5.00,5.00,5.00,5.00,5.00,5.00,5.00,5.00,5.00,5.00,5.00,5.00"
					( Origin gBackEnd )
				)
				( attribute "LINE_TO_TESTPIN_SPACING" "13.10,17.00,17.00,17.00,17.00,17.00,17.00,17.00,17.00,17.00,17.00,17.00,17.00,13.10"
					( Origin gBackEnd )
				)
				( attribute "SHAPE_TO_TESTPIN_SPACING" "5.00,5.00,5.00,5.00,5.00,5.00,5.00,5.00,5.00,5.00,5.00,5.00,5.00,5.00"
					( Origin gBackEnd )
				)
				( attribute "THRUVIA_TO_THRUVIA_SPACING" "6.00,6.00,6.00,6.00,6.00,6.00,6.00,6.00,6.00,6.00,6.00,6.00,6.00,6.00"
					( Origin gBackEnd )
				)
				( attribute "TESTVIA_TO_THRUVIA_SPACING" "6.00,6.00,6.00,6.00,6.00,6.00,6.00,6.00,6.00,6.00,6.00,6.00,6.00,6.00"
					( Origin gBackEnd )
				)
				( attribute "BBV_TO_THRUVIA_SPACING" "5.00,5.00,5.00,5.00,5.00,5.00,5.00,5.00,5.00,5.00,5.00,5.00,5.00,5.00"
					( Origin gBackEnd )
				)
				( attribute "BONDPAD_TO_THRUVIA_SPACING" "5.00,5.00,5.00,5.00,5.00,5.00,5.00,5.00,5.00,5.00,5.00,5.00,5.00,5.00"
					( Origin gBackEnd )
				)
				( attribute "LINE_TO_THRUVIA_SPACING" "12.00,5.00,13.00,5.00,13.00,5.00,5.00,5.00,5.00,13.00,5.00,13.00,5.00,12.00"
					( Origin gBackEnd )
				)
				( attribute "SHAPE_TO_THRUVIA_SPACING" "5.00,5.00,5.00,5.00,5.00,5.00,5.00,5.00,5.00,5.00,5.00,5.00,5.00,5.00"
					( Origin gBackEnd )
				)
				( attribute "TESTVIA_TO_TESTVIA_SPACING" "6.00,6.00,6.00,6.00,6.00,6.00,6.00,6.00,6.00,6.00,6.00,6.00,6.00,6.00"
					( Origin gBackEnd )
				)
				( attribute "BBV_TO_TESTVIA_SPACING" "5.00,5.00,5.00,5.00,5.00,5.00,5.00,5.00,5.00,5.00,5.00,5.00,5.00,5.00"
					( Origin gBackEnd )
				)
				( attribute "BONDPAD_TO_TESTVIA_SPACING" "5.00,5.00,5.00,5.00,5.00,5.00,5.00,5.00,5.00,5.00,5.00,5.00,5.00,5.00"
					( Origin gBackEnd )
				)
				( attribute "LINE_TO_TESTVIA_SPACING" "4.50,5.00,13.00,5.00,13.00,5.00,5.00,5.00,5.00,13.00,5.00,13.00,5.00,4.50"
					( Origin gBackEnd )
				)
				( attribute "SHAPE_TO_TESTVIA_SPACING" "5.00,5.00,5.00,5.00,5.00,5.00,5.00,5.00,5.00,5.00,5.00,5.00,5.00,5.00"
					( Origin gBackEnd )
				)
				( attribute "BBV_TO_BBV_SPACING" "5.00,5.00,5.00,5.00,5.00,5.00,5.00,5.00,5.00,5.00,5.00,5.00,5.00,5.00"
					( Origin gBackEnd )
				)
				( attribute "BONDPAD_TO_BBV_SPACING" "5.00,5.00,5.00,5.00,5.00,5.00,5.00,5.00,5.00,5.00,5.00,5.00,5.00,5.00"
					( Origin gBackEnd )
				)
				( attribute "BBV_TO_LINE_SPACING" "5.00,5.00,5.00,5.00,5.00,5.00,5.00,5.00,5.00,5.00,5.00,5.00,5.00,5.00"
					( Origin gBackEnd )
				)
				( attribute "BBV_TO_SHAPE_SPACING" "5.00,5.00,5.00,5.00,5.00,5.00,5.00,5.00,5.00,5.00,5.00,5.00,5.00,5.00"
					( Origin gBackEnd )
				)
				( attribute "BONDPAD_TO_BONDPAD_SPACING" "5.00,5.00,5.00,5.00,5.00,5.00,5.00,5.00,5.00,5.00,5.00,5.00,5.00,5.00"
					( Origin gBackEnd )
				)
				( attribute "BONDPAD_TO_LINE_SPACING" "5.00,5.00,5.00,5.00,5.00,5.00,5.00,5.00,5.00,5.00,5.00,5.00,5.00,5.00"
					( Origin gBackEnd )
				)
				( attribute "BONDPAD_TO_SHAPE_SPACING" "5.00,5.00,5.00,5.00,5.00,5.00,5.00,5.00,5.00,5.00,5.00,5.00,5.00,5.00"
					( Origin gBackEnd )
				)
				( attribute "LINE_TO_LINE_SPACING" "24.03,9.00,9.00,9.00,9.00,9.00,9.00,9.00,9.00,9.00,9.00,9.00,9.00,24.03"
					( Origin gBackEnd )
				)
				( attribute "LINE_TO_SHAPE_SPACING" "24.30,20.00,20.00,20.00,20.00,20.00,20.00,20.00,20.00,20.00,20.00,20.00,20.00,24.30"
					( Origin gBackEnd )
				)
				( attribute "SHAPE_TO_SHAPE_SPACING" "10.00,10.00,10.00,10.00,10.00,10.00,10.00,10.00,10.00,10.00,10.00,10.00,10.00,10.00"
					( Origin gBackEnd )
				)
				( attribute "HOLE_TO_PIN_SPACING" "8.00,8.00,8.00,8.00,8.00,8.00,8.00,8.00,8.00,8.00,8.00,8.00,8.00,8.00"
					( Origin gBackEnd )
				)
				( attribute "HOLE_TO_VIA_SPACING" "8.00,8.00,8.00,8.00,8.00,8.00,8.00,8.00,8.00,8.00,8.00,8.00,8.00,8.00"
					( Origin gBackEnd )
				)
				( attribute "HOLE_TO_LINE_SPACING" "8.00,8.00,8.00,8.00,8.00,8.00,8.00,8.00,8.00,8.00,8.00,8.00,8.00,8.00"
					( Origin gBackEnd )
				)
				( attribute "HOLE_TO_SHAPE_SPACING" "8.00,8.00,8.00,8.00,8.00,8.00,8.00,8.00,8.00,8.00,8.00,8.00,8.00,8.00"
					( Origin gBackEnd )
				)
				( attribute "HOLE_TO_HOLE_SPACING" "8.00,8.00,8.00,8.00,8.00,8.00,8.00,8.00,8.00,8.00,8.00,8.00,8.00,8.00"
					( Origin gBackEnd )
				)
				( attribute "MVIA_TO_MVIA_SPACING" "5.00,5.00,5.00,5.00,5.00,5.00,5.00,5.00,5.00,5.00,5.00,5.00,5.00,5.00"
					( Origin gBackEnd )
				)
				( attribute "MVIA_TO_THRUPIN_SPACING" "5.00,5.00,5.00,5.00,5.00,5.00,5.00,5.00,5.00,5.00,5.00,5.00,5.00,5.00"
					( Origin gBackEnd )
				)
				( attribute "MVIA_TO_SMDPIN_SPACING" "5.00,5.00,5.00,5.00,5.00,5.00,5.00,5.00,5.00,5.00,5.00,5.00,5.00,5.00"
					( Origin gBackEnd )
				)
				( attribute "MVIA_TO_THRUVIA_SPACING" "5.00,5.00,5.00,5.00,5.00,5.00,5.00,5.00,5.00,5.00,5.00,5.00,5.00,5.00"
					( Origin gBackEnd )
				)
				( attribute "MVIA_TO_BBV_SPACING" "5.00,5.00,5.00,5.00,5.00,5.00,5.00,5.00,5.00,5.00,5.00,5.00,5.00,5.00"
					( Origin gBackEnd )
				)
				( attribute "MVIA_TO_LINE_SPACING" "5.00,5.00,5.00,5.00,5.00,5.00,5.00,5.00,5.00,5.00,5.00,5.00,5.00,5.00"
					( Origin gBackEnd )
				)
				( attribute "MVIA_TO_SHAPE_SPACING" "5.00,5.00,5.00,5.00,5.00,5.00,5.00,5.00,5.00,5.00,5.00,5.00,5.00,5.00"
					( Origin gBackEnd )
				)
				( attribute "MVIA_TO_TESTPIN_SPACING" "5.00,5.00,5.00,5.00,5.00,5.00,5.00,5.00,5.00,5.00,5.00,5.00,5.00,5.00"
					( Origin gBackEnd )
				)
				( attribute "MVIA_TO_TESTVIA_SPACING" "5.00,5.00,5.00,5.00,5.00,5.00,5.00,5.00,5.00,5.00,5.00,5.00,5.00,5.00"
					( Origin gBackEnd )
				)
				( attribute "BONDPAD_TO_MVIA_SPACING" "5.00,5.00,5.00,5.00,5.00,5.00,5.00,5.00,5.00,5.00,5.00,5.00,5.00,5.00"
					( Origin gBackEnd )
				)
				( attribute "MIN_BVIA_GAP" "5.00"
					( Origin gBackEnd )
				)
				( attribute "BONDPAD_TO_BONDPAD_DIFFP_SPC" "5.00,5.00,5.00,5.00,5.00,5.00,5.00,5.00,5.00,5.00,5.00,5.00,5.00,5.00"
					( Origin gBackEnd )
				)
				( objectStatus "9H_US_&_3H_SL_VIA_3H+A" )
			)
			( spacingCSet "@sapphirecity_baseboard_lib.sapphirecity_baseboard(sch_1):\20_MILS_VIA+2H_A\"
				( attribute "THRUPIN_TO_THRUPIN_SPACING" "5.00,5.00,5.00,5.00,5.00,5.00,5.00,5.00,5.00,5.00,5.00,5.00,5.00,5.00"
					( Origin gBackEnd )
				)
				( attribute "THRUPIN_TO_SMDPIN_SPACING" "5.00,5.00,5.00,5.00,5.00,5.00,5.00,5.00,5.00,5.00,5.00,5.00,5.00,5.00"
					( Origin gBackEnd )
				)
				( attribute "TESTPIN_TO_THRUPIN_SPACING" "5.00,5.00,5.00,5.00,5.00,5.00,5.00,5.00,5.00,5.00,5.00,5.00,5.00,5.00"
					( Origin gBackEnd )
				)
				( attribute "THRUPIN_TO_THRUVIA_SPACING" "5.00,5.00,5.00,5.00,5.00,5.00,5.00,5.00,5.00,5.00,5.00,5.00,5.00,5.00"
					( Origin gBackEnd )
				)
				( attribute "TESTVIA_TO_THRUPIN_SPACING" "5.00,5.00,5.00,5.00,5.00,5.00,5.00,5.00,5.00,5.00,5.00,5.00,5.00,5.00"
					( Origin gBackEnd )
				)
				( attribute "BBV_TO_THRUPIN_SPACING" "5.00,5.00,5.00,5.00,5.00,5.00,5.00,5.00,5.00,5.00,5.00,5.00,5.00,5.00"
					( Origin gBackEnd )
				)
				( attribute "THRUPIN_TO_BONDPAD_SPACING" "5.00,5.00,5.00,5.00,5.00,5.00,5.00,5.00,5.00,5.00,5.00,5.00,5.00,5.00"
					( Origin gBackEnd )
				)
				( attribute "LINE_TO_THRUPIN_SPACING" "4.50,4.00,4.00,4.00,4.00,4.00,4.00,4.00,4.00,4.00,4.00,4.00,4.00,4.50"
					( Origin gBackEnd )
				)
				( attribute "THRUPIN_TO_SHAPE_SPACING" "4.50,4.00,4.00,4.00,4.00,4.00,4.00,4.00,4.00,4.00,4.00,4.00,4.00,4.00"
					( Origin gBackEnd )
				)
				( attribute "SMDPIN_TO_SMDPIN_SPACING" "5.00,5.00,5.00,5.00,5.00,5.00,5.00,5.00,5.00,5.00,5.00,5.00,5.00,5.00"
					( Origin gBackEnd )
				)
				( attribute "SMDPIN_TO_TESTPIN_SPACING" "5.00,5.00,5.00,5.00,5.00,5.00,5.00,5.00,5.00,5.00,5.00,5.00,5.00,25.00"
					( Origin gBackEnd )
				)
				( attribute "SMDPIN_TO_THRUVIA_SPACING" "5.00,5.00,5.00,5.00,5.00,5.00,5.00,5.00,5.00,5.00,5.00,5.00,5.00,5.00"
					( Origin gBackEnd )
				)
				( attribute "SMDPIN_TO_TESTVIA_SPACING" "5.00,5.00,5.00,5.00,5.00,5.00,5.00,5.00,5.00,5.00,5.00,5.00,5.00,5.00"
					( Origin gBackEnd )
				)
				( attribute "BBV_TO_SMDPIN_SPACING" "5.00,5.00,5.00,5.00,5.00,5.00,5.00,5.00,5.00,5.00,5.00,5.00,5.00,5.00"
					( Origin gBackEnd )
				)
				( attribute "SMDPIN_TO_BONDPAD_SPACING" "5.00,5.00,5.00,5.00,5.00,5.00,5.00,5.00,5.00,5.00,5.00,5.00,5.00,5.00"
					( Origin gBackEnd )
				)
				( attribute "LINE_TO_SMDPIN_SPACING" "4.50,4.50,4.50,4.50,4.50,4.50,4.50,4.50,4.50,4.50,4.50,4.50,4.50,4.50"
					( Origin gBackEnd )
				)
				( attribute "SHAPE_TO_SMDPIN_SPACING" "5.00,5.00,5.00,5.00,5.00,5.00,5.00,5.00,5.00,5.00,5.00,5.00,5.00,5.00"
					( Origin gBackEnd )
				)
				( attribute "TESTPIN_TO_TESTPIN_SPACING" "5.00,5.00,5.00,5.00,5.00,5.00,5.00,5.00,5.00,5.00,5.00,5.00,5.00,5.00"
					( Origin gBackEnd )
				)
				( attribute "TESTPIN_TO_THRUVIA_SPACING" "5.00,5.00,5.00,5.00,5.00,5.00,5.00,5.00,5.00,5.00,5.00,5.00,5.00,5.00"
					( Origin gBackEnd )
				)
				( attribute "TESTPIN_TO_TESTVIA_SPACING" "5.00,5.00,5.00,5.00,5.00,5.00,5.00,5.00,5.00,5.00,5.00,5.00,5.00,5.00"
					( Origin gBackEnd )
				)
				( attribute "BBV_TO_TESTPIN_SPACING" "5.00,5.00,5.00,5.00,5.00,5.00,5.00,5.00,5.00,5.00,5.00,5.00,5.00,5.00"
					( Origin gBackEnd )
				)
				( attribute "BONDPAD_TO_TESTPIN_SPACING" "5.00,5.00,5.00,5.00,5.00,5.00,5.00,5.00,5.00,5.00,5.00,5.00,5.00,5.00"
					( Origin gBackEnd )
				)
				( attribute "LINE_TO_TESTPIN_SPACING" "4.50,5.00,5.00,5.00,5.00,5.00,5.00,5.00,5.00,5.00,5.00,5.00,5.00,5.00"
					( Origin gBackEnd )
				)
				( attribute "SHAPE_TO_TESTPIN_SPACING" "4.50,4.00,4.00,4.00,4.00,4.00,4.00,4.00,4.00,4.00,4.00,4.00,4.00,4.00"
					( Origin gBackEnd )
				)
				( attribute "THRUVIA_TO_THRUVIA_SPACING" "5.00,5.00,5.00,5.00,5.00,5.00,5.00,5.00,5.00,5.00,5.00,5.00,5.00,5.00"
					( Origin gBackEnd )
				)
				( attribute "TESTVIA_TO_THRUVIA_SPACING" "5.00,5.00,5.00,5.00,5.00,5.00,5.00,5.00,5.00,5.00,5.00,5.00,5.00,5.00"
					( Origin gBackEnd )
				)
				( attribute "BBV_TO_THRUVIA_SPACING" "5.00,5.00,5.00,5.00,5.00,5.00,5.00,5.00,5.00,5.00,5.00,5.00,5.00,5.00"
					( Origin gBackEnd )
				)
				( attribute "BONDPAD_TO_THRUVIA_SPACING" "5.00,5.00,5.00,5.00,5.00,5.00,5.00,5.00,5.00,5.00,5.00,5.00,5.00,5.00"
					( Origin gBackEnd )
				)
				( attribute "LINE_TO_THRUVIA_SPACING" "9.40,5.00,10.00,5.00,10.00,5.00,5.00,5.00,5.00,10.00,5.00,10.00,5.00,9.40"
					( Origin gBackEnd )
				)
				( attribute "SHAPE_TO_THRUVIA_SPACING" "4.50,4.00,4.00,4.00,4.00,4.00,4.00,4.00,4.00,4.00,4.00,4.00,4.00,4.00"
					( Origin gBackEnd )
				)
				( attribute "TESTVIA_TO_TESTVIA_SPACING" "5.00,5.00,5.00,5.00,5.00,5.00,5.00,5.00,5.00,5.00,5.00,5.00,5.00,5.00"
					( Origin gBackEnd )
				)
				( attribute "BBV_TO_TESTVIA_SPACING" "5.00,5.00,5.00,5.00,5.00,5.00,5.00,5.00,5.00,5.00,5.00,5.00,5.00,5.00"
					( Origin gBackEnd )
				)
				( attribute "BONDPAD_TO_TESTVIA_SPACING" "5.00,5.00,5.00,5.00,5.00,5.00,5.00,5.00,5.00,5.00,5.00,5.00,5.00,5.00"
					( Origin gBackEnd )
				)
				( attribute "LINE_TO_TESTVIA_SPACING" "9.40,5.00,10.00,5.00,10.00,5.00,5.00,5.00,5.00,10.00,5.00,10.00,5.00,9.40"
					( Origin gBackEnd )
				)
				( attribute "SHAPE_TO_TESTVIA_SPACING" "4.50,4.00,4.00,4.00,4.00,4.00,4.00,4.00,4.00,4.00,4.00,4.00,4.00,4.00"
					( Origin gBackEnd )
				)
				( attribute "BBV_TO_BBV_SPACING" "5.00,5.00,5.00,5.00,5.00,5.00,5.00,5.00,5.00,5.00,5.00,5.00,5.00,5.00"
					( Origin gBackEnd )
				)
				( attribute "BONDPAD_TO_BBV_SPACING" "5.00,5.00,5.00,5.00,5.00,5.00,5.00,5.00,5.00,5.00,5.00,5.00,5.00,5.00"
					( Origin gBackEnd )
				)
				( attribute "BBV_TO_LINE_SPACING" "5.00,5.00,5.00,5.00,5.00,5.00,5.00,5.00,5.00,5.00,5.00,5.00,5.00,5.00"
					( Origin gBackEnd )
				)
				( attribute "BBV_TO_SHAPE_SPACING" "5.00,5.00,5.00,5.00,5.00,5.00,5.00,5.00,5.00,5.00,5.00,5.00,5.00,5.00"
					( Origin gBackEnd )
				)
				( attribute "BONDPAD_TO_BONDPAD_SPACING" "5.00,5.00,5.00,5.00,5.00,5.00,5.00,5.00,5.00,5.00,5.00,5.00,5.00,5.00"
					( Origin gBackEnd )
				)
				( attribute "BONDPAD_TO_LINE_SPACING" "5.00,5.00,5.00,5.00,5.00,5.00,5.00,5.00,5.00,5.00,5.00,5.00,5.00,5.00"
					( Origin gBackEnd )
				)
				( attribute "BONDPAD_TO_SHAPE_SPACING" "5.00,5.00,5.00,5.00,5.00,5.00,5.00,5.00,5.00,5.00,5.00,5.00,5.00,5.00"
					( Origin gBackEnd )
				)
				( attribute "LINE_TO_LINE_SPACING" "20.00,20.00,20.00,20.00,20.00,20.00,20.00,20.00,20.00,20.00,20.00,20.00,20.00,20.00"
					( Origin gBackEnd )
				)
				( attribute "LINE_TO_SHAPE_SPACING" "5.00,5.00,5.00,5.00,5.00,5.00,5.00,5.00,5.00,5.00,5.00,5.00,5.00,5.00"
					( Origin gBackEnd )
				)
				( attribute "SHAPE_TO_SHAPE_SPACING" "10.00,10.00,10.00,10.00,10.00,10.00,10.00,10.00,10.00,10.00,10.00,10.00,10.00,10.00"
					( Origin gBackEnd )
				)
				( attribute "HOLE_TO_PIN_SPACING" "8.00,8.00,8.00,8.00,8.00,8.00,8.00,8.00,8.00,8.00,8.00,8.00,8.00,8.00"
					( Origin gBackEnd )
				)
				( attribute "HOLE_TO_VIA_SPACING" "8.00,8.00,8.00,8.00,8.00,8.00,8.00,8.00,8.00,8.00,8.00,8.00,8.00,8.00"
					( Origin gBackEnd )
				)
				( attribute "HOLE_TO_LINE_SPACING" "8.00,8.00,8.00,8.00,8.00,8.00,8.00,8.00,8.00,8.00,8.00,8.00,8.00,8.00"
					( Origin gBackEnd )
				)
				( attribute "HOLE_TO_SHAPE_SPACING" "8.00,8.00,8.00,8.00,8.00,8.00,8.00,8.00,8.00,8.00,8.00,8.00,8.00,8.00"
					( Origin gBackEnd )
				)
				( attribute "HOLE_TO_HOLE_SPACING" "8.00,8.00,8.00,8.00,8.00,8.00,8.00,8.00,8.00,8.00,8.00,8.00,8.00,8.00"
					( Origin gBackEnd )
				)
				( attribute "MVIA_TO_MVIA_SPACING" "5.00,5.00,5.00,5.00,5.00,5.00,5.00,5.00,5.00,5.00,5.00,5.00,5.00,5.00"
					( Origin gBackEnd )
				)
				( attribute "MVIA_TO_THRUPIN_SPACING" "5.00,5.00,5.00,5.00,5.00,5.00,5.00,5.00,5.00,5.00,5.00,5.00,5.00,5.00"
					( Origin gBackEnd )
				)
				( attribute "MVIA_TO_SMDPIN_SPACING" "5.00,5.00,5.00,5.00,5.00,5.00,5.00,5.00,5.00,5.00,5.00,5.00,5.00,5.00"
					( Origin gBackEnd )
				)
				( attribute "MVIA_TO_THRUVIA_SPACING" "5.00,5.00,5.00,5.00,5.00,5.00,5.00,5.00,5.00,5.00,5.00,5.00,5.00,5.00"
					( Origin gBackEnd )
				)
				( attribute "MVIA_TO_BBV_SPACING" "5.00,5.00,5.00,5.00,5.00,5.00,5.00,5.00,5.00,5.00,5.00,5.00,5.00,5.00"
					( Origin gBackEnd )
				)
				( attribute "MVIA_TO_LINE_SPACING" "5.00,5.00,5.00,5.00,5.00,5.00,5.00,5.00,5.00,5.00,5.00,5.00,5.00,5.00"
					( Origin gBackEnd )
				)
				( attribute "MVIA_TO_SHAPE_SPACING" "5.00,5.00,5.00,5.00,5.00,5.00,5.00,5.00,5.00,5.00,5.00,5.00,5.00,5.00"
					( Origin gBackEnd )
				)
				( attribute "MVIA_TO_TESTPIN_SPACING" "5.00,5.00,5.00,5.00,5.00,5.00,5.00,5.00,5.00,5.00,5.00,5.00,5.00,5.00"
					( Origin gBackEnd )
				)
				( attribute "MVIA_TO_TESTVIA_SPACING" "5.00,5.00,5.00,5.00,5.00,5.00,5.00,5.00,5.00,5.00,5.00,5.00,5.00,5.00"
					( Origin gBackEnd )
				)
				( attribute "BONDPAD_TO_MVIA_SPACING" "5.00,5.00,5.00,5.00,5.00,5.00,5.00,5.00,5.00,5.00,5.00,5.00,5.00,5.00"
					( Origin gBackEnd )
				)
				( attribute "MIN_BVIA_GAP" "5.00"
					( Origin gBackEnd )
				)
				( attribute "BONDPAD_TO_BONDPAD_DIFFP_SPC" "5.00,5.00,5.00,5.00,5.00,5.00,5.00,5.00,5.00,5.00,5.00,5.00,5.00,5.00"
					( Origin gBackEnd )
				)
				( objectStatus "20_MILS_VIA_2H+A" )
			)
			( spacingCSet "@sapphirecity_baseboard_lib.sapphirecity_baseboard(sch_1):\DDR4_2SPC_DQ/DQS\"
				( attribute "THRUPIN_TO_THRUPIN_SPACING" "5.00,5.00,5.00,5.00,5.00,5.00,5.00,5.00,5.00,5.00,5.00,5.00,5.00,5.00"
					( Origin gBackEnd )
				)
				( attribute "THRUPIN_TO_SMDPIN_SPACING" "5.00,5.00,5.00,5.00,5.00,5.00,5.00,5.00,5.00,5.00,5.00,5.00,5.00,5.00"
					( Origin gBackEnd )
				)
				( attribute "TESTPIN_TO_THRUPIN_SPACING" "5.00,5.00,5.00,5.00,5.00,5.00,5.00,5.00,5.00,5.00,5.00,5.00,5.00,5.00"
					( Origin gBackEnd )
				)
				( attribute "THRUPIN_TO_THRUVIA_SPACING" "5.00,5.00,5.00,5.00,5.00,5.00,5.00,5.00,5.00,5.00,5.00,5.00,5.00,5.00"
					( Origin gBackEnd )
				)
				( attribute "TESTVIA_TO_THRUPIN_SPACING" "5.00,5.00,5.00,5.00,5.00,5.00,5.00,5.00,5.00,5.00,5.00,5.00,5.00,5.00"
					( Origin gBackEnd )
				)
				( attribute "BBV_TO_THRUPIN_SPACING" "5.00,5.00,5.00,5.00,5.00,5.00,5.00,5.00,5.00,5.00,5.00,5.00,5.00,5.00"
					( Origin gBackEnd )
				)
				( attribute "THRUPIN_TO_BONDPAD_SPACING" "5.00,5.00,5.00,5.00,5.00,5.00,5.00,5.00,5.00,5.00,5.00,5.00,5.00,5.00"
					( Origin gBackEnd )
				)
				( attribute "LINE_TO_THRUPIN_SPACING" "4.50,4.00,4.00,4.00,4.00,4.00,4.00,4.00,4.00,4.00,4.00,4.00,4.00,4.50"
					( Origin gBackEnd )
				)
				( attribute "THRUPIN_TO_SHAPE_SPACING" "4.50,4.00,4.00,4.00,4.00,4.00,4.00,4.00,4.00,4.00,4.00,4.00,4.00,4.00"
					( Origin gBackEnd )
				)
				( attribute "SMDPIN_TO_SMDPIN_SPACING" "5.00,5.00,5.00,5.00,5.00,5.00,5.00,5.00,5.00,5.00,5.00,5.00,5.00,5.00"
					( Origin gBackEnd )
				)
				( attribute "SMDPIN_TO_TESTPIN_SPACING" "5.00,5.00,5.00,5.00,5.00,5.00,5.00,5.00,5.00,5.00,5.00,5.00,5.00,5.00"
					( Origin gBackEnd )
				)
				( attribute "SMDPIN_TO_THRUVIA_SPACING" "5.00,5.00,5.00,5.00,5.00,5.00,5.00,5.00,5.00,5.00,5.00,5.00,5.00,5.00"
					( Origin gBackEnd )
				)
				( attribute "SMDPIN_TO_TESTVIA_SPACING" "5.00,5.00,5.00,5.00,5.00,5.00,5.00,5.00,5.00,5.00,5.00,5.00,5.00,5.00"
					( Origin gBackEnd )
				)
				( attribute "BBV_TO_SMDPIN_SPACING" "5.00,5.00,5.00,5.00,5.00,5.00,5.00,5.00,5.00,5.00,5.00,5.00,5.00,5.00"
					( Origin gBackEnd )
				)
				( attribute "SMDPIN_TO_BONDPAD_SPACING" "5.00,5.00,5.00,5.00,5.00,5.00,5.00,5.00,5.00,5.00,5.00,5.00,5.00,5.00"
					( Origin gBackEnd )
				)
				( attribute "LINE_TO_SMDPIN_SPACING" "4.50,4.50,4.50,4.50,4.50,4.50,4.50,4.50,4.50,4.50,4.50,4.50,4.50,4.50"
					( Origin gBackEnd )
				)
				( attribute "SHAPE_TO_SMDPIN_SPACING" "5.00,5.00,5.00,5.00,5.00,5.00,5.00,5.00,5.00,5.00,5.00,5.00,5.00,5.00"
					( Origin gBackEnd )
				)
				( attribute "TESTPIN_TO_TESTPIN_SPACING" "5.00,5.00,5.00,5.00,5.00,5.00,5.00,5.00,5.00,5.00,5.00,5.00,5.00,5.00"
					( Origin gBackEnd )
				)
				( attribute "TESTPIN_TO_THRUVIA_SPACING" "5.00,5.00,5.00,5.00,5.00,5.00,5.00,5.00,5.00,5.00,5.00,5.00,5.00,5.00"
					( Origin gBackEnd )
				)
				( attribute "TESTPIN_TO_TESTVIA_SPACING" "5.00,5.00,5.00,5.00,5.00,5.00,5.00,5.00,5.00,5.00,5.00,5.00,5.00,5.00"
					( Origin gBackEnd )
				)
				( attribute "BBV_TO_TESTPIN_SPACING" "5.00,5.00,5.00,5.00,5.00,5.00,5.00,5.00,5.00,5.00,5.00,5.00,5.00,5.00"
					( Origin gBackEnd )
				)
				( attribute "BONDPAD_TO_TESTPIN_SPACING" "5.00,5.00,5.00,5.00,5.00,5.00,5.00,5.00,5.00,5.00,5.00,5.00,5.00,5.00"
					( Origin gBackEnd )
				)
				( attribute "LINE_TO_TESTPIN_SPACING" "4.50,5.00,5.00,5.00,5.00,5.00,5.00,5.00,5.00,5.00,5.00,5.00,5.00,5.00"
					( Origin gBackEnd )
				)
				( attribute "SHAPE_TO_TESTPIN_SPACING" "4.50,4.00,4.00,4.00,4.00,4.00,4.00,4.00,4.00,4.00,4.00,4.00,4.00,4.00"
					( Origin gBackEnd )
				)
				( attribute "THRUVIA_TO_THRUVIA_SPACING" "5.00,5.00,5.00,5.00,5.00,5.00,5.00,5.00,5.00,5.00,5.00,5.00,5.00,5.00"
					( Origin gBackEnd )
				)
				( attribute "TESTVIA_TO_THRUVIA_SPACING" "5.00,5.00,5.00,5.00,5.00,5.00,5.00,5.00,5.00,5.00,5.00,5.00,5.00,5.00"
					( Origin gBackEnd )
				)
				( attribute "BBV_TO_THRUVIA_SPACING" "5.00,5.00,5.00,5.00,5.00,5.00,5.00,5.00,5.00,5.00,5.00,5.00,5.00,5.00"
					( Origin gBackEnd )
				)
				( attribute "BONDPAD_TO_THRUVIA_SPACING" "5.00,5.00,5.00,5.00,5.00,5.00,5.00,5.00,5.00,5.00,5.00,5.00,5.00,5.00"
					( Origin gBackEnd )
				)
				( attribute "LINE_TO_THRUVIA_SPACING" "4.50,4.00,4.00,4.00,4.00,4.00,4.00,4.00,4.00,4.00,4.00,4.00,4.00,4.50"
					( Origin gBackEnd )
				)
				( attribute "SHAPE_TO_THRUVIA_SPACING" "4.50,4.00,4.00,4.00,4.00,4.00,4.00,4.00,4.00,4.00,4.00,4.00,4.00,4.00"
					( Origin gBackEnd )
				)
				( attribute "TESTVIA_TO_TESTVIA_SPACING" "5.00,5.00,5.00,5.00,5.00,5.00,5.00,5.00,5.00,5.00,5.00,5.00,5.00,5.00"
					( Origin gBackEnd )
				)
				( attribute "BBV_TO_TESTVIA_SPACING" "5.00,5.00,5.00,5.00,5.00,5.00,5.00,5.00,5.00,5.00,5.00,5.00,5.00,5.00"
					( Origin gBackEnd )
				)
				( attribute "BONDPAD_TO_TESTVIA_SPACING" "5.00,5.00,5.00,5.00,5.00,5.00,5.00,5.00,5.00,5.00,5.00,5.00,5.00,5.00"
					( Origin gBackEnd )
				)
				( attribute "LINE_TO_TESTVIA_SPACING" "4.50,5.00,4.00,5.00,4.00,5.00,5.00,5.00,5.00,4.00,5.00,4.00,5.00,4.50"
					( Origin gBackEnd )
				)
				( attribute "SHAPE_TO_TESTVIA_SPACING" "4.50,4.00,4.00,4.00,4.00,4.00,4.00,4.00,4.00,4.00,4.00,4.00,4.00,4.00"
					( Origin gBackEnd )
				)
				( attribute "BBV_TO_BBV_SPACING" "5.00,5.00,5.00,5.00,5.00,5.00,5.00,5.00,5.00,5.00,5.00,5.00,5.00,5.00"
					( Origin gBackEnd )
				)
				( attribute "BONDPAD_TO_BBV_SPACING" "5.00,5.00,5.00,5.00,5.00,5.00,5.00,5.00,5.00,5.00,5.00,5.00,5.00,5.00"
					( Origin gBackEnd )
				)
				( attribute "BBV_TO_LINE_SPACING" "5.00,5.00,5.00,5.00,5.00,5.00,5.00,5.00,5.00,5.00,5.00,5.00,5.00,5.00"
					( Origin gBackEnd )
				)
				( attribute "BBV_TO_SHAPE_SPACING" "5.00,5.00,5.00,5.00,5.00,5.00,5.00,5.00,5.00,5.00,5.00,5.00,5.00,5.00"
					( Origin gBackEnd )
				)
				( attribute "BONDPAD_TO_BONDPAD_SPACING" "5.00,5.00,5.00,5.00,5.00,5.00,5.00,5.00,5.00,5.00,5.00,5.00,5.00,5.00"
					( Origin gBackEnd )
				)
				( attribute "BONDPAD_TO_LINE_SPACING" "5.00,5.00,5.00,5.00,5.00,5.00,5.00,5.00,5.00,5.00,5.00,5.00,5.00,5.00"
					( Origin gBackEnd )
				)
				( attribute "BONDPAD_TO_SHAPE_SPACING" "5.00,5.00,5.00,5.00,5.00,5.00,5.00,5.00,5.00,5.00,5.00,5.00,5.00,5.00"
					( Origin gBackEnd )
				)
				( attribute "LINE_TO_LINE_SPACING" "18.69,12.75,12.75,12.75,12.75,12.75,12.75,12.75,12.75,12.75,12.75,12.75,12.75,18.69"
					( Origin gBackEnd )
				)
				( attribute "LINE_TO_SHAPE_SPACING" "5.00,5.00,5.00,5.00,5.00,5.00,5.00,5.00,5.00,5.00,5.00,5.00,5.00,5.00"
					( Origin gBackEnd )
				)
				( attribute "SHAPE_TO_SHAPE_SPACING" "10.00,10.00,10.00,10.00,10.00,10.00,10.00,10.00,10.00,10.00,10.00,10.00,10.00,10.00"
					( Origin gBackEnd )
				)
				( attribute "HOLE_TO_PIN_SPACING" "8.00,8.00,8.00,8.00,8.00,8.00,8.00,8.00,8.00,8.00,8.00,8.00,8.00,8.00"
					( Origin gBackEnd )
				)
				( attribute "HOLE_TO_VIA_SPACING" "8.00,8.00,8.00,8.00,8.00,8.00,8.00,8.00,8.00,8.00,8.00,8.00,8.00,8.00"
					( Origin gBackEnd )
				)
				( attribute "HOLE_TO_LINE_SPACING" "8.00,8.00,8.00,8.00,8.00,8.00,8.00,8.00,8.00,8.00,8.00,8.00,8.00,8.00"
					( Origin gBackEnd )
				)
				( attribute "HOLE_TO_SHAPE_SPACING" "8.00,8.00,8.00,8.00,8.00,8.00,8.00,8.00,8.00,8.00,8.00,8.00,8.00,8.00"
					( Origin gBackEnd )
				)
				( attribute "HOLE_TO_HOLE_SPACING" "8.00,8.00,8.00,8.00,8.00,8.00,8.00,8.00,8.00,8.00,8.00,8.00,8.00,8.00"
					( Origin gBackEnd )
				)
				( attribute "MVIA_TO_MVIA_SPACING" "5.00,5.00,5.00,5.00,5.00,5.00,5.00,5.00,5.00,5.00,5.00,5.00,5.00,5.00"
					( Origin gBackEnd )
				)
				( attribute "MVIA_TO_THRUPIN_SPACING" "5.00,5.00,5.00,5.00,5.00,5.00,5.00,5.00,5.00,5.00,5.00,5.00,5.00,5.00"
					( Origin gBackEnd )
				)
				( attribute "MVIA_TO_SMDPIN_SPACING" "5.00,5.00,5.00,5.00,5.00,5.00,5.00,5.00,5.00,5.00,5.00,5.00,5.00,5.00"
					( Origin gBackEnd )
				)
				( attribute "MVIA_TO_THRUVIA_SPACING" "5.00,5.00,5.00,5.00,5.00,5.00,5.00,5.00,5.00,5.00,5.00,5.00,5.00,5.00"
					( Origin gBackEnd )
				)
				( attribute "MVIA_TO_BBV_SPACING" "5.00,5.00,5.00,5.00,5.00,5.00,5.00,5.00,5.00,5.00,5.00,5.00,5.00,5.00"
					( Origin gBackEnd )
				)
				( attribute "MVIA_TO_LINE_SPACING" "5.00,5.00,5.00,5.00,5.00,5.00,5.00,5.00,5.00,5.00,5.00,5.00,5.00,5.00"
					( Origin gBackEnd )
				)
				( attribute "MVIA_TO_SHAPE_SPACING" "5.00,5.00,5.00,5.00,5.00,5.00,5.00,5.00,5.00,5.00,5.00,5.00,5.00,5.00"
					( Origin gBackEnd )
				)
				( attribute "MVIA_TO_TESTPIN_SPACING" "5.00,5.00,5.00,5.00,5.00,5.00,5.00,5.00,5.00,5.00,5.00,5.00,5.00,5.00"
					( Origin gBackEnd )
				)
				( attribute "MVIA_TO_TESTVIA_SPACING" "5.00,5.00,5.00,5.00,5.00,5.00,5.00,5.00,5.00,5.00,5.00,5.00,5.00,5.00"
					( Origin gBackEnd )
				)
				( attribute "BONDPAD_TO_MVIA_SPACING" "5.00,5.00,5.00,5.00,5.00,5.00,5.00,5.00,5.00,5.00,5.00,5.00,5.00,5.00"
					( Origin gBackEnd )
				)
				( attribute "MIN_BVIA_GAP" "5.00"
					( Origin gBackEnd )
				)
				( attribute "BONDPAD_TO_BONDPAD_DIFFP_SPC" "5.00,5.00,5.00,5.00,5.00,5.00,5.00,5.00,5.00,5.00,5.00,5.00,5.00,5.00"
					( Origin gBackEnd )
				)
				( objectStatus "7H_US_&_4P25H_SL" )
			)
			( spacingCSet "@sapphirecity_baseboard_lib.sapphirecity_baseboard(sch_1):\KTI_SPACING\"
				( attribute "THRUPIN_TO_THRUPIN_SPACING" "5.00,5.00,5.00,5.00,5.00,5.00,5.00,5.00,5.00,5.00,5.00,5.00,5.00,5.00"
					( Origin gBackEnd )
				)
				( attribute "THRUPIN_TO_SMDPIN_SPACING" "5.00,5.00,5.00,5.00,5.00,5.00,5.00,5.00,5.00,5.00,5.00,5.00,5.00,5.00"
					( Origin gBackEnd )
				)
				( attribute "TESTPIN_TO_THRUPIN_SPACING" "5.00,5.00,5.00,5.00,5.00,5.00,5.00,5.00,5.00,5.00,5.00,5.00,5.00,5.00"
					( Origin gBackEnd )
				)
				( attribute "THRUPIN_TO_THRUVIA_SPACING" "5.00,5.00,5.00,5.00,5.00,5.00,5.00,5.00,5.00,5.00,5.00,5.00,5.00,5.00"
					( Origin gBackEnd )
				)
				( attribute "TESTVIA_TO_THRUPIN_SPACING" "5.00,5.00,5.00,5.00,5.00,5.00,5.00,5.00,5.00,5.00,5.00,5.00,5.00,5.00"
					( Origin gBackEnd )
				)
				( attribute "BBV_TO_THRUPIN_SPACING" "5.00,5.00,5.00,5.00,5.00,5.00,5.00,5.00,5.00,5.00,5.00,5.00,5.00,5.00"
					( Origin gBackEnd )
				)
				( attribute "THRUPIN_TO_BONDPAD_SPACING" "5.00,5.00,5.00,5.00,5.00,5.00,5.00,5.00,5.00,5.00,5.00,5.00,5.00,5.00"
					( Origin gBackEnd )
				)
				( attribute "LINE_TO_THRUPIN_SPACING" "5.00,5.00,5.00,5.00,5.00,5.00,5.00,5.00,5.00,5.00,5.00,5.00,5.00,5.00"
					( Origin gBackEnd )
				)
				( attribute "THRUPIN_TO_SHAPE_SPACING" "5.00,5.00,5.00,5.00,5.00,5.00,5.00,5.00,5.00,5.00,5.00,5.00,5.00,5.00"
					( Origin gBackEnd )
				)
				( attribute "SMDPIN_TO_SMDPIN_SPACING" "5.00,5.00,5.00,5.00,5.00,5.00,5.00,5.00,5.00,5.00,5.00,5.00,5.00,5.00"
					( Origin gBackEnd )
				)
				( attribute "SMDPIN_TO_TESTPIN_SPACING" "5.00,5.00,5.00,5.00,5.00,5.00,5.00,5.00,5.00,5.00,5.00,5.00,5.00,5.00"
					( Origin gBackEnd )
				)
				( attribute "SMDPIN_TO_THRUVIA_SPACING" "5.00,5.00,5.00,5.00,5.00,5.00,5.00,5.00,5.00,5.00,5.00,5.00,5.00,5.00"
					( Origin gBackEnd )
				)
				( attribute "SMDPIN_TO_TESTVIA_SPACING" "5.00,5.00,5.00,5.00,5.00,5.00,5.00,5.00,5.00,5.00,5.00,5.00,5.00,5.00"
					( Origin gBackEnd )
				)
				( attribute "BBV_TO_SMDPIN_SPACING" "5.00,5.00,5.00,5.00,5.00,5.00,5.00,5.00,5.00,5.00,5.00,5.00,5.00,5.00"
					( Origin gBackEnd )
				)
				( attribute "SMDPIN_TO_BONDPAD_SPACING" "5.00,5.00,5.00,5.00,5.00,5.00,5.00,5.00,5.00,5.00,5.00,5.00,5.00,5.00"
					( Origin gBackEnd )
				)
				( attribute "LINE_TO_SMDPIN_SPACING" "4.50,4.50,4.50,4.50,4.50,4.50,4.50,4.50,4.50,4.50,4.50,4.50,4.50,4.50"
					( Origin gBackEnd )
				)
				( attribute "SHAPE_TO_SMDPIN_SPACING" "5.00,5.00,5.00,5.00,5.00,5.00,5.00,5.00,5.00,5.00,5.00,5.00,5.00,5.00"
					( Origin gBackEnd )
				)
				( attribute "TESTPIN_TO_TESTPIN_SPACING" "5.00,5.00,5.00,5.00,5.00,5.00,5.00,5.00,5.00,5.00,5.00,5.00,5.00,5.00"
					( Origin gBackEnd )
				)
				( attribute "TESTPIN_TO_THRUVIA_SPACING" "5.00,5.00,5.00,5.00,5.00,5.00,5.00,5.00,5.00,5.00,5.00,5.00,5.00,5.00"
					( Origin gBackEnd )
				)
				( attribute "TESTPIN_TO_TESTVIA_SPACING" "5.00,5.00,5.00,5.00,5.00,5.00,5.00,5.00,5.00,5.00,5.00,5.00,5.00,5.00"
					( Origin gBackEnd )
				)
				( attribute "BBV_TO_TESTPIN_SPACING" "5.00,5.00,5.00,5.00,5.00,5.00,5.00,5.00,5.00,5.00,5.00,5.00,5.00,5.00"
					( Origin gBackEnd )
				)
				( attribute "BONDPAD_TO_TESTPIN_SPACING" "5.00,5.00,5.00,5.00,5.00,5.00,5.00,5.00,5.00,5.00,5.00,5.00,5.00,5.00"
					( Origin gBackEnd )
				)
				( attribute "LINE_TO_TESTPIN_SPACING" "4.50,5.00,5.00,5.00,5.00,5.00,5.00,5.00,5.00,5.00,5.00,5.00,5.00,5.00"
					( Origin gBackEnd )
				)
				( attribute "SHAPE_TO_TESTPIN_SPACING" "5.00,5.00,5.00,5.00,5.00,5.00,5.00,5.00,5.00,5.00,5.00,5.00,5.00,5.00"
					( Origin gBackEnd )
				)
				( attribute "THRUVIA_TO_THRUVIA_SPACING" "5.00,5.00,5.00,5.00,5.00,5.00,5.00,5.00,5.00,5.00,5.00,5.00,5.00,5.00"
					( Origin gBackEnd )
				)
				( attribute "TESTVIA_TO_THRUVIA_SPACING" "5.00,5.00,5.00,5.00,5.00,5.00,5.00,5.00,5.00,5.00,5.00,5.00,5.00,5.00"
					( Origin gBackEnd )
				)
				( attribute "BBV_TO_THRUVIA_SPACING" "5.00,5.00,5.00,5.00,5.00,5.00,5.00,5.00,5.00,5.00,5.00,5.00,5.00,5.00"
					( Origin gBackEnd )
				)
				( attribute "BONDPAD_TO_THRUVIA_SPACING" "5.00,5.00,5.00,5.00,5.00,5.00,5.00,5.00,5.00,5.00,5.00,5.00,5.00,5.00"
					( Origin gBackEnd )
				)
				( attribute "LINE_TO_THRUVIA_SPACING" "4.50,4.00,4.00,4.00,4.00,4.00,4.00,4.00,4.00,4.00,4.00,4.00,4.00,4.50"
					( Origin gBackEnd )
				)
				( attribute "SHAPE_TO_THRUVIA_SPACING" "5.00,5.00,5.00,5.00,5.00,5.00,5.00,5.00,5.00,5.00,5.00,5.00,5.00,5.00"
					( Origin gBackEnd )
				)
				( attribute "TESTVIA_TO_TESTVIA_SPACING" "5.00,5.00,5.00,5.00,5.00,5.00,5.00,5.00,5.00,5.00,5.00,5.00,5.00,5.00"
					( Origin gBackEnd )
				)
				( attribute "BBV_TO_TESTVIA_SPACING" "5.00,5.00,5.00,5.00,5.00,5.00,5.00,5.00,5.00,5.00,5.00,5.00,5.00,5.00"
					( Origin gBackEnd )
				)
				( attribute "BONDPAD_TO_TESTVIA_SPACING" "5.00,5.00,5.00,5.00,5.00,5.00,5.00,5.00,5.00,5.00,5.00,5.00,5.00,5.00"
					( Origin gBackEnd )
				)
				( attribute "LINE_TO_TESTVIA_SPACING" "4.50,5.00,5.00,5.00,5.00,5.00,5.00,5.00,5.00,5.00,5.00,5.00,5.00,4.50"
					( Origin gBackEnd )
				)
				( attribute "SHAPE_TO_TESTVIA_SPACING" "5.00,5.00,5.00,5.00,5.00,5.00,5.00,5.00,5.00,5.00,5.00,5.00,5.00,5.00"
					( Origin gBackEnd )
				)
				( attribute "BBV_TO_BBV_SPACING" "5.00,5.00,5.00,5.00,5.00,5.00,5.00,5.00,5.00,5.00,5.00,5.00,5.00,5.00"
					( Origin gBackEnd )
				)
				( attribute "BONDPAD_TO_BBV_SPACING" "5.00,5.00,5.00,5.00,5.00,5.00,5.00,5.00,5.00,5.00,5.00,5.00,5.00,5.00"
					( Origin gBackEnd )
				)
				( attribute "BBV_TO_LINE_SPACING" "5.00,5.00,5.00,5.00,5.00,5.00,5.00,5.00,5.00,5.00,5.00,5.00,5.00,5.00"
					( Origin gBackEnd )
				)
				( attribute "BBV_TO_SHAPE_SPACING" "5.00,5.00,5.00,5.00,5.00,5.00,5.00,5.00,5.00,5.00,5.00,5.00,5.00,5.00"
					( Origin gBackEnd )
				)
				( attribute "BONDPAD_TO_BONDPAD_SPACING" "5.00,5.00,5.00,5.00,5.00,5.00,5.00,5.00,5.00,5.00,5.00,5.00,5.00,5.00"
					( Origin gBackEnd )
				)
				( attribute "BONDPAD_TO_LINE_SPACING" "5.00,5.00,5.00,5.00,5.00,5.00,5.00,5.00,5.00,5.00,5.00,5.00,5.00,5.00"
					( Origin gBackEnd )
				)
				( attribute "BONDPAD_TO_SHAPE_SPACING" "5.00,5.00,5.00,5.00,5.00,5.00,5.00,5.00,5.00,5.00,5.00,5.00,5.00,5.00"
					( Origin gBackEnd )
				)
				( attribute "LINE_TO_LINE_SPACING" "9.00,9.00,9.00,9.00,9.00,9.00,9.00,9.00,9.00,9.00,9.00,9.00,9.00,9.00"
					( Origin gBackEnd )
				)
				( attribute "LINE_TO_SHAPE_SPACING" "5.00,5.00,5.00,5.00,5.00,5.00,5.00,5.00,5.00,5.00,5.00,5.00,5.00,5.00"
					( Origin gBackEnd )
				)
				( attribute "SHAPE_TO_SHAPE_SPACING" "10.00,10.00,10.00,10.00,10.00,10.00,10.00,10.00,10.00,10.00,10.00,10.00,10.00,10.00"
					( Origin gBackEnd )
				)
				( attribute "HOLE_TO_PIN_SPACING" "8.00,8.00,8.00,8.00,8.00,8.00,8.00,8.00,8.00,8.00,8.00,8.00,8.00,8.00"
					( Origin gBackEnd )
				)
				( attribute "HOLE_TO_VIA_SPACING" "8.00,8.00,8.00,8.00,8.00,8.00,8.00,8.00,8.00,8.00,8.00,8.00,8.00,8.00"
					( Origin gBackEnd )
				)
				( attribute "HOLE_TO_LINE_SPACING" "8.00,8.00,8.00,8.00,8.00,8.00,8.00,8.00,8.00,8.00,8.00,8.00,8.00,8.00"
					( Origin gBackEnd )
				)
				( attribute "HOLE_TO_SHAPE_SPACING" "8.00,8.00,8.00,8.00,8.00,8.00,8.00,8.00,8.00,8.00,8.00,8.00,8.00,8.00"
					( Origin gBackEnd )
				)
				( attribute "HOLE_TO_HOLE_SPACING" "8.00,8.00,8.00,8.00,8.00,8.00,8.00,8.00,8.00,8.00,8.00,8.00,8.00,8.00"
					( Origin gBackEnd )
				)
				( attribute "MVIA_TO_MVIA_SPACING" "5.00,5.00,5.00,5.00,5.00,5.00,5.00,5.00,5.00,5.00,5.00,5.00,5.00,5.00"
					( Origin gBackEnd )
				)
				( attribute "MVIA_TO_THRUPIN_SPACING" "5.00,5.00,5.00,5.00,5.00,5.00,5.00,5.00,5.00,5.00,5.00,5.00,5.00,5.00"
					( Origin gBackEnd )
				)
				( attribute "MVIA_TO_SMDPIN_SPACING" "5.00,5.00,5.00,5.00,5.00,5.00,5.00,5.00,5.00,5.00,5.00,5.00,5.00,5.00"
					( Origin gBackEnd )
				)
				( attribute "MVIA_TO_THRUVIA_SPACING" "5.00,5.00,5.00,5.00,5.00,5.00,5.00,5.00,5.00,5.00,5.00,5.00,5.00,5.00"
					( Origin gBackEnd )
				)
				( attribute "MVIA_TO_BBV_SPACING" "5.00,5.00,5.00,5.00,5.00,5.00,5.00,5.00,5.00,5.00,5.00,5.00,5.00,5.00"
					( Origin gBackEnd )
				)
				( attribute "MVIA_TO_LINE_SPACING" "5.00,5.00,5.00,5.00,5.00,5.00,5.00,5.00,5.00,5.00,5.00,5.00,5.00,5.00"
					( Origin gBackEnd )
				)
				( attribute "MVIA_TO_SHAPE_SPACING" "5.00,5.00,5.00,5.00,5.00,5.00,5.00,5.00,5.00,5.00,5.00,5.00,5.00,5.00"
					( Origin gBackEnd )
				)
				( attribute "MVIA_TO_TESTPIN_SPACING" "5.00,5.00,5.00,5.00,5.00,5.00,5.00,5.00,5.00,5.00,5.00,5.00,5.00,5.00"
					( Origin gBackEnd )
				)
				( attribute "MVIA_TO_TESTVIA_SPACING" "5.00,5.00,5.00,5.00,5.00,5.00,5.00,5.00,5.00,5.00,5.00,5.00,5.00,5.00"
					( Origin gBackEnd )
				)
				( attribute "BONDPAD_TO_MVIA_SPACING" "5.00,5.00,5.00,5.00,5.00,5.00,5.00,5.00,5.00,5.00,5.00,5.00,5.00,5.00"
					( Origin gBackEnd )
				)
				( attribute "MIN_BVIA_GAP" "5.00"
					( Origin gBackEnd )
				)
				( attribute "BONDPAD_TO_BONDPAD_DIFFP_SPC" "5.00,5.00,5.00,5.00,5.00,5.00,5.00,5.00,5.00,5.00,5.00,5.00,5.00,5.00"
					( Origin gBackEnd )
				)
				( objectStatus "KTI_SPACING" )
			)
			( spacingCSet "@sapphirecity_baseboard_lib.sapphirecity_baseboard(sch_1):\11MIL_MS_16MIL_SL\"
				( attribute "THRUPIN_TO_THRUPIN_SPACING" "5.00,5.00,5.00,5.00,5.00,5.00,5.00,5.00,5.00,5.00,5.00,5.00,5.00,5.00"
					( Origin gBackEnd )
				)
				( attribute "THRUPIN_TO_SMDPIN_SPACING" "5.00,5.00,5.00,5.00,5.00,5.00,5.00,5.00,5.00,5.00,5.00,5.00,5.00,5.00"
					( Origin gBackEnd )
				)
				( attribute "TESTPIN_TO_THRUPIN_SPACING" "5.00,5.00,5.00,5.00,5.00,5.00,5.00,5.00,5.00,5.00,5.00,5.00,5.00,5.00"
					( Origin gBackEnd )
				)
				( attribute "THRUPIN_TO_THRUVIA_SPACING" "5.00,5.00,5.00,5.00,5.00,5.00,5.00,5.00,5.00,5.00,5.00,5.00,5.00,5.00"
					( Origin gBackEnd )
				)
				( attribute "TESTVIA_TO_THRUPIN_SPACING" "5.00,5.00,5.00,5.00,5.00,5.00,5.00,5.00,5.00,5.00,5.00,5.00,5.00,5.00"
					( Origin gBackEnd )
				)
				( attribute "BBV_TO_THRUPIN_SPACING" "5.00,5.00,5.00,5.00,5.00,5.00,5.00,5.00,5.00,5.00,5.00,5.00,5.00,5.00"
					( Origin gBackEnd )
				)
				( attribute "THRUPIN_TO_BONDPAD_SPACING" "5.00,5.00,5.00,5.00,5.00,5.00,5.00,5.00,5.00,5.00,5.00,5.00,5.00,5.00"
					( Origin gBackEnd )
				)
				( attribute "LINE_TO_THRUPIN_SPACING" "4.50,4.00,4.00,4.00,4.00,4.00,4.00,4.00,4.00,4.00,4.00,4.00,4.00,4.50"
					( Origin gBackEnd )
				)
				( attribute "THRUPIN_TO_SHAPE_SPACING" "5.00,5.00,5.00,5.00,5.00,5.00,5.00,5.00,5.00,5.00,5.00,5.00,5.00,5.00"
					( Origin gBackEnd )
				)
				( attribute "SMDPIN_TO_SMDPIN_SPACING" "5.00,5.00,5.00,5.00,5.00,5.00,5.00,5.00,5.00,5.00,5.00,5.00,5.00,5.00"
					( Origin gBackEnd )
				)
				( attribute "SMDPIN_TO_TESTPIN_SPACING" "5.00,5.00,5.00,5.00,5.00,5.00,5.00,5.00,5.00,5.00,5.00,5.00,5.00,25.00"
					( Origin gBackEnd )
				)
				( attribute "SMDPIN_TO_THRUVIA_SPACING" "5.00,5.00,5.00,5.00,5.00,5.00,5.00,5.00,5.00,5.00,5.00,5.00,5.00,5.00"
					( Origin gBackEnd )
				)
				( attribute "SMDPIN_TO_TESTVIA_SPACING" "5.00,5.00,5.00,5.00,5.00,5.00,5.00,5.00,5.00,5.00,5.00,5.00,5.00,5.00"
					( Origin gBackEnd )
				)
				( attribute "BBV_TO_SMDPIN_SPACING" "5.00,5.00,5.00,5.00,5.00,5.00,5.00,5.00,5.00,5.00,5.00,5.00,5.00,5.00"
					( Origin gBackEnd )
				)
				( attribute "SMDPIN_TO_BONDPAD_SPACING" "5.00,5.00,5.00,5.00,5.00,5.00,5.00,5.00,5.00,5.00,5.00,5.00,5.00,5.00"
					( Origin gBackEnd )
				)
				( attribute "LINE_TO_SMDPIN_SPACING" "4.50,4.50,4.50,4.50,4.50,4.50,4.50,4.50,4.50,4.50,4.50,4.50,4.50,4.50"
					( Origin gBackEnd )
				)
				( attribute "SHAPE_TO_SMDPIN_SPACING" "5.00,5.00,5.00,5.00,5.00,5.00,5.00,5.00,5.00,5.00,5.00,5.00,5.00,5.00"
					( Origin gBackEnd )
				)
				( attribute "TESTPIN_TO_TESTPIN_SPACING" "5.00,5.00,5.00,5.00,5.00,5.00,5.00,5.00,5.00,5.00,5.00,5.00,5.00,5.00"
					( Origin gBackEnd )
				)
				( attribute "TESTPIN_TO_THRUVIA_SPACING" "5.00,5.00,5.00,5.00,5.00,5.00,5.00,5.00,5.00,5.00,5.00,5.00,5.00,5.00"
					( Origin gBackEnd )
				)
				( attribute "TESTPIN_TO_TESTVIA_SPACING" "5.00,5.00,5.00,5.00,5.00,5.00,5.00,5.00,5.00,5.00,5.00,5.00,5.00,5.00"
					( Origin gBackEnd )
				)
				( attribute "BBV_TO_TESTPIN_SPACING" "5.00,5.00,5.00,5.00,5.00,5.00,5.00,5.00,5.00,5.00,5.00,5.00,5.00,5.00"
					( Origin gBackEnd )
				)
				( attribute "BONDPAD_TO_TESTPIN_SPACING" "5.00,5.00,5.00,5.00,5.00,5.00,5.00,5.00,5.00,5.00,5.00,5.00,5.00,5.00"
					( Origin gBackEnd )
				)
				( attribute "LINE_TO_TESTPIN_SPACING" "5.00,4.00,4.00,4.00,4.00,4.00,4.00,4.00,4.00,4.00,4.00,4.00,4.00,5.00"
					( Origin gBackEnd )
				)
				( attribute "SHAPE_TO_TESTPIN_SPACING" "5.00,5.00,5.00,5.00,5.00,5.00,5.00,5.00,5.00,5.00,5.00,5.00,5.00,5.00"
					( Origin gBackEnd )
				)
				( attribute "THRUVIA_TO_THRUVIA_SPACING" "6.00,6.00,6.00,6.00,6.00,6.00,6.00,6.00,6.00,6.00,6.00,6.00,6.00,6.00"
					( Origin gBackEnd )
				)
				( attribute "TESTVIA_TO_THRUVIA_SPACING" "6.00,6.00,6.00,6.00,6.00,6.00,6.00,6.00,6.00,6.00,6.00,6.00,6.00,6.00"
					( Origin gBackEnd )
				)
				( attribute "BBV_TO_THRUVIA_SPACING" "5.00,5.00,5.00,5.00,5.00,5.00,5.00,5.00,5.00,5.00,5.00,5.00,5.00,5.00"
					( Origin gBackEnd )
				)
				( attribute "BONDPAD_TO_THRUVIA_SPACING" "5.00,5.00,5.00,5.00,5.00,5.00,5.00,5.00,5.00,5.00,5.00,5.00,5.00,5.00"
					( Origin gBackEnd )
				)
				( attribute "LINE_TO_THRUVIA_SPACING" "4.50,4.00,4.00,4.00,4.00,4.00,4.00,4.00,4.00,4.00,4.00,4.00,4.00,4.50"
					( Origin gBackEnd )
				)
				( attribute "SHAPE_TO_THRUVIA_SPACING" "5.00,5.00,5.00,5.00,5.00,5.00,5.00,5.00,5.00,5.00,5.00,5.00,5.00,5.00"
					( Origin gBackEnd )
				)
				( attribute "TESTVIA_TO_TESTVIA_SPACING" "6.00,6.00,6.00,6.00,6.00,6.00,6.00,6.00,6.00,6.00,6.00,6.00,6.00,6.00"
					( Origin gBackEnd )
				)
				( attribute "BBV_TO_TESTVIA_SPACING" "5.00,5.00,5.00,5.00,5.00,5.00,5.00,5.00,5.00,5.00,5.00,5.00,5.00,5.00"
					( Origin gBackEnd )
				)
				( attribute "BONDPAD_TO_TESTVIA_SPACING" "5.00,5.00,5.00,5.00,5.00,5.00,5.00,5.00,5.00,5.00,5.00,5.00,5.00,5.00"
					( Origin gBackEnd )
				)
				( attribute "LINE_TO_TESTVIA_SPACING" "4.50,4.00,4.00,4.00,4.00,4.00,4.00,4.00,4.00,4.00,4.00,4.00,4.00,4.50"
					( Origin gBackEnd )
				)
				( attribute "SHAPE_TO_TESTVIA_SPACING" "5.00,5.00,5.00,5.00,5.00,5.00,5.00,5.00,5.00,5.00,5.00,5.00,5.00,5.00"
					( Origin gBackEnd )
				)
				( attribute "BBV_TO_BBV_SPACING" "5.00,5.00,5.00,5.00,5.00,5.00,5.00,5.00,5.00,5.00,5.00,5.00,5.00,5.00"
					( Origin gBackEnd )
				)
				( attribute "BONDPAD_TO_BBV_SPACING" "5.00,5.00,5.00,5.00,5.00,5.00,5.00,5.00,5.00,5.00,5.00,5.00,5.00,5.00"
					( Origin gBackEnd )
				)
				( attribute "BBV_TO_LINE_SPACING" "5.00,5.00,5.00,5.00,5.00,5.00,5.00,5.00,5.00,5.00,5.00,5.00,5.00,5.00"
					( Origin gBackEnd )
				)
				( attribute "BBV_TO_SHAPE_SPACING" "5.00,5.00,5.00,5.00,5.00,5.00,5.00,5.00,5.00,5.00,5.00,5.00,5.00,5.00"
					( Origin gBackEnd )
				)
				( attribute "BONDPAD_TO_BONDPAD_SPACING" "5.00,5.00,5.00,5.00,5.00,5.00,5.00,5.00,5.00,5.00,5.00,5.00,5.00,5.00"
					( Origin gBackEnd )
				)
				( attribute "BONDPAD_TO_LINE_SPACING" "5.00,5.00,5.00,5.00,5.00,5.00,5.00,5.00,5.00,5.00,5.00,5.00,5.00,5.00"
					( Origin gBackEnd )
				)
				( attribute "BONDPAD_TO_SHAPE_SPACING" "5.00,5.00,5.00,5.00,5.00,5.00,5.00,5.00,5.00,5.00,5.00,5.00,5.00,5.00"
					( Origin gBackEnd )
				)
				( attribute "LINE_TO_LINE_SPACING" "11.00,16.00,16.00,16.00,16.00,16.00,16.00,16.00,16.00,16.00,16.00,16.00,16.00,11.00"
					( Origin gBackEnd )
				)
				( attribute "LINE_TO_SHAPE_SPACING" "10.00,10.00,10.00,10.00,10.00,10.00,10.00,10.00,10.00,10.00,10.00,10.00,10.00,10.00"
					( Origin gBackEnd )
				)
				( attribute "SHAPE_TO_SHAPE_SPACING" "10.00,10.00,10.00,10.00,10.00,10.00,10.00,10.00,10.00,10.00,10.00,10.00,10.00,10.00"
					( Origin gBackEnd )
				)
				( attribute "HOLE_TO_PIN_SPACING" "8.00,8.00,8.00,8.00,8.00,8.00,8.00,8.00,8.00,8.00,8.00,8.00,8.00,8.00"
					( Origin gBackEnd )
				)
				( attribute "HOLE_TO_VIA_SPACING" "8.00,8.00,8.00,8.00,8.00,8.00,8.00,8.00,8.00,8.00,8.00,8.00,8.00,8.00"
					( Origin gBackEnd )
				)
				( attribute "HOLE_TO_LINE_SPACING" "8.00,8.00,8.00,8.00,8.00,8.00,8.00,8.00,8.00,8.00,8.00,8.00,8.00,8.00"
					( Origin gBackEnd )
				)
				( attribute "HOLE_TO_SHAPE_SPACING" "8.00,8.00,8.00,8.00,8.00,8.00,8.00,8.00,8.00,8.00,8.00,8.00,8.00,8.00"
					( Origin gBackEnd )
				)
				( attribute "HOLE_TO_HOLE_SPACING" "8.00,8.00,8.00,8.00,8.00,8.00,8.00,8.00,8.00,8.00,8.00,8.00,8.00,8.00"
					( Origin gBackEnd )
				)
				( attribute "MVIA_TO_MVIA_SPACING" "5.00,5.00,5.00,5.00,5.00,5.00,5.00,5.00,5.00,5.00,5.00,5.00,5.00,5.00"
					( Origin gBackEnd )
				)
				( attribute "MVIA_TO_THRUPIN_SPACING" "5.00,5.00,5.00,5.00,5.00,5.00,5.00,5.00,5.00,5.00,5.00,5.00,5.00,5.00"
					( Origin gBackEnd )
				)
				( attribute "MVIA_TO_SMDPIN_SPACING" "5.00,5.00,5.00,5.00,5.00,5.00,5.00,5.00,5.00,5.00,5.00,5.00,5.00,5.00"
					( Origin gBackEnd )
				)
				( attribute "MVIA_TO_THRUVIA_SPACING" "5.00,5.00,5.00,5.00,5.00,5.00,5.00,5.00,5.00,5.00,5.00,5.00,5.00,5.00"
					( Origin gBackEnd )
				)
				( attribute "MVIA_TO_BBV_SPACING" "5.00,5.00,5.00,5.00,5.00,5.00,5.00,5.00,5.00,5.00,5.00,5.00,5.00,5.00"
					( Origin gBackEnd )
				)
				( attribute "MVIA_TO_LINE_SPACING" "5.00,5.00,5.00,5.00,5.00,5.00,5.00,5.00,5.00,5.00,5.00,5.00,5.00,5.00"
					( Origin gBackEnd )
				)
				( attribute "MVIA_TO_SHAPE_SPACING" "5.00,5.00,5.00,5.00,5.00,5.00,5.00,5.00,5.00,5.00,5.00,5.00,5.00,5.00"
					( Origin gBackEnd )
				)
				( attribute "MVIA_TO_TESTPIN_SPACING" "5.00,5.00,5.00,5.00,5.00,5.00,5.00,5.00,5.00,5.00,5.00,5.00,5.00,5.00"
					( Origin gBackEnd )
				)
				( attribute "MVIA_TO_TESTVIA_SPACING" "5.00,5.00,5.00,5.00,5.00,5.00,5.00,5.00,5.00,5.00,5.00,5.00,5.00,5.00"
					( Origin gBackEnd )
				)
				( attribute "BONDPAD_TO_MVIA_SPACING" "5.00,5.00,5.00,5.00,5.00,5.00,5.00,5.00,5.00,5.00,5.00,5.00,5.00,5.00"
					( Origin gBackEnd )
				)
				( attribute "MIN_BVIA_GAP" "5.00"
					( Origin gBackEnd )
				)
				( attribute "BONDPAD_TO_BONDPAD_DIFFP_SPC" "5.00,5.00,5.00,5.00,5.00,5.00,5.00,5.00,5.00,5.00,5.00,5.00,5.00,5.00"
					( Origin gBackEnd )
				)
				( objectStatus "11MIL_US_&_16MIL_SL" )
			)
			( spacingCSet "@sapphirecity_baseboard_lib.sapphirecity_baseboard(sch_1):\30MIL_VIA_2H+A\"
				( attribute "THRUPIN_TO_THRUPIN_SPACING" "5.00,5.00,5.00,5.00,5.00,5.00,5.00,5.00,5.00,5.00,5.00,5.00,5.00,5.00"
					( Origin gBackEnd )
				)
				( attribute "THRUPIN_TO_SMDPIN_SPACING" "5.00,5.00,5.00,5.00,5.00,5.00,5.00,5.00,5.00,5.00,5.00,5.00,5.00,5.00"
					( Origin gBackEnd )
				)
				( attribute "TESTPIN_TO_THRUPIN_SPACING" "5.00,5.00,5.00,5.00,5.00,5.00,5.00,5.00,5.00,5.00,5.00,5.00,5.00,5.00"
					( Origin gBackEnd )
				)
				( attribute "THRUPIN_TO_THRUVIA_SPACING" "5.00,5.00,5.00,5.00,5.00,5.00,5.00,5.00,5.00,5.00,5.00,5.00,5.00,5.00"
					( Origin gBackEnd )
				)
				( attribute "TESTVIA_TO_THRUPIN_SPACING" "5.00,5.00,5.00,5.00,5.00,5.00,5.00,5.00,5.00,5.00,5.00,5.00,5.00,5.00"
					( Origin gBackEnd )
				)
				( attribute "BBV_TO_THRUPIN_SPACING" "5.00,5.00,5.00,5.00,5.00,5.00,5.00,5.00,5.00,5.00,5.00,5.00,5.00,5.00"
					( Origin gBackEnd )
				)
				( attribute "THRUPIN_TO_BONDPAD_SPACING" "5.00,5.00,5.00,5.00,5.00,5.00,5.00,5.00,5.00,5.00,5.00,5.00,5.00,5.00"
					( Origin gBackEnd )
				)
				( attribute "LINE_TO_THRUPIN_SPACING" "10.40,13.00,13.00,13.00,13.00,13.00,13.00,13.00,13.00,13.00,13.00,13.00,13.00,10.40"
					( Origin gBackEnd )
				)
				( attribute "THRUPIN_TO_SHAPE_SPACING" "5.00,5.00,5.00,5.00,5.00,5.00,5.00,5.00,5.00,5.00,5.00,5.00,5.00,5.00"
					( Origin gBackEnd )
				)
				( attribute "SMDPIN_TO_SMDPIN_SPACING" "5.00,5.00,5.00,5.00,5.00,5.00,5.00,5.00,5.00,5.00,5.00,5.00,5.00,5.00"
					( Origin gBackEnd )
				)
				( attribute "SMDPIN_TO_TESTPIN_SPACING" "5.00,5.00,5.00,5.00,5.00,5.00,5.00,5.00,5.00,5.00,5.00,5.00,5.00,25.00"
					( Origin gBackEnd )
				)
				( attribute "SMDPIN_TO_THRUVIA_SPACING" "5.00,5.00,5.00,5.00,5.00,5.00,5.00,5.00,5.00,5.00,5.00,5.00,5.00,5.00"
					( Origin gBackEnd )
				)
				( attribute "SMDPIN_TO_TESTVIA_SPACING" "5.00,5.00,5.00,5.00,5.00,5.00,5.00,5.00,5.00,5.00,5.00,5.00,5.00,5.00"
					( Origin gBackEnd )
				)
				( attribute "BBV_TO_SMDPIN_SPACING" "5.00,5.00,5.00,5.00,5.00,5.00,5.00,5.00,5.00,5.00,5.00,5.00,5.00,5.00"
					( Origin gBackEnd )
				)
				( attribute "SMDPIN_TO_BONDPAD_SPACING" "5.00,5.00,5.00,5.00,5.00,5.00,5.00,5.00,5.00,5.00,5.00,5.00,5.00,5.00"
					( Origin gBackEnd )
				)
				( attribute "LINE_TO_SMDPIN_SPACING" "4.50,4.50,4.50,4.50,4.50,4.50,4.50,4.50,4.50,4.50,4.50,4.50,4.50,4.50"
					( Origin gBackEnd )
				)
				( attribute "SHAPE_TO_SMDPIN_SPACING" "5.00,5.00,5.00,5.00,5.00,5.00,5.00,5.00,5.00,5.00,5.00,5.00,5.00,5.00"
					( Origin gBackEnd )
				)
				( attribute "TESTPIN_TO_TESTPIN_SPACING" "5.00,5.00,5.00,5.00,5.00,5.00,5.00,5.00,5.00,5.00,5.00,5.00,5.00,5.00"
					( Origin gBackEnd )
				)
				( attribute "TESTPIN_TO_THRUVIA_SPACING" "5.00,5.00,5.00,5.00,5.00,5.00,5.00,5.00,5.00,5.00,5.00,5.00,5.00,5.00"
					( Origin gBackEnd )
				)
				( attribute "TESTPIN_TO_TESTVIA_SPACING" "5.00,5.00,5.00,5.00,5.00,5.00,5.00,5.00,5.00,5.00,5.00,5.00,5.00,5.00"
					( Origin gBackEnd )
				)
				( attribute "BBV_TO_TESTPIN_SPACING" "5.00,5.00,5.00,5.00,5.00,5.00,5.00,5.00,5.00,5.00,5.00,5.00,5.00,5.00"
					( Origin gBackEnd )
				)
				( attribute "BONDPAD_TO_TESTPIN_SPACING" "5.00,5.00,5.00,5.00,5.00,5.00,5.00,5.00,5.00,5.00,5.00,5.00,5.00,5.00"
					( Origin gBackEnd )
				)
				( attribute "LINE_TO_TESTPIN_SPACING" "10.40,13.00,13.00,13.00,13.00,13.00,13.00,13.00,13.00,13.00,13.00,13.00,13.00,10.40"
					( Origin gBackEnd )
				)
				( attribute "SHAPE_TO_TESTPIN_SPACING" "5.00,5.00,5.00,5.00,5.00,5.00,5.00,5.00,5.00,5.00,5.00,5.00,5.00,5.00"
					( Origin gBackEnd )
				)
				( attribute "THRUVIA_TO_THRUVIA_SPACING" "5.00,5.00,5.00,5.00,5.00,5.00,5.00,5.00,5.00,5.00,5.00,5.00,5.00,5.00"
					( Origin gBackEnd )
				)
				( attribute "TESTVIA_TO_THRUVIA_SPACING" "6.00,6.00,6.00,6.00,6.00,6.00,6.00,6.00,6.00,6.00,6.00,6.00,6.00,6.00"
					( Origin gBackEnd )
				)
				( attribute "BBV_TO_THRUVIA_SPACING" "5.00,5.00,5.00,5.00,5.00,5.00,5.00,5.00,5.00,5.00,5.00,5.00,5.00,5.00"
					( Origin gBackEnd )
				)
				( attribute "BONDPAD_TO_THRUVIA_SPACING" "5.00,5.00,5.00,5.00,5.00,5.00,5.00,5.00,5.00,5.00,5.00,5.00,5.00,5.00"
					( Origin gBackEnd )
				)
				( attribute "LINE_TO_THRUVIA_SPACING" "9.40,5.00,10.00,5.00,10.00,5.00,5.00,5.00,5.00,10.00,5.00,10.00,5.00,9.40"
					( Origin gBackEnd )
				)
				( attribute "SHAPE_TO_THRUVIA_SPACING" "5.00,5.00,5.00,5.00,5.00,5.00,5.00,5.00,5.00,5.00,5.00,5.00,5.00,5.00"
					( Origin gBackEnd )
				)
				( attribute "TESTVIA_TO_TESTVIA_SPACING" "6.00,6.00,6.00,6.00,6.00,6.00,6.00,6.00,6.00,6.00,6.00,6.00,6.00,6.00"
					( Origin gBackEnd )
				)
				( attribute "BBV_TO_TESTVIA_SPACING" "5.00,5.00,5.00,5.00,5.00,5.00,5.00,5.00,5.00,5.00,5.00,5.00,5.00,5.00"
					( Origin gBackEnd )
				)
				( attribute "BONDPAD_TO_TESTVIA_SPACING" "5.00,5.00,5.00,5.00,5.00,5.00,5.00,5.00,5.00,5.00,5.00,5.00,5.00,5.00"
					( Origin gBackEnd )
				)
				( attribute "LINE_TO_TESTVIA_SPACING" "4.50,5.00,10.00,5.00,10.00,5.00,5.00,5.00,5.00,10.00,5.00,10.00,5.00,9.40"
					( Origin gBackEnd )
				)
				( attribute "SHAPE_TO_TESTVIA_SPACING" "5.00,5.00,5.00,5.00,5.00,5.00,5.00,5.00,5.00,5.00,5.00,5.00,5.00,5.00"
					( Origin gBackEnd )
				)
				( attribute "BBV_TO_BBV_SPACING" "5.00,5.00,5.00,5.00,5.00,5.00,5.00,5.00,5.00,5.00,5.00,5.00,5.00,5.00"
					( Origin gBackEnd )
				)
				( attribute "BONDPAD_TO_BBV_SPACING" "5.00,5.00,5.00,5.00,5.00,5.00,5.00,5.00,5.00,5.00,5.00,5.00,5.00,5.00"
					( Origin gBackEnd )
				)
				( attribute "BBV_TO_LINE_SPACING" "5.00,5.00,5.00,5.00,5.00,5.00,5.00,5.00,5.00,5.00,5.00,5.00,5.00,5.00"
					( Origin gBackEnd )
				)
				( attribute "BBV_TO_SHAPE_SPACING" "5.00,5.00,5.00,5.00,5.00,5.00,5.00,5.00,5.00,5.00,5.00,5.00,5.00,5.00"
					( Origin gBackEnd )
				)
				( attribute "BONDPAD_TO_BONDPAD_SPACING" "5.00,5.00,5.00,5.00,5.00,5.00,5.00,5.00,5.00,5.00,5.00,5.00,5.00,5.00"
					( Origin gBackEnd )
				)
				( attribute "BONDPAD_TO_LINE_SPACING" "5.00,5.00,5.00,5.00,5.00,5.00,5.00,5.00,5.00,5.00,5.00,5.00,5.00,5.00"
					( Origin gBackEnd )
				)
				( attribute "BONDPAD_TO_SHAPE_SPACING" "5.00,5.00,5.00,5.00,5.00,5.00,5.00,5.00,5.00,5.00,5.00,5.00,5.00,5.00"
					( Origin gBackEnd )
				)
				( attribute "LINE_TO_LINE_SPACING" "30.00,30.00,30.00,30.00,30.00,30.00,30.00,30.00,30.00,30.00,30.00,30.00,30.00,30.00"
					( Origin gBackEnd )
				)
				( attribute "LINE_TO_SHAPE_SPACING" "10.00,10.00,10.00,10.00,10.00,10.00,10.00,10.00,10.00,10.00,10.00,10.00,10.00,10.00"
					( Origin gBackEnd )
				)
				( attribute "SHAPE_TO_SHAPE_SPACING" "10.00,10.00,10.00,10.00,10.00,10.00,10.00,10.00,10.00,10.00,10.00,10.00,10.00,10.00"
					( Origin gBackEnd )
				)
				( attribute "HOLE_TO_PIN_SPACING" "8.00,8.00,8.00,8.00,8.00,8.00,8.00,8.00,8.00,8.00,8.00,8.00,8.00,8.00"
					( Origin gBackEnd )
				)
				( attribute "HOLE_TO_VIA_SPACING" "8.00,8.00,8.00,8.00,8.00,8.00,8.00,8.00,8.00,8.00,8.00,8.00,8.00,8.00"
					( Origin gBackEnd )
				)
				( attribute "HOLE_TO_LINE_SPACING" "8.00,8.00,8.00,8.00,8.00,8.00,8.00,8.00,8.00,8.00,8.00,8.00,8.00,8.00"
					( Origin gBackEnd )
				)
				( attribute "HOLE_TO_SHAPE_SPACING" "8.00,8.00,8.00,8.00,8.00,8.00,8.00,8.00,8.00,8.00,8.00,8.00,8.00,8.00"
					( Origin gBackEnd )
				)
				( attribute "HOLE_TO_HOLE_SPACING" "8.00,8.00,8.00,8.00,8.00,8.00,8.00,8.00,8.00,8.00,8.00,8.00,8.00,8.00"
					( Origin gBackEnd )
				)
				( attribute "MVIA_TO_MVIA_SPACING" "5.00,5.00,5.00,5.00,5.00,5.00,5.00,5.00,5.00,5.00,5.00,5.00,5.00,5.00"
					( Origin gBackEnd )
				)
				( attribute "MVIA_TO_THRUPIN_SPACING" "5.00,5.00,5.00,5.00,5.00,5.00,5.00,5.00,5.00,5.00,5.00,5.00,5.00,5.00"
					( Origin gBackEnd )
				)
				( attribute "MVIA_TO_SMDPIN_SPACING" "5.00,5.00,5.00,5.00,5.00,5.00,5.00,5.00,5.00,5.00,5.00,5.00,5.00,5.00"
					( Origin gBackEnd )
				)
				( attribute "MVIA_TO_THRUVIA_SPACING" "5.00,5.00,5.00,5.00,5.00,5.00,5.00,5.00,5.00,5.00,5.00,5.00,5.00,5.00"
					( Origin gBackEnd )
				)
				( attribute "MVIA_TO_BBV_SPACING" "5.00,5.00,5.00,5.00,5.00,5.00,5.00,5.00,5.00,5.00,5.00,5.00,5.00,5.00"
					( Origin gBackEnd )
				)
				( attribute "MVIA_TO_LINE_SPACING" "5.00,5.00,5.00,5.00,5.00,5.00,5.00,5.00,5.00,5.00,5.00,5.00,5.00,5.00"
					( Origin gBackEnd )
				)
				( attribute "MVIA_TO_SHAPE_SPACING" "5.00,5.00,5.00,5.00,5.00,5.00,5.00,5.00,5.00,5.00,5.00,5.00,5.00,5.00"
					( Origin gBackEnd )
				)
				( attribute "MVIA_TO_TESTPIN_SPACING" "5.00,5.00,5.00,5.00,5.00,5.00,5.00,5.00,5.00,5.00,5.00,5.00,5.00,5.00"
					( Origin gBackEnd )
				)
				( attribute "MVIA_TO_TESTVIA_SPACING" "5.00,5.00,5.00,5.00,5.00,5.00,5.00,5.00,5.00,5.00,5.00,5.00,5.00,5.00"
					( Origin gBackEnd )
				)
				( attribute "BONDPAD_TO_MVIA_SPACING" "5.00,5.00,5.00,5.00,5.00,5.00,5.00,5.00,5.00,5.00,5.00,5.00,5.00,5.00"
					( Origin gBackEnd )
				)
				( attribute "MIN_BVIA_GAP" "5.00"
					( Origin gBackEnd )
				)
				( attribute "BONDPAD_TO_BONDPAD_DIFFP_SPC" "5.00,5.00,5.00,5.00,5.00,5.00,5.00,5.00,5.00,5.00,5.00,5.00,5.00,5.00"
					( Origin gBackEnd )
				)
				( objectStatus "30MIL_VIA_2H+A" )
			)
			( spacingCSet "@sapphirecity_baseboard_lib.sapphirecity_baseboard(sch_1):\8MIL\"
				( attribute "THRUPIN_TO_THRUPIN_SPACING" "5.00,5.00,5.00,5.00,5.00,5.00,5.00,5.00,5.00,5.00,5.00,5.00,5.00,5.00"
					( Origin gBackEnd )
				)
				( attribute "THRUPIN_TO_SMDPIN_SPACING" "5.00,5.00,5.00,5.00,5.00,5.00,5.00,5.00,5.00,5.00,5.00,5.00,5.00,5.00"
					( Origin gBackEnd )
				)
				( attribute "TESTPIN_TO_THRUPIN_SPACING" "5.00,5.00,5.00,5.00,5.00,5.00,5.00,5.00,5.00,5.00,5.00,5.00,5.00,5.00"
					( Origin gBackEnd )
				)
				( attribute "THRUPIN_TO_THRUVIA_SPACING" "5.00,5.00,5.00,5.00,5.00,5.00,5.00,5.00,5.00,5.00,5.00,5.00,5.00,5.00"
					( Origin gBackEnd )
				)
				( attribute "TESTVIA_TO_THRUPIN_SPACING" "5.00,5.00,5.00,5.00,5.00,5.00,5.00,5.00,5.00,5.00,5.00,5.00,5.00,5.00"
					( Origin gBackEnd )
				)
				( attribute "BBV_TO_THRUPIN_SPACING" "5.00,5.00,5.00,5.00,5.00,5.00,5.00,5.00,5.00,5.00,5.00,5.00,5.00,5.00"
					( Origin gBackEnd )
				)
				( attribute "THRUPIN_TO_BONDPAD_SPACING" "5.00,5.00,5.00,5.00,5.00,5.00,5.00,5.00,5.00,5.00,5.00,5.00,5.00,5.00"
					( Origin gBackEnd )
				)
				( attribute "LINE_TO_THRUPIN_SPACING" "5.00,4.00,4.00,4.00,4.00,4.00,4.00,4.00,4.00,4.00,4.00,4.00,4.00,5.00"
					( Origin gBackEnd )
				)
				( attribute "THRUPIN_TO_SHAPE_SPACING" "5.00,5.00,5.00,5.00,5.00,5.00,5.00,5.00,5.00,5.00,5.00,5.00,5.00,5.00"
					( Origin gBackEnd )
				)
				( attribute "SMDPIN_TO_SMDPIN_SPACING" "5.00,5.00,5.00,5.00,5.00,5.00,5.00,5.00,5.00,5.00,5.00,5.00,5.00,5.00"
					( Origin gBackEnd )
				)
				( attribute "SMDPIN_TO_TESTPIN_SPACING" "5.00,5.00,5.00,5.00,5.00,5.00,5.00,5.00,5.00,5.00,5.00,5.00,5.00,25.00"
					( Origin gBackEnd )
				)
				( attribute "SMDPIN_TO_THRUVIA_SPACING" "5.00,5.00,5.00,5.00,5.00,5.00,5.00,5.00,5.00,5.00,5.00,5.00,5.00,5.00"
					( Origin gBackEnd )
				)
				( attribute "SMDPIN_TO_TESTVIA_SPACING" "5.00,5.00,5.00,5.00,5.00,5.00,5.00,5.00,5.00,5.00,5.00,5.00,5.00,5.00"
					( Origin gBackEnd )
				)
				( attribute "BBV_TO_SMDPIN_SPACING" "5.00,5.00,5.00,5.00,5.00,5.00,5.00,5.00,5.00,5.00,5.00,5.00,5.00,5.00"
					( Origin gBackEnd )
				)
				( attribute "SMDPIN_TO_BONDPAD_SPACING" "5.00,5.00,5.00,5.00,5.00,5.00,5.00,5.00,5.00,5.00,5.00,5.00,5.00,5.00"
					( Origin gBackEnd )
				)
				( attribute "LINE_TO_SMDPIN_SPACING" "4.50,4.50,4.50,4.50,4.50,4.50,4.50,4.50,4.50,4.50,4.50,4.50,4.50,4.50"
					( Origin gBackEnd )
				)
				( attribute "SHAPE_TO_SMDPIN_SPACING" "5.00,5.00,5.00,5.00,5.00,5.00,5.00,5.00,5.00,5.00,5.00,5.00,5.00,5.00"
					( Origin gBackEnd )
				)
				( attribute "TESTPIN_TO_TESTPIN_SPACING" "5.00,5.00,5.00,5.00,5.00,5.00,5.00,5.00,5.00,5.00,5.00,5.00,5.00,5.00"
					( Origin gBackEnd )
				)
				( attribute "TESTPIN_TO_THRUVIA_SPACING" "5.00,5.00,5.00,5.00,5.00,5.00,5.00,5.00,5.00,5.00,5.00,5.00,5.00,5.00"
					( Origin gBackEnd )
				)
				( attribute "TESTPIN_TO_TESTVIA_SPACING" "5.00,5.00,5.00,5.00,5.00,5.00,5.00,5.00,5.00,5.00,5.00,5.00,5.00,5.00"
					( Origin gBackEnd )
				)
				( attribute "BBV_TO_TESTPIN_SPACING" "5.00,5.00,5.00,5.00,5.00,5.00,5.00,5.00,5.00,5.00,5.00,5.00,5.00,5.00"
					( Origin gBackEnd )
				)
				( attribute "BONDPAD_TO_TESTPIN_SPACING" "5.00,5.00,5.00,5.00,5.00,5.00,5.00,5.00,5.00,5.00,5.00,5.00,5.00,5.00"
					( Origin gBackEnd )
				)
				( attribute "LINE_TO_TESTPIN_SPACING" "5.00,4.00,4.00,4.00,4.00,4.00,4.00,4.00,4.00,4.00,4.00,4.00,4.00,5.00"
					( Origin gBackEnd )
				)
				( attribute "SHAPE_TO_TESTPIN_SPACING" "5.00,5.00,5.00,5.00,5.00,5.00,5.00,5.00,5.00,5.00,5.00,5.00,5.00,5.00"
					( Origin gBackEnd )
				)
				( attribute "THRUVIA_TO_THRUVIA_SPACING" "6.00,6.00,6.00,6.00,6.00,6.00,6.00,6.00,6.00,6.00,6.00,6.00,6.00,6.00"
					( Origin gBackEnd )
				)
				( attribute "TESTVIA_TO_THRUVIA_SPACING" "6.00,6.00,6.00,6.00,6.00,6.00,6.00,6.00,6.00,6.00,6.00,6.00,6.00,6.00"
					( Origin gBackEnd )
				)
				( attribute "BBV_TO_THRUVIA_SPACING" "5.00,5.00,5.00,5.00,5.00,5.00,5.00,5.00,5.00,5.00,5.00,5.00,5.00,5.00"
					( Origin gBackEnd )
				)
				( attribute "BONDPAD_TO_THRUVIA_SPACING" "5.00,5.00,5.00,5.00,5.00,5.00,5.00,5.00,5.00,5.00,5.00,5.00,5.00,5.00"
					( Origin gBackEnd )
				)
				( attribute "LINE_TO_THRUVIA_SPACING" "4.50,4.00,4.00,4.00,4.00,4.00,4.00,4.00,4.00,4.00,4.00,4.00,4.00,4.50"
					( Origin gBackEnd )
				)
				( attribute "SHAPE_TO_THRUVIA_SPACING" "5.00,5.00,5.00,5.00,5.00,5.00,5.00,5.00,5.00,5.00,5.00,5.00,5.00,5.00"
					( Origin gBackEnd )
				)
				( attribute "TESTVIA_TO_TESTVIA_SPACING" "6.00,6.00,6.00,6.00,6.00,6.00,6.00,6.00,6.00,6.00,6.00,6.00,6.00,6.00"
					( Origin gBackEnd )
				)
				( attribute "BBV_TO_TESTVIA_SPACING" "5.00,5.00,5.00,5.00,5.00,5.00,5.00,5.00,5.00,5.00,5.00,5.00,5.00,5.00"
					( Origin gBackEnd )
				)
				( attribute "BONDPAD_TO_TESTVIA_SPACING" "5.00,5.00,5.00,5.00,5.00,5.00,5.00,5.00,5.00,5.00,5.00,5.00,5.00,5.00"
					( Origin gBackEnd )
				)
				( attribute "LINE_TO_TESTVIA_SPACING" "4.50,4.00,4.00,4.00,4.00,4.00,4.00,4.00,4.00,4.00,4.00,4.00,4.00,4.50"
					( Origin gBackEnd )
				)
				( attribute "SHAPE_TO_TESTVIA_SPACING" "5.00,5.00,5.00,5.00,5.00,5.00,5.00,5.00,5.00,5.00,5.00,5.00,5.00,5.00"
					( Origin gBackEnd )
				)
				( attribute "BBV_TO_BBV_SPACING" "5.00,5.00,5.00,5.00,5.00,5.00,5.00,5.00,5.00,5.00,5.00,5.00,5.00,5.00"
					( Origin gBackEnd )
				)
				( attribute "BONDPAD_TO_BBV_SPACING" "5.00,5.00,5.00,5.00,5.00,5.00,5.00,5.00,5.00,5.00,5.00,5.00,5.00,5.00"
					( Origin gBackEnd )
				)
				( attribute "BBV_TO_LINE_SPACING" "5.00,5.00,5.00,5.00,5.00,5.00,5.00,5.00,5.00,5.00,5.00,5.00,5.00,5.00"
					( Origin gBackEnd )
				)
				( attribute "BBV_TO_SHAPE_SPACING" "5.00,5.00,5.00,5.00,5.00,5.00,5.00,5.00,5.00,5.00,5.00,5.00,5.00,5.00"
					( Origin gBackEnd )
				)
				( attribute "BONDPAD_TO_BONDPAD_SPACING" "5.00,5.00,5.00,5.00,5.00,5.00,5.00,5.00,5.00,5.00,5.00,5.00,5.00,5.00"
					( Origin gBackEnd )
				)
				( attribute "BONDPAD_TO_LINE_SPACING" "5.00,5.00,5.00,5.00,5.00,5.00,5.00,5.00,5.00,5.00,5.00,5.00,5.00,5.00"
					( Origin gBackEnd )
				)
				( attribute "BONDPAD_TO_SHAPE_SPACING" "5.00,5.00,5.00,5.00,5.00,5.00,5.00,5.00,5.00,5.00,5.00,5.00,5.00,5.00"
					( Origin gBackEnd )
				)
				( attribute "LINE_TO_LINE_SPACING" "8.00,8.00,8.00,8.00,8.00,8.00,8.00,8.00,8.00,8.00,8.00,8.00,8.00,8.00"
					( Origin gBackEnd )
				)
				( attribute "LINE_TO_SHAPE_SPACING" "10.00,10.00,10.00,10.00,10.00,10.00,10.00,10.00,10.00,10.00,10.00,10.00,10.00,10.00"
					( Origin gBackEnd )
				)
				( attribute "SHAPE_TO_SHAPE_SPACING" "10.00,10.00,10.00,10.00,10.00,10.00,10.00,10.00,10.00,10.00,10.00,10.00,10.00,10.00"
					( Origin gBackEnd )
				)
				( attribute "HOLE_TO_PIN_SPACING" "8.00,8.00,8.00,8.00,8.00,8.00,8.00,8.00,8.00,8.00,8.00,8.00,8.00,8.00"
					( Origin gBackEnd )
				)
				( attribute "HOLE_TO_VIA_SPACING" "8.00,8.00,8.00,8.00,8.00,8.00,8.00,8.00,8.00,8.00,8.00,8.00,8.00,8.00"
					( Origin gBackEnd )
				)
				( attribute "HOLE_TO_LINE_SPACING" "8.00,8.00,8.00,8.00,8.00,8.00,8.00,8.00,8.00,8.00,8.00,8.00,8.00,8.00"
					( Origin gBackEnd )
				)
				( attribute "HOLE_TO_SHAPE_SPACING" "8.00,8.00,8.00,8.00,8.00,8.00,8.00,8.00,8.00,8.00,8.00,8.00,8.00,8.00"
					( Origin gBackEnd )
				)
				( attribute "HOLE_TO_HOLE_SPACING" "8.00,8.00,8.00,8.00,8.00,8.00,8.00,8.00,8.00,8.00,8.00,8.00,8.00,8.00"
					( Origin gBackEnd )
				)
				( attribute "MVIA_TO_MVIA_SPACING" "5.00,5.00,5.00,5.00,5.00,5.00,5.00,5.00,5.00,5.00,5.00,5.00,5.00,5.00"
					( Origin gBackEnd )
				)
				( attribute "MVIA_TO_THRUPIN_SPACING" "5.00,5.00,5.00,5.00,5.00,5.00,5.00,5.00,5.00,5.00,5.00,5.00,5.00,5.00"
					( Origin gBackEnd )
				)
				( attribute "MVIA_TO_SMDPIN_SPACING" "5.00,5.00,5.00,5.00,5.00,5.00,5.00,5.00,5.00,5.00,5.00,5.00,5.00,5.00"
					( Origin gBackEnd )
				)
				( attribute "MVIA_TO_THRUVIA_SPACING" "5.00,5.00,5.00,5.00,5.00,5.00,5.00,5.00,5.00,5.00,5.00,5.00,5.00,5.00"
					( Origin gBackEnd )
				)
				( attribute "MVIA_TO_BBV_SPACING" "5.00,5.00,5.00,5.00,5.00,5.00,5.00,5.00,5.00,5.00,5.00,5.00,5.00,5.00"
					( Origin gBackEnd )
				)
				( attribute "MVIA_TO_LINE_SPACING" "5.00,5.00,5.00,5.00,5.00,5.00,5.00,5.00,5.00,5.00,5.00,5.00,5.00,5.00"
					( Origin gBackEnd )
				)
				( attribute "MVIA_TO_SHAPE_SPACING" "5.00,5.00,5.00,5.00,5.00,5.00,5.00,5.00,5.00,5.00,5.00,5.00,5.00,5.00"
					( Origin gBackEnd )
				)
				( attribute "MVIA_TO_TESTPIN_SPACING" "5.00,5.00,5.00,5.00,5.00,5.00,5.00,5.00,5.00,5.00,5.00,5.00,5.00,5.00"
					( Origin gBackEnd )
				)
				( attribute "MVIA_TO_TESTVIA_SPACING" "5.00,5.00,5.00,5.00,5.00,5.00,5.00,5.00,5.00,5.00,5.00,5.00,5.00,5.00"
					( Origin gBackEnd )
				)
				( attribute "BONDPAD_TO_MVIA_SPACING" "5.00,5.00,5.00,5.00,5.00,5.00,5.00,5.00,5.00,5.00,5.00,5.00,5.00,5.00"
					( Origin gBackEnd )
				)
				( attribute "MIN_BVIA_GAP" "5.00"
					( Origin gBackEnd )
				)
				( attribute "BONDPAD_TO_BONDPAD_DIFFP_SPC" "5.00,5.00,5.00,5.00,5.00,5.00,5.00,5.00,5.00,5.00,5.00,5.00,5.00,5.00"
					( Origin gBackEnd )
				)
				( objectStatus "8MIL" )
			)
			( spacingCSet "@sapphirecity_baseboard_lib.sapphirecity_baseboard(sch_1):\35_MILS\"
				( attribute "THRUPIN_TO_THRUPIN_SPACING" "5.00,5.00,5.00,5.00,5.00,5.00,5.00,5.00,5.00,5.00,5.00,5.00,5.00,5.00"
					( Origin gBackEnd )
				)
				( attribute "THRUPIN_TO_SMDPIN_SPACING" "5.00,5.00,5.00,5.00,5.00,5.00,5.00,5.00,5.00,5.00,5.00,5.00,5.00,5.00"
					( Origin gBackEnd )
				)
				( attribute "TESTPIN_TO_THRUPIN_SPACING" "5.00,5.00,5.00,5.00,5.00,5.00,5.00,5.00,5.00,5.00,5.00,5.00,5.00,5.00"
					( Origin gBackEnd )
				)
				( attribute "THRUPIN_TO_THRUVIA_SPACING" "5.00,5.00,5.00,5.00,5.00,5.00,5.00,5.00,5.00,5.00,5.00,5.00,5.00,5.00"
					( Origin gBackEnd )
				)
				( attribute "TESTVIA_TO_THRUPIN_SPACING" "5.00,5.00,5.00,5.00,5.00,5.00,5.00,5.00,5.00,5.00,5.00,5.00,5.00,5.00"
					( Origin gBackEnd )
				)
				( attribute "BBV_TO_THRUPIN_SPACING" "5.00,5.00,5.00,5.00,5.00,5.00,5.00,5.00,5.00,5.00,5.00,5.00,5.00,5.00"
					( Origin gBackEnd )
				)
				( attribute "THRUPIN_TO_BONDPAD_SPACING" "5.00,5.00,5.00,5.00,5.00,5.00,5.00,5.00,5.00,5.00,5.00,5.00,5.00,5.00"
					( Origin gBackEnd )
				)
				( attribute "LINE_TO_THRUPIN_SPACING" "4.50,4.00,4.00,4.00,4.00,4.00,4.00,4.00,4.00,4.00,4.00,4.00,4.00,4.50"
					( Origin gBackEnd )
				)
				( attribute "THRUPIN_TO_SHAPE_SPACING" "4.50,4.00,4.00,4.00,4.00,4.00,4.00,4.00,4.00,4.00,4.00,4.00,4.00,4.00"
					( Origin gBackEnd )
				)
				( attribute "SMDPIN_TO_SMDPIN_SPACING" "5.00,5.00,5.00,5.00,5.00,5.00,5.00,5.00,5.00,5.00,5.00,5.00,5.00,5.00"
					( Origin gBackEnd )
				)
				( attribute "SMDPIN_TO_TESTPIN_SPACING" "5.00,5.00,5.00,5.00,5.00,5.00,5.00,5.00,5.00,5.00,5.00,5.00,5.00,25.00"
					( Origin gBackEnd )
				)
				( attribute "SMDPIN_TO_THRUVIA_SPACING" "5.00,5.00,5.00,5.00,5.00,5.00,5.00,5.00,5.00,5.00,5.00,5.00,5.00,5.00"
					( Origin gBackEnd )
				)
				( attribute "SMDPIN_TO_TESTVIA_SPACING" "5.00,5.00,5.00,5.00,5.00,5.00,5.00,5.00,5.00,5.00,5.00,5.00,5.00,5.00"
					( Origin gBackEnd )
				)
				( attribute "BBV_TO_SMDPIN_SPACING" "5.00,5.00,5.00,5.00,5.00,5.00,5.00,5.00,5.00,5.00,5.00,5.00,5.00,5.00"
					( Origin gBackEnd )
				)
				( attribute "SMDPIN_TO_BONDPAD_SPACING" "5.00,5.00,5.00,5.00,5.00,5.00,5.00,5.00,5.00,5.00,5.00,5.00,5.00,5.00"
					( Origin gBackEnd )
				)
				( attribute "LINE_TO_SMDPIN_SPACING" "4.50,4.50,4.50,4.50,4.50,4.50,4.50,4.50,4.50,4.50,4.50,4.50,4.50,4.50"
					( Origin gBackEnd )
				)
				( attribute "SHAPE_TO_SMDPIN_SPACING" "5.00,5.00,5.00,5.00,5.00,5.00,5.00,5.00,5.00,5.00,5.00,5.00,5.00,5.00"
					( Origin gBackEnd )
				)
				( attribute "TESTPIN_TO_TESTPIN_SPACING" "5.00,5.00,5.00,5.00,5.00,5.00,5.00,5.00,5.00,5.00,5.00,5.00,5.00,5.00"
					( Origin gBackEnd )
				)
				( attribute "TESTPIN_TO_THRUVIA_SPACING" "5.00,5.00,5.00,5.00,5.00,5.00,5.00,5.00,5.00,5.00,5.00,5.00,5.00,5.00"
					( Origin gBackEnd )
				)
				( attribute "TESTPIN_TO_TESTVIA_SPACING" "5.00,5.00,5.00,5.00,5.00,5.00,5.00,5.00,5.00,5.00,5.00,5.00,5.00,5.00"
					( Origin gBackEnd )
				)
				( attribute "BBV_TO_TESTPIN_SPACING" "5.00,5.00,5.00,5.00,5.00,5.00,5.00,5.00,5.00,5.00,5.00,5.00,5.00,5.00"
					( Origin gBackEnd )
				)
				( attribute "BONDPAD_TO_TESTPIN_SPACING" "5.00,5.00,5.00,5.00,5.00,5.00,5.00,5.00,5.00,5.00,5.00,5.00,5.00,5.00"
					( Origin gBackEnd )
				)
				( attribute "LINE_TO_TESTPIN_SPACING" "4.50,5.00,5.00,5.00,5.00,5.00,5.00,5.00,5.00,5.00,5.00,5.00,5.00,5.00"
					( Origin gBackEnd )
				)
				( attribute "SHAPE_TO_TESTPIN_SPACING" "4.50,4.00,4.00,4.00,4.00,4.00,4.00,4.00,4.00,4.00,4.00,4.00,4.00,4.00"
					( Origin gBackEnd )
				)
				( attribute "THRUVIA_TO_THRUVIA_SPACING" "5.00,5.00,5.00,5.00,5.00,5.00,5.00,5.00,5.00,5.00,5.00,5.00,5.00,5.00"
					( Origin gBackEnd )
				)
				( attribute "TESTVIA_TO_THRUVIA_SPACING" "5.00,5.00,5.00,5.00,5.00,5.00,5.00,5.00,5.00,5.00,5.00,5.00,5.00,5.00"
					( Origin gBackEnd )
				)
				( attribute "BBV_TO_THRUVIA_SPACING" "5.00,5.00,5.00,5.00,5.00,5.00,5.00,5.00,5.00,5.00,5.00,5.00,5.00,5.00"
					( Origin gBackEnd )
				)
				( attribute "BONDPAD_TO_THRUVIA_SPACING" "5.00,5.00,5.00,5.00,5.00,5.00,5.00,5.00,5.00,5.00,5.00,5.00,5.00,5.00"
					( Origin gBackEnd )
				)
				( attribute "LINE_TO_THRUVIA_SPACING" "4.50,4.00,4.00,4.00,4.00,4.00,4.00,4.00,4.00,4.00,4.00,4.00,4.00,4.50"
					( Origin gBackEnd )
				)
				( attribute "SHAPE_TO_THRUVIA_SPACING" "4.50,4.00,4.00,4.00,4.00,4.00,4.00,4.00,4.00,4.00,4.00,4.00,4.00,4.00"
					( Origin gBackEnd )
				)
				( attribute "TESTVIA_TO_TESTVIA_SPACING" "5.00,5.00,5.00,5.00,5.00,5.00,5.00,5.00,5.00,5.00,5.00,5.00,5.00,5.00"
					( Origin gBackEnd )
				)
				( attribute "BBV_TO_TESTVIA_SPACING" "5.00,5.00,5.00,5.00,5.00,5.00,5.00,5.00,5.00,5.00,5.00,5.00,5.00,5.00"
					( Origin gBackEnd )
				)
				( attribute "BONDPAD_TO_TESTVIA_SPACING" "5.00,5.00,5.00,5.00,5.00,5.00,5.00,5.00,5.00,5.00,5.00,5.00,5.00,5.00"
					( Origin gBackEnd )
				)
				( attribute "LINE_TO_TESTVIA_SPACING" "4.50,5.00,4.00,5.00,4.00,5.00,5.00,5.00,5.00,4.00,5.00,4.00,5.00,4.50"
					( Origin gBackEnd )
				)
				( attribute "SHAPE_TO_TESTVIA_SPACING" "4.50,4.00,4.00,4.00,4.00,4.00,4.00,4.00,4.00,4.00,4.00,4.00,4.00,4.00"
					( Origin gBackEnd )
				)
				( attribute "BBV_TO_BBV_SPACING" "5.00,5.00,5.00,5.00,5.00,5.00,5.00,5.00,5.00,5.00,5.00,5.00,5.00,5.00"
					( Origin gBackEnd )
				)
				( attribute "BONDPAD_TO_BBV_SPACING" "5.00,5.00,5.00,5.00,5.00,5.00,5.00,5.00,5.00,5.00,5.00,5.00,5.00,5.00"
					( Origin gBackEnd )
				)
				( attribute "BBV_TO_LINE_SPACING" "5.00,5.00,5.00,5.00,5.00,5.00,5.00,5.00,5.00,5.00,5.00,5.00,5.00,5.00"
					( Origin gBackEnd )
				)
				( attribute "BBV_TO_SHAPE_SPACING" "5.00,5.00,5.00,5.00,5.00,5.00,5.00,5.00,5.00,5.00,5.00,5.00,5.00,5.00"
					( Origin gBackEnd )
				)
				( attribute "BONDPAD_TO_BONDPAD_SPACING" "5.00,5.00,5.00,5.00,5.00,5.00,5.00,5.00,5.00,5.00,5.00,5.00,5.00,5.00"
					( Origin gBackEnd )
				)
				( attribute "BONDPAD_TO_LINE_SPACING" "5.00,5.00,5.00,5.00,5.00,5.00,5.00,5.00,5.00,5.00,5.00,5.00,5.00,5.00"
					( Origin gBackEnd )
				)
				( attribute "BONDPAD_TO_SHAPE_SPACING" "5.00,5.00,5.00,5.00,5.00,5.00,5.00,5.00,5.00,5.00,5.00,5.00,5.00,5.00"
					( Origin gBackEnd )
				)
				( attribute "LINE_TO_LINE_SPACING" "35.00,35.00,35.00,35.00,35.00,35.00,35.00,35.00,35.00,35.00,35.00,35.00,35.00,35.00"
					( Origin gBackEnd )
				)
				( attribute "LINE_TO_SHAPE_SPACING" "5.00,5.00,5.00,5.00,5.00,5.00,5.00,5.00,5.00,5.00,5.00,5.00,5.00,5.00"
					( Origin gBackEnd )
				)
				( attribute "SHAPE_TO_SHAPE_SPACING" "10.00,10.00,10.00,10.00,10.00,10.00,10.00,10.00,10.00,10.00,10.00,10.00,10.00,10.00"
					( Origin gBackEnd )
				)
				( attribute "HOLE_TO_PIN_SPACING" "8.00,8.00,8.00,8.00,8.00,8.00,8.00,8.00,8.00,8.00,8.00,8.00,8.00,8.00"
					( Origin gBackEnd )
				)
				( attribute "HOLE_TO_VIA_SPACING" "8.00,8.00,8.00,8.00,8.00,8.00,8.00,8.00,8.00,8.00,8.00,8.00,8.00,8.00"
					( Origin gBackEnd )
				)
				( attribute "HOLE_TO_LINE_SPACING" "8.00,8.00,8.00,8.00,8.00,8.00,8.00,8.00,8.00,8.00,8.00,8.00,8.00,8.00"
					( Origin gBackEnd )
				)
				( attribute "HOLE_TO_SHAPE_SPACING" "8.00,8.00,8.00,8.00,8.00,8.00,8.00,8.00,8.00,8.00,8.00,8.00,8.00,8.00"
					( Origin gBackEnd )
				)
				( attribute "HOLE_TO_HOLE_SPACING" "8.00,8.00,8.00,8.00,8.00,8.00,8.00,8.00,8.00,8.00,8.00,8.00,8.00,8.00"
					( Origin gBackEnd )
				)
				( attribute "MVIA_TO_MVIA_SPACING" "5.00,5.00,5.00,5.00,5.00,5.00,5.00,5.00,5.00,5.00,5.00,5.00,5.00,5.00"
					( Origin gBackEnd )
				)
				( attribute "MVIA_TO_THRUPIN_SPACING" "5.00,5.00,5.00,5.00,5.00,5.00,5.00,5.00,5.00,5.00,5.00,5.00,5.00,5.00"
					( Origin gBackEnd )
				)
				( attribute "MVIA_TO_SMDPIN_SPACING" "5.00,5.00,5.00,5.00,5.00,5.00,5.00,5.00,5.00,5.00,5.00,5.00,5.00,5.00"
					( Origin gBackEnd )
				)
				( attribute "MVIA_TO_THRUVIA_SPACING" "5.00,5.00,5.00,5.00,5.00,5.00,5.00,5.00,5.00,5.00,5.00,5.00,5.00,5.00"
					( Origin gBackEnd )
				)
				( attribute "MVIA_TO_BBV_SPACING" "5.00,5.00,5.00,5.00,5.00,5.00,5.00,5.00,5.00,5.00,5.00,5.00,5.00,5.00"
					( Origin gBackEnd )
				)
				( attribute "MVIA_TO_LINE_SPACING" "5.00,5.00,5.00,5.00,5.00,5.00,5.00,5.00,5.00,5.00,5.00,5.00,5.00,5.00"
					( Origin gBackEnd )
				)
				( attribute "MVIA_TO_SHAPE_SPACING" "5.00,5.00,5.00,5.00,5.00,5.00,5.00,5.00,5.00,5.00,5.00,5.00,5.00,5.00"
					( Origin gBackEnd )
				)
				( attribute "MVIA_TO_TESTPIN_SPACING" "5.00,5.00,5.00,5.00,5.00,5.00,5.00,5.00,5.00,5.00,5.00,5.00,5.00,5.00"
					( Origin gBackEnd )
				)
				( attribute "MVIA_TO_TESTVIA_SPACING" "5.00,5.00,5.00,5.00,5.00,5.00,5.00,5.00,5.00,5.00,5.00,5.00,5.00,5.00"
					( Origin gBackEnd )
				)
				( attribute "BONDPAD_TO_MVIA_SPACING" "5.00,5.00,5.00,5.00,5.00,5.00,5.00,5.00,5.00,5.00,5.00,5.00,5.00,5.00"
					( Origin gBackEnd )
				)
				( attribute "MIN_BVIA_GAP" "5.00"
					( Origin gBackEnd )
				)
				( attribute "BONDPAD_TO_BONDPAD_DIFFP_SPC" "5.00,5.00,5.00,5.00,5.00,5.00,5.00,5.00,5.00,5.00,5.00,5.00,5.00,5.00"
					( Origin gBackEnd )
				)
				( objectStatus "35_MILS" )
			)
			( spacingCSet "@sapphirecity_baseboard_lib.sapphirecity_baseboard(sch_1):\2.5H_SL_3H_MS\"
				( attribute "THRUPIN_TO_THRUPIN_SPACING" "5.00,5.00,5.00,5.00,5.00,5.00,5.00,5.00,5.00,5.00,5.00,5.00,5.00,5.00"
					( Origin gBackEnd )
				)
				( attribute "THRUPIN_TO_SMDPIN_SPACING" "5.00,5.00,5.00,5.00,5.00,5.00,5.00,5.00,5.00,5.00,5.00,5.00,5.00,5.00"
					( Origin gBackEnd )
				)
				( attribute "TESTPIN_TO_THRUPIN_SPACING" "5.00,5.00,5.00,5.00,5.00,5.00,5.00,5.00,5.00,5.00,5.00,5.00,5.00,5.00"
					( Origin gBackEnd )
				)
				( attribute "THRUPIN_TO_THRUVIA_SPACING" "5.00,5.00,5.00,5.00,5.00,5.00,5.00,5.00,5.00,5.00,5.00,5.00,5.00,5.00"
					( Origin gBackEnd )
				)
				( attribute "TESTVIA_TO_THRUPIN_SPACING" "5.00,5.00,5.00,5.00,5.00,5.00,5.00,5.00,5.00,5.00,5.00,5.00,5.00,5.00"
					( Origin gBackEnd )
				)
				( attribute "BBV_TO_THRUPIN_SPACING" "5.00,5.00,5.00,5.00,5.00,5.00,5.00,5.00,5.00,5.00,5.00,5.00,5.00,5.00"
					( Origin gBackEnd )
				)
				( attribute "THRUPIN_TO_BONDPAD_SPACING" "5.00,5.00,5.00,5.00,5.00,5.00,5.00,5.00,5.00,5.00,5.00,5.00,5.00,5.00"
					( Origin gBackEnd )
				)
				( attribute "LINE_TO_THRUPIN_SPACING" "5.00,4.00,4.00,4.00,4.00,4.00,4.00,4.00,4.00,4.00,4.00,4.00,4.00,5.00"
					( Origin gBackEnd )
				)
				( attribute "THRUPIN_TO_SHAPE_SPACING" "5.00,5.00,5.00,5.00,5.00,5.00,5.00,5.00,5.00,5.00,5.00,5.00,5.00,5.00"
					( Origin gBackEnd )
				)
				( attribute "SMDPIN_TO_SMDPIN_SPACING" "5.00,5.00,5.00,5.00,5.00,5.00,5.00,5.00,5.00,5.00,5.00,5.00,5.00,5.00"
					( Origin gBackEnd )
				)
				( attribute "SMDPIN_TO_TESTPIN_SPACING" "5.00,5.00,5.00,5.00,5.00,5.00,5.00,5.00,5.00,5.00,5.00,5.00,5.00,25.00"
					( Origin gBackEnd )
				)
				( attribute "SMDPIN_TO_THRUVIA_SPACING" "5.00,5.00,5.00,5.00,5.00,5.00,5.00,5.00,5.00,5.00,5.00,5.00,5.00,5.00"
					( Origin gBackEnd )
				)
				( attribute "SMDPIN_TO_TESTVIA_SPACING" "5.00,5.00,5.00,5.00,5.00,5.00,5.00,5.00,5.00,5.00,5.00,5.00,5.00,5.00"
					( Origin gBackEnd )
				)
				( attribute "BBV_TO_SMDPIN_SPACING" "5.00,5.00,5.00,5.00,5.00,5.00,5.00,5.00,5.00,5.00,5.00,5.00,5.00,5.00"
					( Origin gBackEnd )
				)
				( attribute "SMDPIN_TO_BONDPAD_SPACING" "5.00,5.00,5.00,5.00,5.00,5.00,5.00,5.00,5.00,5.00,5.00,5.00,5.00,5.00"
					( Origin gBackEnd )
				)
				( attribute "LINE_TO_SMDPIN_SPACING" "4.50,4.50,4.50,4.50,4.50,4.50,4.50,4.50,4.50,4.50,4.50,4.50,4.50,4.50"
					( Origin gBackEnd )
				)
				( attribute "SHAPE_TO_SMDPIN_SPACING" "5.00,5.00,5.00,5.00,5.00,5.00,5.00,5.00,5.00,5.00,5.00,5.00,5.00,5.00"
					( Origin gBackEnd )
				)
				( attribute "TESTPIN_TO_TESTPIN_SPACING" "5.00,5.00,5.00,5.00,5.00,5.00,5.00,5.00,5.00,5.00,5.00,5.00,5.00,5.00"
					( Origin gBackEnd )
				)
				( attribute "TESTPIN_TO_THRUVIA_SPACING" "5.00,5.00,5.00,5.00,5.00,5.00,5.00,5.00,5.00,5.00,5.00,5.00,5.00,5.00"
					( Origin gBackEnd )
				)
				( attribute "TESTPIN_TO_TESTVIA_SPACING" "5.00,5.00,5.00,5.00,5.00,5.00,5.00,5.00,5.00,5.00,5.00,5.00,5.00,5.00"
					( Origin gBackEnd )
				)
				( attribute "BBV_TO_TESTPIN_SPACING" "5.00,5.00,5.00,5.00,5.00,5.00,5.00,5.00,5.00,5.00,5.00,5.00,5.00,5.00"
					( Origin gBackEnd )
				)
				( attribute "BONDPAD_TO_TESTPIN_SPACING" "5.00,5.00,5.00,5.00,5.00,5.00,5.00,5.00,5.00,5.00,5.00,5.00,5.00,5.00"
					( Origin gBackEnd )
				)
				( attribute "LINE_TO_TESTPIN_SPACING" "5.00,4.00,4.00,4.00,4.00,4.00,4.00,4.00,4.00,4.00,4.00,4.00,4.00,5.00"
					( Origin gBackEnd )
				)
				( attribute "SHAPE_TO_TESTPIN_SPACING" "5.00,5.00,5.00,5.00,5.00,5.00,5.00,5.00,5.00,5.00,5.00,5.00,5.00,5.00"
					( Origin gBackEnd )
				)
				( attribute "THRUVIA_TO_THRUVIA_SPACING" "6.00,6.00,6.00,6.00,6.00,6.00,6.00,6.00,6.00,6.00,6.00,6.00,6.00,6.00"
					( Origin gBackEnd )
				)
				( attribute "TESTVIA_TO_THRUVIA_SPACING" "6.00,6.00,6.00,6.00,6.00,6.00,6.00,6.00,6.00,6.00,6.00,6.00,6.00,6.00"
					( Origin gBackEnd )
				)
				( attribute "BBV_TO_THRUVIA_SPACING" "5.00,5.00,5.00,5.00,5.00,5.00,5.00,5.00,5.00,5.00,5.00,5.00,5.00,5.00"
					( Origin gBackEnd )
				)
				( attribute "BONDPAD_TO_THRUVIA_SPACING" "5.00,5.00,5.00,5.00,5.00,5.00,5.00,5.00,5.00,5.00,5.00,5.00,5.00,5.00"
					( Origin gBackEnd )
				)
				( attribute "LINE_TO_THRUVIA_SPACING" "4.50,4.00,4.00,4.00,4.00,4.00,4.00,4.00,4.00,4.00,4.00,4.00,4.00,4.50"
					( Origin gBackEnd )
				)
				( attribute "SHAPE_TO_THRUVIA_SPACING" "5.00,5.00,5.00,5.00,5.00,5.00,5.00,5.00,5.00,5.00,5.00,5.00,5.00,5.00"
					( Origin gBackEnd )
				)
				( attribute "TESTVIA_TO_TESTVIA_SPACING" "6.00,6.00,6.00,6.00,6.00,6.00,6.00,6.00,6.00,6.00,6.00,6.00,6.00,6.00"
					( Origin gBackEnd )
				)
				( attribute "BBV_TO_TESTVIA_SPACING" "5.00,5.00,5.00,5.00,5.00,5.00,5.00,5.00,5.00,5.00,5.00,5.00,5.00,5.00"
					( Origin gBackEnd )
				)
				( attribute "BONDPAD_TO_TESTVIA_SPACING" "5.00,5.00,5.00,5.00,5.00,5.00,5.00,5.00,5.00,5.00,5.00,5.00,5.00,5.00"
					( Origin gBackEnd )
				)
				( attribute "LINE_TO_TESTVIA_SPACING" "4.50,4.00,4.00,4.00,4.00,4.00,4.00,4.00,4.00,4.00,4.00,4.00,4.00,5.00"
					( Origin gBackEnd )
				)
				( attribute "SHAPE_TO_TESTVIA_SPACING" "5.00,5.00,5.00,5.00,5.00,5.00,5.00,5.00,5.00,5.00,5.00,5.00,5.00,5.00"
					( Origin gBackEnd )
				)
				( attribute "BBV_TO_BBV_SPACING" "5.00,5.00,5.00,5.00,5.00,5.00,5.00,5.00,5.00,5.00,5.00,5.00,5.00,5.00"
					( Origin gBackEnd )
				)
				( attribute "BONDPAD_TO_BBV_SPACING" "5.00,5.00,5.00,5.00,5.00,5.00,5.00,5.00,5.00,5.00,5.00,5.00,5.00,5.00"
					( Origin gBackEnd )
				)
				( attribute "BBV_TO_LINE_SPACING" "5.00,5.00,5.00,5.00,5.00,5.00,5.00,5.00,5.00,5.00,5.00,5.00,5.00,5.00"
					( Origin gBackEnd )
				)
				( attribute "BBV_TO_SHAPE_SPACING" "5.00,5.00,5.00,5.00,5.00,5.00,5.00,5.00,5.00,5.00,5.00,5.00,5.00,5.00"
					( Origin gBackEnd )
				)
				( attribute "BONDPAD_TO_BONDPAD_SPACING" "5.00,5.00,5.00,5.00,5.00,5.00,5.00,5.00,5.00,5.00,5.00,5.00,5.00,5.00"
					( Origin gBackEnd )
				)
				( attribute "BONDPAD_TO_LINE_SPACING" "5.00,5.00,5.00,5.00,5.00,5.00,5.00,5.00,5.00,5.00,5.00,5.00,5.00,5.00"
					( Origin gBackEnd )
				)
				( attribute "BONDPAD_TO_SHAPE_SPACING" "5.00,5.00,5.00,5.00,5.00,5.00,5.00,5.00,5.00,5.00,5.00,5.00,5.00,5.00"
					( Origin gBackEnd )
				)
				( attribute "LINE_TO_LINE_SPACING" "8.10,7.50,7.50,7.50,7.50,7.50,7.50,7.50,7.50,7.50,7.50,7.50,7.50,8.10"
					( Origin gBackEnd )
				)
				( attribute "LINE_TO_SHAPE_SPACING" "10.00,10.00,10.00,10.00,10.00,10.00,10.00,10.00,10.00,10.00,10.00,10.00,10.00,10.00"
					( Origin gBackEnd )
				)
				( attribute "SHAPE_TO_SHAPE_SPACING" "10.00,10.00,10.00,10.00,10.00,10.00,10.00,10.00,10.00,10.00,10.00,10.00,10.00,10.00"
					( Origin gBackEnd )
				)
				( attribute "HOLE_TO_PIN_SPACING" "8.00,8.00,8.00,8.00,8.00,8.00,8.00,8.00,8.00,8.00,8.00,8.00,8.00,8.00"
					( Origin gBackEnd )
				)
				( attribute "HOLE_TO_VIA_SPACING" "8.00,8.00,8.00,8.00,8.00,8.00,8.00,8.00,8.00,8.00,8.00,8.00,8.00,8.00"
					( Origin gBackEnd )
				)
				( attribute "HOLE_TO_LINE_SPACING" "8.00,8.00,8.00,8.00,8.00,8.00,8.00,8.00,8.00,8.00,8.00,8.00,8.00,8.00"
					( Origin gBackEnd )
				)
				( attribute "HOLE_TO_SHAPE_SPACING" "8.00,8.00,8.00,8.00,8.00,8.00,8.00,8.00,8.00,8.00,8.00,8.00,8.00,8.00"
					( Origin gBackEnd )
				)
				( attribute "HOLE_TO_HOLE_SPACING" "8.00,8.00,8.00,8.00,8.00,8.00,8.00,8.00,8.00,8.00,8.00,8.00,8.00,8.00"
					( Origin gBackEnd )
				)
				( attribute "MVIA_TO_MVIA_SPACING" "5.00,5.00,5.00,5.00,5.00,5.00,5.00,5.00,5.00,5.00,5.00,5.00,5.00,5.00"
					( Origin gBackEnd )
				)
				( attribute "MVIA_TO_THRUPIN_SPACING" "5.00,5.00,5.00,5.00,5.00,5.00,5.00,5.00,5.00,5.00,5.00,5.00,5.00,5.00"
					( Origin gBackEnd )
				)
				( attribute "MVIA_TO_SMDPIN_SPACING" "5.00,5.00,5.00,5.00,5.00,5.00,5.00,5.00,5.00,5.00,5.00,5.00,5.00,5.00"
					( Origin gBackEnd )
				)
				( attribute "MVIA_TO_THRUVIA_SPACING" "5.00,5.00,5.00,5.00,5.00,5.00,5.00,5.00,5.00,5.00,5.00,5.00,5.00,5.00"
					( Origin gBackEnd )
				)
				( attribute "MVIA_TO_BBV_SPACING" "5.00,5.00,5.00,5.00,5.00,5.00,5.00,5.00,5.00,5.00,5.00,5.00,5.00,5.00"
					( Origin gBackEnd )
				)
				( attribute "MVIA_TO_LINE_SPACING" "5.00,5.00,5.00,5.00,5.00,5.00,5.00,5.00,5.00,5.00,5.00,5.00,5.00,5.00"
					( Origin gBackEnd )
				)
				( attribute "MVIA_TO_SHAPE_SPACING" "5.00,5.00,5.00,5.00,5.00,5.00,5.00,5.00,5.00,5.00,5.00,5.00,5.00,5.00"
					( Origin gBackEnd )
				)
				( attribute "MVIA_TO_TESTPIN_SPACING" "5.00,5.00,5.00,5.00,5.00,5.00,5.00,5.00,5.00,5.00,5.00,5.00,5.00,5.00"
					( Origin gBackEnd )
				)
				( attribute "MVIA_TO_TESTVIA_SPACING" "5.00,5.00,5.00,5.00,5.00,5.00,5.00,5.00,5.00,5.00,5.00,5.00,5.00,5.00"
					( Origin gBackEnd )
				)
				( attribute "BONDPAD_TO_MVIA_SPACING" "5.00,5.00,5.00,5.00,5.00,5.00,5.00,5.00,5.00,5.00,5.00,5.00,5.00,5.00"
					( Origin gBackEnd )
				)
				( attribute "MIN_BVIA_GAP" "5.00"
					( Origin gBackEnd )
				)
				( attribute "BONDPAD_TO_BONDPAD_DIFFP_SPC" "5.00,5.00,5.00,5.00,5.00,5.00,5.00,5.00,5.00,5.00,5.00,5.00,5.00,5.00"
					( Origin gBackEnd )
				)
				( objectStatus "3H_US_&_2.5H_SL" )
			)
			( spacingCSet "@sapphirecity_baseboard_lib.sapphirecity_baseboard(sch_1):\12_MIL\"
				( attribute "THRUPIN_TO_THRUPIN_SPACING" "5.00,5.00,5.00,5.00,5.00,5.00,5.00,5.00,5.00,5.00,5.00,5.00,5.00,5.00"
					( Origin gBackEnd )
				)
				( attribute "THRUPIN_TO_SMDPIN_SPACING" "5.00,5.00,5.00,5.00,5.00,5.00,5.00,5.00,5.00,5.00,5.00,5.00,5.00,5.00"
					( Origin gBackEnd )
				)
				( attribute "TESTPIN_TO_THRUPIN_SPACING" "5.00,5.00,5.00,5.00,5.00,5.00,5.00,5.00,5.00,5.00,5.00,5.00,5.00,5.00"
					( Origin gBackEnd )
				)
				( attribute "THRUPIN_TO_THRUVIA_SPACING" "5.00,5.00,5.00,5.00,5.00,5.00,5.00,5.00,5.00,5.00,5.00,5.00,5.00,5.00"
					( Origin gBackEnd )
				)
				( attribute "TESTVIA_TO_THRUPIN_SPACING" "5.00,5.00,5.00,5.00,5.00,5.00,5.00,5.00,5.00,5.00,5.00,5.00,5.00,5.00"
					( Origin gBackEnd )
				)
				( attribute "BBV_TO_THRUPIN_SPACING" "5.00,5.00,5.00,5.00,5.00,5.00,5.00,5.00,5.00,5.00,5.00,5.00,5.00,5.00"
					( Origin gBackEnd )
				)
				( attribute "THRUPIN_TO_BONDPAD_SPACING" "5.00,5.00,5.00,5.00,5.00,5.00,5.00,5.00,5.00,5.00,5.00,5.00,5.00,5.00"
					( Origin gBackEnd )
				)
				( attribute "LINE_TO_THRUPIN_SPACING" "4.50,4.00,4.00,4.00,4.00,4.00,4.00,4.00,4.00,4.00,4.00,4.00,4.00,4.50"
					( Origin gBackEnd )
				)
				( attribute "THRUPIN_TO_SHAPE_SPACING" "5.00,5.00,5.00,5.00,5.00,5.00,5.00,5.00,5.00,5.00,5.00,5.00,5.00,5.00"
					( Origin gBackEnd )
				)
				( attribute "SMDPIN_TO_SMDPIN_SPACING" "5.00,5.00,5.00,5.00,5.00,5.00,5.00,5.00,5.00,5.00,5.00,5.00,5.00,5.00"
					( Origin gBackEnd )
				)
				( attribute "SMDPIN_TO_TESTPIN_SPACING" "5.00,5.00,5.00,5.00,5.00,5.00,5.00,5.00,5.00,5.00,5.00,5.00,5.00,25.00"
					( Origin gBackEnd )
				)
				( attribute "SMDPIN_TO_THRUVIA_SPACING" "5.00,5.00,5.00,5.00,5.00,5.00,5.00,5.00,5.00,5.00,5.00,5.00,5.00,5.00"
					( Origin gBackEnd )
				)
				( attribute "SMDPIN_TO_TESTVIA_SPACING" "5.00,5.00,5.00,5.00,5.00,5.00,5.00,5.00,5.00,5.00,5.00,5.00,5.00,5.00"
					( Origin gBackEnd )
				)
				( attribute "BBV_TO_SMDPIN_SPACING" "5.00,5.00,5.00,5.00,5.00,5.00,5.00,5.00,5.00,5.00,5.00,5.00,5.00,5.00"
					( Origin gBackEnd )
				)
				( attribute "SMDPIN_TO_BONDPAD_SPACING" "5.00,5.00,5.00,5.00,5.00,5.00,5.00,5.00,5.00,5.00,5.00,5.00,5.00,5.00"
					( Origin gBackEnd )
				)
				( attribute "LINE_TO_SMDPIN_SPACING" "4.50,4.50,4.50,4.50,4.50,4.50,4.50,4.50,4.50,4.50,4.50,4.50,4.50,4.50"
					( Origin gBackEnd )
				)
				( attribute "SHAPE_TO_SMDPIN_SPACING" "5.00,5.00,5.00,5.00,5.00,5.00,5.00,5.00,5.00,5.00,5.00,5.00,5.00,5.00"
					( Origin gBackEnd )
				)
				( attribute "TESTPIN_TO_TESTPIN_SPACING" "5.00,5.00,5.00,5.00,5.00,5.00,5.00,5.00,5.00,5.00,5.00,5.00,5.00,5.00"
					( Origin gBackEnd )
				)
				( attribute "TESTPIN_TO_THRUVIA_SPACING" "5.00,5.00,5.00,5.00,5.00,5.00,5.00,5.00,5.00,5.00,5.00,5.00,5.00,5.00"
					( Origin gBackEnd )
				)
				( attribute "TESTPIN_TO_TESTVIA_SPACING" "5.00,5.00,5.00,5.00,5.00,5.00,5.00,5.00,5.00,5.00,5.00,5.00,5.00,5.00"
					( Origin gBackEnd )
				)
				( attribute "BBV_TO_TESTPIN_SPACING" "5.00,5.00,5.00,5.00,5.00,5.00,5.00,5.00,5.00,5.00,5.00,5.00,5.00,5.00"
					( Origin gBackEnd )
				)
				( attribute "BONDPAD_TO_TESTPIN_SPACING" "5.00,5.00,5.00,5.00,5.00,5.00,5.00,5.00,5.00,5.00,5.00,5.00,5.00,5.00"
					( Origin gBackEnd )
				)
				( attribute "LINE_TO_TESTPIN_SPACING" "5.00,5.00,5.00,5.00,5.00,5.00,5.00,5.00,5.00,5.00,5.00,5.00,5.00,5.00"
					( Origin gBackEnd )
				)
				( attribute "SHAPE_TO_TESTPIN_SPACING" "5.00,5.00,5.00,5.00,5.00,5.00,5.00,5.00,5.00,5.00,5.00,5.00,5.00,5.00"
					( Origin gBackEnd )
				)
				( attribute "THRUVIA_TO_THRUVIA_SPACING" "5.00,5.00,5.00,5.00,5.00,5.00,5.00,5.00,5.00,5.00,5.00,5.00,5.00,5.00"
					( Origin gBackEnd )
				)
				( attribute "TESTVIA_TO_THRUVIA_SPACING" "6.00,6.00,6.00,6.00,6.00,6.00,6.00,6.00,6.00,6.00,6.00,6.00,6.00,6.00"
					( Origin gBackEnd )
				)
				( attribute "BBV_TO_THRUVIA_SPACING" "5.00,5.00,5.00,5.00,5.00,5.00,5.00,5.00,5.00,5.00,5.00,5.00,5.00,5.00"
					( Origin gBackEnd )
				)
				( attribute "BONDPAD_TO_THRUVIA_SPACING" "5.00,5.00,5.00,5.00,5.00,5.00,5.00,5.00,5.00,5.00,5.00,5.00,5.00,5.00"
					( Origin gBackEnd )
				)
				( attribute "LINE_TO_THRUVIA_SPACING" "4.50,4.00,4.00,4.00,4.00,4.00,4.00,4.00,4.00,4.00,4.00,4.00,4.00,4.50"
					( Origin gBackEnd )
				)
				( attribute "SHAPE_TO_THRUVIA_SPACING" "5.00,5.00,5.00,5.00,5.00,5.00,5.00,5.00,5.00,5.00,5.00,5.00,5.00,5.00"
					( Origin gBackEnd )
				)
				( attribute "TESTVIA_TO_TESTVIA_SPACING" "6.00,6.00,6.00,6.00,6.00,6.00,6.00,6.00,6.00,6.00,6.00,6.00,6.00,6.00"
					( Origin gBackEnd )
				)
				( attribute "BBV_TO_TESTVIA_SPACING" "5.00,5.00,5.00,5.00,5.00,5.00,5.00,5.00,5.00,5.00,5.00,5.00,5.00,5.00"
					( Origin gBackEnd )
				)
				( attribute "BONDPAD_TO_TESTVIA_SPACING" "5.00,5.00,5.00,5.00,5.00,5.00,5.00,5.00,5.00,5.00,5.00,5.00,5.00,5.00"
					( Origin gBackEnd )
				)
				( attribute "LINE_TO_TESTVIA_SPACING" "4.50,5.00,5.00,5.00,5.00,5.00,5.00,5.00,5.00,5.00,5.00,5.00,5.00,4.50"
					( Origin gBackEnd )
				)
				( attribute "SHAPE_TO_TESTVIA_SPACING" "5.00,5.00,5.00,5.00,5.00,5.00,5.00,5.00,5.00,5.00,5.00,5.00,5.00,5.00"
					( Origin gBackEnd )
				)
				( attribute "BBV_TO_BBV_SPACING" "5.00,5.00,5.00,5.00,5.00,5.00,5.00,5.00,5.00,5.00,5.00,5.00,5.00,5.00"
					( Origin gBackEnd )
				)
				( attribute "BONDPAD_TO_BBV_SPACING" "5.00,5.00,5.00,5.00,5.00,5.00,5.00,5.00,5.00,5.00,5.00,5.00,5.00,5.00"
					( Origin gBackEnd )
				)
				( attribute "BBV_TO_LINE_SPACING" "5.00,5.00,5.00,5.00,5.00,5.00,5.00,5.00,5.00,5.00,5.00,5.00,5.00,5.00"
					( Origin gBackEnd )
				)
				( attribute "BBV_TO_SHAPE_SPACING" "5.00,5.00,5.00,5.00,5.00,5.00,5.00,5.00,5.00,5.00,5.00,5.00,5.00,5.00"
					( Origin gBackEnd )
				)
				( attribute "BONDPAD_TO_BONDPAD_SPACING" "5.00,5.00,5.00,5.00,5.00,5.00,5.00,5.00,5.00,5.00,5.00,5.00,5.00,5.00"
					( Origin gBackEnd )
				)
				( attribute "BONDPAD_TO_LINE_SPACING" "5.00,5.00,5.00,5.00,5.00,5.00,5.00,5.00,5.00,5.00,5.00,5.00,5.00,5.00"
					( Origin gBackEnd )
				)
				( attribute "BONDPAD_TO_SHAPE_SPACING" "5.00,5.00,5.00,5.00,5.00,5.00,5.00,5.00,5.00,5.00,5.00,5.00,5.00,5.00"
					( Origin gBackEnd )
				)
				( attribute "LINE_TO_LINE_SPACING" "12.00,12.00,12.00,12.00,12.00,12.00,12.00,12.00,12.00,12.00,12.00,12.00,12.00,12.00"
					( Origin gBackEnd )
				)
				( attribute "LINE_TO_SHAPE_SPACING" "10.00,10.00,10.00,10.00,10.00,10.00,10.00,10.00,10.00,10.00,10.00,10.00,10.00,10.00"
					( Origin gBackEnd )
				)
				( attribute "SHAPE_TO_SHAPE_SPACING" "10.00,10.00,10.00,10.00,10.00,10.00,10.00,10.00,10.00,10.00,10.00,10.00,10.00,10.00"
					( Origin gBackEnd )
				)
				( attribute "HOLE_TO_PIN_SPACING" "8.00,8.00,8.00,8.00,8.00,8.00,8.00,8.00,8.00,8.00,8.00,8.00,8.00,8.00"
					( Origin gBackEnd )
				)
				( attribute "HOLE_TO_VIA_SPACING" "8.00,8.00,8.00,8.00,8.00,8.00,8.00,8.00,8.00,8.00,8.00,8.00,8.00,8.00"
					( Origin gBackEnd )
				)
				( attribute "HOLE_TO_LINE_SPACING" "8.00,8.00,8.00,8.00,8.00,8.00,8.00,8.00,8.00,8.00,8.00,8.00,8.00,8.00"
					( Origin gBackEnd )
				)
				( attribute "HOLE_TO_SHAPE_SPACING" "8.00,8.00,8.00,8.00,8.00,8.00,8.00,8.00,8.00,8.00,8.00,8.00,8.00,8.00"
					( Origin gBackEnd )
				)
				( attribute "HOLE_TO_HOLE_SPACING" "8.00,8.00,8.00,8.00,8.00,8.00,8.00,8.00,8.00,8.00,8.00,8.00,8.00,8.00"
					( Origin gBackEnd )
				)
				( attribute "MVIA_TO_MVIA_SPACING" "5.00,5.00,5.00,5.00,5.00,5.00,5.00,5.00,5.00,5.00,5.00,5.00,5.00,5.00"
					( Origin gBackEnd )
				)
				( attribute "MVIA_TO_THRUPIN_SPACING" "5.00,5.00,5.00,5.00,5.00,5.00,5.00,5.00,5.00,5.00,5.00,5.00,5.00,5.00"
					( Origin gBackEnd )
				)
				( attribute "MVIA_TO_SMDPIN_SPACING" "5.00,5.00,5.00,5.00,5.00,5.00,5.00,5.00,5.00,5.00,5.00,5.00,5.00,5.00"
					( Origin gBackEnd )
				)
				( attribute "MVIA_TO_THRUVIA_SPACING" "5.00,5.00,5.00,5.00,5.00,5.00,5.00,5.00,5.00,5.00,5.00,5.00,5.00,5.00"
					( Origin gBackEnd )
				)
				( attribute "MVIA_TO_BBV_SPACING" "5.00,5.00,5.00,5.00,5.00,5.00,5.00,5.00,5.00,5.00,5.00,5.00,5.00,5.00"
					( Origin gBackEnd )
				)
				( attribute "MVIA_TO_LINE_SPACING" "5.00,5.00,5.00,5.00,5.00,5.00,5.00,5.00,5.00,5.00,5.00,5.00,5.00,5.00"
					( Origin gBackEnd )
				)
				( attribute "MVIA_TO_SHAPE_SPACING" "5.00,5.00,5.00,5.00,5.00,5.00,5.00,5.00,5.00,5.00,5.00,5.00,5.00,5.00"
					( Origin gBackEnd )
				)
				( attribute "MVIA_TO_TESTPIN_SPACING" "5.00,5.00,5.00,5.00,5.00,5.00,5.00,5.00,5.00,5.00,5.00,5.00,5.00,5.00"
					( Origin gBackEnd )
				)
				( attribute "MVIA_TO_TESTVIA_SPACING" "5.00,5.00,5.00,5.00,5.00,5.00,5.00,5.00,5.00,5.00,5.00,5.00,5.00,5.00"
					( Origin gBackEnd )
				)
				( attribute "BONDPAD_TO_MVIA_SPACING" "5.00,5.00,5.00,5.00,5.00,5.00,5.00,5.00,5.00,5.00,5.00,5.00,5.00,5.00"
					( Origin gBackEnd )
				)
				( attribute "MIN_BVIA_GAP" "5.00"
					( Origin gBackEnd )
				)
				( attribute "BONDPAD_TO_BONDPAD_DIFFP_SPC" "5.00,5.00,5.00,5.00,5.00,5.00,5.00,5.00,5.00,5.00,5.00,5.00,5.00,5.00"
					( Origin gBackEnd )
				)
				( objectStatus "12_MIL" )
			)
			( spacingCSet "@sapphirecity_baseboard_lib.sapphirecity_baseboard(sch_1):\8MIL_SL_7MIL_MS\"
				( attribute "THRUPIN_TO_THRUPIN_SPACING" "5.00,5.00,5.00,5.00,5.00,5.00,5.00,5.00,5.00,5.00,5.00,5.00,5.00,5.00"
					( Origin gBackEnd )
				)
				( attribute "THRUPIN_TO_SMDPIN_SPACING" "5.00,5.00,5.00,5.00,5.00,5.00,5.00,5.00,5.00,5.00,5.00,5.00,5.00,5.00"
					( Origin gBackEnd )
				)
				( attribute "TESTPIN_TO_THRUPIN_SPACING" "5.00,5.00,5.00,5.00,5.00,5.00,5.00,5.00,5.00,5.00,5.00,5.00,5.00,5.00"
					( Origin gBackEnd )
				)
				( attribute "THRUPIN_TO_THRUVIA_SPACING" "5.00,5.00,5.00,5.00,5.00,5.00,5.00,5.00,5.00,5.00,5.00,5.00,5.00,5.00"
					( Origin gBackEnd )
				)
				( attribute "TESTVIA_TO_THRUPIN_SPACING" "5.00,5.00,5.00,5.00,5.00,5.00,5.00,5.00,5.00,5.00,5.00,5.00,5.00,5.00"
					( Origin gBackEnd )
				)
				( attribute "BBV_TO_THRUPIN_SPACING" "5.00,5.00,5.00,5.00,5.00,5.00,5.00,5.00,5.00,5.00,5.00,5.00,5.00,5.00"
					( Origin gBackEnd )
				)
				( attribute "THRUPIN_TO_BONDPAD_SPACING" "5.00,5.00,5.00,5.00,5.00,5.00,5.00,5.00,5.00,5.00,5.00,5.00,5.00,5.00"
					( Origin gBackEnd )
				)
				( attribute "LINE_TO_THRUPIN_SPACING" "5.00,4.00,4.00,4.00,4.00,4.00,4.00,4.00,4.00,4.00,4.00,4.00,4.00,5.00"
					( Origin gBackEnd )
				)
				( attribute "THRUPIN_TO_SHAPE_SPACING" "5.00,5.00,5.00,5.00,5.00,5.00,5.00,5.00,5.00,5.00,5.00,5.00,5.00,5.00"
					( Origin gBackEnd )
				)
				( attribute "SMDPIN_TO_SMDPIN_SPACING" "5.00,5.00,5.00,5.00,5.00,5.00,5.00,5.00,5.00,5.00,5.00,5.00,5.00,5.00"
					( Origin gBackEnd )
				)
				( attribute "SMDPIN_TO_TESTPIN_SPACING" "5.00,5.00,5.00,5.00,5.00,5.00,5.00,5.00,5.00,5.00,5.00,5.00,5.00,25.00"
					( Origin gBackEnd )
				)
				( attribute "SMDPIN_TO_THRUVIA_SPACING" "5.00,5.00,5.00,5.00,5.00,5.00,5.00,5.00,5.00,5.00,5.00,5.00,5.00,5.00"
					( Origin gBackEnd )
				)
				( attribute "SMDPIN_TO_TESTVIA_SPACING" "5.00,5.00,5.00,5.00,5.00,5.00,5.00,5.00,5.00,5.00,5.00,5.00,5.00,5.00"
					( Origin gBackEnd )
				)
				( attribute "BBV_TO_SMDPIN_SPACING" "5.00,5.00,5.00,5.00,5.00,5.00,5.00,5.00,5.00,5.00,5.00,5.00,5.00,5.00"
					( Origin gBackEnd )
				)
				( attribute "SMDPIN_TO_BONDPAD_SPACING" "5.00,5.00,5.00,5.00,5.00,5.00,5.00,5.00,5.00,5.00,5.00,5.00,5.00,5.00"
					( Origin gBackEnd )
				)
				( attribute "LINE_TO_SMDPIN_SPACING" "4.50,4.50,4.50,4.50,4.50,4.50,4.50,4.50,4.50,4.50,4.50,4.50,4.50,4.50"
					( Origin gBackEnd )
				)
				( attribute "SHAPE_TO_SMDPIN_SPACING" "5.00,5.00,5.00,5.00,5.00,5.00,5.00,5.00,5.00,5.00,5.00,5.00,5.00,5.00"
					( Origin gBackEnd )
				)
				( attribute "TESTPIN_TO_TESTPIN_SPACING" "5.00,5.00,5.00,5.00,5.00,5.00,5.00,5.00,5.00,5.00,5.00,5.00,5.00,5.00"
					( Origin gBackEnd )
				)
				( attribute "TESTPIN_TO_THRUVIA_SPACING" "5.00,5.00,5.00,5.00,5.00,5.00,5.00,5.00,5.00,5.00,5.00,5.00,5.00,5.00"
					( Origin gBackEnd )
				)
				( attribute "TESTPIN_TO_TESTVIA_SPACING" "5.00,5.00,5.00,5.00,5.00,5.00,5.00,5.00,5.00,5.00,5.00,5.00,5.00,5.00"
					( Origin gBackEnd )
				)
				( attribute "BBV_TO_TESTPIN_SPACING" "5.00,5.00,5.00,5.00,5.00,5.00,5.00,5.00,5.00,5.00,5.00,5.00,5.00,5.00"
					( Origin gBackEnd )
				)
				( attribute "BONDPAD_TO_TESTPIN_SPACING" "5.00,5.00,5.00,5.00,5.00,5.00,5.00,5.00,5.00,5.00,5.00,5.00,5.00,5.00"
					( Origin gBackEnd )
				)
				( attribute "LINE_TO_TESTPIN_SPACING" "5.00,4.00,4.00,4.00,4.00,4.00,4.00,4.00,4.00,4.00,4.00,4.00,4.00,5.00"
					( Origin gBackEnd )
				)
				( attribute "SHAPE_TO_TESTPIN_SPACING" "5.00,5.00,5.00,5.00,5.00,5.00,5.00,5.00,5.00,5.00,5.00,5.00,5.00,5.00"
					( Origin gBackEnd )
				)
				( attribute "THRUVIA_TO_THRUVIA_SPACING" "6.00,6.00,6.00,6.00,6.00,6.00,6.00,6.00,6.00,6.00,6.00,6.00,6.00,6.00"
					( Origin gBackEnd )
				)
				( attribute "TESTVIA_TO_THRUVIA_SPACING" "6.00,6.00,6.00,6.00,6.00,6.00,6.00,6.00,6.00,6.00,6.00,6.00,6.00,6.00"
					( Origin gBackEnd )
				)
				( attribute "BBV_TO_THRUVIA_SPACING" "5.00,5.00,5.00,5.00,5.00,5.00,5.00,5.00,5.00,5.00,5.00,5.00,5.00,5.00"
					( Origin gBackEnd )
				)
				( attribute "BONDPAD_TO_THRUVIA_SPACING" "5.00,5.00,5.00,5.00,5.00,5.00,5.00,5.00,5.00,5.00,5.00,5.00,5.00,5.00"
					( Origin gBackEnd )
				)
				( attribute "LINE_TO_THRUVIA_SPACING" "4.50,4.00,4.00,4.00,4.00,4.00,4.00,4.00,4.00,4.00,4.00,4.00,4.00,4.50"
					( Origin gBackEnd )
				)
				( attribute "SHAPE_TO_THRUVIA_SPACING" "5.00,5.00,5.00,5.00,5.00,5.00,5.00,5.00,5.00,5.00,5.00,5.00,5.00,5.00"
					( Origin gBackEnd )
				)
				( attribute "TESTVIA_TO_TESTVIA_SPACING" "6.00,6.00,6.00,6.00,6.00,6.00,6.00,6.00,6.00,6.00,6.00,6.00,6.00,6.00"
					( Origin gBackEnd )
				)
				( attribute "BBV_TO_TESTVIA_SPACING" "5.00,5.00,5.00,5.00,5.00,5.00,5.00,5.00,5.00,5.00,5.00,5.00,5.00,5.00"
					( Origin gBackEnd )
				)
				( attribute "BONDPAD_TO_TESTVIA_SPACING" "5.00,5.00,5.00,5.00,5.00,5.00,5.00,5.00,5.00,5.00,5.00,5.00,5.00,5.00"
					( Origin gBackEnd )
				)
				( attribute "LINE_TO_TESTVIA_SPACING" "4.50,4.00,4.00,4.00,4.00,4.00,4.00,4.00,4.00,4.00,4.00,4.00,4.00,4.50"
					( Origin gBackEnd )
				)
				( attribute "SHAPE_TO_TESTVIA_SPACING" "5.00,5.00,5.00,5.00,5.00,5.00,5.00,5.00,5.00,5.00,5.00,5.00,5.00,5.00"
					( Origin gBackEnd )
				)
				( attribute "BBV_TO_BBV_SPACING" "5.00,5.00,5.00,5.00,5.00,5.00,5.00,5.00,5.00,5.00,5.00,5.00,5.00,5.00"
					( Origin gBackEnd )
				)
				( attribute "BONDPAD_TO_BBV_SPACING" "5.00,5.00,5.00,5.00,5.00,5.00,5.00,5.00,5.00,5.00,5.00,5.00,5.00,5.00"
					( Origin gBackEnd )
				)
				( attribute "BBV_TO_LINE_SPACING" "5.00,5.00,5.00,5.00,5.00,5.00,5.00,5.00,5.00,5.00,5.00,5.00,5.00,5.00"
					( Origin gBackEnd )
				)
				( attribute "BBV_TO_SHAPE_SPACING" "5.00,5.00,5.00,5.00,5.00,5.00,5.00,5.00,5.00,5.00,5.00,5.00,5.00,5.00"
					( Origin gBackEnd )
				)
				( attribute "BONDPAD_TO_BONDPAD_SPACING" "5.00,5.00,5.00,5.00,5.00,5.00,5.00,5.00,5.00,5.00,5.00,5.00,5.00,5.00"
					( Origin gBackEnd )
				)
				( attribute "BONDPAD_TO_LINE_SPACING" "5.00,5.00,5.00,5.00,5.00,5.00,5.00,5.00,5.00,5.00,5.00,5.00,5.00,5.00"
					( Origin gBackEnd )
				)
				( attribute "BONDPAD_TO_SHAPE_SPACING" "5.00,5.00,5.00,5.00,5.00,5.00,5.00,5.00,5.00,5.00,5.00,5.00,5.00,5.00"
					( Origin gBackEnd )
				)
				( attribute "LINE_TO_LINE_SPACING" "7.00,8.00,8.00,8.00,8.00,8.00,8.00,8.00,8.00,8.00,8.00,8.00,8.00,7.00"
					( Origin gBackEnd )
				)
				( attribute "LINE_TO_SHAPE_SPACING" "10.00,10.00,10.00,10.00,10.00,10.00,10.00,10.00,10.00,10.00,10.00,10.00,10.00,10.00"
					( Origin gBackEnd )
				)
				( attribute "SHAPE_TO_SHAPE_SPACING" "10.00,10.00,10.00,10.00,10.00,10.00,10.00,10.00,10.00,10.00,10.00,10.00,10.00,10.00"
					( Origin gBackEnd )
				)
				( attribute "HOLE_TO_PIN_SPACING" "8.00,8.00,8.00,8.00,8.00,8.00,8.00,8.00,8.00,8.00,8.00,8.00,8.00,8.00"
					( Origin gBackEnd )
				)
				( attribute "HOLE_TO_VIA_SPACING" "8.00,8.00,8.00,8.00,8.00,8.00,8.00,8.00,8.00,8.00,8.00,8.00,8.00,8.00"
					( Origin gBackEnd )
				)
				( attribute "HOLE_TO_LINE_SPACING" "8.00,8.00,8.00,8.00,8.00,8.00,8.00,8.00,8.00,8.00,8.00,8.00,8.00,8.00"
					( Origin gBackEnd )
				)
				( attribute "HOLE_TO_SHAPE_SPACING" "8.00,8.00,8.00,8.00,8.00,8.00,8.00,8.00,8.00,8.00,8.00,8.00,8.00,8.00"
					( Origin gBackEnd )
				)
				( attribute "HOLE_TO_HOLE_SPACING" "8.00,8.00,8.00,8.00,8.00,8.00,8.00,8.00,8.00,8.00,8.00,8.00,8.00,8.00"
					( Origin gBackEnd )
				)
				( attribute "MVIA_TO_MVIA_SPACING" "5.00,5.00,5.00,5.00,5.00,5.00,5.00,5.00,5.00,5.00,5.00,5.00,5.00,5.00"
					( Origin gBackEnd )
				)
				( attribute "MVIA_TO_THRUPIN_SPACING" "5.00,5.00,5.00,5.00,5.00,5.00,5.00,5.00,5.00,5.00,5.00,5.00,5.00,5.00"
					( Origin gBackEnd )
				)
				( attribute "MVIA_TO_SMDPIN_SPACING" "5.00,5.00,5.00,5.00,5.00,5.00,5.00,5.00,5.00,5.00,5.00,5.00,5.00,5.00"
					( Origin gBackEnd )
				)
				( attribute "MVIA_TO_THRUVIA_SPACING" "5.00,5.00,5.00,5.00,5.00,5.00,5.00,5.00,5.00,5.00,5.00,5.00,5.00,5.00"
					( Origin gBackEnd )
				)
				( attribute "MVIA_TO_BBV_SPACING" "5.00,5.00,5.00,5.00,5.00,5.00,5.00,5.00,5.00,5.00,5.00,5.00,5.00,5.00"
					( Origin gBackEnd )
				)
				( attribute "MVIA_TO_LINE_SPACING" "5.00,5.00,5.00,5.00,5.00,5.00,5.00,5.00,5.00,5.00,5.00,5.00,5.00,5.00"
					( Origin gBackEnd )
				)
				( attribute "MVIA_TO_SHAPE_SPACING" "5.00,5.00,5.00,5.00,5.00,5.00,5.00,5.00,5.00,5.00,5.00,5.00,5.00,5.00"
					( Origin gBackEnd )
				)
				( attribute "MVIA_TO_TESTPIN_SPACING" "5.00,5.00,5.00,5.00,5.00,5.00,5.00,5.00,5.00,5.00,5.00,5.00,5.00,5.00"
					( Origin gBackEnd )
				)
				( attribute "MVIA_TO_TESTVIA_SPACING" "5.00,5.00,5.00,5.00,5.00,5.00,5.00,5.00,5.00,5.00,5.00,5.00,5.00,5.00"
					( Origin gBackEnd )
				)
				( attribute "BONDPAD_TO_MVIA_SPACING" "5.00,5.00,5.00,5.00,5.00,5.00,5.00,5.00,5.00,5.00,5.00,5.00,5.00,5.00"
					( Origin gBackEnd )
				)
				( attribute "MIN_BVIA_GAP" "5.00"
					( Origin gBackEnd )
				)
				( attribute "BONDPAD_TO_BONDPAD_DIFFP_SPC" "5.00,5.00,5.00,5.00,5.00,5.00,5.00,5.00,5.00,5.00,5.00,5.00,5.00,5.00"
					( Origin gBackEnd )
				)
				( objectStatus "7MIL_US_&_8MIL_SL" )
			)
			( spacingCSet "@sapphirecity_baseboard_lib.sapphirecity_baseboard(sch_1):\5H_SL_7H_MS_VIA_3H_A\"
				( attribute "THRUPIN_TO_THRUPIN_SPACING" "5.00,5.00,5.00,5.00,5.00,5.00,5.00,5.00,5.00,5.00,5.00,5.00,5.00,5.00"
					( Origin gBackEnd )
				)
				( attribute "THRUPIN_TO_SMDPIN_SPACING" "5.00,5.00,5.00,5.00,5.00,5.00,5.00,5.00,5.00,5.00,5.00,5.00,5.00,5.00"
					( Origin gBackEnd )
				)
				( attribute "TESTPIN_TO_THRUPIN_SPACING" "5.00,5.00,5.00,5.00,5.00,5.00,5.00,5.00,5.00,5.00,5.00,5.00,5.00,5.00"
					( Origin gBackEnd )
				)
				( attribute "THRUPIN_TO_THRUVIA_SPACING" "5.00,5.00,5.00,5.00,5.00,5.00,5.00,5.00,5.00,5.00,5.00,5.00,5.00,5.00"
					( Origin gBackEnd )
				)
				( attribute "TESTVIA_TO_THRUPIN_SPACING" "5.00,5.00,5.00,5.00,5.00,5.00,5.00,5.00,5.00,5.00,5.00,5.00,5.00,5.00"
					( Origin gBackEnd )
				)
				( attribute "BBV_TO_THRUPIN_SPACING" "5.00,5.00,5.00,5.00,5.00,5.00,5.00,5.00,5.00,5.00,5.00,5.00,5.00,5.00"
					( Origin gBackEnd )
				)
				( attribute "THRUPIN_TO_BONDPAD_SPACING" "5.00,5.00,5.00,5.00,5.00,5.00,5.00,5.00,5.00,5.00,5.00,5.00,5.00,5.00"
					( Origin gBackEnd )
				)
				( attribute "LINE_TO_THRUPIN_SPACING" "13.10,17.00,17.00,17.00,17.00,17.00,17.00,17.00,17.00,17.00,17.00,17.00,17.00,13.10"
					( Origin gBackEnd )
				)
				( attribute "THRUPIN_TO_SHAPE_SPACING" "5.00,5.00,5.00,5.00,5.00,5.00,5.00,5.00,5.00,5.00,5.00,5.00,5.00,5.00"
					( Origin gBackEnd )
				)
				( attribute "SMDPIN_TO_SMDPIN_SPACING" "5.00,5.00,5.00,5.00,5.00,5.00,5.00,5.00,5.00,5.00,5.00,5.00,5.00,5.00"
					( Origin gBackEnd )
				)
				( attribute "SMDPIN_TO_TESTPIN_SPACING" "5.00,5.00,5.00,5.00,5.00,5.00,5.00,5.00,5.00,5.00,5.00,5.00,5.00,25.00"
					( Origin gBackEnd )
				)
				( attribute "SMDPIN_TO_THRUVIA_SPACING" "5.00,5.00,5.00,5.00,5.00,5.00,5.00,5.00,5.00,5.00,5.00,5.00,5.00,5.00"
					( Origin gBackEnd )
				)
				( attribute "SMDPIN_TO_TESTVIA_SPACING" "5.00,5.00,5.00,5.00,5.00,5.00,5.00,5.00,5.00,5.00,5.00,5.00,5.00,5.00"
					( Origin gBackEnd )
				)
				( attribute "BBV_TO_SMDPIN_SPACING" "5.00,5.00,5.00,5.00,5.00,5.00,5.00,5.00,5.00,5.00,5.00,5.00,5.00,5.00"
					( Origin gBackEnd )
				)
				( attribute "SMDPIN_TO_BONDPAD_SPACING" "5.00,5.00,5.00,5.00,5.00,5.00,5.00,5.00,5.00,5.00,5.00,5.00,5.00,5.00"
					( Origin gBackEnd )
				)
				( attribute "LINE_TO_SMDPIN_SPACING" "4.50,4.50,4.50,4.50,4.50,4.50,4.50,4.50,4.50,4.50,4.50,4.50,4.50,4.50"
					( Origin gBackEnd )
				)
				( attribute "SHAPE_TO_SMDPIN_SPACING" "5.00,5.00,5.00,5.00,5.00,5.00,5.00,5.00,5.00,5.00,5.00,5.00,5.00,5.00"
					( Origin gBackEnd )
				)
				( attribute "TESTPIN_TO_TESTPIN_SPACING" "5.00,5.00,5.00,5.00,5.00,5.00,5.00,5.00,5.00,5.00,5.00,5.00,5.00,5.00"
					( Origin gBackEnd )
				)
				( attribute "TESTPIN_TO_THRUVIA_SPACING" "5.00,5.00,5.00,5.00,5.00,5.00,5.00,5.00,5.00,5.00,5.00,5.00,5.00,5.00"
					( Origin gBackEnd )
				)
				( attribute "TESTPIN_TO_TESTVIA_SPACING" "5.00,5.00,5.00,5.00,5.00,5.00,5.00,5.00,5.00,5.00,5.00,5.00,5.00,5.00"
					( Origin gBackEnd )
				)
				( attribute "BBV_TO_TESTPIN_SPACING" "5.00,5.00,5.00,5.00,5.00,5.00,5.00,5.00,5.00,5.00,5.00,5.00,5.00,5.00"
					( Origin gBackEnd )
				)
				( attribute "BONDPAD_TO_TESTPIN_SPACING" "5.00,5.00,5.00,5.00,5.00,5.00,5.00,5.00,5.00,5.00,5.00,5.00,5.00,5.00"
					( Origin gBackEnd )
				)
				( attribute "LINE_TO_TESTPIN_SPACING" "13.10,17.00,17.00,17.00,17.00,17.00,17.00,17.00,17.00,17.00,17.00,17.00,17.00,13.10"
					( Origin gBackEnd )
				)
				( attribute "SHAPE_TO_TESTPIN_SPACING" "5.00,5.00,5.00,5.00,5.00,5.00,5.00,5.00,5.00,5.00,5.00,5.00,5.00,5.00"
					( Origin gBackEnd )
				)
				( attribute "THRUVIA_TO_THRUVIA_SPACING" "6.00,6.00,6.00,6.00,6.00,6.00,6.00,6.00,6.00,6.00,6.00,6.00,6.00,6.00"
					( Origin gBackEnd )
				)
				( attribute "TESTVIA_TO_THRUVIA_SPACING" "6.00,6.00,6.00,6.00,6.00,6.00,6.00,6.00,6.00,6.00,6.00,6.00,6.00,6.00"
					( Origin gBackEnd )
				)
				( attribute "BBV_TO_THRUVIA_SPACING" "5.00,5.00,5.00,5.00,5.00,5.00,5.00,5.00,5.00,5.00,5.00,5.00,5.00,5.00"
					( Origin gBackEnd )
				)
				( attribute "BONDPAD_TO_THRUVIA_SPACING" "5.00,5.00,5.00,5.00,5.00,5.00,5.00,5.00,5.00,5.00,5.00,5.00,5.00,5.00"
					( Origin gBackEnd )
				)
				( attribute "LINE_TO_THRUVIA_SPACING" "12.00,5.00,13.00,5.00,13.00,5.00,5.00,5.00,5.00,13.00,5.00,13.00,5.00,12.00"
					( Origin gBackEnd )
				)
				( attribute "SHAPE_TO_THRUVIA_SPACING" "5.00,5.00,5.00,5.00,5.00,5.00,5.00,5.00,5.00,5.00,5.00,5.00,5.00,5.00"
					( Origin gBackEnd )
				)
				( attribute "TESTVIA_TO_TESTVIA_SPACING" "6.00,6.00,6.00,6.00,6.00,6.00,6.00,6.00,6.00,6.00,6.00,6.00,6.00,6.00"
					( Origin gBackEnd )
				)
				( attribute "BBV_TO_TESTVIA_SPACING" "5.00,5.00,5.00,5.00,5.00,5.00,5.00,5.00,5.00,5.00,5.00,5.00,5.00,5.00"
					( Origin gBackEnd )
				)
				( attribute "BONDPAD_TO_TESTVIA_SPACING" "5.00,5.00,5.00,5.00,5.00,5.00,5.00,5.00,5.00,5.00,5.00,5.00,5.00,5.00"
					( Origin gBackEnd )
				)
				( attribute "LINE_TO_TESTVIA_SPACING" "12.00,5.00,13.00,5.00,13.00,5.00,5.00,5.00,5.00,13.00,5.00,13.00,5.00,12.00"
					( Origin gBackEnd )
				)
				( attribute "SHAPE_TO_TESTVIA_SPACING" "5.00,5.00,5.00,5.00,5.00,5.00,5.00,5.00,5.00,5.00,5.00,5.00,5.00,5.00"
					( Origin gBackEnd )
				)
				( attribute "BBV_TO_BBV_SPACING" "5.00,5.00,5.00,5.00,5.00,5.00,5.00,5.00,5.00,5.00,5.00,5.00,5.00,5.00"
					( Origin gBackEnd )
				)
				( attribute "BONDPAD_TO_BBV_SPACING" "5.00,5.00,5.00,5.00,5.00,5.00,5.00,5.00,5.00,5.00,5.00,5.00,5.00,5.00"
					( Origin gBackEnd )
				)
				( attribute "BBV_TO_LINE_SPACING" "5.00,5.00,5.00,5.00,5.00,5.00,5.00,5.00,5.00,5.00,5.00,5.00,5.00,5.00"
					( Origin gBackEnd )
				)
				( attribute "BBV_TO_SHAPE_SPACING" "5.00,5.00,5.00,5.00,5.00,5.00,5.00,5.00,5.00,5.00,5.00,5.00,5.00,5.00"
					( Origin gBackEnd )
				)
				( attribute "BONDPAD_TO_BONDPAD_SPACING" "5.00,5.00,5.00,5.00,5.00,5.00,5.00,5.00,5.00,5.00,5.00,5.00,5.00,5.00"
					( Origin gBackEnd )
				)
				( attribute "BONDPAD_TO_LINE_SPACING" "5.00,5.00,5.00,5.00,5.00,5.00,5.00,5.00,5.00,5.00,5.00,5.00,5.00,5.00"
					( Origin gBackEnd )
				)
				( attribute "BONDPAD_TO_SHAPE_SPACING" "5.00,5.00,5.00,5.00,5.00,5.00,5.00,5.00,5.00,5.00,5.00,5.00,5.00,5.00"
					( Origin gBackEnd )
				)
				( attribute "LINE_TO_LINE_SPACING" "18.69,15.00,15.00,15.00,15.00,15.00,15.00,15.00,15.00,15.00,15.00,15.00,15.00,18.69"
					( Origin gBackEnd )
				)
				( attribute "LINE_TO_SHAPE_SPACING" "24.30,20.00,20.00,20.00,20.00,20.00,20.00,20.00,20.00,20.00,20.00,20.00,20.00,24.30"
					( Origin gBackEnd )
				)
				( attribute "SHAPE_TO_SHAPE_SPACING" "10.00,10.00,10.00,10.00,10.00,10.00,10.00,10.00,10.00,10.00,10.00,10.00,10.00,10.00"
					( Origin gBackEnd )
				)
				( attribute "HOLE_TO_PIN_SPACING" "8.00,8.00,8.00,8.00,8.00,8.00,8.00,8.00,8.00,8.00,8.00,8.00,8.00,8.00"
					( Origin gBackEnd )
				)
				( attribute "HOLE_TO_VIA_SPACING" "8.00,8.00,8.00,8.00,8.00,8.00,8.00,8.00,8.00,8.00,8.00,8.00,8.00,8.00"
					( Origin gBackEnd )
				)
				( attribute "HOLE_TO_LINE_SPACING" "8.00,8.00,8.00,8.00,8.00,8.00,8.00,8.00,8.00,8.00,8.00,8.00,8.00,8.00"
					( Origin gBackEnd )
				)
				( attribute "HOLE_TO_SHAPE_SPACING" "8.00,8.00,8.00,8.00,8.00,8.00,8.00,8.00,8.00,8.00,8.00,8.00,8.00,8.00"
					( Origin gBackEnd )
				)
				( attribute "HOLE_TO_HOLE_SPACING" "8.00,8.00,8.00,8.00,8.00,8.00,8.00,8.00,8.00,8.00,8.00,8.00,8.00,8.00"
					( Origin gBackEnd )
				)
				( attribute "MVIA_TO_MVIA_SPACING" "5.00,5.00,5.00,5.00,5.00,5.00,5.00,5.00,5.00,5.00,5.00,5.00,5.00,5.00"
					( Origin gBackEnd )
				)
				( attribute "MVIA_TO_THRUPIN_SPACING" "5.00,5.00,5.00,5.00,5.00,5.00,5.00,5.00,5.00,5.00,5.00,5.00,5.00,5.00"
					( Origin gBackEnd )
				)
				( attribute "MVIA_TO_SMDPIN_SPACING" "5.00,5.00,5.00,5.00,5.00,5.00,5.00,5.00,5.00,5.00,5.00,5.00,5.00,5.00"
					( Origin gBackEnd )
				)
				( attribute "MVIA_TO_THRUVIA_SPACING" "5.00,5.00,5.00,5.00,5.00,5.00,5.00,5.00,5.00,5.00,5.00,5.00,5.00,5.00"
					( Origin gBackEnd )
				)
				( attribute "MVIA_TO_BBV_SPACING" "5.00,5.00,5.00,5.00,5.00,5.00,5.00,5.00,5.00,5.00,5.00,5.00,5.00,5.00"
					( Origin gBackEnd )
				)
				( attribute "MVIA_TO_LINE_SPACING" "5.00,5.00,5.00,5.00,5.00,5.00,5.00,5.00,5.00,5.00,5.00,5.00,5.00,5.00"
					( Origin gBackEnd )
				)
				( attribute "MVIA_TO_SHAPE_SPACING" "5.00,5.00,5.00,5.00,5.00,5.00,5.00,5.00,5.00,5.00,5.00,5.00,5.00,5.00"
					( Origin gBackEnd )
				)
				( attribute "MVIA_TO_TESTPIN_SPACING" "5.00,5.00,5.00,5.00,5.00,5.00,5.00,5.00,5.00,5.00,5.00,5.00,5.00,5.00"
					( Origin gBackEnd )
				)
				( attribute "MVIA_TO_TESTVIA_SPACING" "5.00,5.00,5.00,5.00,5.00,5.00,5.00,5.00,5.00,5.00,5.00,5.00,5.00,5.00"
					( Origin gBackEnd )
				)
				( attribute "BONDPAD_TO_MVIA_SPACING" "5.00,5.00,5.00,5.00,5.00,5.00,5.00,5.00,5.00,5.00,5.00,5.00,5.00,5.00"
					( Origin gBackEnd )
				)
				( attribute "MIN_BVIA_GAP" "5.00"
					( Origin gBackEnd )
				)
				( attribute "BONDPAD_TO_BONDPAD_DIFFP_SPC" "5.00,5.00,5.00,5.00,5.00,5.00,5.00,5.00,5.00,5.00,5.00,5.00,5.00,5.00"
					( Origin gBackEnd )
				)
				( objectStatus "7H_US_&_5H_SL_VIA_3H+A" )
			)
			( spacingCSet "@sapphirecity_baseboard_lib.sapphirecity_baseboard(sch_1):\15MIL\"
				( attribute "THRUPIN_TO_THRUPIN_SPACING" "5.00,5.00,5.00,5.00,5.00,5.00,5.00,5.00,5.00,5.00,5.00,5.00,5.00,5.00"
					( Origin gBackEnd )
				)
				( attribute "THRUPIN_TO_SMDPIN_SPACING" "5.00,5.00,5.00,5.00,5.00,5.00,5.00,5.00,5.00,5.00,5.00,5.00,5.00,5.00"
					( Origin gBackEnd )
				)
				( attribute "TESTPIN_TO_THRUPIN_SPACING" "5.00,5.00,5.00,5.00,5.00,5.00,5.00,5.00,5.00,5.00,5.00,5.00,5.00,5.00"
					( Origin gBackEnd )
				)
				( attribute "THRUPIN_TO_THRUVIA_SPACING" "5.00,5.00,5.00,5.00,5.00,5.00,5.00,5.00,5.00,5.00,5.00,5.00,5.00,5.00"
					( Origin gBackEnd )
				)
				( attribute "TESTVIA_TO_THRUPIN_SPACING" "5.00,5.00,5.00,5.00,5.00,5.00,5.00,5.00,5.00,5.00,5.00,5.00,5.00,5.00"
					( Origin gBackEnd )
				)
				( attribute "BBV_TO_THRUPIN_SPACING" "5.00,5.00,5.00,5.00,5.00,5.00,5.00,5.00,5.00,5.00,5.00,5.00,5.00,5.00"
					( Origin gBackEnd )
				)
				( attribute "THRUPIN_TO_BONDPAD_SPACING" "5.00,5.00,5.00,5.00,5.00,5.00,5.00,5.00,5.00,5.00,5.00,5.00,5.00,5.00"
					( Origin gBackEnd )
				)
				( attribute "LINE_TO_THRUPIN_SPACING" "5.00,4.00,4.00,4.00,4.00,4.00,4.00,4.00,4.00,4.00,4.00,4.00,4.00,5.00"
					( Origin gBackEnd )
				)
				( attribute "THRUPIN_TO_SHAPE_SPACING" "5.00,5.00,5.00,5.00,5.00,5.00,5.00,5.00,5.00,5.00,5.00,5.00,5.00,5.00"
					( Origin gBackEnd )
				)
				( attribute "SMDPIN_TO_SMDPIN_SPACING" "5.00,5.00,5.00,5.00,5.00,5.00,5.00,5.00,5.00,5.00,5.00,5.00,5.00,5.00"
					( Origin gBackEnd )
				)
				( attribute "SMDPIN_TO_TESTPIN_SPACING" "5.00,5.00,5.00,5.00,5.00,5.00,5.00,5.00,5.00,5.00,5.00,5.00,5.00,25.00"
					( Origin gBackEnd )
				)
				( attribute "SMDPIN_TO_THRUVIA_SPACING" "5.00,5.00,5.00,5.00,5.00,5.00,5.00,5.00,5.00,5.00,5.00,5.00,5.00,5.00"
					( Origin gBackEnd )
				)
				( attribute "SMDPIN_TO_TESTVIA_SPACING" "5.00,5.00,5.00,5.00,5.00,5.00,5.00,5.00,5.00,5.00,5.00,5.00,5.00,5.00"
					( Origin gBackEnd )
				)
				( attribute "BBV_TO_SMDPIN_SPACING" "5.00,5.00,5.00,5.00,5.00,5.00,5.00,5.00,5.00,5.00,5.00,5.00,5.00,5.00"
					( Origin gBackEnd )
				)
				( attribute "SMDPIN_TO_BONDPAD_SPACING" "5.00,5.00,5.00,5.00,5.00,5.00,5.00,5.00,5.00,5.00,5.00,5.00,5.00,5.00"
					( Origin gBackEnd )
				)
				( attribute "LINE_TO_SMDPIN_SPACING" "4.50,4.50,4.50,4.50,4.50,4.50,4.50,4.50,4.50,4.50,4.50,4.50,4.50,4.50"
					( Origin gBackEnd )
				)
				( attribute "SHAPE_TO_SMDPIN_SPACING" "5.00,5.00,5.00,5.00,5.00,5.00,5.00,5.00,5.00,5.00,5.00,5.00,5.00,5.00"
					( Origin gBackEnd )
				)
				( attribute "TESTPIN_TO_TESTPIN_SPACING" "5.00,5.00,5.00,5.00,5.00,5.00,5.00,5.00,5.00,5.00,5.00,5.00,5.00,5.00"
					( Origin gBackEnd )
				)
				( attribute "TESTPIN_TO_THRUVIA_SPACING" "5.00,5.00,5.00,5.00,5.00,5.00,5.00,5.00,5.00,5.00,5.00,5.00,5.00,5.00"
					( Origin gBackEnd )
				)
				( attribute "TESTPIN_TO_TESTVIA_SPACING" "5.00,5.00,5.00,5.00,5.00,5.00,5.00,5.00,5.00,5.00,5.00,5.00,5.00,5.00"
					( Origin gBackEnd )
				)
				( attribute "BBV_TO_TESTPIN_SPACING" "5.00,5.00,5.00,5.00,5.00,5.00,5.00,5.00,5.00,5.00,5.00,5.00,5.00,5.00"
					( Origin gBackEnd )
				)
				( attribute "BONDPAD_TO_TESTPIN_SPACING" "5.00,5.00,5.00,5.00,5.00,5.00,5.00,5.00,5.00,5.00,5.00,5.00,5.00,5.00"
					( Origin gBackEnd )
				)
				( attribute "LINE_TO_TESTPIN_SPACING" "5.00,4.00,4.00,4.00,4.00,4.00,4.00,4.00,4.00,4.00,4.00,4.00,4.00,5.00"
					( Origin gBackEnd )
				)
				( attribute "SHAPE_TO_TESTPIN_SPACING" "5.00,5.00,5.00,5.00,5.00,5.00,5.00,5.00,5.00,5.00,5.00,5.00,5.00,5.00"
					( Origin gBackEnd )
				)
				( attribute "THRUVIA_TO_THRUVIA_SPACING" "5.00,5.00,5.00,5.00,5.00,5.00,5.00,5.00,5.00,5.00,5.00,5.00,5.00,5.00"
					( Origin gBackEnd )
				)
				( attribute "TESTVIA_TO_THRUVIA_SPACING" "6.00,6.00,6.00,6.00,6.00,6.00,6.00,6.00,6.00,6.00,6.00,6.00,6.00,6.00"
					( Origin gBackEnd )
				)
				( attribute "BBV_TO_THRUVIA_SPACING" "5.00,5.00,5.00,5.00,5.00,5.00,5.00,5.00,5.00,5.00,5.00,5.00,5.00,5.00"
					( Origin gBackEnd )
				)
				( attribute "BONDPAD_TO_THRUVIA_SPACING" "5.00,5.00,5.00,5.00,5.00,5.00,5.00,5.00,5.00,5.00,5.00,5.00,5.00,5.00"
					( Origin gBackEnd )
				)
				( attribute "LINE_TO_THRUVIA_SPACING" "4.50,4.00,4.00,4.00,4.00,4.00,4.00,4.00,4.00,4.00,4.00,4.00,4.00,4.50"
					( Origin gBackEnd )
				)
				( attribute "SHAPE_TO_THRUVIA_SPACING" "5.00,5.00,5.00,5.00,5.00,5.00,5.00,5.00,5.00,5.00,5.00,5.00,5.00,5.00"
					( Origin gBackEnd )
				)
				( attribute "TESTVIA_TO_TESTVIA_SPACING" "6.00,6.00,6.00,6.00,6.00,6.00,6.00,6.00,6.00,6.00,6.00,6.00,6.00,6.00"
					( Origin gBackEnd )
				)
				( attribute "BBV_TO_TESTVIA_SPACING" "5.00,5.00,5.00,5.00,5.00,5.00,5.00,5.00,5.00,5.00,5.00,5.00,5.00,5.00"
					( Origin gBackEnd )
				)
				( attribute "BONDPAD_TO_TESTVIA_SPACING" "5.00,5.00,5.00,5.00,5.00,5.00,5.00,5.00,5.00,5.00,5.00,5.00,5.00,5.00"
					( Origin gBackEnd )
				)
				( attribute "LINE_TO_TESTVIA_SPACING" "4.50,4.00,4.00,4.00,4.00,4.00,4.00,4.00,4.00,4.00,4.00,4.00,4.00,4.50"
					( Origin gBackEnd )
				)
				( attribute "SHAPE_TO_TESTVIA_SPACING" "5.00,5.00,5.00,5.00,5.00,5.00,5.00,5.00,5.00,5.00,5.00,5.00,5.00,5.00"
					( Origin gBackEnd )
				)
				( attribute "BBV_TO_BBV_SPACING" "5.00,5.00,5.00,5.00,5.00,5.00,5.00,5.00,5.00,5.00,5.00,5.00,5.00,5.00"
					( Origin gBackEnd )
				)
				( attribute "BONDPAD_TO_BBV_SPACING" "5.00,5.00,5.00,5.00,5.00,5.00,5.00,5.00,5.00,5.00,5.00,5.00,5.00,5.00"
					( Origin gBackEnd )
				)
				( attribute "BBV_TO_LINE_SPACING" "5.00,5.00,5.00,5.00,5.00,5.00,5.00,5.00,5.00,5.00,5.00,5.00,5.00,5.00"
					( Origin gBackEnd )
				)
				( attribute "BBV_TO_SHAPE_SPACING" "5.00,5.00,5.00,5.00,5.00,5.00,5.00,5.00,5.00,5.00,5.00,5.00,5.00,5.00"
					( Origin gBackEnd )
				)
				( attribute "BONDPAD_TO_BONDPAD_SPACING" "5.00,5.00,5.00,5.00,5.00,5.00,5.00,5.00,5.00,5.00,5.00,5.00,5.00,5.00"
					( Origin gBackEnd )
				)
				( attribute "BONDPAD_TO_LINE_SPACING" "5.00,5.00,5.00,5.00,5.00,5.00,5.00,5.00,5.00,5.00,5.00,5.00,5.00,5.00"
					( Origin gBackEnd )
				)
				( attribute "BONDPAD_TO_SHAPE_SPACING" "5.00,5.00,5.00,5.00,5.00,5.00,5.00,5.00,5.00,5.00,5.00,5.00,5.00,5.00"
					( Origin gBackEnd )
				)
				( attribute "LINE_TO_LINE_SPACING" "15.00,15.00,15.00,15.00,15.00,15.00,15.00,15.00,15.00,15.00,15.00,15.00,15.00,15.00"
					( Origin gBackEnd )
				)
				( attribute "LINE_TO_SHAPE_SPACING" "10.00,10.00,10.00,10.00,10.00,10.00,10.00,10.00,10.00,10.00,10.00,10.00,10.00,10.00"
					( Origin gBackEnd )
				)
				( attribute "SHAPE_TO_SHAPE_SPACING" "10.00,10.00,10.00,10.00,10.00,10.00,10.00,10.00,10.00,10.00,10.00,10.00,10.00,10.00"
					( Origin gBackEnd )
				)
				( attribute "HOLE_TO_PIN_SPACING" "8.00,8.00,8.00,8.00,8.00,8.00,8.00,8.00,8.00,8.00,8.00,8.00,8.00,8.00"
					( Origin gBackEnd )
				)
				( attribute "HOLE_TO_VIA_SPACING" "8.00,8.00,8.00,8.00,8.00,8.00,8.00,8.00,8.00,8.00,8.00,8.00,8.00,8.00"
					( Origin gBackEnd )
				)
				( attribute "HOLE_TO_LINE_SPACING" "8.00,8.00,8.00,8.00,8.00,8.00,8.00,8.00,8.00,8.00,8.00,8.00,8.00,8.00"
					( Origin gBackEnd )
				)
				( attribute "HOLE_TO_SHAPE_SPACING" "8.00,8.00,8.00,8.00,8.00,8.00,8.00,8.00,8.00,8.00,8.00,8.00,8.00,8.00"
					( Origin gBackEnd )
				)
				( attribute "HOLE_TO_HOLE_SPACING" "8.00,8.00,8.00,8.00,8.00,8.00,8.00,8.00,8.00,8.00,8.00,8.00,8.00,8.00"
					( Origin gBackEnd )
				)
				( attribute "MVIA_TO_MVIA_SPACING" "5.00,5.00,5.00,5.00,5.00,5.00,5.00,5.00,5.00,5.00,5.00,5.00,5.00,5.00"
					( Origin gBackEnd )
				)
				( attribute "MVIA_TO_THRUPIN_SPACING" "5.00,5.00,5.00,5.00,5.00,5.00,5.00,5.00,5.00,5.00,5.00,5.00,5.00,5.00"
					( Origin gBackEnd )
				)
				( attribute "MVIA_TO_SMDPIN_SPACING" "5.00,5.00,5.00,5.00,5.00,5.00,5.00,5.00,5.00,5.00,5.00,5.00,5.00,5.00"
					( Origin gBackEnd )
				)
				( attribute "MVIA_TO_THRUVIA_SPACING" "5.00,5.00,5.00,5.00,5.00,5.00,5.00,5.00,5.00,5.00,5.00,5.00,5.00,5.00"
					( Origin gBackEnd )
				)
				( attribute "MVIA_TO_BBV_SPACING" "5.00,5.00,5.00,5.00,5.00,5.00,5.00,5.00,5.00,5.00,5.00,5.00,5.00,5.00"
					( Origin gBackEnd )
				)
				( attribute "MVIA_TO_LINE_SPACING" "5.00,5.00,5.00,5.00,5.00,5.00,5.00,5.00,5.00,5.00,5.00,5.00,5.00,5.00"
					( Origin gBackEnd )
				)
				( attribute "MVIA_TO_SHAPE_SPACING" "5.00,5.00,5.00,5.00,5.00,5.00,5.00,5.00,5.00,5.00,5.00,5.00,5.00,5.00"
					( Origin gBackEnd )
				)
				( attribute "MVIA_TO_TESTPIN_SPACING" "5.00,5.00,5.00,5.00,5.00,5.00,5.00,5.00,5.00,5.00,5.00,5.00,5.00,5.00"
					( Origin gBackEnd )
				)
				( attribute "MVIA_TO_TESTVIA_SPACING" "5.00,5.00,5.00,5.00,5.00,5.00,5.00,5.00,5.00,5.00,5.00,5.00,5.00,5.00"
					( Origin gBackEnd )
				)
				( attribute "BONDPAD_TO_MVIA_SPACING" "5.00,5.00,5.00,5.00,5.00,5.00,5.00,5.00,5.00,5.00,5.00,5.00,5.00,5.00"
					( Origin gBackEnd )
				)
				( attribute "MIN_BVIA_GAP" "5.00"
					( Origin gBackEnd )
				)
				( attribute "BONDPAD_TO_BONDPAD_DIFFP_SPC" "5.00,5.00,5.00,5.00,5.00,5.00,5.00,5.00,5.00,5.00,5.00,5.00,5.00,5.00"
					( Origin gBackEnd )
				)
				( objectStatus "15MIL" )
			)
			( spacingCSet "@sapphirecity_baseboard_lib.sapphirecity_baseboard(sch_1):\8MIL_SL_10MIL_MS\"
				( attribute "THRUPIN_TO_THRUPIN_SPACING" "5.00,5.00,5.00,5.00,5.00,5.00,5.00,5.00,5.00,5.00,5.00,5.00,5.00,5.00"
					( Origin gBackEnd )
				)
				( attribute "THRUPIN_TO_SMDPIN_SPACING" "5.00,5.00,5.00,5.00,5.00,5.00,5.00,5.00,5.00,5.00,5.00,5.00,5.00,5.00"
					( Origin gBackEnd )
				)
				( attribute "TESTPIN_TO_THRUPIN_SPACING" "5.00,5.00,5.00,5.00,5.00,5.00,5.00,5.00,5.00,5.00,5.00,5.00,5.00,5.00"
					( Origin gBackEnd )
				)
				( attribute "THRUPIN_TO_THRUVIA_SPACING" "5.00,5.00,5.00,5.00,5.00,5.00,5.00,5.00,5.00,5.00,5.00,5.00,5.00,5.00"
					( Origin gBackEnd )
				)
				( attribute "TESTVIA_TO_THRUPIN_SPACING" "5.00,5.00,5.00,5.00,5.00,5.00,5.00,5.00,5.00,5.00,5.00,5.00,5.00,5.00"
					( Origin gBackEnd )
				)
				( attribute "BBV_TO_THRUPIN_SPACING" "5.00,5.00,5.00,5.00,5.00,5.00,5.00,5.00,5.00,5.00,5.00,5.00,5.00,5.00"
					( Origin gBackEnd )
				)
				( attribute "THRUPIN_TO_BONDPAD_SPACING" "5.00,5.00,5.00,5.00,5.00,5.00,5.00,5.00,5.00,5.00,5.00,5.00,5.00,5.00"
					( Origin gBackEnd )
				)
				( attribute "LINE_TO_THRUPIN_SPACING" "5.00,4.00,4.00,4.00,4.00,4.00,4.00,4.00,4.00,4.00,4.00,4.00,4.00,5.00"
					( Origin gBackEnd )
				)
				( attribute "THRUPIN_TO_SHAPE_SPACING" "5.00,5.00,5.00,5.00,5.00,5.00,5.00,5.00,5.00,5.00,5.00,5.00,5.00,5.00"
					( Origin gBackEnd )
				)
				( attribute "SMDPIN_TO_SMDPIN_SPACING" "5.00,5.00,5.00,5.00,5.00,5.00,5.00,5.00,5.00,5.00,5.00,5.00,5.00,5.00"
					( Origin gBackEnd )
				)
				( attribute "SMDPIN_TO_TESTPIN_SPACING" "5.00,5.00,5.00,5.00,5.00,5.00,5.00,5.00,5.00,5.00,5.00,5.00,5.00,25.00"
					( Origin gBackEnd )
				)
				( attribute "SMDPIN_TO_THRUVIA_SPACING" "5.00,5.00,5.00,5.00,5.00,5.00,5.00,5.00,5.00,5.00,5.00,5.00,5.00,5.00"
					( Origin gBackEnd )
				)
				( attribute "SMDPIN_TO_TESTVIA_SPACING" "5.00,5.00,5.00,5.00,5.00,5.00,5.00,5.00,5.00,5.00,5.00,5.00,5.00,5.00"
					( Origin gBackEnd )
				)
				( attribute "BBV_TO_SMDPIN_SPACING" "5.00,5.00,5.00,5.00,5.00,5.00,5.00,5.00,5.00,5.00,5.00,5.00,5.00,5.00"
					( Origin gBackEnd )
				)
				( attribute "SMDPIN_TO_BONDPAD_SPACING" "5.00,5.00,5.00,5.00,5.00,5.00,5.00,5.00,5.00,5.00,5.00,5.00,5.00,5.00"
					( Origin gBackEnd )
				)
				( attribute "LINE_TO_SMDPIN_SPACING" "4.50,4.50,4.50,4.50,4.50,4.50,4.50,4.50,4.50,4.50,4.50,4.50,4.50,4.50"
					( Origin gBackEnd )
				)
				( attribute "SHAPE_TO_SMDPIN_SPACING" "5.00,5.00,5.00,5.00,5.00,5.00,5.00,5.00,5.00,5.00,5.00,5.00,5.00,5.00"
					( Origin gBackEnd )
				)
				( attribute "TESTPIN_TO_TESTPIN_SPACING" "5.00,5.00,5.00,5.00,5.00,5.00,5.00,5.00,5.00,5.00,5.00,5.00,5.00,5.00"
					( Origin gBackEnd )
				)
				( attribute "TESTPIN_TO_THRUVIA_SPACING" "5.00,5.00,5.00,5.00,5.00,5.00,5.00,5.00,5.00,5.00,5.00,5.00,5.00,5.00"
					( Origin gBackEnd )
				)
				( attribute "TESTPIN_TO_TESTVIA_SPACING" "5.00,5.00,5.00,5.00,5.00,5.00,5.00,5.00,5.00,5.00,5.00,5.00,5.00,5.00"
					( Origin gBackEnd )
				)
				( attribute "BBV_TO_TESTPIN_SPACING" "5.00,5.00,5.00,5.00,5.00,5.00,5.00,5.00,5.00,5.00,5.00,5.00,5.00,5.00"
					( Origin gBackEnd )
				)
				( attribute "BONDPAD_TO_TESTPIN_SPACING" "5.00,5.00,5.00,5.00,5.00,5.00,5.00,5.00,5.00,5.00,5.00,5.00,5.00,5.00"
					( Origin gBackEnd )
				)
				( attribute "LINE_TO_TESTPIN_SPACING" "5.00,4.00,4.00,4.00,4.00,4.00,4.00,4.00,4.00,4.00,4.00,4.00,4.00,5.00"
					( Origin gBackEnd )
				)
				( attribute "SHAPE_TO_TESTPIN_SPACING" "5.00,5.00,5.00,5.00,5.00,5.00,5.00,5.00,5.00,5.00,5.00,5.00,5.00,5.00"
					( Origin gBackEnd )
				)
				( attribute "THRUVIA_TO_THRUVIA_SPACING" "5.00,5.00,5.00,5.00,5.00,5.00,5.00,5.00,5.00,5.00,5.00,5.00,5.00,5.00"
					( Origin gBackEnd )
				)
				( attribute "TESTVIA_TO_THRUVIA_SPACING" "6.00,6.00,6.00,6.00,6.00,6.00,6.00,6.00,6.00,6.00,6.00,6.00,6.00,6.00"
					( Origin gBackEnd )
				)
				( attribute "BBV_TO_THRUVIA_SPACING" "5.00,5.00,5.00,5.00,5.00,5.00,5.00,5.00,5.00,5.00,5.00,5.00,5.00,5.00"
					( Origin gBackEnd )
				)
				( attribute "BONDPAD_TO_THRUVIA_SPACING" "5.00,5.00,5.00,5.00,5.00,5.00,5.00,5.00,5.00,5.00,5.00,5.00,5.00,5.00"
					( Origin gBackEnd )
				)
				( attribute "LINE_TO_THRUVIA_SPACING" "4.50,4.00,4.00,4.00,4.00,4.00,4.00,4.00,4.00,4.00,4.00,4.00,4.00,4.50"
					( Origin gBackEnd )
				)
				( attribute "SHAPE_TO_THRUVIA_SPACING" "4.50,4.00,4.00,4.00,4.00,4.00,5.00,5.00,4.00,4.00,4.00,4.00,4.00,4.50"
					( Origin gBackEnd )
				)
				( attribute "TESTVIA_TO_TESTVIA_SPACING" "6.00,6.00,6.00,6.00,6.00,6.00,6.00,6.00,6.00,6.00,6.00,6.00,6.00,6.00"
					( Origin gBackEnd )
				)
				( attribute "BBV_TO_TESTVIA_SPACING" "5.00,5.00,5.00,5.00,5.00,5.00,5.00,5.00,5.00,5.00,5.00,5.00,5.00,5.00"
					( Origin gBackEnd )
				)
				( attribute "BONDPAD_TO_TESTVIA_SPACING" "5.00,5.00,5.00,5.00,5.00,5.00,5.00,5.00,5.00,5.00,5.00,5.00,5.00,5.00"
					( Origin gBackEnd )
				)
				( attribute "LINE_TO_TESTVIA_SPACING" "4.50,4.00,4.00,4.00,4.00,4.00,4.00,4.00,4.00,4.00,4.00,4.00,4.00,4.50"
					( Origin gBackEnd )
				)
				( attribute "SHAPE_TO_TESTVIA_SPACING" "5.00,5.00,5.00,5.00,5.00,5.00,5.00,5.00,5.00,5.00,5.00,5.00,5.00,5.00"
					( Origin gBackEnd )
				)
				( attribute "BBV_TO_BBV_SPACING" "5.00,5.00,5.00,5.00,5.00,5.00,5.00,5.00,5.00,5.00,5.00,5.00,5.00,5.00"
					( Origin gBackEnd )
				)
				( attribute "BONDPAD_TO_BBV_SPACING" "5.00,5.00,5.00,5.00,5.00,5.00,5.00,5.00,5.00,5.00,5.00,5.00,5.00,5.00"
					( Origin gBackEnd )
				)
				( attribute "BBV_TO_LINE_SPACING" "5.00,5.00,5.00,5.00,5.00,5.00,5.00,5.00,5.00,5.00,5.00,5.00,5.00,5.00"
					( Origin gBackEnd )
				)
				( attribute "BBV_TO_SHAPE_SPACING" "5.00,5.00,5.00,5.00,5.00,5.00,5.00,5.00,5.00,5.00,5.00,5.00,5.00,5.00"
					( Origin gBackEnd )
				)
				( attribute "BONDPAD_TO_BONDPAD_SPACING" "5.00,5.00,5.00,5.00,5.00,5.00,5.00,5.00,5.00,5.00,5.00,5.00,5.00,5.00"
					( Origin gBackEnd )
				)
				( attribute "BONDPAD_TO_LINE_SPACING" "5.00,5.00,5.00,5.00,5.00,5.00,5.00,5.00,5.00,5.00,5.00,5.00,5.00,5.00"
					( Origin gBackEnd )
				)
				( attribute "BONDPAD_TO_SHAPE_SPACING" "5.00,5.00,5.00,5.00,5.00,5.00,5.00,5.00,5.00,5.00,5.00,5.00,5.00,5.00"
					( Origin gBackEnd )
				)
				( attribute "LINE_TO_LINE_SPACING" "10.00,8.00,8.00,8.00,8.00,8.00,8.00,8.00,8.00,8.00,8.00,8.00,8.00,10.00"
					( Origin gBackEnd )
				)
				( attribute "LINE_TO_SHAPE_SPACING" "10.00,10.00,10.00,10.00,10.00,10.00,10.00,10.00,10.00,10.00,10.00,10.00,10.00,10.00"
					( Origin gBackEnd )
				)
				( attribute "SHAPE_TO_SHAPE_SPACING" "10.00,10.00,10.00,10.00,10.00,10.00,10.00,10.00,10.00,10.00,10.00,10.00,10.00,10.00"
					( Origin gBackEnd )
				)
				( attribute "HOLE_TO_PIN_SPACING" "8.00,8.00,8.00,8.00,8.00,8.00,8.00,8.00,8.00,8.00,8.00,8.00,8.00,8.00"
					( Origin gBackEnd )
				)
				( attribute "HOLE_TO_VIA_SPACING" "8.00,8.00,8.00,8.00,8.00,8.00,8.00,8.00,8.00,8.00,8.00,8.00,8.00,8.00"
					( Origin gBackEnd )
				)
				( attribute "HOLE_TO_LINE_SPACING" "8.00,8.00,8.00,8.00,8.00,8.00,8.00,8.00,8.00,8.00,8.00,8.00,8.00,8.00"
					( Origin gBackEnd )
				)
				( attribute "HOLE_TO_SHAPE_SPACING" "8.00,8.00,8.00,8.00,8.00,8.00,8.00,8.00,8.00,8.00,8.00,8.00,8.00,8.00"
					( Origin gBackEnd )
				)
				( attribute "HOLE_TO_HOLE_SPACING" "8.00,8.00,8.00,8.00,8.00,8.00,8.00,8.00,8.00,8.00,8.00,8.00,8.00,8.00"
					( Origin gBackEnd )
				)
				( attribute "MVIA_TO_MVIA_SPACING" "5.00,5.00,5.00,5.00,5.00,5.00,5.00,5.00,5.00,5.00,5.00,5.00,5.00,5.00"
					( Origin gBackEnd )
				)
				( attribute "MVIA_TO_THRUPIN_SPACING" "5.00,5.00,5.00,5.00,5.00,5.00,5.00,5.00,5.00,5.00,5.00,5.00,5.00,5.00"
					( Origin gBackEnd )
				)
				( attribute "MVIA_TO_SMDPIN_SPACING" "5.00,5.00,5.00,5.00,5.00,5.00,5.00,5.00,5.00,5.00,5.00,5.00,5.00,5.00"
					( Origin gBackEnd )
				)
				( attribute "MVIA_TO_THRUVIA_SPACING" "5.00,5.00,5.00,5.00,5.00,5.00,5.00,5.00,5.00,5.00,5.00,5.00,5.00,5.00"
					( Origin gBackEnd )
				)
				( attribute "MVIA_TO_BBV_SPACING" "5.00,5.00,5.00,5.00,5.00,5.00,5.00,5.00,5.00,5.00,5.00,5.00,5.00,5.00"
					( Origin gBackEnd )
				)
				( attribute "MVIA_TO_LINE_SPACING" "5.00,5.00,5.00,5.00,5.00,5.00,5.00,5.00,5.00,5.00,5.00,5.00,5.00,5.00"
					( Origin gBackEnd )
				)
				( attribute "MVIA_TO_SHAPE_SPACING" "5.00,5.00,5.00,5.00,5.00,5.00,5.00,5.00,5.00,5.00,5.00,5.00,5.00,5.00"
					( Origin gBackEnd )
				)
				( attribute "MVIA_TO_TESTPIN_SPACING" "5.00,5.00,5.00,5.00,5.00,5.00,5.00,5.00,5.00,5.00,5.00,5.00,5.00,5.00"
					( Origin gBackEnd )
				)
				( attribute "MVIA_TO_TESTVIA_SPACING" "5.00,5.00,5.00,5.00,5.00,5.00,5.00,5.00,5.00,5.00,5.00,5.00,5.00,5.00"
					( Origin gBackEnd )
				)
				( attribute "BONDPAD_TO_MVIA_SPACING" "5.00,5.00,5.00,5.00,5.00,5.00,5.00,5.00,5.00,5.00,5.00,5.00,5.00,5.00"
					( Origin gBackEnd )
				)
				( attribute "MIN_BVIA_GAP" "5.00"
					( Origin gBackEnd )
				)
				( attribute "BONDPAD_TO_BONDPAD_DIFFP_SPC" "5.00,5.00,5.00,5.00,5.00,5.00,5.00,5.00,5.00,5.00,5.00,5.00,5.00,5.00"
					( Origin gBackEnd )
				)
				( objectStatus "10MIL_US_&_8MIL_SL" )
			)
			( spacingCSet "@sapphirecity_baseboard_lib.sapphirecity_baseboard(sch_1):\20MIL_VIA_2H+A\"
				( attribute "THRUPIN_TO_THRUPIN_SPACING" "5.00,5.00,5.00,5.00,5.00,5.00,5.00,5.00,5.00,5.00,5.00,5.00,5.00,5.00"
					( Origin gBackEnd )
				)
				( attribute "THRUPIN_TO_SMDPIN_SPACING" "5.00,5.00,5.00,5.00,5.00,5.00,5.00,5.00,5.00,5.00,5.00,5.00,5.00,5.00"
					( Origin gBackEnd )
				)
				( attribute "TESTPIN_TO_THRUPIN_SPACING" "5.00,5.00,5.00,5.00,5.00,5.00,5.00,5.00,5.00,5.00,5.00,5.00,5.00,5.00"
					( Origin gBackEnd )
				)
				( attribute "THRUPIN_TO_THRUVIA_SPACING" "5.00,5.00,5.00,5.00,5.00,5.00,5.00,5.00,5.00,5.00,5.00,5.00,5.00,5.00"
					( Origin gBackEnd )
				)
				( attribute "TESTVIA_TO_THRUPIN_SPACING" "5.00,5.00,5.00,5.00,5.00,5.00,5.00,5.00,5.00,5.00,5.00,5.00,5.00,5.00"
					( Origin gBackEnd )
				)
				( attribute "BBV_TO_THRUPIN_SPACING" "5.00,5.00,5.00,5.00,5.00,5.00,5.00,5.00,5.00,5.00,5.00,5.00,5.00,5.00"
					( Origin gBackEnd )
				)
				( attribute "THRUPIN_TO_BONDPAD_SPACING" "5.00,5.00,5.00,5.00,5.00,5.00,5.00,5.00,5.00,5.00,5.00,5.00,5.00,5.00"
					( Origin gBackEnd )
				)
				( attribute "LINE_TO_THRUPIN_SPACING" "10.40,13.00,13.00,13.00,13.00,13.00,13.00,13.00,13.00,13.00,13.00,13.00,13.00,10.40"
					( Origin gBackEnd )
				)
				( attribute "THRUPIN_TO_SHAPE_SPACING" "5.00,5.00,5.00,5.00,5.00,5.00,5.00,5.00,5.00,5.00,5.00,5.00,5.00,5.00"
					( Origin gBackEnd )
				)
				( attribute "SMDPIN_TO_SMDPIN_SPACING" "5.00,5.00,5.00,5.00,5.00,5.00,5.00,5.00,5.00,5.00,5.00,5.00,5.00,5.00"
					( Origin gBackEnd )
				)
				( attribute "SMDPIN_TO_TESTPIN_SPACING" "5.00,5.00,5.00,5.00,5.00,5.00,5.00,5.00,5.00,5.00,5.00,5.00,5.00,25.00"
					( Origin gBackEnd )
				)
				( attribute "SMDPIN_TO_THRUVIA_SPACING" "5.00,5.00,5.00,5.00,5.00,5.00,5.00,5.00,5.00,5.00,5.00,5.00,5.00,5.00"
					( Origin gBackEnd )
				)
				( attribute "SMDPIN_TO_TESTVIA_SPACING" "5.00,5.00,5.00,5.00,5.00,5.00,5.00,5.00,5.00,5.00,5.00,5.00,5.00,5.00"
					( Origin gBackEnd )
				)
				( attribute "BBV_TO_SMDPIN_SPACING" "5.00,5.00,5.00,5.00,5.00,5.00,5.00,5.00,5.00,5.00,5.00,5.00,5.00,5.00"
					( Origin gBackEnd )
				)
				( attribute "SMDPIN_TO_BONDPAD_SPACING" "5.00,5.00,5.00,5.00,5.00,5.00,5.00,5.00,5.00,5.00,5.00,5.00,5.00,5.00"
					( Origin gBackEnd )
				)
				( attribute "LINE_TO_SMDPIN_SPACING" "4.50,4.50,4.50,4.50,4.50,4.50,4.50,4.50,4.50,4.50,4.50,4.50,4.50,4.50"
					( Origin gBackEnd )
				)
				( attribute "SHAPE_TO_SMDPIN_SPACING" "5.00,5.00,5.00,5.00,5.00,5.00,5.00,5.00,5.00,5.00,5.00,5.00,5.00,5.00"
					( Origin gBackEnd )
				)
				( attribute "TESTPIN_TO_TESTPIN_SPACING" "5.00,5.00,5.00,5.00,5.00,5.00,5.00,5.00,5.00,5.00,5.00,5.00,5.00,5.00"
					( Origin gBackEnd )
				)
				( attribute "TESTPIN_TO_THRUVIA_SPACING" "5.00,5.00,5.00,5.00,5.00,5.00,5.00,5.00,5.00,5.00,5.00,5.00,5.00,5.00"
					( Origin gBackEnd )
				)
				( attribute "TESTPIN_TO_TESTVIA_SPACING" "5.00,5.00,5.00,5.00,5.00,5.00,5.00,5.00,5.00,5.00,5.00,5.00,5.00,5.00"
					( Origin gBackEnd )
				)
				( attribute "BBV_TO_TESTPIN_SPACING" "5.00,5.00,5.00,5.00,5.00,5.00,5.00,5.00,5.00,5.00,5.00,5.00,5.00,5.00"
					( Origin gBackEnd )
				)
				( attribute "BONDPAD_TO_TESTPIN_SPACING" "5.00,5.00,5.00,5.00,5.00,5.00,5.00,5.00,5.00,5.00,5.00,5.00,5.00,5.00"
					( Origin gBackEnd )
				)
				( attribute "LINE_TO_TESTPIN_SPACING" "10.40,13.00,13.00,13.00,13.00,13.00,13.00,13.00,13.00,13.00,13.00,13.00,13.00,10.40"
					( Origin gBackEnd )
				)
				( attribute "SHAPE_TO_TESTPIN_SPACING" "5.00,5.00,5.00,5.00,5.00,5.00,5.00,5.00,5.00,5.00,5.00,5.00,5.00,5.00"
					( Origin gBackEnd )
				)
				( attribute "THRUVIA_TO_THRUVIA_SPACING" "6.00,6.00,6.00,6.00,6.00,6.00,6.00,6.00,6.00,6.00,6.00,6.00,6.00,6.00"
					( Origin gBackEnd )
				)
				( attribute "TESTVIA_TO_THRUVIA_SPACING" "6.00,6.00,6.00,6.00,6.00,6.00,6.00,6.00,6.00,6.00,6.00,6.00,6.00,6.00"
					( Origin gBackEnd )
				)
				( attribute "BBV_TO_THRUVIA_SPACING" "5.00,5.00,5.00,5.00,5.00,5.00,5.00,5.00,5.00,5.00,5.00,5.00,5.00,5.00"
					( Origin gBackEnd )
				)
				( attribute "BONDPAD_TO_THRUVIA_SPACING" "5.00,5.00,5.00,5.00,5.00,5.00,5.00,5.00,5.00,5.00,5.00,5.00,5.00,5.00"
					( Origin gBackEnd )
				)
				( attribute "LINE_TO_THRUVIA_SPACING" "9.40,5.00,10.00,5.00,10.00,5.00,5.00,5.00,5.00,10.00,5.00,10.00,5.00,9.40"
					( Origin gBackEnd )
				)
				( attribute "SHAPE_TO_THRUVIA_SPACING" "5.00,5.00,5.00,5.00,5.00,5.00,5.00,5.00,5.00,5.00,5.00,5.00,5.00,5.00"
					( Origin gBackEnd )
				)
				( attribute "TESTVIA_TO_TESTVIA_SPACING" "6.00,6.00,6.00,6.00,6.00,6.00,6.00,6.00,6.00,6.00,6.00,6.00,6.00,6.00"
					( Origin gBackEnd )
				)
				( attribute "BBV_TO_TESTVIA_SPACING" "5.00,5.00,5.00,5.00,5.00,5.00,5.00,5.00,5.00,5.00,5.00,5.00,5.00,5.00"
					( Origin gBackEnd )
				)
				( attribute "BONDPAD_TO_TESTVIA_SPACING" "5.00,5.00,5.00,5.00,5.00,5.00,5.00,5.00,5.00,5.00,5.00,5.00,5.00,5.00"
					( Origin gBackEnd )
				)
				( attribute "LINE_TO_TESTVIA_SPACING" "9.40,5.00,10.00,5.00,10.00,5.00,5.00,5.00,5.00,10.00,5.00,10.00,5.00,9.40"
					( Origin gBackEnd )
				)
				( attribute "SHAPE_TO_TESTVIA_SPACING" "5.00,5.00,5.00,5.00,5.00,5.00,5.00,5.00,5.00,5.00,5.00,5.00,5.00,5.00"
					( Origin gBackEnd )
				)
				( attribute "BBV_TO_BBV_SPACING" "5.00,5.00,5.00,5.00,5.00,5.00,5.00,5.00,5.00,5.00,5.00,5.00,5.00,5.00"
					( Origin gBackEnd )
				)
				( attribute "BONDPAD_TO_BBV_SPACING" "5.00,5.00,5.00,5.00,5.00,5.00,5.00,5.00,5.00,5.00,5.00,5.00,5.00,5.00"
					( Origin gBackEnd )
				)
				( attribute "BBV_TO_LINE_SPACING" "5.00,5.00,5.00,5.00,5.00,5.00,5.00,5.00,5.00,5.00,5.00,5.00,5.00,5.00"
					( Origin gBackEnd )
				)
				( attribute "BBV_TO_SHAPE_SPACING" "5.00,5.00,5.00,5.00,5.00,5.00,5.00,5.00,5.00,5.00,5.00,5.00,5.00,5.00"
					( Origin gBackEnd )
				)
				( attribute "BONDPAD_TO_BONDPAD_SPACING" "5.00,5.00,5.00,5.00,5.00,5.00,5.00,5.00,5.00,5.00,5.00,5.00,5.00,5.00"
					( Origin gBackEnd )
				)
				( attribute "BONDPAD_TO_LINE_SPACING" "5.00,5.00,5.00,5.00,5.00,5.00,5.00,5.00,5.00,5.00,5.00,5.00,5.00,5.00"
					( Origin gBackEnd )
				)
				( attribute "BONDPAD_TO_SHAPE_SPACING" "5.00,5.00,5.00,5.00,5.00,5.00,5.00,5.00,5.00,5.00,5.00,5.00,5.00,5.00"
					( Origin gBackEnd )
				)
				( attribute "LINE_TO_LINE_SPACING" "20.00,20.00,20.00,20.00,20.00,20.00,20.00,20.00,20.00,20.00,20.00,20.00,20.00,20.00"
					( Origin gBackEnd )
				)
				( attribute "LINE_TO_SHAPE_SPACING" "10.00,10.00,10.00,10.00,10.00,10.00,10.00,10.00,10.00,10.00,10.00,10.00,10.00,10.00"
					( Origin gBackEnd )
				)
				( attribute "SHAPE_TO_SHAPE_SPACING" "10.00,10.00,10.00,10.00,10.00,10.00,10.00,10.00,10.00,10.00,10.00,10.00,10.00,10.00"
					( Origin gBackEnd )
				)
				( attribute "HOLE_TO_PIN_SPACING" "8.00,8.00,8.00,8.00,8.00,8.00,8.00,8.00,8.00,8.00,8.00,8.00,8.00,8.00"
					( Origin gBackEnd )
				)
				( attribute "HOLE_TO_VIA_SPACING" "8.00,8.00,8.00,8.00,8.00,8.00,8.00,8.00,8.00,8.00,8.00,8.00,8.00,8.00"
					( Origin gBackEnd )
				)
				( attribute "HOLE_TO_LINE_SPACING" "8.00,8.00,8.00,8.00,8.00,8.00,8.00,8.00,8.00,8.00,8.00,8.00,8.00,8.00"
					( Origin gBackEnd )
				)
				( attribute "HOLE_TO_SHAPE_SPACING" "8.00,8.00,8.00,8.00,8.00,8.00,8.00,8.00,8.00,8.00,8.00,8.00,8.00,8.00"
					( Origin gBackEnd )
				)
				( attribute "HOLE_TO_HOLE_SPACING" "8.00,8.00,8.00,8.00,8.00,8.00,8.00,8.00,8.00,8.00,8.00,8.00,8.00,8.00"
					( Origin gBackEnd )
				)
				( attribute "MVIA_TO_MVIA_SPACING" "5.00,5.00,5.00,5.00,5.00,5.00,5.00,5.00,5.00,5.00,5.00,5.00,5.00,5.00"
					( Origin gBackEnd )
				)
				( attribute "MVIA_TO_THRUPIN_SPACING" "5.00,5.00,5.00,5.00,5.00,5.00,5.00,5.00,5.00,5.00,5.00,5.00,5.00,5.00"
					( Origin gBackEnd )
				)
				( attribute "MVIA_TO_SMDPIN_SPACING" "5.00,5.00,5.00,5.00,5.00,5.00,5.00,5.00,5.00,5.00,5.00,5.00,5.00,5.00"
					( Origin gBackEnd )
				)
				( attribute "MVIA_TO_THRUVIA_SPACING" "5.00,5.00,5.00,5.00,5.00,5.00,5.00,5.00,5.00,5.00,5.00,5.00,5.00,5.00"
					( Origin gBackEnd )
				)
				( attribute "MVIA_TO_BBV_SPACING" "5.00,5.00,5.00,5.00,5.00,5.00,5.00,5.00,5.00,5.00,5.00,5.00,5.00,5.00"
					( Origin gBackEnd )
				)
				( attribute "MVIA_TO_LINE_SPACING" "5.00,5.00,5.00,5.00,5.00,5.00,5.00,5.00,5.00,5.00,5.00,5.00,5.00,5.00"
					( Origin gBackEnd )
				)
				( attribute "MVIA_TO_SHAPE_SPACING" "5.00,5.00,5.00,5.00,5.00,5.00,5.00,5.00,5.00,5.00,5.00,5.00,5.00,5.00"
					( Origin gBackEnd )
				)
				( attribute "MVIA_TO_TESTPIN_SPACING" "5.00,5.00,5.00,5.00,5.00,5.00,5.00,5.00,5.00,5.00,5.00,5.00,5.00,5.00"
					( Origin gBackEnd )
				)
				( attribute "MVIA_TO_TESTVIA_SPACING" "5.00,5.00,5.00,5.00,5.00,5.00,5.00,5.00,5.00,5.00,5.00,5.00,5.00,5.00"
					( Origin gBackEnd )
				)
				( attribute "BONDPAD_TO_MVIA_SPACING" "5.00,5.00,5.00,5.00,5.00,5.00,5.00,5.00,5.00,5.00,5.00,5.00,5.00,5.00"
					( Origin gBackEnd )
				)
				( attribute "MIN_BVIA_GAP" "5.00"
					( Origin gBackEnd )
				)
				( attribute "BONDPAD_TO_BONDPAD_DIFFP_SPC" "5.00,5.00,5.00,5.00,5.00,5.00,5.00,5.00,5.00,5.00,5.00,5.00,5.00,5.00"
					( Origin gBackEnd )
				)
				( objectStatus "20MIL_VIA_2H+A" )
			)
			( spacingCSet "@sapphirecity_baseboard_lib.sapphirecity_baseboard(sch_1):\10MIL\"
				( attribute "THRUPIN_TO_THRUPIN_SPACING" "5.00,5.00,5.00,5.00,5.00,5.00,5.00,5.00,5.00,5.00,5.00,5.00,5.00,5.00"
					( Origin gBackEnd )
				)
				( attribute "THRUPIN_TO_SMDPIN_SPACING" "5.00,5.00,5.00,5.00,5.00,5.00,5.00,5.00,5.00,5.00,5.00,5.00,5.00,5.00"
					( Origin gBackEnd )
				)
				( attribute "TESTPIN_TO_THRUPIN_SPACING" "5.00,5.00,5.00,5.00,5.00,5.00,5.00,5.00,5.00,5.00,5.00,5.00,5.00,5.00"
					( Origin gBackEnd )
				)
				( attribute "THRUPIN_TO_THRUVIA_SPACING" "5.00,5.00,5.00,5.00,5.00,5.00,5.00,5.00,5.00,5.00,5.00,5.00,5.00,5.00"
					( Origin gBackEnd )
				)
				( attribute "TESTVIA_TO_THRUPIN_SPACING" "5.00,5.00,5.00,5.00,5.00,5.00,5.00,5.00,5.00,5.00,5.00,5.00,5.00,5.00"
					( Origin gBackEnd )
				)
				( attribute "BBV_TO_THRUPIN_SPACING" "5.00,5.00,5.00,5.00,5.00,5.00,5.00,5.00,5.00,5.00,5.00,5.00,5.00,5.00"
					( Origin gBackEnd )
				)
				( attribute "THRUPIN_TO_BONDPAD_SPACING" "5.00,5.00,5.00,5.00,5.00,5.00,5.00,5.00,5.00,5.00,5.00,5.00,5.00,5.00"
					( Origin gBackEnd )
				)
				( attribute "LINE_TO_THRUPIN_SPACING" "4.50,4.00,4.00,4.00,4.00,4.00,4.00,4.00,4.00,4.00,4.00,4.00,4.00,4.50"
					( Origin gBackEnd )
				)
				( attribute "THRUPIN_TO_SHAPE_SPACING" "5.00,5.00,5.00,5.00,5.00,5.00,5.00,5.00,5.00,5.00,5.00,5.00,5.00,5.00"
					( Origin gBackEnd )
				)
				( attribute "SMDPIN_TO_SMDPIN_SPACING" "5.00,5.00,5.00,5.00,5.00,5.00,5.00,5.00,5.00,5.00,5.00,5.00,5.00,5.00"
					( Origin gBackEnd )
				)
				( attribute "SMDPIN_TO_TESTPIN_SPACING" "5.00,5.00,5.00,5.00,5.00,5.00,5.00,5.00,5.00,5.00,5.00,5.00,5.00,25.00"
					( Origin gBackEnd )
				)
				( attribute "SMDPIN_TO_THRUVIA_SPACING" "5.00,5.00,5.00,5.00,5.00,5.00,5.00,5.00,5.00,5.00,5.00,5.00,5.00,5.00"
					( Origin gBackEnd )
				)
				( attribute "SMDPIN_TO_TESTVIA_SPACING" "5.00,5.00,5.00,5.00,5.00,5.00,5.00,5.00,5.00,5.00,5.00,5.00,5.00,5.00"
					( Origin gBackEnd )
				)
				( attribute "BBV_TO_SMDPIN_SPACING" "5.00,5.00,5.00,5.00,5.00,5.00,5.00,5.00,5.00,5.00,5.00,5.00,5.00,5.00"
					( Origin gBackEnd )
				)
				( attribute "SMDPIN_TO_BONDPAD_SPACING" "5.00,5.00,5.00,5.00,5.00,5.00,5.00,5.00,5.00,5.00,5.00,5.00,5.00,5.00"
					( Origin gBackEnd )
				)
				( attribute "LINE_TO_SMDPIN_SPACING" "4.50,4.50,4.50,4.50,4.50,4.50,4.50,4.50,4.50,4.50,4.50,4.50,4.50,4.50"
					( Origin gBackEnd )
				)
				( attribute "SHAPE_TO_SMDPIN_SPACING" "5.00,5.00,5.00,5.00,5.00,5.00,5.00,5.00,5.00,5.00,5.00,5.00,5.00,5.00"
					( Origin gBackEnd )
				)
				( attribute "TESTPIN_TO_TESTPIN_SPACING" "5.00,5.00,5.00,5.00,5.00,5.00,5.00,5.00,5.00,5.00,5.00,5.00,5.00,5.00"
					( Origin gBackEnd )
				)
				( attribute "TESTPIN_TO_THRUVIA_SPACING" "5.00,5.00,5.00,5.00,5.00,5.00,5.00,5.00,5.00,5.00,5.00,5.00,5.00,5.00"
					( Origin gBackEnd )
				)
				( attribute "TESTPIN_TO_TESTVIA_SPACING" "5.00,5.00,5.00,5.00,5.00,5.00,5.00,5.00,5.00,5.00,5.00,5.00,5.00,5.00"
					( Origin gBackEnd )
				)
				( attribute "BBV_TO_TESTPIN_SPACING" "5.00,5.00,5.00,5.00,5.00,5.00,5.00,5.00,5.00,5.00,5.00,5.00,5.00,5.00"
					( Origin gBackEnd )
				)
				( attribute "BONDPAD_TO_TESTPIN_SPACING" "5.00,5.00,5.00,5.00,5.00,5.00,5.00,5.00,5.00,5.00,5.00,5.00,5.00,5.00"
					( Origin gBackEnd )
				)
				( attribute "LINE_TO_TESTPIN_SPACING" "5.00,4.00,4.00,4.00,4.00,4.00,4.00,4.00,4.00,4.00,4.00,4.00,4.00,5.00"
					( Origin gBackEnd )
				)
				( attribute "SHAPE_TO_TESTPIN_SPACING" "5.00,5.00,5.00,5.00,5.00,5.00,5.00,5.00,5.00,5.00,5.00,5.00,5.00,5.00"
					( Origin gBackEnd )
				)
				( attribute "THRUVIA_TO_THRUVIA_SPACING" "5.00,5.00,5.00,5.00,5.00,5.00,5.00,5.00,5.00,5.00,5.00,5.00,5.00,5.00"
					( Origin gBackEnd )
				)
				( attribute "TESTVIA_TO_THRUVIA_SPACING" "6.00,6.00,6.00,6.00,6.00,6.00,6.00,6.00,6.00,6.00,6.00,6.00,6.00,6.00"
					( Origin gBackEnd )
				)
				( attribute "BBV_TO_THRUVIA_SPACING" "5.00,5.00,5.00,5.00,5.00,5.00,5.00,5.00,5.00,5.00,5.00,5.00,5.00,5.00"
					( Origin gBackEnd )
				)
				( attribute "BONDPAD_TO_THRUVIA_SPACING" "5.00,5.00,5.00,5.00,5.00,5.00,5.00,5.00,5.00,5.00,5.00,5.00,5.00,5.00"
					( Origin gBackEnd )
				)
				( attribute "LINE_TO_THRUVIA_SPACING" "4.50,4.00,4.00,4.00,4.00,4.00,4.00,4.00,4.00,4.00,4.00,4.00,4.00,4.50"
					( Origin gBackEnd )
				)
				( attribute "SHAPE_TO_THRUVIA_SPACING" "4.50,4.00,4.00,4.00,4.00,4.00,5.00,5.00,4.00,4.00,4.00,4.00,4.00,4.50"
					( Origin gBackEnd )
				)
				( attribute "TESTVIA_TO_TESTVIA_SPACING" "6.00,6.00,6.00,6.00,6.00,6.00,6.00,6.00,6.00,6.00,6.00,6.00,6.00,6.00"
					( Origin gBackEnd )
				)
				( attribute "BBV_TO_TESTVIA_SPACING" "5.00,5.00,5.00,5.00,5.00,5.00,5.00,5.00,5.00,5.00,5.00,5.00,5.00,5.00"
					( Origin gBackEnd )
				)
				( attribute "BONDPAD_TO_TESTVIA_SPACING" "5.00,5.00,5.00,5.00,5.00,5.00,5.00,5.00,5.00,5.00,5.00,5.00,5.00,5.00"
					( Origin gBackEnd )
				)
				( attribute "LINE_TO_TESTVIA_SPACING" "4.50,4.00,4.00,4.00,4.00,4.00,4.00,4.00,4.00,4.00,4.00,4.00,4.00,4.50"
					( Origin gBackEnd )
				)
				( attribute "SHAPE_TO_TESTVIA_SPACING" "4.00,4.00,4.00,4.00,4.00,4.00,4.00,4.00,4.00,4.00,4.00,4.00,4.00,4.00"
					( Origin gBackEnd )
				)
				( attribute "BBV_TO_BBV_SPACING" "5.00,5.00,5.00,5.00,5.00,5.00,5.00,5.00,5.00,5.00,5.00,5.00,5.00,5.00"
					( Origin gBackEnd )
				)
				( attribute "BONDPAD_TO_BBV_SPACING" "5.00,5.00,5.00,5.00,5.00,5.00,5.00,5.00,5.00,5.00,5.00,5.00,5.00,5.00"
					( Origin gBackEnd )
				)
				( attribute "BBV_TO_LINE_SPACING" "5.00,5.00,5.00,5.00,5.00,5.00,5.00,5.00,5.00,5.00,5.00,5.00,5.00,5.00"
					( Origin gBackEnd )
				)
				( attribute "BBV_TO_SHAPE_SPACING" "5.00,5.00,5.00,5.00,5.00,5.00,5.00,5.00,5.00,5.00,5.00,5.00,5.00,5.00"
					( Origin gBackEnd )
				)
				( attribute "BONDPAD_TO_BONDPAD_SPACING" "5.00,5.00,5.00,5.00,5.00,5.00,5.00,5.00,5.00,5.00,5.00,5.00,5.00,5.00"
					( Origin gBackEnd )
				)
				( attribute "BONDPAD_TO_LINE_SPACING" "5.00,5.00,5.00,5.00,5.00,5.00,5.00,5.00,5.00,5.00,5.00,5.00,5.00,5.00"
					( Origin gBackEnd )
				)
				( attribute "BONDPAD_TO_SHAPE_SPACING" "5.00,5.00,5.00,5.00,5.00,5.00,5.00,5.00,5.00,5.00,5.00,5.00,5.00,5.00"
					( Origin gBackEnd )
				)
				( attribute "LINE_TO_LINE_SPACING" "10.00,10.00,10.00,10.00,10.00,10.00,10.00,10.00,10.00,10.00,10.00,10.00,10.00,10.00"
					( Origin gBackEnd )
				)
				( attribute "LINE_TO_SHAPE_SPACING" "10.00,10.00,10.00,10.00,10.00,10.00,10.00,10.00,10.00,10.00,10.00,10.00,10.00,10.00"
					( Origin gBackEnd )
				)
				( attribute "SHAPE_TO_SHAPE_SPACING" "10.00,10.00,10.00,10.00,10.00,10.00,10.00,10.00,10.00,10.00,10.00,10.00,10.00,10.00"
					( Origin gBackEnd )
				)
				( attribute "HOLE_TO_PIN_SPACING" "8.00,8.00,8.00,8.00,8.00,8.00,8.00,8.00,8.00,8.00,8.00,8.00,8.00,8.00"
					( Origin gBackEnd )
				)
				( attribute "HOLE_TO_VIA_SPACING" "8.00,8.00,8.00,8.00,8.00,8.00,8.00,8.00,8.00,8.00,8.00,8.00,8.00,8.00"
					( Origin gBackEnd )
				)
				( attribute "HOLE_TO_LINE_SPACING" "8.00,8.00,8.00,8.00,8.00,8.00,8.00,8.00,8.00,8.00,8.00,8.00,8.00,8.00"
					( Origin gBackEnd )
				)
				( attribute "HOLE_TO_SHAPE_SPACING" "8.00,8.00,8.00,8.00,8.00,8.00,8.00,8.00,8.00,8.00,8.00,8.00,8.00,8.00"
					( Origin gBackEnd )
				)
				( attribute "HOLE_TO_HOLE_SPACING" "8.00,8.00,8.00,8.00,8.00,8.00,8.00,8.00,8.00,8.00,8.00,8.00,8.00,8.00"
					( Origin gBackEnd )
				)
				( attribute "MVIA_TO_MVIA_SPACING" "5.00,5.00,5.00,5.00,5.00,5.00,5.00,5.00,5.00,5.00,5.00,5.00,5.00,5.00"
					( Origin gBackEnd )
				)
				( attribute "MVIA_TO_THRUPIN_SPACING" "5.00,5.00,5.00,5.00,5.00,5.00,5.00,5.00,5.00,5.00,5.00,5.00,5.00,5.00"
					( Origin gBackEnd )
				)
				( attribute "MVIA_TO_SMDPIN_SPACING" "5.00,5.00,5.00,5.00,5.00,5.00,5.00,5.00,5.00,5.00,5.00,5.00,5.00,5.00"
					( Origin gBackEnd )
				)
				( attribute "MVIA_TO_THRUVIA_SPACING" "5.00,5.00,5.00,5.00,5.00,5.00,5.00,5.00,5.00,5.00,5.00,5.00,5.00,5.00"
					( Origin gBackEnd )
				)
				( attribute "MVIA_TO_BBV_SPACING" "5.00,5.00,5.00,5.00,5.00,5.00,5.00,5.00,5.00,5.00,5.00,5.00,5.00,5.00"
					( Origin gBackEnd )
				)
				( attribute "MVIA_TO_LINE_SPACING" "5.00,5.00,5.00,5.00,5.00,5.00,5.00,5.00,5.00,5.00,5.00,5.00,5.00,5.00"
					( Origin gBackEnd )
				)
				( attribute "MVIA_TO_SHAPE_SPACING" "5.00,5.00,5.00,5.00,5.00,5.00,5.00,5.00,5.00,5.00,5.00,5.00,5.00,5.00"
					( Origin gBackEnd )
				)
				( attribute "MVIA_TO_TESTPIN_SPACING" "5.00,5.00,5.00,5.00,5.00,5.00,5.00,5.00,5.00,5.00,5.00,5.00,5.00,5.00"
					( Origin gBackEnd )
				)
				( attribute "MVIA_TO_TESTVIA_SPACING" "5.00,5.00,5.00,5.00,5.00,5.00,5.00,5.00,5.00,5.00,5.00,5.00,5.00,5.00"
					( Origin gBackEnd )
				)
				( attribute "BONDPAD_TO_MVIA_SPACING" "5.00,5.00,5.00,5.00,5.00,5.00,5.00,5.00,5.00,5.00,5.00,5.00,5.00,5.00"
					( Origin gBackEnd )
				)
				( attribute "MIN_BVIA_GAP" "5.00"
					( Origin gBackEnd )
				)
				( attribute "BONDPAD_TO_BONDPAD_DIFFP_SPC" "5.00,5.00,5.00,5.00,5.00,5.00,5.00,5.00,5.00,5.00,5.00,5.00,5.00,5.00"
					( Origin gBackEnd )
				)
				( objectStatus "10_MIL" )
			)
			( spacingCSet "@sapphirecity_baseboard_lib.sapphirecity_baseboard(sch_1):\20MIL\"
				( attribute "THRUPIN_TO_THRUPIN_SPACING" "5.00,5.00,5.00,5.00,5.00,5.00,5.00,5.00,5.00,5.00,5.00,5.00,5.00,5.00"
					( Origin gBackEnd )
				)
				( attribute "THRUPIN_TO_SMDPIN_SPACING" "5.00,5.00,5.00,5.00,5.00,5.00,5.00,5.00,5.00,5.00,5.00,5.00,5.00,5.00"
					( Origin gBackEnd )
				)
				( attribute "TESTPIN_TO_THRUPIN_SPACING" "5.00,5.00,5.00,5.00,5.00,5.00,5.00,5.00,5.00,5.00,5.00,5.00,5.00,5.00"
					( Origin gBackEnd )
				)
				( attribute "THRUPIN_TO_THRUVIA_SPACING" "5.00,5.00,5.00,5.00,5.00,5.00,5.00,5.00,5.00,5.00,5.00,5.00,5.00,5.00"
					( Origin gBackEnd )
				)
				( attribute "TESTVIA_TO_THRUPIN_SPACING" "5.00,5.00,5.00,5.00,5.00,5.00,5.00,5.00,5.00,5.00,5.00,5.00,5.00,5.00"
					( Origin gBackEnd )
				)
				( attribute "BBV_TO_THRUPIN_SPACING" "5.00,5.00,5.00,5.00,5.00,5.00,5.00,5.00,5.00,5.00,5.00,5.00,5.00,5.00"
					( Origin gBackEnd )
				)
				( attribute "THRUPIN_TO_BONDPAD_SPACING" "5.00,5.00,5.00,5.00,5.00,5.00,5.00,5.00,5.00,5.00,5.00,5.00,5.00,5.00"
					( Origin gBackEnd )
				)
				( attribute "LINE_TO_THRUPIN_SPACING" "5.00,4.00,4.00,4.00,4.00,4.00,4.00,4.00,4.00,4.00,4.00,4.00,4.00,5.00"
					( Origin gBackEnd )
				)
				( attribute "THRUPIN_TO_SHAPE_SPACING" "5.00,5.00,5.00,5.00,5.00,5.00,5.00,5.00,5.00,5.00,5.00,5.00,5.00,5.00"
					( Origin gBackEnd )
				)
				( attribute "SMDPIN_TO_SMDPIN_SPACING" "5.00,5.00,5.00,5.00,5.00,5.00,5.00,5.00,5.00,5.00,5.00,5.00,5.00,5.00"
					( Origin gBackEnd )
				)
				( attribute "SMDPIN_TO_TESTPIN_SPACING" "5.00,5.00,5.00,5.00,5.00,5.00,5.00,5.00,5.00,5.00,5.00,5.00,5.00,25.00"
					( Origin gBackEnd )
				)
				( attribute "SMDPIN_TO_THRUVIA_SPACING" "5.00,5.00,5.00,5.00,5.00,5.00,5.00,5.00,5.00,5.00,5.00,5.00,5.00,5.00"
					( Origin gBackEnd )
				)
				( attribute "SMDPIN_TO_TESTVIA_SPACING" "5.00,5.00,5.00,5.00,5.00,5.00,5.00,5.00,5.00,5.00,5.00,5.00,5.00,5.00"
					( Origin gBackEnd )
				)
				( attribute "BBV_TO_SMDPIN_SPACING" "5.00,5.00,5.00,5.00,5.00,5.00,5.00,5.00,5.00,5.00,5.00,5.00,5.00,5.00"
					( Origin gBackEnd )
				)
				( attribute "SMDPIN_TO_BONDPAD_SPACING" "5.00,5.00,5.00,5.00,5.00,5.00,5.00,5.00,5.00,5.00,5.00,5.00,5.00,5.00"
					( Origin gBackEnd )
				)
				( attribute "LINE_TO_SMDPIN_SPACING" "4.50,4.50,4.50,4.50,4.50,4.50,4.50,4.50,4.50,4.50,4.50,4.50,4.50,4.50"
					( Origin gBackEnd )
				)
				( attribute "SHAPE_TO_SMDPIN_SPACING" "5.00,5.00,5.00,5.00,5.00,5.00,5.00,5.00,5.00,5.00,5.00,5.00,5.00,5.00"
					( Origin gBackEnd )
				)
				( attribute "TESTPIN_TO_TESTPIN_SPACING" "5.00,5.00,5.00,5.00,5.00,5.00,5.00,5.00,5.00,5.00,5.00,5.00,5.00,5.00"
					( Origin gBackEnd )
				)
				( attribute "TESTPIN_TO_THRUVIA_SPACING" "5.00,5.00,5.00,5.00,5.00,5.00,5.00,5.00,5.00,5.00,5.00,5.00,5.00,5.00"
					( Origin gBackEnd )
				)
				( attribute "TESTPIN_TO_TESTVIA_SPACING" "5.00,5.00,5.00,5.00,5.00,5.00,5.00,5.00,5.00,5.00,5.00,5.00,5.00,5.00"
					( Origin gBackEnd )
				)
				( attribute "BBV_TO_TESTPIN_SPACING" "5.00,5.00,5.00,5.00,5.00,5.00,5.00,5.00,5.00,5.00,5.00,5.00,5.00,5.00"
					( Origin gBackEnd )
				)
				( attribute "BONDPAD_TO_TESTPIN_SPACING" "5.00,5.00,5.00,5.00,5.00,5.00,5.00,5.00,5.00,5.00,5.00,5.00,5.00,5.00"
					( Origin gBackEnd )
				)
				( attribute "LINE_TO_TESTPIN_SPACING" "5.00,4.00,4.00,4.00,4.00,4.00,4.00,4.00,4.00,4.00,4.00,4.00,4.00,5.00"
					( Origin gBackEnd )
				)
				( attribute "SHAPE_TO_TESTPIN_SPACING" "5.00,5.00,5.00,5.00,5.00,5.00,5.00,5.00,5.00,5.00,5.00,5.00,5.00,5.00"
					( Origin gBackEnd )
				)
				( attribute "THRUVIA_TO_THRUVIA_SPACING" "6.00,6.00,6.00,6.00,6.00,6.00,6.00,6.00,6.00,6.00,6.00,6.00,6.00,6.00"
					( Origin gBackEnd )
				)
				( attribute "TESTVIA_TO_THRUVIA_SPACING" "6.00,6.00,6.00,6.00,6.00,6.00,6.00,6.00,6.00,6.00,6.00,6.00,6.00,6.00"
					( Origin gBackEnd )
				)
				( attribute "BBV_TO_THRUVIA_SPACING" "5.00,5.00,5.00,5.00,5.00,5.00,5.00,5.00,5.00,5.00,5.00,5.00,5.00,5.00"
					( Origin gBackEnd )
				)
				( attribute "BONDPAD_TO_THRUVIA_SPACING" "5.00,5.00,5.00,5.00,5.00,5.00,5.00,5.00,5.00,5.00,5.00,5.00,5.00,5.00"
					( Origin gBackEnd )
				)
				( attribute "LINE_TO_THRUVIA_SPACING" "4.50,4.00,4.00,4.00,4.00,4.00,4.00,4.00,4.00,4.00,4.00,4.00,4.00,4.50"
					( Origin gBackEnd )
				)
				( attribute "SHAPE_TO_THRUVIA_SPACING" "5.00,5.00,5.00,5.00,5.00,5.00,5.00,5.00,5.00,5.00,5.00,5.00,5.00,5.00"
					( Origin gBackEnd )
				)
				( attribute "TESTVIA_TO_TESTVIA_SPACING" "6.00,6.00,6.00,6.00,6.00,6.00,6.00,6.00,6.00,6.00,6.00,6.00,6.00,6.00"
					( Origin gBackEnd )
				)
				( attribute "BBV_TO_TESTVIA_SPACING" "5.00,5.00,5.00,5.00,5.00,5.00,5.00,5.00,5.00,5.00,5.00,5.00,5.00,5.00"
					( Origin gBackEnd )
				)
				( attribute "BONDPAD_TO_TESTVIA_SPACING" "5.00,5.00,5.00,5.00,5.00,5.00,5.00,5.00,5.00,5.00,5.00,5.00,5.00,5.00"
					( Origin gBackEnd )
				)
				( attribute "LINE_TO_TESTVIA_SPACING" "4.50,4.00,4.00,4.00,4.00,4.00,4.00,4.00,4.00,4.00,4.00,4.00,4.00,4.50"
					( Origin gBackEnd )
				)
				( attribute "SHAPE_TO_TESTVIA_SPACING" "5.00,5.00,5.00,5.00,5.00,5.00,5.00,5.00,5.00,5.00,5.00,5.00,5.00,5.00"
					( Origin gBackEnd )
				)
				( attribute "BBV_TO_BBV_SPACING" "5.00,5.00,5.00,5.00,5.00,5.00,5.00,5.00,5.00,5.00,5.00,5.00,5.00,5.00"
					( Origin gBackEnd )
				)
				( attribute "BONDPAD_TO_BBV_SPACING" "5.00,5.00,5.00,5.00,5.00,5.00,5.00,5.00,5.00,5.00,5.00,5.00,5.00,5.00"
					( Origin gBackEnd )
				)
				( attribute "BBV_TO_LINE_SPACING" "5.00,5.00,5.00,5.00,5.00,5.00,5.00,5.00,5.00,5.00,5.00,5.00,5.00,5.00"
					( Origin gBackEnd )
				)
				( attribute "BBV_TO_SHAPE_SPACING" "5.00,5.00,5.00,5.00,5.00,5.00,5.00,5.00,5.00,5.00,5.00,5.00,5.00,5.00"
					( Origin gBackEnd )
				)
				( attribute "BONDPAD_TO_BONDPAD_SPACING" "5.00,5.00,5.00,5.00,5.00,5.00,5.00,5.00,5.00,5.00,5.00,5.00,5.00,5.00"
					( Origin gBackEnd )
				)
				( attribute "BONDPAD_TO_LINE_SPACING" "5.00,5.00,5.00,5.00,5.00,5.00,5.00,5.00,5.00,5.00,5.00,5.00,5.00,5.00"
					( Origin gBackEnd )
				)
				( attribute "BONDPAD_TO_SHAPE_SPACING" "5.00,5.00,5.00,5.00,5.00,5.00,5.00,5.00,5.00,5.00,5.00,5.00,5.00,5.00"
					( Origin gBackEnd )
				)
				( attribute "LINE_TO_LINE_SPACING" "20.00,20.00,20.00,20.00,20.00,20.00,20.00,20.00,20.00,20.00,20.00,20.00,20.00,20.00"
					( Origin gBackEnd )
				)
				( attribute "LINE_TO_SHAPE_SPACING" "10.00,10.00,10.00,10.00,10.00,10.00,10.00,10.00,10.00,10.00,10.00,10.00,10.00,10.00"
					( Origin gBackEnd )
				)
				( attribute "SHAPE_TO_SHAPE_SPACING" "10.00,10.00,10.00,10.00,10.00,10.00,10.00,10.00,10.00,10.00,10.00,10.00,10.00,10.00"
					( Origin gBackEnd )
				)
				( attribute "HOLE_TO_PIN_SPACING" "8.00,8.00,8.00,8.00,8.00,8.00,8.00,8.00,8.00,8.00,8.00,8.00,8.00,8.00"
					( Origin gBackEnd )
				)
				( attribute "HOLE_TO_VIA_SPACING" "8.00,8.00,8.00,8.00,8.00,8.00,8.00,8.00,8.00,8.00,8.00,8.00,8.00,8.00"
					( Origin gBackEnd )
				)
				( attribute "HOLE_TO_LINE_SPACING" "8.00,8.00,8.00,8.00,8.00,8.00,8.00,8.00,8.00,8.00,8.00,8.00,8.00,8.00"
					( Origin gBackEnd )
				)
				( attribute "HOLE_TO_SHAPE_SPACING" "8.00,8.00,8.00,8.00,8.00,8.00,8.00,8.00,8.00,8.00,8.00,8.00,8.00,8.00"
					( Origin gBackEnd )
				)
				( attribute "HOLE_TO_HOLE_SPACING" "8.00,8.00,8.00,8.00,8.00,8.00,8.00,8.00,8.00,8.00,8.00,8.00,8.00,8.00"
					( Origin gBackEnd )
				)
				( attribute "MVIA_TO_MVIA_SPACING" "5.00,5.00,5.00,5.00,5.00,5.00,5.00,5.00,5.00,5.00,5.00,5.00,5.00,5.00"
					( Origin gBackEnd )
				)
				( attribute "MVIA_TO_THRUPIN_SPACING" "5.00,5.00,5.00,5.00,5.00,5.00,5.00,5.00,5.00,5.00,5.00,5.00,5.00,5.00"
					( Origin gBackEnd )
				)
				( attribute "MVIA_TO_SMDPIN_SPACING" "5.00,5.00,5.00,5.00,5.00,5.00,5.00,5.00,5.00,5.00,5.00,5.00,5.00,5.00"
					( Origin gBackEnd )
				)
				( attribute "MVIA_TO_THRUVIA_SPACING" "5.00,5.00,5.00,5.00,5.00,5.00,5.00,5.00,5.00,5.00,5.00,5.00,5.00,5.00"
					( Origin gBackEnd )
				)
				( attribute "MVIA_TO_BBV_SPACING" "5.00,5.00,5.00,5.00,5.00,5.00,5.00,5.00,5.00,5.00,5.00,5.00,5.00,5.00"
					( Origin gBackEnd )
				)
				( attribute "MVIA_TO_LINE_SPACING" "5.00,5.00,5.00,5.00,5.00,5.00,5.00,5.00,5.00,5.00,5.00,5.00,5.00,5.00"
					( Origin gBackEnd )
				)
				( attribute "MVIA_TO_SHAPE_SPACING" "5.00,5.00,5.00,5.00,5.00,5.00,5.00,5.00,5.00,5.00,5.00,5.00,5.00,5.00"
					( Origin gBackEnd )
				)
				( attribute "MVIA_TO_TESTPIN_SPACING" "5.00,5.00,5.00,5.00,5.00,5.00,5.00,5.00,5.00,5.00,5.00,5.00,5.00,5.00"
					( Origin gBackEnd )
				)
				( attribute "MVIA_TO_TESTVIA_SPACING" "5.00,5.00,5.00,5.00,5.00,5.00,5.00,5.00,5.00,5.00,5.00,5.00,5.00,5.00"
					( Origin gBackEnd )
				)
				( attribute "BONDPAD_TO_MVIA_SPACING" "5.00,5.00,5.00,5.00,5.00,5.00,5.00,5.00,5.00,5.00,5.00,5.00,5.00,5.00"
					( Origin gBackEnd )
				)
				( attribute "MIN_BVIA_GAP" "5.00"
					( Origin gBackEnd )
				)
				( attribute "BONDPAD_TO_BONDPAD_DIFFP_SPC" "5.00,5.00,5.00,5.00,5.00,5.00,5.00,5.00,5.00,5.00,5.00,5.00,5.00,5.00"
					( Origin gBackEnd )
				)
				( objectStatus "20MIL" )
			)
			( spacingCSet "@sapphirecity_baseboard_lib.sapphirecity_baseboard(sch_1):\16MIL\"
				( attribute "THRUPIN_TO_THRUPIN_SPACING" "5.00,5.00,5.00,5.00,5.00,5.00,5.00,5.00,5.00,5.00,5.00,5.00,5.00,5.00"
					( Origin gBackEnd )
				)
				( attribute "THRUPIN_TO_SMDPIN_SPACING" "5.00,5.00,5.00,5.00,5.00,5.00,5.00,5.00,5.00,5.00,5.00,5.00,5.00,5.00"
					( Origin gBackEnd )
				)
				( attribute "TESTPIN_TO_THRUPIN_SPACING" "5.00,5.00,5.00,5.00,5.00,5.00,5.00,5.00,5.00,5.00,5.00,5.00,5.00,5.00"
					( Origin gBackEnd )
				)
				( attribute "THRUPIN_TO_THRUVIA_SPACING" "5.00,5.00,5.00,5.00,5.00,5.00,5.00,5.00,5.00,5.00,5.00,5.00,5.00,5.00"
					( Origin gBackEnd )
				)
				( attribute "TESTVIA_TO_THRUPIN_SPACING" "5.00,5.00,5.00,5.00,5.00,5.00,5.00,5.00,5.00,5.00,5.00,5.00,5.00,5.00"
					( Origin gBackEnd )
				)
				( attribute "BBV_TO_THRUPIN_SPACING" "5.00,5.00,5.00,5.00,5.00,5.00,5.00,5.00,5.00,5.00,5.00,5.00,5.00,5.00"
					( Origin gBackEnd )
				)
				( attribute "THRUPIN_TO_BONDPAD_SPACING" "5.00,5.00,5.00,5.00,5.00,5.00,5.00,5.00,5.00,5.00,5.00,5.00,5.00,5.00"
					( Origin gBackEnd )
				)
				( attribute "LINE_TO_THRUPIN_SPACING" "4.50,4.00,4.00,4.00,4.00,4.00,4.00,4.00,4.00,4.00,4.00,4.00,4.00,4.50"
					( Origin gBackEnd )
				)
				( attribute "THRUPIN_TO_SHAPE_SPACING" "5.00,5.00,5.00,5.00,5.00,5.00,5.00,5.00,5.00,5.00,5.00,5.00,5.00,5.00"
					( Origin gBackEnd )
				)
				( attribute "SMDPIN_TO_SMDPIN_SPACING" "5.00,5.00,5.00,5.00,5.00,5.00,5.00,5.00,5.00,5.00,5.00,5.00,5.00,5.00"
					( Origin gBackEnd )
				)
				( attribute "SMDPIN_TO_TESTPIN_SPACING" "5.00,5.00,5.00,5.00,5.00,5.00,5.00,5.00,5.00,5.00,5.00,5.00,5.00,25.00"
					( Origin gBackEnd )
				)
				( attribute "SMDPIN_TO_THRUVIA_SPACING" "5.00,5.00,5.00,5.00,5.00,5.00,5.00,5.00,5.00,5.00,5.00,5.00,5.00,5.00"
					( Origin gBackEnd )
				)
				( attribute "SMDPIN_TO_TESTVIA_SPACING" "5.00,5.00,5.00,5.00,5.00,5.00,5.00,5.00,5.00,5.00,5.00,5.00,5.00,5.00"
					( Origin gBackEnd )
				)
				( attribute "BBV_TO_SMDPIN_SPACING" "5.00,5.00,5.00,5.00,5.00,5.00,5.00,5.00,5.00,5.00,5.00,5.00,5.00,5.00"
					( Origin gBackEnd )
				)
				( attribute "SMDPIN_TO_BONDPAD_SPACING" "5.00,5.00,5.00,5.00,5.00,5.00,5.00,5.00,5.00,5.00,5.00,5.00,5.00,5.00"
					( Origin gBackEnd )
				)
				( attribute "LINE_TO_SMDPIN_SPACING" "4.50,4.50,4.50,4.50,4.50,4.50,4.50,4.50,4.50,4.50,4.50,4.50,4.50,4.50"
					( Origin gBackEnd )
				)
				( attribute "SHAPE_TO_SMDPIN_SPACING" "5.00,5.00,5.00,5.00,5.00,5.00,5.00,5.00,5.00,5.00,5.00,5.00,5.00,5.00"
					( Origin gBackEnd )
				)
				( attribute "TESTPIN_TO_TESTPIN_SPACING" "5.00,5.00,5.00,5.00,5.00,5.00,5.00,5.00,5.00,5.00,5.00,5.00,5.00,5.00"
					( Origin gBackEnd )
				)
				( attribute "TESTPIN_TO_THRUVIA_SPACING" "5.00,5.00,5.00,5.00,5.00,5.00,5.00,5.00,5.00,5.00,5.00,5.00,5.00,5.00"
					( Origin gBackEnd )
				)
				( attribute "TESTPIN_TO_TESTVIA_SPACING" "5.00,5.00,5.00,5.00,5.00,5.00,5.00,5.00,5.00,5.00,5.00,5.00,5.00,5.00"
					( Origin gBackEnd )
				)
				( attribute "BBV_TO_TESTPIN_SPACING" "5.00,5.00,5.00,5.00,5.00,5.00,5.00,5.00,5.00,5.00,5.00,5.00,5.00,5.00"
					( Origin gBackEnd )
				)
				( attribute "BONDPAD_TO_TESTPIN_SPACING" "5.00,5.00,5.00,5.00,5.00,5.00,5.00,5.00,5.00,5.00,5.00,5.00,5.00,5.00"
					( Origin gBackEnd )
				)
				( attribute "LINE_TO_TESTPIN_SPACING" "5.00,4.00,4.00,4.00,4.00,4.00,4.00,4.00,4.00,4.00,4.00,4.00,4.00,5.00"
					( Origin gBackEnd )
				)
				( attribute "SHAPE_TO_TESTPIN_SPACING" "5.00,5.00,5.00,5.00,5.00,5.00,5.00,5.00,5.00,5.00,5.00,5.00,5.00,5.00"
					( Origin gBackEnd )
				)
				( attribute "THRUVIA_TO_THRUVIA_SPACING" "5.00,5.00,5.00,5.00,5.00,5.00,5.00,5.00,5.00,5.00,5.00,5.00,5.00,5.00"
					( Origin gBackEnd )
				)
				( attribute "TESTVIA_TO_THRUVIA_SPACING" "6.00,6.00,6.00,6.00,6.00,6.00,6.00,6.00,6.00,6.00,6.00,6.00,6.00,6.00"
					( Origin gBackEnd )
				)
				( attribute "BBV_TO_THRUVIA_SPACING" "5.00,5.00,5.00,5.00,5.00,5.00,5.00,5.00,5.00,5.00,5.00,5.00,5.00,5.00"
					( Origin gBackEnd )
				)
				( attribute "BONDPAD_TO_THRUVIA_SPACING" "5.00,5.00,5.00,5.00,5.00,5.00,5.00,5.00,5.00,5.00,5.00,5.00,5.00,5.00"
					( Origin gBackEnd )
				)
				( attribute "LINE_TO_THRUVIA_SPACING" "4.50,4.00,4.00,4.00,4.00,4.00,4.00,4.00,4.00,4.00,4.00,4.00,4.00,4.50"
					( Origin gBackEnd )
				)
				( attribute "SHAPE_TO_THRUVIA_SPACING" "5.00,5.00,5.00,5.00,5.00,5.00,5.00,5.00,5.00,5.00,5.00,5.00,5.00,5.00"
					( Origin gBackEnd )
				)
				( attribute "TESTVIA_TO_TESTVIA_SPACING" "6.00,6.00,6.00,6.00,6.00,6.00,6.00,6.00,6.00,6.00,6.00,6.00,6.00,6.00"
					( Origin gBackEnd )
				)
				( attribute "BBV_TO_TESTVIA_SPACING" "5.00,5.00,5.00,5.00,5.00,5.00,5.00,5.00,5.00,5.00,5.00,5.00,5.00,5.00"
					( Origin gBackEnd )
				)
				( attribute "BONDPAD_TO_TESTVIA_SPACING" "5.00,5.00,5.00,5.00,5.00,5.00,5.00,5.00,5.00,5.00,5.00,5.00,5.00,5.00"
					( Origin gBackEnd )
				)
				( attribute "LINE_TO_TESTVIA_SPACING" "4.50,4.00,4.00,4.00,4.00,4.00,4.00,4.00,4.00,4.00,4.00,4.00,4.00,4.50"
					( Origin gBackEnd )
				)
				( attribute "SHAPE_TO_TESTVIA_SPACING" "5.00,5.00,5.00,5.00,5.00,5.00,5.00,5.00,5.00,5.00,5.00,5.00,5.00,5.00"
					( Origin gBackEnd )
				)
				( attribute "BBV_TO_BBV_SPACING" "5.00,5.00,5.00,5.00,5.00,5.00,5.00,5.00,5.00,5.00,5.00,5.00,5.00,5.00"
					( Origin gBackEnd )
				)
				( attribute "BONDPAD_TO_BBV_SPACING" "5.00,5.00,5.00,5.00,5.00,5.00,5.00,5.00,5.00,5.00,5.00,5.00,5.00,5.00"
					( Origin gBackEnd )
				)
				( attribute "BBV_TO_LINE_SPACING" "5.00,5.00,5.00,5.00,5.00,5.00,5.00,5.00,5.00,5.00,5.00,5.00,5.00,5.00"
					( Origin gBackEnd )
				)
				( attribute "BBV_TO_SHAPE_SPACING" "5.00,5.00,5.00,5.00,5.00,5.00,5.00,5.00,5.00,5.00,5.00,5.00,5.00,5.00"
					( Origin gBackEnd )
				)
				( attribute "BONDPAD_TO_BONDPAD_SPACING" "5.00,5.00,5.00,5.00,5.00,5.00,5.00,5.00,5.00,5.00,5.00,5.00,5.00,5.00"
					( Origin gBackEnd )
				)
				( attribute "BONDPAD_TO_LINE_SPACING" "5.00,5.00,5.00,5.00,5.00,5.00,5.00,5.00,5.00,5.00,5.00,5.00,5.00,5.00"
					( Origin gBackEnd )
				)
				( attribute "BONDPAD_TO_SHAPE_SPACING" "5.00,5.00,5.00,5.00,5.00,5.00,5.00,5.00,5.00,5.00,5.00,5.00,5.00,5.00"
					( Origin gBackEnd )
				)
				( attribute "LINE_TO_LINE_SPACING" "16.00,16.00,16.00,16.00,16.00,16.00,16.00,16.00,16.00,16.00,16.00,16.00,16.00,16.00"
					( Origin gBackEnd )
				)
				( attribute "LINE_TO_SHAPE_SPACING" "10.00,10.00,10.00,10.00,10.00,10.00,10.00,10.00,10.00,10.00,10.00,10.00,10.00,10.00"
					( Origin gBackEnd )
				)
				( attribute "SHAPE_TO_SHAPE_SPACING" "10.00,10.00,10.00,10.00,10.00,10.00,10.00,10.00,10.00,10.00,10.00,10.00,10.00,10.00"
					( Origin gBackEnd )
				)
				( attribute "HOLE_TO_PIN_SPACING" "8.00,8.00,8.00,8.00,8.00,8.00,8.00,8.00,8.00,8.00,8.00,8.00,8.00,8.00"
					( Origin gBackEnd )
				)
				( attribute "HOLE_TO_VIA_SPACING" "8.00,8.00,8.00,8.00,8.00,8.00,8.00,8.00,8.00,8.00,8.00,8.00,8.00,8.00"
					( Origin gBackEnd )
				)
				( attribute "HOLE_TO_LINE_SPACING" "8.00,8.00,8.00,8.00,8.00,8.00,8.00,8.00,8.00,8.00,8.00,8.00,8.00,8.00"
					( Origin gBackEnd )
				)
				( attribute "HOLE_TO_SHAPE_SPACING" "8.00,8.00,8.00,8.00,8.00,8.00,8.00,8.00,8.00,8.00,8.00,8.00,8.00,8.00"
					( Origin gBackEnd )
				)
				( attribute "HOLE_TO_HOLE_SPACING" "8.00,8.00,8.00,8.00,8.00,8.00,8.00,8.00,8.00,8.00,8.00,8.00,8.00,8.00"
					( Origin gBackEnd )
				)
				( attribute "MVIA_TO_MVIA_SPACING" "5.00,5.00,5.00,5.00,5.00,5.00,5.00,5.00,5.00,5.00,5.00,5.00,5.00,5.00"
					( Origin gBackEnd )
				)
				( attribute "MVIA_TO_THRUPIN_SPACING" "5.00,5.00,5.00,5.00,5.00,5.00,5.00,5.00,5.00,5.00,5.00,5.00,5.00,5.00"
					( Origin gBackEnd )
				)
				( attribute "MVIA_TO_SMDPIN_SPACING" "5.00,5.00,5.00,5.00,5.00,5.00,5.00,5.00,5.00,5.00,5.00,5.00,5.00,5.00"
					( Origin gBackEnd )
				)
				( attribute "MVIA_TO_THRUVIA_SPACING" "5.00,5.00,5.00,5.00,5.00,5.00,5.00,5.00,5.00,5.00,5.00,5.00,5.00,5.00"
					( Origin gBackEnd )
				)
				( attribute "MVIA_TO_BBV_SPACING" "5.00,5.00,5.00,5.00,5.00,5.00,5.00,5.00,5.00,5.00,5.00,5.00,5.00,5.00"
					( Origin gBackEnd )
				)
				( attribute "MVIA_TO_LINE_SPACING" "5.00,5.00,5.00,5.00,5.00,5.00,5.00,5.00,5.00,5.00,5.00,5.00,5.00,5.00"
					( Origin gBackEnd )
				)
				( attribute "MVIA_TO_SHAPE_SPACING" "5.00,5.00,5.00,5.00,5.00,5.00,5.00,5.00,5.00,5.00,5.00,5.00,5.00,5.00"
					( Origin gBackEnd )
				)
				( attribute "MVIA_TO_TESTPIN_SPACING" "5.00,5.00,5.00,5.00,5.00,5.00,5.00,5.00,5.00,5.00,5.00,5.00,5.00,5.00"
					( Origin gBackEnd )
				)
				( attribute "MVIA_TO_TESTVIA_SPACING" "5.00,5.00,5.00,5.00,5.00,5.00,5.00,5.00,5.00,5.00,5.00,5.00,5.00,5.00"
					( Origin gBackEnd )
				)
				( attribute "BONDPAD_TO_MVIA_SPACING" "5.00,5.00,5.00,5.00,5.00,5.00,5.00,5.00,5.00,5.00,5.00,5.00,5.00,5.00"
					( Origin gBackEnd )
				)
				( attribute "MIN_BVIA_GAP" "5.00"
					( Origin gBackEnd )
				)
				( attribute "BONDPAD_TO_BONDPAD_DIFFP_SPC" "5.00,5.00,5.00,5.00,5.00,5.00,5.00,5.00,5.00,5.00,5.00,5.00,5.00,5.00"
					( Origin gBackEnd )
				)
				( objectStatus "16MIL" )
			)
			( spacingCSet "@sapphirecity_baseboard_lib.sapphirecity_baseboard(sch_1):\30MIL\"
				( attribute "THRUPIN_TO_THRUPIN_SPACING" "5.00,5.00,5.00,5.00,5.00,5.00,5.00,5.00,5.00,5.00,5.00,5.00,5.00,5.00"
					( Origin gBackEnd )
				)
				( attribute "THRUPIN_TO_SMDPIN_SPACING" "5.00,5.00,5.00,5.00,5.00,5.00,5.00,5.00,5.00,5.00,5.00,5.00,5.00,5.00"
					( Origin gBackEnd )
				)
				( attribute "TESTPIN_TO_THRUPIN_SPACING" "5.00,5.00,5.00,5.00,5.00,5.00,5.00,5.00,5.00,5.00,5.00,5.00,5.00,5.00"
					( Origin gBackEnd )
				)
				( attribute "THRUPIN_TO_THRUVIA_SPACING" "5.00,5.00,5.00,5.00,5.00,5.00,5.00,5.00,5.00,5.00,5.00,5.00,5.00,5.00"
					( Origin gBackEnd )
				)
				( attribute "TESTVIA_TO_THRUPIN_SPACING" "5.00,5.00,5.00,5.00,5.00,5.00,5.00,5.00,5.00,5.00,5.00,5.00,5.00,5.00"
					( Origin gBackEnd )
				)
				( attribute "BBV_TO_THRUPIN_SPACING" "5.00,5.00,5.00,5.00,5.00,5.00,5.00,5.00,5.00,5.00,5.00,5.00,5.00,5.00"
					( Origin gBackEnd )
				)
				( attribute "THRUPIN_TO_BONDPAD_SPACING" "5.00,5.00,5.00,5.00,5.00,5.00,5.00,5.00,5.00,5.00,5.00,5.00,5.00,5.00"
					( Origin gBackEnd )
				)
				( attribute "LINE_TO_THRUPIN_SPACING" "4.50,4.00,4.00,4.00,4.00,4.00,4.00,4.00,4.00,4.00,4.00,4.00,4.00,4.50"
					( Origin gBackEnd )
				)
				( attribute "THRUPIN_TO_SHAPE_SPACING" "5.00,5.00,5.00,5.00,5.00,5.00,5.00,5.00,5.00,5.00,5.00,5.00,5.00,5.00"
					( Origin gBackEnd )
				)
				( attribute "SMDPIN_TO_SMDPIN_SPACING" "5.00,5.00,5.00,5.00,5.00,5.00,5.00,5.00,5.00,5.00,5.00,5.00,5.00,5.00"
					( Origin gBackEnd )
				)
				( attribute "SMDPIN_TO_TESTPIN_SPACING" "5.00,5.00,5.00,5.00,5.00,5.00,5.00,5.00,5.00,5.00,5.00,5.00,5.00,25.00"
					( Origin gBackEnd )
				)
				( attribute "SMDPIN_TO_THRUVIA_SPACING" "5.00,5.00,5.00,5.00,5.00,5.00,5.00,5.00,5.00,5.00,5.00,5.00,5.00,5.00"
					( Origin gBackEnd )
				)
				( attribute "SMDPIN_TO_TESTVIA_SPACING" "5.00,5.00,5.00,5.00,5.00,5.00,5.00,5.00,5.00,5.00,5.00,5.00,5.00,5.00"
					( Origin gBackEnd )
				)
				( attribute "BBV_TO_SMDPIN_SPACING" "5.00,5.00,5.00,5.00,5.00,5.00,5.00,5.00,5.00,5.00,5.00,5.00,5.00,5.00"
					( Origin gBackEnd )
				)
				( attribute "SMDPIN_TO_BONDPAD_SPACING" "5.00,5.00,5.00,5.00,5.00,5.00,5.00,5.00,5.00,5.00,5.00,5.00,5.00,5.00"
					( Origin gBackEnd )
				)
				( attribute "LINE_TO_SMDPIN_SPACING" "4.50,4.50,4.50,4.50,4.50,4.50,4.50,4.50,4.50,4.50,4.50,4.50,4.50,4.50"
					( Origin gBackEnd )
				)
				( attribute "SHAPE_TO_SMDPIN_SPACING" "5.00,5.00,5.00,5.00,5.00,5.00,5.00,5.00,5.00,5.00,5.00,5.00,5.00,5.00"
					( Origin gBackEnd )
				)
				( attribute "TESTPIN_TO_TESTPIN_SPACING" "5.00,5.00,5.00,5.00,5.00,5.00,5.00,5.00,5.00,5.00,5.00,5.00,5.00,5.00"
					( Origin gBackEnd )
				)
				( attribute "TESTPIN_TO_THRUVIA_SPACING" "5.00,5.00,5.00,5.00,5.00,5.00,5.00,5.00,5.00,5.00,5.00,5.00,5.00,5.00"
					( Origin gBackEnd )
				)
				( attribute "TESTPIN_TO_TESTVIA_SPACING" "5.00,5.00,5.00,5.00,5.00,5.00,5.00,5.00,5.00,5.00,5.00,5.00,5.00,5.00"
					( Origin gBackEnd )
				)
				( attribute "BBV_TO_TESTPIN_SPACING" "5.00,5.00,5.00,5.00,5.00,5.00,5.00,5.00,5.00,5.00,5.00,5.00,5.00,5.00"
					( Origin gBackEnd )
				)
				( attribute "BONDPAD_TO_TESTPIN_SPACING" "5.00,5.00,5.00,5.00,5.00,5.00,5.00,5.00,5.00,5.00,5.00,5.00,5.00,5.00"
					( Origin gBackEnd )
				)
				( attribute "LINE_TO_TESTPIN_SPACING" "5.00,4.00,4.00,4.00,4.00,4.00,4.00,4.00,4.00,4.00,4.00,4.00,4.00,5.00"
					( Origin gBackEnd )
				)
				( attribute "SHAPE_TO_TESTPIN_SPACING" "5.00,5.00,5.00,5.00,5.00,5.00,5.00,5.00,5.00,5.00,5.00,5.00,5.00,5.00"
					( Origin gBackEnd )
				)
				( attribute "THRUVIA_TO_THRUVIA_SPACING" "5.00,5.00,5.00,5.00,5.00,5.00,5.00,5.00,5.00,5.00,5.00,5.00,5.00,5.00"
					( Origin gBackEnd )
				)
				( attribute "TESTVIA_TO_THRUVIA_SPACING" "6.00,6.00,6.00,6.00,6.00,6.00,6.00,6.00,6.00,6.00,6.00,6.00,6.00,6.00"
					( Origin gBackEnd )
				)
				( attribute "BBV_TO_THRUVIA_SPACING" "5.00,5.00,5.00,5.00,5.00,5.00,5.00,5.00,5.00,5.00,5.00,5.00,5.00,5.00"
					( Origin gBackEnd )
				)
				( attribute "BONDPAD_TO_THRUVIA_SPACING" "5.00,5.00,5.00,5.00,5.00,5.00,5.00,5.00,5.00,5.00,5.00,5.00,5.00,5.00"
					( Origin gBackEnd )
				)
				( attribute "LINE_TO_THRUVIA_SPACING" "4.50,4.00,4.00,4.00,4.00,4.00,4.00,4.00,4.00,4.00,4.00,4.00,4.00,4.50"
					( Origin gBackEnd )
				)
				( attribute "SHAPE_TO_THRUVIA_SPACING" "5.00,5.00,5.00,5.00,5.00,5.00,5.00,5.00,5.00,5.00,5.00,5.00,5.00,5.00"
					( Origin gBackEnd )
				)
				( attribute "TESTVIA_TO_TESTVIA_SPACING" "6.00,6.00,6.00,6.00,6.00,6.00,6.00,6.00,6.00,6.00,6.00,6.00,6.00,6.00"
					( Origin gBackEnd )
				)
				( attribute "BBV_TO_TESTVIA_SPACING" "5.00,5.00,5.00,5.00,5.00,5.00,5.00,5.00,5.00,5.00,5.00,5.00,5.00,5.00"
					( Origin gBackEnd )
				)
				( attribute "BONDPAD_TO_TESTVIA_SPACING" "5.00,5.00,5.00,5.00,5.00,5.00,5.00,5.00,5.00,5.00,5.00,5.00,5.00,5.00"
					( Origin gBackEnd )
				)
				( attribute "LINE_TO_TESTVIA_SPACING" "4.50,4.00,4.00,4.00,4.00,4.00,4.00,4.00,4.00,4.00,4.00,4.00,4.00,4.50"
					( Origin gBackEnd )
				)
				( attribute "SHAPE_TO_TESTVIA_SPACING" "5.00,5.00,5.00,5.00,5.00,5.00,5.00,5.00,5.00,5.00,5.00,5.00,5.00,5.00"
					( Origin gBackEnd )
				)
				( attribute "BBV_TO_BBV_SPACING" "5.00,5.00,5.00,5.00,5.00,5.00,5.00,5.00,5.00,5.00,5.00,5.00,5.00,5.00"
					( Origin gBackEnd )
				)
				( attribute "BONDPAD_TO_BBV_SPACING" "5.00,5.00,5.00,5.00,5.00,5.00,5.00,5.00,5.00,5.00,5.00,5.00,5.00,5.00"
					( Origin gBackEnd )
				)
				( attribute "BBV_TO_LINE_SPACING" "5.00,5.00,5.00,5.00,5.00,5.00,5.00,5.00,5.00,5.00,5.00,5.00,5.00,5.00"
					( Origin gBackEnd )
				)
				( attribute "BBV_TO_SHAPE_SPACING" "5.00,5.00,5.00,5.00,5.00,5.00,5.00,5.00,5.00,5.00,5.00,5.00,5.00,5.00"
					( Origin gBackEnd )
				)
				( attribute "BONDPAD_TO_BONDPAD_SPACING" "5.00,5.00,5.00,5.00,5.00,5.00,5.00,5.00,5.00,5.00,5.00,5.00,5.00,5.00"
					( Origin gBackEnd )
				)
				( attribute "BONDPAD_TO_LINE_SPACING" "5.00,5.00,5.00,5.00,5.00,5.00,5.00,5.00,5.00,5.00,5.00,5.00,5.00,5.00"
					( Origin gBackEnd )
				)
				( attribute "BONDPAD_TO_SHAPE_SPACING" "5.00,5.00,5.00,5.00,5.00,5.00,5.00,5.00,5.00,5.00,5.00,5.00,5.00,5.00"
					( Origin gBackEnd )
				)
				( attribute "LINE_TO_LINE_SPACING" "30.00,30.00,30.00,30.00,30.00,30.00,30.00,30.00,30.00,30.00,30.00,30.00,30.00,30.00"
					( Origin gBackEnd )
				)
				( attribute "LINE_TO_SHAPE_SPACING" "10.00,10.00,10.00,10.00,10.00,10.00,10.00,10.00,10.00,10.00,10.00,10.00,10.00,10.00"
					( Origin gBackEnd )
				)
				( attribute "SHAPE_TO_SHAPE_SPACING" "10.00,10.00,10.00,10.00,10.00,10.00,10.00,10.00,10.00,10.00,10.00,10.00,10.00,10.00"
					( Origin gBackEnd )
				)
				( attribute "HOLE_TO_PIN_SPACING" "8.00,8.00,8.00,8.00,8.00,8.00,8.00,8.00,8.00,8.00,8.00,8.00,8.00,8.00"
					( Origin gBackEnd )
				)
				( attribute "HOLE_TO_VIA_SPACING" "8.00,8.00,8.00,8.00,8.00,8.00,8.00,8.00,8.00,8.00,8.00,8.00,8.00,8.00"
					( Origin gBackEnd )
				)
				( attribute "HOLE_TO_LINE_SPACING" "8.00,8.00,8.00,8.00,8.00,8.00,8.00,8.00,8.00,8.00,8.00,8.00,8.00,8.00"
					( Origin gBackEnd )
				)
				( attribute "HOLE_TO_SHAPE_SPACING" "8.00,8.00,8.00,8.00,8.00,8.00,8.00,8.00,8.00,8.00,8.00,8.00,8.00,8.00"
					( Origin gBackEnd )
				)
				( attribute "HOLE_TO_HOLE_SPACING" "8.00,8.00,8.00,8.00,8.00,8.00,8.00,8.00,8.00,8.00,8.00,8.00,8.00,8.00"
					( Origin gBackEnd )
				)
				( attribute "MVIA_TO_MVIA_SPACING" "5.00,5.00,5.00,5.00,5.00,5.00,5.00,5.00,5.00,5.00,5.00,5.00,5.00,5.00"
					( Origin gBackEnd )
				)
				( attribute "MVIA_TO_THRUPIN_SPACING" "5.00,5.00,5.00,5.00,5.00,5.00,5.00,5.00,5.00,5.00,5.00,5.00,5.00,5.00"
					( Origin gBackEnd )
				)
				( attribute "MVIA_TO_SMDPIN_SPACING" "5.00,5.00,5.00,5.00,5.00,5.00,5.00,5.00,5.00,5.00,5.00,5.00,5.00,5.00"
					( Origin gBackEnd )
				)
				( attribute "MVIA_TO_THRUVIA_SPACING" "5.00,5.00,5.00,5.00,5.00,5.00,5.00,5.00,5.00,5.00,5.00,5.00,5.00,5.00"
					( Origin gBackEnd )
				)
				( attribute "MVIA_TO_BBV_SPACING" "5.00,5.00,5.00,5.00,5.00,5.00,5.00,5.00,5.00,5.00,5.00,5.00,5.00,5.00"
					( Origin gBackEnd )
				)
				( attribute "MVIA_TO_LINE_SPACING" "5.00,5.00,5.00,5.00,5.00,5.00,5.00,5.00,5.00,5.00,5.00,5.00,5.00,5.00"
					( Origin gBackEnd )
				)
				( attribute "MVIA_TO_SHAPE_SPACING" "5.00,5.00,5.00,5.00,5.00,5.00,5.00,5.00,5.00,5.00,5.00,5.00,5.00,5.00"
					( Origin gBackEnd )
				)
				( attribute "MVIA_TO_TESTPIN_SPACING" "5.00,5.00,5.00,5.00,5.00,5.00,5.00,5.00,5.00,5.00,5.00,5.00,5.00,5.00"
					( Origin gBackEnd )
				)
				( attribute "MVIA_TO_TESTVIA_SPACING" "5.00,5.00,5.00,5.00,5.00,5.00,5.00,5.00,5.00,5.00,5.00,5.00,5.00,5.00"
					( Origin gBackEnd )
				)
				( attribute "BONDPAD_TO_MVIA_SPACING" "5.00,5.00,5.00,5.00,5.00,5.00,5.00,5.00,5.00,5.00,5.00,5.00,5.00,5.00"
					( Origin gBackEnd )
				)
				( attribute "MIN_BVIA_GAP" "5.00"
					( Origin gBackEnd )
				)
				( attribute "BONDPAD_TO_BONDPAD_DIFFP_SPC" "5.00,5.00,5.00,5.00,5.00,5.00,5.00,5.00,5.00,5.00,5.00,5.00,5.00,5.00"
					( Origin gBackEnd )
				)
				( objectStatus "30MIL" )
			)
			( spacingCSet "@sapphirecity_baseboard_lib.sapphirecity_baseboard(sch_1):\3H\"
				( attribute "THRUPIN_TO_THRUPIN_SPACING" "5.00,5.00,5.00,5.00,5.00,5.00,5.00,5.00,5.00,5.00,5.00,5.00,5.00,5.00"
					( Origin gBackEnd )
				)
				( attribute "THRUPIN_TO_SMDPIN_SPACING" "5.00,5.00,5.00,5.00,5.00,5.00,5.00,5.00,5.00,5.00,5.00,5.00,5.00,5.00"
					( Origin gBackEnd )
				)
				( attribute "TESTPIN_TO_THRUPIN_SPACING" "5.00,5.00,5.00,5.00,5.00,5.00,5.00,5.00,5.00,5.00,5.00,5.00,5.00,5.00"
					( Origin gBackEnd )
				)
				( attribute "THRUPIN_TO_THRUVIA_SPACING" "5.00,5.00,5.00,5.00,5.00,5.00,5.00,5.00,5.00,5.00,5.00,5.00,5.00,5.00"
					( Origin gBackEnd )
				)
				( attribute "TESTVIA_TO_THRUPIN_SPACING" "5.00,5.00,5.00,5.00,5.00,5.00,5.00,5.00,5.00,5.00,5.00,5.00,5.00,5.00"
					( Origin gBackEnd )
				)
				( attribute "BBV_TO_THRUPIN_SPACING" "5.00,5.00,5.00,5.00,5.00,5.00,5.00,5.00,5.00,5.00,5.00,5.00,5.00,5.00"
					( Origin gBackEnd )
				)
				( attribute "THRUPIN_TO_BONDPAD_SPACING" "5.00,5.00,5.00,5.00,5.00,5.00,5.00,5.00,5.00,5.00,5.00,5.00,5.00,5.00"
					( Origin gBackEnd )
				)
				( attribute "LINE_TO_THRUPIN_SPACING" "4.50,4.00,4.00,4.00,4.00,4.00,4.00,4.00,4.00,4.00,4.00,4.00,4.00,4.50"
					( Origin gBackEnd )
				)
				( attribute "THRUPIN_TO_SHAPE_SPACING" "4.50,4.00,4.00,4.00,4.00,4.00,4.00,4.00,4.00,4.00,4.00,4.00,4.00,4.00"
					( Origin gBackEnd )
				)
				( attribute "SMDPIN_TO_SMDPIN_SPACING" "5.00,5.00,5.00,5.00,5.00,5.00,5.00,5.00,5.00,5.00,5.00,5.00,5.00,5.00"
					( Origin gBackEnd )
				)
				( attribute "SMDPIN_TO_TESTPIN_SPACING" "5.00,5.00,5.00,5.00,5.00,5.00,5.00,5.00,5.00,5.00,5.00,5.00,5.00,5.00"
					( Origin gBackEnd )
				)
				( attribute "SMDPIN_TO_THRUVIA_SPACING" "5.00,5.00,5.00,5.00,5.00,5.00,5.00,5.00,5.00,5.00,5.00,5.00,5.00,5.00"
					( Origin gBackEnd )
				)
				( attribute "SMDPIN_TO_TESTVIA_SPACING" "5.00,5.00,5.00,5.00,5.00,5.00,5.00,5.00,5.00,5.00,5.00,5.00,5.00,5.00"
					( Origin gBackEnd )
				)
				( attribute "BBV_TO_SMDPIN_SPACING" "5.00,5.00,5.00,5.00,5.00,5.00,5.00,5.00,5.00,5.00,5.00,5.00,5.00,5.00"
					( Origin gBackEnd )
				)
				( attribute "SMDPIN_TO_BONDPAD_SPACING" "5.00,5.00,5.00,5.00,5.00,5.00,5.00,5.00,5.00,5.00,5.00,5.00,5.00,5.00"
					( Origin gBackEnd )
				)
				( attribute "LINE_TO_SMDPIN_SPACING" "4.50,4.50,4.50,4.50,4.50,4.50,4.50,4.50,4.50,4.50,4.50,4.50,4.50,4.50"
					( Origin gBackEnd )
				)
				( attribute "SHAPE_TO_SMDPIN_SPACING" "5.00,5.00,5.00,5.00,5.00,5.00,5.00,5.00,5.00,5.00,5.00,5.00,5.00,5.00"
					( Origin gBackEnd )
				)
				( attribute "TESTPIN_TO_TESTPIN_SPACING" "5.00,5.00,5.00,5.00,5.00,5.00,5.00,5.00,5.00,5.00,5.00,5.00,5.00,5.00"
					( Origin gBackEnd )
				)
				( attribute "TESTPIN_TO_THRUVIA_SPACING" "5.00,5.00,5.00,5.00,5.00,5.00,5.00,5.00,5.00,5.00,5.00,5.00,5.00,5.00"
					( Origin gBackEnd )
				)
				( attribute "TESTPIN_TO_TESTVIA_SPACING" "5.00,5.00,5.00,5.00,5.00,5.00,5.00,5.00,5.00,5.00,5.00,5.00,5.00,5.00"
					( Origin gBackEnd )
				)
				( attribute "BBV_TO_TESTPIN_SPACING" "5.00,5.00,5.00,5.00,5.00,5.00,5.00,5.00,5.00,5.00,5.00,5.00,5.00,5.00"
					( Origin gBackEnd )
				)
				( attribute "BONDPAD_TO_TESTPIN_SPACING" "5.00,5.00,5.00,5.00,5.00,5.00,5.00,5.00,5.00,5.00,5.00,5.00,5.00,5.00"
					( Origin gBackEnd )
				)
				( attribute "LINE_TO_TESTPIN_SPACING" "4.50,5.00,5.00,5.00,5.00,5.00,5.00,5.00,5.00,5.00,5.00,5.00,5.00,5.00"
					( Origin gBackEnd )
				)
				( attribute "SHAPE_TO_TESTPIN_SPACING" "4.50,4.00,4.00,4.00,4.00,4.00,4.00,4.00,4.00,4.00,4.00,4.00,4.00,4.00"
					( Origin gBackEnd )
				)
				( attribute "THRUVIA_TO_THRUVIA_SPACING" "5.00,5.00,5.00,5.00,5.00,5.00,5.00,5.00,5.00,5.00,5.00,5.00,5.00,5.00"
					( Origin gBackEnd )
				)
				( attribute "TESTVIA_TO_THRUVIA_SPACING" "5.00,5.00,5.00,5.00,5.00,5.00,5.00,5.00,5.00,5.00,5.00,5.00,5.00,5.00"
					( Origin gBackEnd )
				)
				( attribute "BBV_TO_THRUVIA_SPACING" "5.00,5.00,5.00,5.00,5.00,5.00,5.00,5.00,5.00,5.00,5.00,5.00,5.00,5.00"
					( Origin gBackEnd )
				)
				( attribute "BONDPAD_TO_THRUVIA_SPACING" "5.00,5.00,5.00,5.00,5.00,5.00,5.00,5.00,5.00,5.00,5.00,5.00,5.00,5.00"
					( Origin gBackEnd )
				)
				( attribute "LINE_TO_THRUVIA_SPACING" "4.50,4.00,4.00,4.00,4.00,4.00,4.00,4.00,4.00,4.00,4.00,4.00,4.00,4.50"
					( Origin gBackEnd )
				)
				( attribute "SHAPE_TO_THRUVIA_SPACING" "4.50,4.00,4.00,4.00,4.00,4.00,4.00,4.00,4.00,4.00,4.00,4.00,4.00,4.00"
					( Origin gBackEnd )
				)
				( attribute "TESTVIA_TO_TESTVIA_SPACING" "5.00,5.00,5.00,5.00,5.00,5.00,5.00,5.00,5.00,5.00,5.00,5.00,5.00,5.00"
					( Origin gBackEnd )
				)
				( attribute "BBV_TO_TESTVIA_SPACING" "5.00,5.00,5.00,5.00,5.00,5.00,5.00,5.00,5.00,5.00,5.00,5.00,5.00,5.00"
					( Origin gBackEnd )
				)
				( attribute "BONDPAD_TO_TESTVIA_SPACING" "5.00,5.00,5.00,5.00,5.00,5.00,5.00,5.00,5.00,5.00,5.00,5.00,5.00,5.00"
					( Origin gBackEnd )
				)
				( attribute "LINE_TO_TESTVIA_SPACING" "4.50,5.00,4.00,5.00,4.00,5.00,5.00,5.00,5.00,4.00,5.00,4.00,5.00,4.50"
					( Origin gBackEnd )
				)
				( attribute "SHAPE_TO_TESTVIA_SPACING" "4.50,4.00,4.00,4.00,4.00,4.00,4.00,4.00,4.00,4.00,4.00,4.00,4.00,4.00"
					( Origin gBackEnd )
				)
				( attribute "BBV_TO_BBV_SPACING" "5.00,5.00,5.00,5.00,5.00,5.00,5.00,5.00,5.00,5.00,5.00,5.00,5.00,5.00"
					( Origin gBackEnd )
				)
				( attribute "BONDPAD_TO_BBV_SPACING" "5.00,5.00,5.00,5.00,5.00,5.00,5.00,5.00,5.00,5.00,5.00,5.00,5.00,5.00"
					( Origin gBackEnd )
				)
				( attribute "BBV_TO_LINE_SPACING" "5.00,5.00,5.00,5.00,5.00,5.00,5.00,5.00,5.00,5.00,5.00,5.00,5.00,5.00"
					( Origin gBackEnd )
				)
				( attribute "BBV_TO_SHAPE_SPACING" "5.00,5.00,5.00,5.00,5.00,5.00,5.00,5.00,5.00,5.00,5.00,5.00,5.00,5.00"
					( Origin gBackEnd )
				)
				( attribute "BONDPAD_TO_BONDPAD_SPACING" "5.00,5.00,5.00,5.00,5.00,5.00,5.00,5.00,5.00,5.00,5.00,5.00,5.00,5.00"
					( Origin gBackEnd )
				)
				( attribute "BONDPAD_TO_LINE_SPACING" "5.00,5.00,5.00,5.00,5.00,5.00,5.00,5.00,5.00,5.00,5.00,5.00,5.00,5.00"
					( Origin gBackEnd )
				)
				( attribute "BONDPAD_TO_SHAPE_SPACING" "5.00,5.00,5.00,5.00,5.00,5.00,5.00,5.00,5.00,5.00,5.00,5.00,5.00,5.00"
					( Origin gBackEnd )
				)
				( attribute "LINE_TO_LINE_SPACING" "8.10,9.00,9.00,9.00,9.00,9.00,9.00,9.00,9.00,9.00,9.00,9.00,9.00,8.10"
					( Origin gBackEnd )
				)
				( attribute "LINE_TO_SHAPE_SPACING" "5.00,5.00,5.00,5.00,5.00,5.00,5.00,5.00,5.00,5.00,5.00,5.00,5.00,5.00"
					( Origin gBackEnd )
				)
				( attribute "SHAPE_TO_SHAPE_SPACING" "10.00,10.00,10.00,10.00,10.00,10.00,10.00,10.00,10.00,10.00,10.00,10.00,10.00,10.00"
					( Origin gBackEnd )
				)
				( attribute "HOLE_TO_PIN_SPACING" "8.00,8.00,8.00,8.00,8.00,8.00,8.00,8.00,8.00,8.00,8.00,8.00,8.00,8.00"
					( Origin gBackEnd )
				)
				( attribute "HOLE_TO_VIA_SPACING" "8.00,8.00,8.00,8.00,8.00,8.00,8.00,8.00,8.00,8.00,8.00,8.00,8.00,8.00"
					( Origin gBackEnd )
				)
				( attribute "HOLE_TO_LINE_SPACING" "8.00,8.00,8.00,8.00,8.00,8.00,8.00,8.00,8.00,8.00,8.00,8.00,8.00,8.00"
					( Origin gBackEnd )
				)
				( attribute "HOLE_TO_SHAPE_SPACING" "8.00,8.00,8.00,8.00,8.00,8.00,8.00,8.00,8.00,8.00,8.00,8.00,8.00,8.00"
					( Origin gBackEnd )
				)
				( attribute "HOLE_TO_HOLE_SPACING" "8.00,8.00,8.00,8.00,8.00,8.00,8.00,8.00,8.00,8.00,8.00,8.00,8.00,8.00"
					( Origin gBackEnd )
				)
				( attribute "MVIA_TO_MVIA_SPACING" "5.00,5.00,5.00,5.00,5.00,5.00,5.00,5.00,5.00,5.00,5.00,5.00,5.00,5.00"
					( Origin gBackEnd )
				)
				( attribute "MVIA_TO_THRUPIN_SPACING" "5.00,5.00,5.00,5.00,5.00,5.00,5.00,5.00,5.00,5.00,5.00,5.00,5.00,5.00"
					( Origin gBackEnd )
				)
				( attribute "MVIA_TO_SMDPIN_SPACING" "5.00,5.00,5.00,5.00,5.00,5.00,5.00,5.00,5.00,5.00,5.00,5.00,5.00,5.00"
					( Origin gBackEnd )
				)
				( attribute "MVIA_TO_THRUVIA_SPACING" "5.00,5.00,5.00,5.00,5.00,5.00,5.00,5.00,5.00,5.00,5.00,5.00,5.00,5.00"
					( Origin gBackEnd )
				)
				( attribute "MVIA_TO_BBV_SPACING" "5.00,5.00,5.00,5.00,5.00,5.00,5.00,5.00,5.00,5.00,5.00,5.00,5.00,5.00"
					( Origin gBackEnd )
				)
				( attribute "MVIA_TO_LINE_SPACING" "5.00,5.00,5.00,5.00,5.00,5.00,5.00,5.00,5.00,5.00,5.00,5.00,5.00,5.00"
					( Origin gBackEnd )
				)
				( attribute "MVIA_TO_SHAPE_SPACING" "5.00,5.00,5.00,5.00,5.00,5.00,5.00,5.00,5.00,5.00,5.00,5.00,5.00,5.00"
					( Origin gBackEnd )
				)
				( attribute "MVIA_TO_TESTPIN_SPACING" "5.00,5.00,5.00,5.00,5.00,5.00,5.00,5.00,5.00,5.00,5.00,5.00,5.00,5.00"
					( Origin gBackEnd )
				)
				( attribute "MVIA_TO_TESTVIA_SPACING" "5.00,5.00,5.00,5.00,5.00,5.00,5.00,5.00,5.00,5.00,5.00,5.00,5.00,5.00"
					( Origin gBackEnd )
				)
				( attribute "BONDPAD_TO_MVIA_SPACING" "5.00,5.00,5.00,5.00,5.00,5.00,5.00,5.00,5.00,5.00,5.00,5.00,5.00,5.00"
					( Origin gBackEnd )
				)
				( attribute "MIN_BVIA_GAP" "5.00"
					( Origin gBackEnd )
				)
				( attribute "BONDPAD_TO_BONDPAD_DIFFP_SPC" "5.00,5.00,5.00,5.00,5.00,5.00,5.00,5.00,5.00,5.00,5.00,5.00,5.00,5.00"
					( Origin gBackEnd )
				)
				( objectStatus "3H" )
			)
			( spacingCSet "@sapphirecity_baseboard_lib.sapphirecity_baseboard(sch_1):\30_MILS\"
				( attribute "THRUPIN_TO_THRUPIN_SPACING" "5.00,5.00,5.00,5.00,5.00,5.00,5.00,5.00,5.00,5.00,5.00,5.00,5.00,5.00"
					( Origin gBackEnd )
				)
				( attribute "THRUPIN_TO_SMDPIN_SPACING" "5.00,5.00,5.00,5.00,5.00,5.00,5.00,5.00,5.00,5.00,5.00,5.00,5.00,5.00"
					( Origin gBackEnd )
				)
				( attribute "TESTPIN_TO_THRUPIN_SPACING" "5.00,5.00,5.00,5.00,5.00,5.00,5.00,5.00,5.00,5.00,5.00,5.00,5.00,5.00"
					( Origin gBackEnd )
				)
				( attribute "THRUPIN_TO_THRUVIA_SPACING" "5.00,5.00,5.00,5.00,5.00,5.00,5.00,5.00,5.00,5.00,5.00,5.00,5.00,5.00"
					( Origin gBackEnd )
				)
				( attribute "TESTVIA_TO_THRUPIN_SPACING" "5.00,5.00,5.00,5.00,5.00,5.00,5.00,5.00,5.00,5.00,5.00,5.00,5.00,5.00"
					( Origin gBackEnd )
				)
				( attribute "BBV_TO_THRUPIN_SPACING" "5.00,5.00,5.00,5.00,5.00,5.00,5.00,5.00,5.00,5.00,5.00,5.00,5.00,5.00"
					( Origin gBackEnd )
				)
				( attribute "THRUPIN_TO_BONDPAD_SPACING" "5.00,5.00,5.00,5.00,5.00,5.00,5.00,5.00,5.00,5.00,5.00,5.00,5.00,5.00"
					( Origin gBackEnd )
				)
				( attribute "LINE_TO_THRUPIN_SPACING" "4.50,4.00,4.00,4.00,4.00,4.00,4.00,4.00,4.00,4.00,4.00,4.00,4.00,4.50"
					( Origin gBackEnd )
				)
				( attribute "THRUPIN_TO_SHAPE_SPACING" "4.50,4.00,4.00,4.00,4.00,4.00,4.00,4.00,4.00,4.00,4.00,4.00,4.00,4.00"
					( Origin gBackEnd )
				)
				( attribute "SMDPIN_TO_SMDPIN_SPACING" "5.00,5.00,5.00,5.00,5.00,5.00,5.00,5.00,5.00,5.00,5.00,5.00,5.00,5.00"
					( Origin gBackEnd )
				)
				( attribute "SMDPIN_TO_TESTPIN_SPACING" "5.00,5.00,5.00,5.00,5.00,5.00,5.00,5.00,5.00,5.00,5.00,5.00,5.00,25.00"
					( Origin gBackEnd )
				)
				( attribute "SMDPIN_TO_THRUVIA_SPACING" "5.00,5.00,5.00,5.00,5.00,5.00,5.00,5.00,5.00,5.00,5.00,5.00,5.00,5.00"
					( Origin gBackEnd )
				)
				( attribute "SMDPIN_TO_TESTVIA_SPACING" "5.00,5.00,5.00,5.00,5.00,5.00,5.00,5.00,5.00,5.00,5.00,5.00,5.00,5.00"
					( Origin gBackEnd )
				)
				( attribute "BBV_TO_SMDPIN_SPACING" "5.00,5.00,5.00,5.00,5.00,5.00,5.00,5.00,5.00,5.00,5.00,5.00,5.00,5.00"
					( Origin gBackEnd )
				)
				( attribute "SMDPIN_TO_BONDPAD_SPACING" "5.00,5.00,5.00,5.00,5.00,5.00,5.00,5.00,5.00,5.00,5.00,5.00,5.00,5.00"
					( Origin gBackEnd )
				)
				( attribute "LINE_TO_SMDPIN_SPACING" "4.50,4.50,4.50,4.50,4.50,4.50,4.50,4.50,4.50,4.50,4.50,4.50,4.50,4.50"
					( Origin gBackEnd )
				)
				( attribute "SHAPE_TO_SMDPIN_SPACING" "5.00,5.00,5.00,5.00,5.00,5.00,5.00,5.00,5.00,5.00,5.00,5.00,5.00,5.00"
					( Origin gBackEnd )
				)
				( attribute "TESTPIN_TO_TESTPIN_SPACING" "5.00,5.00,5.00,5.00,5.00,5.00,5.00,5.00,5.00,5.00,5.00,5.00,5.00,5.00"
					( Origin gBackEnd )
				)
				( attribute "TESTPIN_TO_THRUVIA_SPACING" "5.00,5.00,5.00,5.00,5.00,5.00,5.00,5.00,5.00,5.00,5.00,5.00,5.00,5.00"
					( Origin gBackEnd )
				)
				( attribute "TESTPIN_TO_TESTVIA_SPACING" "5.00,5.00,5.00,5.00,5.00,5.00,5.00,5.00,5.00,5.00,5.00,5.00,5.00,5.00"
					( Origin gBackEnd )
				)
				( attribute "BBV_TO_TESTPIN_SPACING" "5.00,5.00,5.00,5.00,5.00,5.00,5.00,5.00,5.00,5.00,5.00,5.00,5.00,5.00"
					( Origin gBackEnd )
				)
				( attribute "BONDPAD_TO_TESTPIN_SPACING" "5.00,5.00,5.00,5.00,5.00,5.00,5.00,5.00,5.00,5.00,5.00,5.00,5.00,5.00"
					( Origin gBackEnd )
				)
				( attribute "LINE_TO_TESTPIN_SPACING" "4.50,5.00,5.00,5.00,5.00,5.00,5.00,5.00,5.00,5.00,5.00,5.00,5.00,5.00"
					( Origin gBackEnd )
				)
				( attribute "SHAPE_TO_TESTPIN_SPACING" "4.50,4.00,4.00,4.00,4.00,4.00,4.00,4.00,4.00,4.00,4.00,4.00,4.00,4.00"
					( Origin gBackEnd )
				)
				( attribute "THRUVIA_TO_THRUVIA_SPACING" "5.00,5.00,5.00,5.00,5.00,5.00,5.00,5.00,5.00,5.00,5.00,5.00,5.00,5.00"
					( Origin gBackEnd )
				)
				( attribute "TESTVIA_TO_THRUVIA_SPACING" "5.00,5.00,5.00,5.00,5.00,5.00,5.00,5.00,5.00,5.00,5.00,5.00,5.00,5.00"
					( Origin gBackEnd )
				)
				( attribute "BBV_TO_THRUVIA_SPACING" "5.00,5.00,5.00,5.00,5.00,5.00,5.00,5.00,5.00,5.00,5.00,5.00,5.00,5.00"
					( Origin gBackEnd )
				)
				( attribute "BONDPAD_TO_THRUVIA_SPACING" "5.00,5.00,5.00,5.00,5.00,5.00,5.00,5.00,5.00,5.00,5.00,5.00,5.00,5.00"
					( Origin gBackEnd )
				)
				( attribute "LINE_TO_THRUVIA_SPACING" "4.50,4.00,4.00,4.00,4.00,4.00,4.00,4.00,4.00,4.00,4.00,4.00,4.00,4.50"
					( Origin gBackEnd )
				)
				( attribute "SHAPE_TO_THRUVIA_SPACING" "4.50,4.00,4.00,4.00,4.00,4.00,4.00,4.00,4.00,4.00,4.00,4.00,4.00,4.00"
					( Origin gBackEnd )
				)
				( attribute "TESTVIA_TO_TESTVIA_SPACING" "5.00,5.00,5.00,5.00,5.00,5.00,5.00,5.00,5.00,5.00,5.00,5.00,5.00,5.00"
					( Origin gBackEnd )
				)
				( attribute "BBV_TO_TESTVIA_SPACING" "5.00,5.00,5.00,5.00,5.00,5.00,5.00,5.00,5.00,5.00,5.00,5.00,5.00,5.00"
					( Origin gBackEnd )
				)
				( attribute "BONDPAD_TO_TESTVIA_SPACING" "5.00,5.00,5.00,5.00,5.00,5.00,5.00,5.00,5.00,5.00,5.00,5.00,5.00,5.00"
					( Origin gBackEnd )
				)
				( attribute "LINE_TO_TESTVIA_SPACING" "4.50,5.00,4.00,5.00,4.00,5.00,5.00,5.00,5.00,4.00,5.00,4.00,5.00,4.50"
					( Origin gBackEnd )
				)
				( attribute "SHAPE_TO_TESTVIA_SPACING" "4.50,4.00,4.00,4.00,4.00,4.00,4.00,4.00,4.00,4.00,4.00,4.00,4.00,4.00"
					( Origin gBackEnd )
				)
				( attribute "BBV_TO_BBV_SPACING" "5.00,5.00,5.00,5.00,5.00,5.00,5.00,5.00,5.00,5.00,5.00,5.00,5.00,5.00"
					( Origin gBackEnd )
				)
				( attribute "BONDPAD_TO_BBV_SPACING" "5.00,5.00,5.00,5.00,5.00,5.00,5.00,5.00,5.00,5.00,5.00,5.00,5.00,5.00"
					( Origin gBackEnd )
				)
				( attribute "BBV_TO_LINE_SPACING" "5.00,5.00,5.00,5.00,5.00,5.00,5.00,5.00,5.00,5.00,5.00,5.00,5.00,5.00"
					( Origin gBackEnd )
				)
				( attribute "BBV_TO_SHAPE_SPACING" "5.00,5.00,5.00,5.00,5.00,5.00,5.00,5.00,5.00,5.00,5.00,5.00,5.00,5.00"
					( Origin gBackEnd )
				)
				( attribute "BONDPAD_TO_BONDPAD_SPACING" "5.00,5.00,5.00,5.00,5.00,5.00,5.00,5.00,5.00,5.00,5.00,5.00,5.00,5.00"
					( Origin gBackEnd )
				)
				( attribute "BONDPAD_TO_LINE_SPACING" "5.00,5.00,5.00,5.00,5.00,5.00,5.00,5.00,5.00,5.00,5.00,5.00,5.00,5.00"
					( Origin gBackEnd )
				)
				( attribute "BONDPAD_TO_SHAPE_SPACING" "5.00,5.00,5.00,5.00,5.00,5.00,5.00,5.00,5.00,5.00,5.00,5.00,5.00,5.00"
					( Origin gBackEnd )
				)
				( attribute "LINE_TO_LINE_SPACING" "30.00,30.00,30.00,30.00,30.00,30.00,30.00,30.00,30.00,30.00,30.00,30.00,30.00,30.00"
					( Origin gBackEnd )
				)
				( attribute "LINE_TO_SHAPE_SPACING" "5.00,5.00,5.00,5.00,5.00,5.00,5.00,5.00,5.00,5.00,5.00,5.00,5.00,5.00"
					( Origin gBackEnd )
				)
				( attribute "SHAPE_TO_SHAPE_SPACING" "10.00,10.00,10.00,10.00,10.00,10.00,10.00,10.00,10.00,10.00,10.00,10.00,10.00,10.00"
					( Origin gBackEnd )
				)
				( attribute "HOLE_TO_PIN_SPACING" "8.00,8.00,8.00,8.00,8.00,8.00,8.00,8.00,8.00,8.00,8.00,8.00,8.00,8.00"
					( Origin gBackEnd )
				)
				( attribute "HOLE_TO_VIA_SPACING" "8.00,8.00,8.00,8.00,8.00,8.00,8.00,8.00,8.00,8.00,8.00,8.00,8.00,8.00"
					( Origin gBackEnd )
				)
				( attribute "HOLE_TO_LINE_SPACING" "8.00,8.00,8.00,8.00,8.00,8.00,8.00,8.00,8.00,8.00,8.00,8.00,8.00,8.00"
					( Origin gBackEnd )
				)
				( attribute "HOLE_TO_SHAPE_SPACING" "8.00,8.00,8.00,8.00,8.00,8.00,8.00,8.00,8.00,8.00,8.00,8.00,8.00,8.00"
					( Origin gBackEnd )
				)
				( attribute "HOLE_TO_HOLE_SPACING" "8.00,8.00,8.00,8.00,8.00,8.00,8.00,8.00,8.00,8.00,8.00,8.00,8.00,8.00"
					( Origin gBackEnd )
				)
				( attribute "MVIA_TO_MVIA_SPACING" "5.00,5.00,5.00,5.00,5.00,5.00,5.00,5.00,5.00,5.00,5.00,5.00,5.00,5.00"
					( Origin gBackEnd )
				)
				( attribute "MVIA_TO_THRUPIN_SPACING" "5.00,5.00,5.00,5.00,5.00,5.00,5.00,5.00,5.00,5.00,5.00,5.00,5.00,5.00"
					( Origin gBackEnd )
				)
				( attribute "MVIA_TO_SMDPIN_SPACING" "5.00,5.00,5.00,5.00,5.00,5.00,5.00,5.00,5.00,5.00,5.00,5.00,5.00,5.00"
					( Origin gBackEnd )
				)
				( attribute "MVIA_TO_THRUVIA_SPACING" "5.00,5.00,5.00,5.00,5.00,5.00,5.00,5.00,5.00,5.00,5.00,5.00,5.00,5.00"
					( Origin gBackEnd )
				)
				( attribute "MVIA_TO_BBV_SPACING" "5.00,5.00,5.00,5.00,5.00,5.00,5.00,5.00,5.00,5.00,5.00,5.00,5.00,5.00"
					( Origin gBackEnd )
				)
				( attribute "MVIA_TO_LINE_SPACING" "5.00,5.00,5.00,5.00,5.00,5.00,5.00,5.00,5.00,5.00,5.00,5.00,5.00,5.00"
					( Origin gBackEnd )
				)
				( attribute "MVIA_TO_SHAPE_SPACING" "5.00,5.00,5.00,5.00,5.00,5.00,5.00,5.00,5.00,5.00,5.00,5.00,5.00,5.00"
					( Origin gBackEnd )
				)
				( attribute "MVIA_TO_TESTPIN_SPACING" "5.00,5.00,5.00,5.00,5.00,5.00,5.00,5.00,5.00,5.00,5.00,5.00,5.00,5.00"
					( Origin gBackEnd )
				)
				( attribute "MVIA_TO_TESTVIA_SPACING" "5.00,5.00,5.00,5.00,5.00,5.00,5.00,5.00,5.00,5.00,5.00,5.00,5.00,5.00"
					( Origin gBackEnd )
				)
				( attribute "BONDPAD_TO_MVIA_SPACING" "5.00,5.00,5.00,5.00,5.00,5.00,5.00,5.00,5.00,5.00,5.00,5.00,5.00,5.00"
					( Origin gBackEnd )
				)
				( attribute "MIN_BVIA_GAP" "5.00"
					( Origin gBackEnd )
				)
				( attribute "BONDPAD_TO_BONDPAD_DIFFP_SPC" "5.00,5.00,5.00,5.00,5.00,5.00,5.00,5.00,5.00,5.00,5.00,5.00,5.00,5.00"
					( Origin gBackEnd )
				)
				( objectStatus "30_MILS" )
			)
			( spacingCSet "@sapphirecity_baseboard_lib.sapphirecity_baseboard(sch_1):\16_MILS\"
				( attribute "THRUPIN_TO_THRUPIN_SPACING" "5.00,5.00,5.00,5.00,5.00,5.00,5.00,5.00,5.00,5.00,5.00,5.00,5.00,5.00"
					( Origin gBackEnd )
				)
				( attribute "THRUPIN_TO_SMDPIN_SPACING" "5.00,5.00,5.00,5.00,5.00,5.00,5.00,5.00,5.00,5.00,5.00,5.00,5.00,5.00"
					( Origin gBackEnd )
				)
				( attribute "TESTPIN_TO_THRUPIN_SPACING" "5.00,5.00,5.00,5.00,5.00,5.00,5.00,5.00,5.00,5.00,5.00,5.00,5.00,5.00"
					( Origin gBackEnd )
				)
				( attribute "THRUPIN_TO_THRUVIA_SPACING" "5.00,5.00,5.00,5.00,5.00,5.00,5.00,5.00,5.00,5.00,5.00,5.00,5.00,5.00"
					( Origin gBackEnd )
				)
				( attribute "TESTVIA_TO_THRUPIN_SPACING" "5.00,5.00,5.00,5.00,5.00,5.00,5.00,5.00,5.00,5.00,5.00,5.00,5.00,5.00"
					( Origin gBackEnd )
				)
				( attribute "BBV_TO_THRUPIN_SPACING" "5.00,5.00,5.00,5.00,5.00,5.00,5.00,5.00,5.00,5.00,5.00,5.00,5.00,5.00"
					( Origin gBackEnd )
				)
				( attribute "THRUPIN_TO_BONDPAD_SPACING" "5.00,5.00,5.00,5.00,5.00,5.00,5.00,5.00,5.00,5.00,5.00,5.00,5.00,5.00"
					( Origin gBackEnd )
				)
				( attribute "LINE_TO_THRUPIN_SPACING" "4.50,4.00,4.00,4.00,4.00,4.00,4.00,4.00,4.00,4.00,4.00,4.00,4.00,4.50"
					( Origin gBackEnd )
				)
				( attribute "THRUPIN_TO_SHAPE_SPACING" "4.50,4.00,4.00,4.00,4.00,4.00,4.00,4.00,4.00,4.00,4.00,4.00,4.00,4.00"
					( Origin gBackEnd )
				)
				( attribute "SMDPIN_TO_SMDPIN_SPACING" "5.00,5.00,5.00,5.00,5.00,5.00,5.00,5.00,5.00,5.00,5.00,5.00,5.00,5.00"
					( Origin gBackEnd )
				)
				( attribute "SMDPIN_TO_TESTPIN_SPACING" "5.00,5.00,5.00,5.00,5.00,5.00,5.00,5.00,5.00,5.00,5.00,5.00,5.00,25.00"
					( Origin gBackEnd )
				)
				( attribute "SMDPIN_TO_THRUVIA_SPACING" "5.00,5.00,5.00,5.00,5.00,5.00,5.00,5.00,5.00,5.00,5.00,5.00,5.00,5.00"
					( Origin gBackEnd )
				)
				( attribute "SMDPIN_TO_TESTVIA_SPACING" "5.00,5.00,5.00,5.00,5.00,5.00,5.00,5.00,5.00,5.00,5.00,5.00,5.00,5.00"
					( Origin gBackEnd )
				)
				( attribute "BBV_TO_SMDPIN_SPACING" "5.00,5.00,5.00,5.00,5.00,5.00,5.00,5.00,5.00,5.00,5.00,5.00,5.00,5.00"
					( Origin gBackEnd )
				)
				( attribute "SMDPIN_TO_BONDPAD_SPACING" "5.00,5.00,5.00,5.00,5.00,5.00,5.00,5.00,5.00,5.00,5.00,5.00,5.00,5.00"
					( Origin gBackEnd )
				)
				( attribute "LINE_TO_SMDPIN_SPACING" "4.50,4.50,4.50,4.50,4.50,4.50,4.50,4.50,4.50,4.50,4.50,4.50,4.50,4.50"
					( Origin gBackEnd )
				)
				( attribute "SHAPE_TO_SMDPIN_SPACING" "5.00,5.00,5.00,5.00,5.00,5.00,5.00,5.00,5.00,5.00,5.00,5.00,5.00,5.00"
					( Origin gBackEnd )
				)
				( attribute "TESTPIN_TO_TESTPIN_SPACING" "5.00,5.00,5.00,5.00,5.00,5.00,5.00,5.00,5.00,5.00,5.00,5.00,5.00,5.00"
					( Origin gBackEnd )
				)
				( attribute "TESTPIN_TO_THRUVIA_SPACING" "5.00,5.00,5.00,5.00,5.00,5.00,5.00,5.00,5.00,5.00,5.00,5.00,5.00,5.00"
					( Origin gBackEnd )
				)
				( attribute "TESTPIN_TO_TESTVIA_SPACING" "5.00,5.00,5.00,5.00,5.00,5.00,5.00,5.00,5.00,5.00,5.00,5.00,5.00,5.00"
					( Origin gBackEnd )
				)
				( attribute "BBV_TO_TESTPIN_SPACING" "5.00,5.00,5.00,5.00,5.00,5.00,5.00,5.00,5.00,5.00,5.00,5.00,5.00,5.00"
					( Origin gBackEnd )
				)
				( attribute "BONDPAD_TO_TESTPIN_SPACING" "5.00,5.00,5.00,5.00,5.00,5.00,5.00,5.00,5.00,5.00,5.00,5.00,5.00,5.00"
					( Origin gBackEnd )
				)
				( attribute "LINE_TO_TESTPIN_SPACING" "4.50,5.00,5.00,5.00,5.00,5.00,5.00,5.00,5.00,5.00,5.00,5.00,5.00,5.00"
					( Origin gBackEnd )
				)
				( attribute "SHAPE_TO_TESTPIN_SPACING" "4.50,4.00,4.00,4.00,4.00,4.00,4.00,4.00,4.00,4.00,4.00,4.00,4.00,4.00"
					( Origin gBackEnd )
				)
				( attribute "THRUVIA_TO_THRUVIA_SPACING" "5.00,5.00,5.00,5.00,5.00,5.00,5.00,5.00,5.00,5.00,5.00,5.00,5.00,5.00"
					( Origin gBackEnd )
				)
				( attribute "TESTVIA_TO_THRUVIA_SPACING" "5.00,5.00,5.00,5.00,5.00,5.00,5.00,5.00,5.00,5.00,5.00,5.00,5.00,5.00"
					( Origin gBackEnd )
				)
				( attribute "BBV_TO_THRUVIA_SPACING" "5.00,5.00,5.00,5.00,5.00,5.00,5.00,5.00,5.00,5.00,5.00,5.00,5.00,5.00"
					( Origin gBackEnd )
				)
				( attribute "BONDPAD_TO_THRUVIA_SPACING" "5.00,5.00,5.00,5.00,5.00,5.00,5.00,5.00,5.00,5.00,5.00,5.00,5.00,5.00"
					( Origin gBackEnd )
				)
				( attribute "LINE_TO_THRUVIA_SPACING" "4.50,4.00,4.00,4.00,4.00,4.00,4.00,4.00,4.00,4.00,4.00,4.00,4.00,4.50"
					( Origin gBackEnd )
				)
				( attribute "SHAPE_TO_THRUVIA_SPACING" "4.50,4.00,4.00,4.00,4.00,4.00,4.00,4.00,4.00,4.00,4.00,4.00,4.00,4.00"
					( Origin gBackEnd )
				)
				( attribute "TESTVIA_TO_TESTVIA_SPACING" "5.00,5.00,5.00,5.00,5.00,5.00,5.00,5.00,5.00,5.00,5.00,5.00,5.00,5.00"
					( Origin gBackEnd )
				)
				( attribute "BBV_TO_TESTVIA_SPACING" "5.00,5.00,5.00,5.00,5.00,5.00,5.00,5.00,5.00,5.00,5.00,5.00,5.00,5.00"
					( Origin gBackEnd )
				)
				( attribute "BONDPAD_TO_TESTVIA_SPACING" "5.00,5.00,5.00,5.00,5.00,5.00,5.00,5.00,5.00,5.00,5.00,5.00,5.00,5.00"
					( Origin gBackEnd )
				)
				( attribute "LINE_TO_TESTVIA_SPACING" "4.50,5.00,4.00,5.00,4.00,5.00,5.00,5.00,5.00,4.00,5.00,4.00,5.00,4.50"
					( Origin gBackEnd )
				)
				( attribute "SHAPE_TO_TESTVIA_SPACING" "4.50,4.00,4.00,4.00,4.00,4.00,4.00,4.00,4.00,4.00,4.00,4.00,4.00,4.00"
					( Origin gBackEnd )
				)
				( attribute "BBV_TO_BBV_SPACING" "5.00,5.00,5.00,5.00,5.00,5.00,5.00,5.00,5.00,5.00,5.00,5.00,5.00,5.00"
					( Origin gBackEnd )
				)
				( attribute "BONDPAD_TO_BBV_SPACING" "5.00,5.00,5.00,5.00,5.00,5.00,5.00,5.00,5.00,5.00,5.00,5.00,5.00,5.00"
					( Origin gBackEnd )
				)
				( attribute "BBV_TO_LINE_SPACING" "5.00,5.00,5.00,5.00,5.00,5.00,5.00,5.00,5.00,5.00,5.00,5.00,5.00,5.00"
					( Origin gBackEnd )
				)
				( attribute "BBV_TO_SHAPE_SPACING" "5.00,5.00,5.00,5.00,5.00,5.00,5.00,5.00,5.00,5.00,5.00,5.00,5.00,5.00"
					( Origin gBackEnd )
				)
				( attribute "BONDPAD_TO_BONDPAD_SPACING" "5.00,5.00,5.00,5.00,5.00,5.00,5.00,5.00,5.00,5.00,5.00,5.00,5.00,5.00"
					( Origin gBackEnd )
				)
				( attribute "BONDPAD_TO_LINE_SPACING" "5.00,5.00,5.00,5.00,5.00,5.00,5.00,5.00,5.00,5.00,5.00,5.00,5.00,5.00"
					( Origin gBackEnd )
				)
				( attribute "BONDPAD_TO_SHAPE_SPACING" "5.00,5.00,5.00,5.00,5.00,5.00,5.00,5.00,5.00,5.00,5.00,5.00,5.00,5.00"
					( Origin gBackEnd )
				)
				( attribute "LINE_TO_LINE_SPACING" "16.00,16.00,16.00,16.00,16.00,16.00,16.00,16.00,16.00,16.00,16.00,16.00,16.00,16.00"
					( Origin gBackEnd )
				)
				( attribute "LINE_TO_SHAPE_SPACING" "5.00,5.00,5.00,5.00,5.00,5.00,5.00,5.00,5.00,5.00,5.00,5.00,5.00,5.00"
					( Origin gBackEnd )
				)
				( attribute "SHAPE_TO_SHAPE_SPACING" "10.00,10.00,10.00,10.00,10.00,10.00,10.00,10.00,10.00,10.00,10.00,10.00,10.00,10.00"
					( Origin gBackEnd )
				)
				( attribute "HOLE_TO_PIN_SPACING" "8.00,8.00,8.00,8.00,8.00,8.00,8.00,8.00,8.00,8.00,8.00,8.00,8.00,8.00"
					( Origin gBackEnd )
				)
				( attribute "HOLE_TO_VIA_SPACING" "8.00,8.00,8.00,8.00,8.00,8.00,8.00,8.00,8.00,8.00,8.00,8.00,8.00,8.00"
					( Origin gBackEnd )
				)
				( attribute "HOLE_TO_LINE_SPACING" "8.00,8.00,8.00,8.00,8.00,8.00,8.00,8.00,8.00,8.00,8.00,8.00,8.00,8.00"
					( Origin gBackEnd )
				)
				( attribute "HOLE_TO_SHAPE_SPACING" "8.00,8.00,8.00,8.00,8.00,8.00,8.00,8.00,8.00,8.00,8.00,8.00,8.00,8.00"
					( Origin gBackEnd )
				)
				( attribute "HOLE_TO_HOLE_SPACING" "8.00,8.00,8.00,8.00,8.00,8.00,8.00,8.00,8.00,8.00,8.00,8.00,8.00,8.00"
					( Origin gBackEnd )
				)
				( attribute "MVIA_TO_MVIA_SPACING" "5.00,5.00,5.00,5.00,5.00,5.00,5.00,5.00,5.00,5.00,5.00,5.00,5.00,5.00"
					( Origin gBackEnd )
				)
				( attribute "MVIA_TO_THRUPIN_SPACING" "5.00,5.00,5.00,5.00,5.00,5.00,5.00,5.00,5.00,5.00,5.00,5.00,5.00,5.00"
					( Origin gBackEnd )
				)
				( attribute "MVIA_TO_SMDPIN_SPACING" "5.00,5.00,5.00,5.00,5.00,5.00,5.00,5.00,5.00,5.00,5.00,5.00,5.00,5.00"
					( Origin gBackEnd )
				)
				( attribute "MVIA_TO_THRUVIA_SPACING" "5.00,5.00,5.00,5.00,5.00,5.00,5.00,5.00,5.00,5.00,5.00,5.00,5.00,5.00"
					( Origin gBackEnd )
				)
				( attribute "MVIA_TO_BBV_SPACING" "5.00,5.00,5.00,5.00,5.00,5.00,5.00,5.00,5.00,5.00,5.00,5.00,5.00,5.00"
					( Origin gBackEnd )
				)
				( attribute "MVIA_TO_LINE_SPACING" "5.00,5.00,5.00,5.00,5.00,5.00,5.00,5.00,5.00,5.00,5.00,5.00,5.00,5.00"
					( Origin gBackEnd )
				)
				( attribute "MVIA_TO_SHAPE_SPACING" "5.00,5.00,5.00,5.00,5.00,5.00,5.00,5.00,5.00,5.00,5.00,5.00,5.00,5.00"
					( Origin gBackEnd )
				)
				( attribute "MVIA_TO_TESTPIN_SPACING" "5.00,5.00,5.00,5.00,5.00,5.00,5.00,5.00,5.00,5.00,5.00,5.00,5.00,5.00"
					( Origin gBackEnd )
				)
				( attribute "MVIA_TO_TESTVIA_SPACING" "5.00,5.00,5.00,5.00,5.00,5.00,5.00,5.00,5.00,5.00,5.00,5.00,5.00,5.00"
					( Origin gBackEnd )
				)
				( attribute "BONDPAD_TO_MVIA_SPACING" "5.00,5.00,5.00,5.00,5.00,5.00,5.00,5.00,5.00,5.00,5.00,5.00,5.00,5.00"
					( Origin gBackEnd )
				)
				( attribute "MIN_BVIA_GAP" "5.00"
					( Origin gBackEnd )
				)
				( attribute "BONDPAD_TO_BONDPAD_DIFFP_SPC" "5.00,5.00,5.00,5.00,5.00,5.00,5.00,5.00,5.00,5.00,5.00,5.00,5.00,5.00"
					( Origin gBackEnd )
				)
				( objectStatus "16_MILS" )
			)
			( spacingCSet "@sapphirecity_baseboard_lib.sapphirecity_baseboard(sch_1):\25_MILS\"
				( attribute "THRUPIN_TO_THRUPIN_SPACING" "5.00,5.00,5.00,5.00,5.00,5.00,5.00,5.00,5.00,5.00,5.00,5.00,5.00,5.00"
					( Origin gBackEnd )
				)
				( attribute "THRUPIN_TO_SMDPIN_SPACING" "5.00,5.00,5.00,5.00,5.00,5.00,5.00,5.00,5.00,5.00,5.00,5.00,5.00,5.00"
					( Origin gBackEnd )
				)
				( attribute "TESTPIN_TO_THRUPIN_SPACING" "5.00,5.00,5.00,5.00,5.00,5.00,5.00,5.00,5.00,5.00,5.00,5.00,5.00,5.00"
					( Origin gBackEnd )
				)
				( attribute "THRUPIN_TO_THRUVIA_SPACING" "5.00,5.00,5.00,5.00,5.00,5.00,5.00,5.00,5.00,5.00,5.00,5.00,5.00,5.00"
					( Origin gBackEnd )
				)
				( attribute "TESTVIA_TO_THRUPIN_SPACING" "5.00,5.00,5.00,5.00,5.00,5.00,5.00,5.00,5.00,5.00,5.00,5.00,5.00,5.00"
					( Origin gBackEnd )
				)
				( attribute "BBV_TO_THRUPIN_SPACING" "5.00,5.00,5.00,5.00,5.00,5.00,5.00,5.00,5.00,5.00,5.00,5.00,5.00,5.00"
					( Origin gBackEnd )
				)
				( attribute "THRUPIN_TO_BONDPAD_SPACING" "5.00,5.00,5.00,5.00,5.00,5.00,5.00,5.00,5.00,5.00,5.00,5.00,5.00,5.00"
					( Origin gBackEnd )
				)
				( attribute "LINE_TO_THRUPIN_SPACING" "4.50,4.00,4.00,4.00,4.00,4.00,4.00,4.00,4.00,4.00,4.00,4.00,4.00,4.50"
					( Origin gBackEnd )
				)
				( attribute "THRUPIN_TO_SHAPE_SPACING" "4.50,4.00,4.00,4.00,4.00,4.00,4.00,4.00,4.00,4.00,4.00,4.00,4.00,4.00"
					( Origin gBackEnd )
				)
				( attribute "SMDPIN_TO_SMDPIN_SPACING" "5.00,5.00,5.00,5.00,5.00,5.00,5.00,5.00,5.00,5.00,5.00,5.00,5.00,5.00"
					( Origin gBackEnd )
				)
				( attribute "SMDPIN_TO_TESTPIN_SPACING" "5.00,5.00,5.00,5.00,5.00,5.00,5.00,5.00,5.00,5.00,5.00,5.00,5.00,25.00"
					( Origin gBackEnd )
				)
				( attribute "SMDPIN_TO_THRUVIA_SPACING" "5.00,5.00,5.00,5.00,5.00,5.00,5.00,5.00,5.00,5.00,5.00,5.00,5.00,5.00"
					( Origin gBackEnd )
				)
				( attribute "SMDPIN_TO_TESTVIA_SPACING" "5.00,5.00,5.00,5.00,5.00,5.00,5.00,5.00,5.00,5.00,5.00,5.00,5.00,5.00"
					( Origin gBackEnd )
				)
				( attribute "BBV_TO_SMDPIN_SPACING" "5.00,5.00,5.00,5.00,5.00,5.00,5.00,5.00,5.00,5.00,5.00,5.00,5.00,5.00"
					( Origin gBackEnd )
				)
				( attribute "SMDPIN_TO_BONDPAD_SPACING" "5.00,5.00,5.00,5.00,5.00,5.00,5.00,5.00,5.00,5.00,5.00,5.00,5.00,5.00"
					( Origin gBackEnd )
				)
				( attribute "LINE_TO_SMDPIN_SPACING" "4.50,4.50,4.50,4.50,4.50,4.50,4.50,4.50,4.50,4.50,4.50,4.50,4.50,4.50"
					( Origin gBackEnd )
				)
				( attribute "SHAPE_TO_SMDPIN_SPACING" "5.00,5.00,5.00,5.00,5.00,5.00,5.00,5.00,5.00,5.00,5.00,5.00,5.00,5.00"
					( Origin gBackEnd )
				)
				( attribute "TESTPIN_TO_TESTPIN_SPACING" "5.00,5.00,5.00,5.00,5.00,5.00,5.00,5.00,5.00,5.00,5.00,5.00,5.00,5.00"
					( Origin gBackEnd )
				)
				( attribute "TESTPIN_TO_THRUVIA_SPACING" "5.00,5.00,5.00,5.00,5.00,5.00,5.00,5.00,5.00,5.00,5.00,5.00,5.00,5.00"
					( Origin gBackEnd )
				)
				( attribute "TESTPIN_TO_TESTVIA_SPACING" "5.00,5.00,5.00,5.00,5.00,5.00,5.00,5.00,5.00,5.00,5.00,5.00,5.00,5.00"
					( Origin gBackEnd )
				)
				( attribute "BBV_TO_TESTPIN_SPACING" "5.00,5.00,5.00,5.00,5.00,5.00,5.00,5.00,5.00,5.00,5.00,5.00,5.00,5.00"
					( Origin gBackEnd )
				)
				( attribute "BONDPAD_TO_TESTPIN_SPACING" "5.00,5.00,5.00,5.00,5.00,5.00,5.00,5.00,5.00,5.00,5.00,5.00,5.00,5.00"
					( Origin gBackEnd )
				)
				( attribute "LINE_TO_TESTPIN_SPACING" "4.50,5.00,5.00,5.00,5.00,5.00,5.00,5.00,5.00,5.00,5.00,5.00,5.00,5.00"
					( Origin gBackEnd )
				)
				( attribute "SHAPE_TO_TESTPIN_SPACING" "4.50,4.00,4.00,4.00,4.00,4.00,4.00,4.00,4.00,4.00,4.00,4.00,4.00,4.00"
					( Origin gBackEnd )
				)
				( attribute "THRUVIA_TO_THRUVIA_SPACING" "5.00,5.00,5.00,5.00,5.00,5.00,5.00,5.00,5.00,5.00,5.00,5.00,5.00,5.00"
					( Origin gBackEnd )
				)
				( attribute "TESTVIA_TO_THRUVIA_SPACING" "5.00,5.00,5.00,5.00,5.00,5.00,5.00,5.00,5.00,5.00,5.00,5.00,5.00,5.00"
					( Origin gBackEnd )
				)
				( attribute "BBV_TO_THRUVIA_SPACING" "5.00,5.00,5.00,5.00,5.00,5.00,5.00,5.00,5.00,5.00,5.00,5.00,5.00,5.00"
					( Origin gBackEnd )
				)
				( attribute "BONDPAD_TO_THRUVIA_SPACING" "5.00,5.00,5.00,5.00,5.00,5.00,5.00,5.00,5.00,5.00,5.00,5.00,5.00,5.00"
					( Origin gBackEnd )
				)
				( attribute "LINE_TO_THRUVIA_SPACING" "4.50,4.00,4.00,4.00,4.00,4.00,4.00,4.00,4.00,4.00,4.00,4.00,4.00,4.50"
					( Origin gBackEnd )
				)
				( attribute "SHAPE_TO_THRUVIA_SPACING" "4.50,4.00,4.00,4.00,4.00,4.00,4.00,4.00,4.00,4.00,4.00,4.00,4.00,4.00"
					( Origin gBackEnd )
				)
				( attribute "TESTVIA_TO_TESTVIA_SPACING" "5.00,5.00,5.00,5.00,5.00,5.00,5.00,5.00,5.00,5.00,5.00,5.00,5.00,5.00"
					( Origin gBackEnd )
				)
				( attribute "BBV_TO_TESTVIA_SPACING" "5.00,5.00,5.00,5.00,5.00,5.00,5.00,5.00,5.00,5.00,5.00,5.00,5.00,5.00"
					( Origin gBackEnd )
				)
				( attribute "BONDPAD_TO_TESTVIA_SPACING" "5.00,5.00,5.00,5.00,5.00,5.00,5.00,5.00,5.00,5.00,5.00,5.00,5.00,5.00"
					( Origin gBackEnd )
				)
				( attribute "LINE_TO_TESTVIA_SPACING" "4.50,5.00,4.00,5.00,4.00,5.00,5.00,5.00,5.00,4.00,5.00,4.00,5.00,4.50"
					( Origin gBackEnd )
				)
				( attribute "SHAPE_TO_TESTVIA_SPACING" "4.50,4.00,4.00,4.00,4.00,4.00,4.00,4.00,4.00,4.00,4.00,4.00,4.00,4.00"
					( Origin gBackEnd )
				)
				( attribute "BBV_TO_BBV_SPACING" "5.00,5.00,5.00,5.00,5.00,5.00,5.00,5.00,5.00,5.00,5.00,5.00,5.00,5.00"
					( Origin gBackEnd )
				)
				( attribute "BONDPAD_TO_BBV_SPACING" "5.00,5.00,5.00,5.00,5.00,5.00,5.00,5.00,5.00,5.00,5.00,5.00,5.00,5.00"
					( Origin gBackEnd )
				)
				( attribute "BBV_TO_LINE_SPACING" "5.00,5.00,5.00,5.00,5.00,5.00,5.00,5.00,5.00,5.00,5.00,5.00,5.00,5.00"
					( Origin gBackEnd )
				)
				( attribute "BBV_TO_SHAPE_SPACING" "5.00,5.00,5.00,5.00,5.00,5.00,5.00,5.00,5.00,5.00,5.00,5.00,5.00,5.00"
					( Origin gBackEnd )
				)
				( attribute "BONDPAD_TO_BONDPAD_SPACING" "5.00,5.00,5.00,5.00,5.00,5.00,5.00,5.00,5.00,5.00,5.00,5.00,5.00,5.00"
					( Origin gBackEnd )
				)
				( attribute "BONDPAD_TO_LINE_SPACING" "5.00,5.00,5.00,5.00,5.00,5.00,5.00,5.00,5.00,5.00,5.00,5.00,5.00,5.00"
					( Origin gBackEnd )
				)
				( attribute "BONDPAD_TO_SHAPE_SPACING" "5.00,5.00,5.00,5.00,5.00,5.00,5.00,5.00,5.00,5.00,5.00,5.00,5.00,5.00"
					( Origin gBackEnd )
				)
				( attribute "LINE_TO_LINE_SPACING" "25.00,25.00,25.00,25.00,25.00,25.00,25.00,25.00,25.00,25.00,25.00,25.00,25.00,25.00"
					( Origin gBackEnd )
				)
				( attribute "LINE_TO_SHAPE_SPACING" "5.00,5.00,5.00,5.00,5.00,5.00,5.00,5.00,5.00,5.00,5.00,5.00,5.00,5.00"
					( Origin gBackEnd )
				)
				( attribute "SHAPE_TO_SHAPE_SPACING" "10.00,10.00,10.00,10.00,10.00,10.00,10.00,10.00,10.00,10.00,10.00,10.00,10.00,10.00"
					( Origin gBackEnd )
				)
				( attribute "HOLE_TO_PIN_SPACING" "8.00,8.00,8.00,8.00,8.00,8.00,8.00,8.00,8.00,8.00,8.00,8.00,8.00,8.00"
					( Origin gBackEnd )
				)
				( attribute "HOLE_TO_VIA_SPACING" "8.00,8.00,8.00,8.00,8.00,8.00,8.00,8.00,8.00,8.00,8.00,8.00,8.00,8.00"
					( Origin gBackEnd )
				)
				( attribute "HOLE_TO_LINE_SPACING" "8.00,8.00,8.00,8.00,8.00,8.00,8.00,8.00,8.00,8.00,8.00,8.00,8.00,8.00"
					( Origin gBackEnd )
				)
				( attribute "HOLE_TO_SHAPE_SPACING" "8.00,8.00,8.00,8.00,8.00,8.00,8.00,8.00,8.00,8.00,8.00,8.00,8.00,8.00"
					( Origin gBackEnd )
				)
				( attribute "HOLE_TO_HOLE_SPACING" "8.00,8.00,8.00,8.00,8.00,8.00,8.00,8.00,8.00,8.00,8.00,8.00,8.00,8.00"
					( Origin gBackEnd )
				)
				( attribute "MVIA_TO_MVIA_SPACING" "5.00,5.00,5.00,5.00,5.00,5.00,5.00,5.00,5.00,5.00,5.00,5.00,5.00,5.00"
					( Origin gBackEnd )
				)
				( attribute "MVIA_TO_THRUPIN_SPACING" "5.00,5.00,5.00,5.00,5.00,5.00,5.00,5.00,5.00,5.00,5.00,5.00,5.00,5.00"
					( Origin gBackEnd )
				)
				( attribute "MVIA_TO_SMDPIN_SPACING" "5.00,5.00,5.00,5.00,5.00,5.00,5.00,5.00,5.00,5.00,5.00,5.00,5.00,5.00"
					( Origin gBackEnd )
				)
				( attribute "MVIA_TO_THRUVIA_SPACING" "5.00,5.00,5.00,5.00,5.00,5.00,5.00,5.00,5.00,5.00,5.00,5.00,5.00,5.00"
					( Origin gBackEnd )
				)
				( attribute "MVIA_TO_BBV_SPACING" "5.00,5.00,5.00,5.00,5.00,5.00,5.00,5.00,5.00,5.00,5.00,5.00,5.00,5.00"
					( Origin gBackEnd )
				)
				( attribute "MVIA_TO_LINE_SPACING" "5.00,5.00,5.00,5.00,5.00,5.00,5.00,5.00,5.00,5.00,5.00,5.00,5.00,5.00"
					( Origin gBackEnd )
				)
				( attribute "MVIA_TO_SHAPE_SPACING" "5.00,5.00,5.00,5.00,5.00,5.00,5.00,5.00,5.00,5.00,5.00,5.00,5.00,5.00"
					( Origin gBackEnd )
				)
				( attribute "MVIA_TO_TESTPIN_SPACING" "5.00,5.00,5.00,5.00,5.00,5.00,5.00,5.00,5.00,5.00,5.00,5.00,5.00,5.00"
					( Origin gBackEnd )
				)
				( attribute "MVIA_TO_TESTVIA_SPACING" "5.00,5.00,5.00,5.00,5.00,5.00,5.00,5.00,5.00,5.00,5.00,5.00,5.00,5.00"
					( Origin gBackEnd )
				)
				( attribute "BONDPAD_TO_MVIA_SPACING" "5.00,5.00,5.00,5.00,5.00,5.00,5.00,5.00,5.00,5.00,5.00,5.00,5.00,5.00"
					( Origin gBackEnd )
				)
				( attribute "MIN_BVIA_GAP" "5.00"
					( Origin gBackEnd )
				)
				( attribute "BONDPAD_TO_BONDPAD_DIFFP_SPC" "5.00,5.00,5.00,5.00,5.00,5.00,5.00,5.00,5.00,5.00,5.00,5.00,5.00,5.00"
					( Origin gBackEnd )
				)
				( objectStatus "25_MILS" )
			)
			( spacingCSet "@sapphirecity_baseboard_lib.sapphirecity_baseboard(sch_1):\11H_US_AND_5H_SL_VIA+2H_A\"
				( attribute "THRUPIN_TO_THRUPIN_SPACING" "5.00,5.00,5.00,5.00,5.00,5.00,5.00,5.00,5.00,5.00,5.00,5.00,5.00,5.00"
					( Origin gBackEnd )
				)
				( attribute "THRUPIN_TO_SMDPIN_SPACING" "5.00,5.00,5.00,5.00,5.00,5.00,5.00,5.00,5.00,5.00,5.00,5.00,5.00,5.00"
					( Origin gBackEnd )
				)
				( attribute "TESTPIN_TO_THRUPIN_SPACING" "5.00,5.00,5.00,5.00,5.00,5.00,5.00,5.00,5.00,5.00,5.00,5.00,5.00,5.00"
					( Origin gBackEnd )
				)
				( attribute "THRUPIN_TO_THRUVIA_SPACING" "5.00,5.00,5.00,5.00,5.00,5.00,5.00,5.00,5.00,5.00,5.00,5.00,5.00,5.00"
					( Origin gBackEnd )
				)
				( attribute "TESTVIA_TO_THRUPIN_SPACING" "5.00,5.00,5.00,5.00,5.00,5.00,5.00,5.00,5.00,5.00,5.00,5.00,5.00,5.00"
					( Origin gBackEnd )
				)
				( attribute "BBV_TO_THRUPIN_SPACING" "5.00,5.00,5.00,5.00,5.00,5.00,5.00,5.00,5.00,5.00,5.00,5.00,5.00,5.00"
					( Origin gBackEnd )
				)
				( attribute "THRUPIN_TO_BONDPAD_SPACING" "5.00,5.00,5.00,5.00,5.00,5.00,5.00,5.00,5.00,5.00,5.00,5.00,5.00,5.00"
					( Origin gBackEnd )
				)
				( attribute "LINE_TO_THRUPIN_SPACING" "4.50,4.00,4.00,4.00,4.00,4.00,4.00,4.00,4.00,4.00,4.00,4.00,4.00,4.50"
					( Origin gBackEnd )
				)
				( attribute "THRUPIN_TO_SHAPE_SPACING" "4.50,4.00,4.00,4.00,4.00,4.00,4.00,4.00,4.00,4.00,4.00,4.00,4.00,4.00"
					( Origin gBackEnd )
				)
				( attribute "SMDPIN_TO_SMDPIN_SPACING" "5.00,5.00,5.00,5.00,5.00,5.00,5.00,5.00,5.00,5.00,5.00,5.00,5.00,5.00"
					( Origin gBackEnd )
				)
				( attribute "SMDPIN_TO_TESTPIN_SPACING" "5.00,5.00,5.00,5.00,5.00,5.00,5.00,5.00,5.00,5.00,5.00,5.00,5.00,5.00"
					( Origin gBackEnd )
				)
				( attribute "SMDPIN_TO_THRUVIA_SPACING" "5.00,5.00,5.00,5.00,5.00,5.00,5.00,5.00,5.00,5.00,5.00,5.00,5.00,5.00"
					( Origin gBackEnd )
				)
				( attribute "SMDPIN_TO_TESTVIA_SPACING" "5.00,5.00,5.00,5.00,5.00,5.00,5.00,5.00,5.00,5.00,5.00,5.00,5.00,5.00"
					( Origin gBackEnd )
				)
				( attribute "BBV_TO_SMDPIN_SPACING" "5.00,5.00,5.00,5.00,5.00,5.00,5.00,5.00,5.00,5.00,5.00,5.00,5.00,5.00"
					( Origin gBackEnd )
				)
				( attribute "SMDPIN_TO_BONDPAD_SPACING" "5.00,5.00,5.00,5.00,5.00,5.00,5.00,5.00,5.00,5.00,5.00,5.00,5.00,5.00"
					( Origin gBackEnd )
				)
				( attribute "LINE_TO_SMDPIN_SPACING" "4.50,4.50,4.50,4.50,4.50,4.50,4.50,4.50,4.50,4.50,4.50,4.50,4.50,4.50"
					( Origin gBackEnd )
				)
				( attribute "SHAPE_TO_SMDPIN_SPACING" "5.00,5.00,5.00,5.00,5.00,5.00,5.00,5.00,5.00,5.00,5.00,5.00,5.00,5.00"
					( Origin gBackEnd )
				)
				( attribute "TESTPIN_TO_TESTPIN_SPACING" "5.00,5.00,5.00,5.00,5.00,5.00,5.00,5.00,5.00,5.00,5.00,5.00,5.00,5.00"
					( Origin gBackEnd )
				)
				( attribute "TESTPIN_TO_THRUVIA_SPACING" "5.00,5.00,5.00,5.00,5.00,5.00,5.00,5.00,5.00,5.00,5.00,5.00,5.00,5.00"
					( Origin gBackEnd )
				)
				( attribute "TESTPIN_TO_TESTVIA_SPACING" "5.00,5.00,5.00,5.00,5.00,5.00,5.00,5.00,5.00,5.00,5.00,5.00,5.00,5.00"
					( Origin gBackEnd )
				)
				( attribute "BBV_TO_TESTPIN_SPACING" "5.00,5.00,5.00,5.00,5.00,5.00,5.00,5.00,5.00,5.00,5.00,5.00,5.00,5.00"
					( Origin gBackEnd )
				)
				( attribute "BONDPAD_TO_TESTPIN_SPACING" "5.00,5.00,5.00,5.00,5.00,5.00,5.00,5.00,5.00,5.00,5.00,5.00,5.00,5.00"
					( Origin gBackEnd )
				)
				( attribute "LINE_TO_TESTPIN_SPACING" "4.50,5.00,5.00,5.00,5.00,5.00,5.00,5.00,5.00,5.00,5.00,5.00,5.00,5.00"
					( Origin gBackEnd )
				)
				( attribute "SHAPE_TO_TESTPIN_SPACING" "4.50,4.00,4.00,4.00,4.00,4.00,4.00,4.00,4.00,4.00,4.00,4.00,4.00,4.00"
					( Origin gBackEnd )
				)
				( attribute "THRUVIA_TO_THRUVIA_SPACING" "5.00,5.00,5.00,5.00,5.00,5.00,5.00,5.00,5.00,5.00,5.00,5.00,5.00,5.00"
					( Origin gBackEnd )
				)
				( attribute "TESTVIA_TO_THRUVIA_SPACING" "5.00,5.00,5.00,5.00,5.00,5.00,5.00,5.00,5.00,5.00,5.00,5.00,5.00,5.00"
					( Origin gBackEnd )
				)
				( attribute "BBV_TO_THRUVIA_SPACING" "5.00,5.00,5.00,5.00,5.00,5.00,5.00,5.00,5.00,5.00,5.00,5.00,5.00,5.00"
					( Origin gBackEnd )
				)
				( attribute "BONDPAD_TO_THRUVIA_SPACING" "5.00,5.00,5.00,5.00,5.00,5.00,5.00,5.00,5.00,5.00,5.00,5.00,5.00,5.00"
					( Origin gBackEnd )
				)
				( attribute "LINE_TO_THRUVIA_SPACING" "9.40,5.00,10.00,5.00,10.00,5.00,5.00,5.00,5.00,10.00,5.00,10.00,5.00,9.40"
					( Origin gBackEnd )
				)
				( attribute "SHAPE_TO_THRUVIA_SPACING" "4.50,4.00,4.00,4.00,4.00,4.00,4.00,4.00,4.00,4.00,4.00,4.00,4.00,4.00"
					( Origin gBackEnd )
				)
				( attribute "TESTVIA_TO_TESTVIA_SPACING" "5.00,5.00,5.00,5.00,5.00,5.00,5.00,5.00,5.00,5.00,5.00,5.00,5.00,5.00"
					( Origin gBackEnd )
				)
				( attribute "BBV_TO_TESTVIA_SPACING" "5.00,5.00,5.00,5.00,5.00,5.00,5.00,5.00,5.00,5.00,5.00,5.00,5.00,5.00"
					( Origin gBackEnd )
				)
				( attribute "BONDPAD_TO_TESTVIA_SPACING" "5.00,5.00,5.00,5.00,5.00,5.00,5.00,5.00,5.00,5.00,5.00,5.00,5.00,5.00"
					( Origin gBackEnd )
				)
				( attribute "LINE_TO_TESTVIA_SPACING" "9.40,5.00,10.00,5.00,10.00,5.00,5.00,5.00,5.00,10.00,5.00,10.00,5.00,9.40"
					( Origin gBackEnd )
				)
				( attribute "SHAPE_TO_TESTVIA_SPACING" "4.50,4.00,4.00,4.00,4.00,4.00,4.00,4.00,4.00,4.00,4.00,4.00,4.00,4.00"
					( Origin gBackEnd )
				)
				( attribute "BBV_TO_BBV_SPACING" "5.00,5.00,5.00,5.00,5.00,5.00,5.00,5.00,5.00,5.00,5.00,5.00,5.00,5.00"
					( Origin gBackEnd )
				)
				( attribute "BONDPAD_TO_BBV_SPACING" "5.00,5.00,5.00,5.00,5.00,5.00,5.00,5.00,5.00,5.00,5.00,5.00,5.00,5.00"
					( Origin gBackEnd )
				)
				( attribute "BBV_TO_LINE_SPACING" "5.00,5.00,5.00,5.00,5.00,5.00,5.00,5.00,5.00,5.00,5.00,5.00,5.00,5.00"
					( Origin gBackEnd )
				)
				( attribute "BBV_TO_SHAPE_SPACING" "5.00,5.00,5.00,5.00,5.00,5.00,5.00,5.00,5.00,5.00,5.00,5.00,5.00,5.00"
					( Origin gBackEnd )
				)
				( attribute "BONDPAD_TO_BONDPAD_SPACING" "5.00,5.00,5.00,5.00,5.00,5.00,5.00,5.00,5.00,5.00,5.00,5.00,5.00,5.00"
					( Origin gBackEnd )
				)
				( attribute "BONDPAD_TO_LINE_SPACING" "5.00,5.00,5.00,5.00,5.00,5.00,5.00,5.00,5.00,5.00,5.00,5.00,5.00,5.00"
					( Origin gBackEnd )
				)
				( attribute "BONDPAD_TO_SHAPE_SPACING" "5.00,5.00,5.00,5.00,5.00,5.00,5.00,5.00,5.00,5.00,5.00,5.00,5.00,5.00"
					( Origin gBackEnd )
				)
				( attribute "LINE_TO_LINE_SPACING" "29.37,15.00,15.00,15.00,15.00,15.00,15.00,15.00,15.00,15.00,15.00,15.00,15.00,29.37"
					( Origin gBackEnd )
				)
				( attribute "LINE_TO_SHAPE_SPACING" "5.00,5.00,5.00,5.00,5.00,5.00,5.00,5.00,5.00,5.00,5.00,5.00,5.00,5.00"
					( Origin gBackEnd )
				)
				( attribute "SHAPE_TO_SHAPE_SPACING" "10.00,10.00,10.00,10.00,10.00,10.00,10.00,10.00,10.00,10.00,10.00,10.00,10.00,10.00"
					( Origin gBackEnd )
				)
				( attribute "HOLE_TO_PIN_SPACING" "8.00,8.00,8.00,8.00,8.00,8.00,8.00,8.00,8.00,8.00,8.00,8.00,8.00,8.00"
					( Origin gBackEnd )
				)
				( attribute "HOLE_TO_VIA_SPACING" "8.00,8.00,8.00,8.00,8.00,8.00,8.00,8.00,8.00,8.00,8.00,8.00,8.00,8.00"
					( Origin gBackEnd )
				)
				( attribute "HOLE_TO_LINE_SPACING" "8.00,8.00,8.00,8.00,8.00,8.00,8.00,8.00,8.00,8.00,8.00,8.00,8.00,8.00"
					( Origin gBackEnd )
				)
				( attribute "HOLE_TO_SHAPE_SPACING" "8.00,8.00,8.00,8.00,8.00,8.00,8.00,8.00,8.00,8.00,8.00,8.00,8.00,8.00"
					( Origin gBackEnd )
				)
				( attribute "HOLE_TO_HOLE_SPACING" "8.00,8.00,8.00,8.00,8.00,8.00,8.00,8.00,8.00,8.00,8.00,8.00,8.00,8.00"
					( Origin gBackEnd )
				)
				( attribute "MVIA_TO_MVIA_SPACING" "5.00,5.00,5.00,5.00,5.00,5.00,5.00,5.00,5.00,5.00,5.00,5.00,5.00,5.00"
					( Origin gBackEnd )
				)
				( attribute "MVIA_TO_THRUPIN_SPACING" "5.00,5.00,5.00,5.00,5.00,5.00,5.00,5.00,5.00,5.00,5.00,5.00,5.00,5.00"
					( Origin gBackEnd )
				)
				( attribute "MVIA_TO_SMDPIN_SPACING" "5.00,5.00,5.00,5.00,5.00,5.00,5.00,5.00,5.00,5.00,5.00,5.00,5.00,5.00"
					( Origin gBackEnd )
				)
				( attribute "MVIA_TO_THRUVIA_SPACING" "5.00,5.00,5.00,5.00,5.00,5.00,5.00,5.00,5.00,5.00,5.00,5.00,5.00,5.00"
					( Origin gBackEnd )
				)
				( attribute "MVIA_TO_BBV_SPACING" "5.00,5.00,5.00,5.00,5.00,5.00,5.00,5.00,5.00,5.00,5.00,5.00,5.00,5.00"
					( Origin gBackEnd )
				)
				( attribute "MVIA_TO_LINE_SPACING" "5.00,5.00,5.00,5.00,5.00,5.00,5.00,5.00,5.00,5.00,5.00,5.00,5.00,5.00"
					( Origin gBackEnd )
				)
				( attribute "MVIA_TO_SHAPE_SPACING" "5.00,5.00,5.00,5.00,5.00,5.00,5.00,5.00,5.00,5.00,5.00,5.00,5.00,5.00"
					( Origin gBackEnd )
				)
				( attribute "MVIA_TO_TESTPIN_SPACING" "5.00,5.00,5.00,5.00,5.00,5.00,5.00,5.00,5.00,5.00,5.00,5.00,5.00,5.00"
					( Origin gBackEnd )
				)
				( attribute "MVIA_TO_TESTVIA_SPACING" "5.00,5.00,5.00,5.00,5.00,5.00,5.00,5.00,5.00,5.00,5.00,5.00,5.00,5.00"
					( Origin gBackEnd )
				)
				( attribute "BONDPAD_TO_MVIA_SPACING" "5.00,5.00,5.00,5.00,5.00,5.00,5.00,5.00,5.00,5.00,5.00,5.00,5.00,5.00"
					( Origin gBackEnd )
				)
				( attribute "MIN_BVIA_GAP" "5.00"
					( Origin gBackEnd )
				)
				( attribute "BONDPAD_TO_BONDPAD_DIFFP_SPC" "5.00,5.00,5.00,5.00,5.00,5.00,5.00,5.00,5.00,5.00,5.00,5.00,5.00,5.00"
					( Origin gBackEnd )
				)
				( objectStatus "11H_US_&_5H_SL_VIA_2H+A" )
			)
			( spacingCSet "@sapphirecity_baseboard_lib.sapphirecity_baseboard(sch_1):\15_MILS\"
				( attribute "THRUPIN_TO_THRUPIN_SPACING" "5.00,5.00,5.00,5.00,5.00,5.00,5.00,5.00,5.00,5.00,5.00,5.00,5.00,5.00"
					( Origin gBackEnd )
				)
				( attribute "THRUPIN_TO_SMDPIN_SPACING" "5.00,5.00,5.00,5.00,5.00,5.00,5.00,5.00,5.00,5.00,5.00,5.00,5.00,5.00"
					( Origin gBackEnd )
				)
				( attribute "TESTPIN_TO_THRUPIN_SPACING" "5.00,5.00,5.00,5.00,5.00,5.00,5.00,5.00,5.00,5.00,5.00,5.00,5.00,5.00"
					( Origin gBackEnd )
				)
				( attribute "THRUPIN_TO_THRUVIA_SPACING" "5.00,5.00,5.00,5.00,5.00,5.00,5.00,5.00,5.00,5.00,5.00,5.00,5.00,5.00"
					( Origin gBackEnd )
				)
				( attribute "TESTVIA_TO_THRUPIN_SPACING" "5.00,5.00,5.00,5.00,5.00,5.00,5.00,5.00,5.00,5.00,5.00,5.00,5.00,5.00"
					( Origin gBackEnd )
				)
				( attribute "BBV_TO_THRUPIN_SPACING" "5.00,5.00,5.00,5.00,5.00,5.00,5.00,5.00,5.00,5.00,5.00,5.00,5.00,5.00"
					( Origin gBackEnd )
				)
				( attribute "THRUPIN_TO_BONDPAD_SPACING" "5.00,5.00,5.00,5.00,5.00,5.00,5.00,5.00,5.00,5.00,5.00,5.00,5.00,5.00"
					( Origin gBackEnd )
				)
				( attribute "LINE_TO_THRUPIN_SPACING" "4.50,4.00,4.00,4.00,4.00,4.00,4.00,4.00,4.00,4.00,4.00,4.00,4.00,4.50"
					( Origin gBackEnd )
				)
				( attribute "THRUPIN_TO_SHAPE_SPACING" "4.50,4.00,4.00,4.00,4.00,4.00,4.00,4.00,4.00,4.00,4.00,4.00,4.00,4.00"
					( Origin gBackEnd )
				)
				( attribute "SMDPIN_TO_SMDPIN_SPACING" "5.00,5.00,5.00,5.00,5.00,5.00,5.00,5.00,5.00,5.00,5.00,5.00,5.00,5.00"
					( Origin gBackEnd )
				)
				( attribute "SMDPIN_TO_TESTPIN_SPACING" "5.00,5.00,5.00,5.00,5.00,5.00,5.00,5.00,5.00,5.00,5.00,5.00,5.00,25.00"
					( Origin gBackEnd )
				)
				( attribute "SMDPIN_TO_THRUVIA_SPACING" "5.00,5.00,5.00,5.00,5.00,5.00,5.00,5.00,5.00,5.00,5.00,5.00,5.00,5.00"
					( Origin gBackEnd )
				)
				( attribute "SMDPIN_TO_TESTVIA_SPACING" "5.00,5.00,5.00,5.00,5.00,5.00,5.00,5.00,5.00,5.00,5.00,5.00,5.00,5.00"
					( Origin gBackEnd )
				)
				( attribute "BBV_TO_SMDPIN_SPACING" "5.00,5.00,5.00,5.00,5.00,5.00,5.00,5.00,5.00,5.00,5.00,5.00,5.00,5.00"
					( Origin gBackEnd )
				)
				( attribute "SMDPIN_TO_BONDPAD_SPACING" "5.00,5.00,5.00,5.00,5.00,5.00,5.00,5.00,5.00,5.00,5.00,5.00,5.00,5.00"
					( Origin gBackEnd )
				)
				( attribute "LINE_TO_SMDPIN_SPACING" "4.50,4.50,4.50,4.50,4.50,4.50,4.50,4.50,4.50,4.50,4.50,4.50,4.50,4.50"
					( Origin gBackEnd )
				)
				( attribute "SHAPE_TO_SMDPIN_SPACING" "5.00,5.00,5.00,5.00,5.00,5.00,5.00,5.00,5.00,5.00,5.00,5.00,5.00,5.00"
					( Origin gBackEnd )
				)
				( attribute "TESTPIN_TO_TESTPIN_SPACING" "5.00,5.00,5.00,5.00,5.00,5.00,5.00,5.00,5.00,5.00,5.00,5.00,5.00,5.00"
					( Origin gBackEnd )
				)
				( attribute "TESTPIN_TO_THRUVIA_SPACING" "5.00,5.00,5.00,5.00,5.00,5.00,5.00,5.00,5.00,5.00,5.00,5.00,5.00,5.00"
					( Origin gBackEnd )
				)
				( attribute "TESTPIN_TO_TESTVIA_SPACING" "5.00,5.00,5.00,5.00,5.00,5.00,5.00,5.00,5.00,5.00,5.00,5.00,5.00,5.00"
					( Origin gBackEnd )
				)
				( attribute "BBV_TO_TESTPIN_SPACING" "5.00,5.00,5.00,5.00,5.00,5.00,5.00,5.00,5.00,5.00,5.00,5.00,5.00,5.00"
					( Origin gBackEnd )
				)
				( attribute "BONDPAD_TO_TESTPIN_SPACING" "5.00,5.00,5.00,5.00,5.00,5.00,5.00,5.00,5.00,5.00,5.00,5.00,5.00,5.00"
					( Origin gBackEnd )
				)
				( attribute "LINE_TO_TESTPIN_SPACING" "4.50,5.00,5.00,5.00,5.00,5.00,5.00,5.00,5.00,5.00,5.00,5.00,5.00,5.00"
					( Origin gBackEnd )
				)
				( attribute "SHAPE_TO_TESTPIN_SPACING" "4.50,4.00,4.00,4.00,4.00,4.00,4.00,4.00,4.00,4.00,4.00,4.00,4.00,4.00"
					( Origin gBackEnd )
				)
				( attribute "THRUVIA_TO_THRUVIA_SPACING" "5.00,5.00,5.00,5.00,5.00,5.00,5.00,5.00,5.00,5.00,5.00,5.00,5.00,5.00"
					( Origin gBackEnd )
				)
				( attribute "TESTVIA_TO_THRUVIA_SPACING" "5.00,5.00,5.00,5.00,5.00,5.00,5.00,5.00,5.00,5.00,5.00,5.00,5.00,5.00"
					( Origin gBackEnd )
				)
				( attribute "BBV_TO_THRUVIA_SPACING" "5.00,5.00,5.00,5.00,5.00,5.00,5.00,5.00,5.00,5.00,5.00,5.00,5.00,5.00"
					( Origin gBackEnd )
				)
				( attribute "BONDPAD_TO_THRUVIA_SPACING" "5.00,5.00,5.00,5.00,5.00,5.00,5.00,5.00,5.00,5.00,5.00,5.00,5.00,5.00"
					( Origin gBackEnd )
				)
				( attribute "LINE_TO_THRUVIA_SPACING" "4.50,4.00,4.00,4.00,4.00,4.00,4.00,4.00,4.00,4.00,4.00,4.00,4.00,4.50"
					( Origin gBackEnd )
				)
				( attribute "SHAPE_TO_THRUVIA_SPACING" "4.50,4.00,4.00,4.00,4.00,4.00,4.00,4.00,4.00,4.00,4.00,4.00,4.00,4.00"
					( Origin gBackEnd )
				)
				( attribute "TESTVIA_TO_TESTVIA_SPACING" "5.00,5.00,5.00,5.00,5.00,5.00,5.00,5.00,5.00,5.00,5.00,5.00,5.00,5.00"
					( Origin gBackEnd )
				)
				( attribute "BBV_TO_TESTVIA_SPACING" "5.00,5.00,5.00,5.00,5.00,5.00,5.00,5.00,5.00,5.00,5.00,5.00,5.00,5.00"
					( Origin gBackEnd )
				)
				( attribute "BONDPAD_TO_TESTVIA_SPACING" "5.00,5.00,5.00,5.00,5.00,5.00,5.00,5.00,5.00,5.00,5.00,5.00,5.00,5.00"
					( Origin gBackEnd )
				)
				( attribute "LINE_TO_TESTVIA_SPACING" "4.50,5.00,4.00,5.00,4.00,5.00,5.00,5.00,5.00,4.00,5.00,4.00,5.00,4.50"
					( Origin gBackEnd )
				)
				( attribute "SHAPE_TO_TESTVIA_SPACING" "4.50,4.00,4.00,4.00,4.00,4.00,4.00,4.00,4.00,4.00,4.00,4.00,4.00,4.00"
					( Origin gBackEnd )
				)
				( attribute "BBV_TO_BBV_SPACING" "5.00,5.00,5.00,5.00,5.00,5.00,5.00,5.00,5.00,5.00,5.00,5.00,5.00,5.00"
					( Origin gBackEnd )
				)
				( attribute "BONDPAD_TO_BBV_SPACING" "5.00,5.00,5.00,5.00,5.00,5.00,5.00,5.00,5.00,5.00,5.00,5.00,5.00,5.00"
					( Origin gBackEnd )
				)
				( attribute "BBV_TO_LINE_SPACING" "5.00,5.00,5.00,5.00,5.00,5.00,5.00,5.00,5.00,5.00,5.00,5.00,5.00,5.00"
					( Origin gBackEnd )
				)
				( attribute "BBV_TO_SHAPE_SPACING" "5.00,5.00,5.00,5.00,5.00,5.00,5.00,5.00,5.00,5.00,5.00,5.00,5.00,5.00"
					( Origin gBackEnd )
				)
				( attribute "BONDPAD_TO_BONDPAD_SPACING" "5.00,5.00,5.00,5.00,5.00,5.00,5.00,5.00,5.00,5.00,5.00,5.00,5.00,5.00"
					( Origin gBackEnd )
				)
				( attribute "BONDPAD_TO_LINE_SPACING" "5.00,5.00,5.00,5.00,5.00,5.00,5.00,5.00,5.00,5.00,5.00,5.00,5.00,5.00"
					( Origin gBackEnd )
				)
				( attribute "BONDPAD_TO_SHAPE_SPACING" "5.00,5.00,5.00,5.00,5.00,5.00,5.00,5.00,5.00,5.00,5.00,5.00,5.00,5.00"
					( Origin gBackEnd )
				)
				( attribute "LINE_TO_LINE_SPACING" "15.00,15.00,15.00,15.00,15.00,15.00,15.00,15.00,15.00,15.00,15.00,15.00,15.00,15.00"
					( Origin gBackEnd )
				)
				( attribute "LINE_TO_SHAPE_SPACING" "5.00,5.00,5.00,5.00,5.00,5.00,5.00,5.00,5.00,5.00,5.00,5.00,5.00,5.00"
					( Origin gBackEnd )
				)
				( attribute "SHAPE_TO_SHAPE_SPACING" "10.00,10.00,10.00,10.00,10.00,10.00,10.00,10.00,10.00,10.00,10.00,10.00,10.00,10.00"
					( Origin gBackEnd )
				)
				( attribute "HOLE_TO_PIN_SPACING" "8.00,8.00,8.00,8.00,8.00,8.00,8.00,8.00,8.00,8.00,8.00,8.00,8.00,8.00"
					( Origin gBackEnd )
				)
				( attribute "HOLE_TO_VIA_SPACING" "8.00,8.00,8.00,8.00,8.00,8.00,8.00,8.00,8.00,8.00,8.00,8.00,8.00,8.00"
					( Origin gBackEnd )
				)
				( attribute "HOLE_TO_LINE_SPACING" "8.00,8.00,8.00,8.00,8.00,8.00,8.00,8.00,8.00,8.00,8.00,8.00,8.00,8.00"
					( Origin gBackEnd )
				)
				( attribute "HOLE_TO_SHAPE_SPACING" "8.00,8.00,8.00,8.00,8.00,8.00,8.00,8.00,8.00,8.00,8.00,8.00,8.00,8.00"
					( Origin gBackEnd )
				)
				( attribute "HOLE_TO_HOLE_SPACING" "8.00,8.00,8.00,8.00,8.00,8.00,8.00,8.00,8.00,8.00,8.00,8.00,8.00,8.00"
					( Origin gBackEnd )
				)
				( attribute "MVIA_TO_MVIA_SPACING" "5.00,5.00,5.00,5.00,5.00,5.00,5.00,5.00,5.00,5.00,5.00,5.00,5.00,5.00"
					( Origin gBackEnd )
				)
				( attribute "MVIA_TO_THRUPIN_SPACING" "5.00,5.00,5.00,5.00,5.00,5.00,5.00,5.00,5.00,5.00,5.00,5.00,5.00,5.00"
					( Origin gBackEnd )
				)
				( attribute "MVIA_TO_SMDPIN_SPACING" "5.00,5.00,5.00,5.00,5.00,5.00,5.00,5.00,5.00,5.00,5.00,5.00,5.00,5.00"
					( Origin gBackEnd )
				)
				( attribute "MVIA_TO_THRUVIA_SPACING" "5.00,5.00,5.00,5.00,5.00,5.00,5.00,5.00,5.00,5.00,5.00,5.00,5.00,5.00"
					( Origin gBackEnd )
				)
				( attribute "MVIA_TO_BBV_SPACING" "5.00,5.00,5.00,5.00,5.00,5.00,5.00,5.00,5.00,5.00,5.00,5.00,5.00,5.00"
					( Origin gBackEnd )
				)
				( attribute "MVIA_TO_LINE_SPACING" "5.00,5.00,5.00,5.00,5.00,5.00,5.00,5.00,5.00,5.00,5.00,5.00,5.00,5.00"
					( Origin gBackEnd )
				)
				( attribute "MVIA_TO_SHAPE_SPACING" "5.00,5.00,5.00,5.00,5.00,5.00,5.00,5.00,5.00,5.00,5.00,5.00,5.00,5.00"
					( Origin gBackEnd )
				)
				( attribute "MVIA_TO_TESTPIN_SPACING" "5.00,5.00,5.00,5.00,5.00,5.00,5.00,5.00,5.00,5.00,5.00,5.00,5.00,5.00"
					( Origin gBackEnd )
				)
				( attribute "MVIA_TO_TESTVIA_SPACING" "5.00,5.00,5.00,5.00,5.00,5.00,5.00,5.00,5.00,5.00,5.00,5.00,5.00,5.00"
					( Origin gBackEnd )
				)
				( attribute "BONDPAD_TO_MVIA_SPACING" "5.00,5.00,5.00,5.00,5.00,5.00,5.00,5.00,5.00,5.00,5.00,5.00,5.00,5.00"
					( Origin gBackEnd )
				)
				( attribute "MIN_BVIA_GAP" "5.00"
					( Origin gBackEnd )
				)
				( attribute "BONDPAD_TO_BONDPAD_DIFFP_SPC" "5.00,5.00,5.00,5.00,5.00,5.00,5.00,5.00,5.00,5.00,5.00,5.00,5.00,5.00"
					( Origin gBackEnd )
				)
				( objectStatus "15_MILS" )
			)
			( spacingCSet "@sapphirecity_baseboard_lib.sapphirecity_baseboard(sch_1):\7H_VIA+2H\"
				( attribute "THRUPIN_TO_THRUPIN_SPACING" "5.00,5.00,5.00,5.00,5.00,5.00,5.00,5.00,5.00,5.00,5.00,5.00,5.00,5.00"
					( Origin gBackEnd )
				)
				( attribute "THRUPIN_TO_SMDPIN_SPACING" "5.00,5.00,5.00,5.00,5.00,5.00,5.00,5.00,5.00,5.00,5.00,5.00,5.00,5.00"
					( Origin gBackEnd )
				)
				( attribute "TESTPIN_TO_THRUPIN_SPACING" "5.00,5.00,5.00,5.00,5.00,5.00,5.00,5.00,5.00,5.00,5.00,5.00,5.00,5.00"
					( Origin gBackEnd )
				)
				( attribute "THRUPIN_TO_THRUVIA_SPACING" "5.00,5.00,5.00,5.00,5.00,5.00,5.00,5.00,5.00,5.00,5.00,5.00,5.00,5.00"
					( Origin gBackEnd )
				)
				( attribute "TESTVIA_TO_THRUPIN_SPACING" "5.00,5.00,5.00,5.00,5.00,5.00,5.00,5.00,5.00,5.00,5.00,5.00,5.00,5.00"
					( Origin gBackEnd )
				)
				( attribute "BBV_TO_THRUPIN_SPACING" "5.00,5.00,5.00,5.00,5.00,5.00,5.00,5.00,5.00,5.00,5.00,5.00,5.00,5.00"
					( Origin gBackEnd )
				)
				( attribute "THRUPIN_TO_BONDPAD_SPACING" "5.00,5.00,5.00,5.00,5.00,5.00,5.00,5.00,5.00,5.00,5.00,5.00,5.00,5.00"
					( Origin gBackEnd )
				)
				( attribute "LINE_TO_THRUPIN_SPACING" "4.50,4.00,4.00,4.00,4.00,4.00,4.00,4.00,4.00,4.00,4.00,4.00,4.00,4.50"
					( Origin gBackEnd )
				)
				( attribute "THRUPIN_TO_SHAPE_SPACING" "4.50,4.00,4.00,4.00,4.00,4.00,4.00,4.00,4.00,4.00,4.00,4.00,4.00,4.00"
					( Origin gBackEnd )
				)
				( attribute "SMDPIN_TO_SMDPIN_SPACING" "5.00,5.00,5.00,5.00,5.00,5.00,5.00,5.00,5.00,5.00,5.00,5.00,5.00,5.00"
					( Origin gBackEnd )
				)
				( attribute "SMDPIN_TO_TESTPIN_SPACING" "5.00,5.00,5.00,5.00,5.00,5.00,5.00,5.00,5.00,5.00,5.00,5.00,5.00,5.00"
					( Origin gBackEnd )
				)
				( attribute "SMDPIN_TO_THRUVIA_SPACING" "5.00,5.00,5.00,5.00,5.00,5.00,5.00,5.00,5.00,5.00,5.00,5.00,5.00,5.00"
					( Origin gBackEnd )
				)
				( attribute "SMDPIN_TO_TESTVIA_SPACING" "5.00,5.00,5.00,5.00,5.00,5.00,5.00,5.00,5.00,5.00,5.00,5.00,5.00,5.00"
					( Origin gBackEnd )
				)
				( attribute "BBV_TO_SMDPIN_SPACING" "5.00,5.00,5.00,5.00,5.00,5.00,5.00,5.00,5.00,5.00,5.00,5.00,5.00,5.00"
					( Origin gBackEnd )
				)
				( attribute "SMDPIN_TO_BONDPAD_SPACING" "5.00,5.00,5.00,5.00,5.00,5.00,5.00,5.00,5.00,5.00,5.00,5.00,5.00,5.00"
					( Origin gBackEnd )
				)
				( attribute "LINE_TO_SMDPIN_SPACING" "4.50,4.50,4.50,4.50,4.50,4.50,4.50,4.50,4.50,4.50,4.50,4.50,4.50,4.50"
					( Origin gBackEnd )
				)
				( attribute "SHAPE_TO_SMDPIN_SPACING" "5.00,5.00,5.00,5.00,5.00,5.00,5.00,5.00,5.00,5.00,5.00,5.00,5.00,5.00"
					( Origin gBackEnd )
				)
				( attribute "TESTPIN_TO_TESTPIN_SPACING" "5.00,5.00,5.00,5.00,5.00,5.00,5.00,5.00,5.00,5.00,5.00,5.00,5.00,5.00"
					( Origin gBackEnd )
				)
				( attribute "TESTPIN_TO_THRUVIA_SPACING" "5.00,5.00,5.00,5.00,5.00,5.00,5.00,5.00,5.00,5.00,5.00,5.00,5.00,5.00"
					( Origin gBackEnd )
				)
				( attribute "TESTPIN_TO_TESTVIA_SPACING" "5.00,5.00,5.00,5.00,5.00,5.00,5.00,5.00,5.00,5.00,5.00,5.00,5.00,5.00"
					( Origin gBackEnd )
				)
				( attribute "BBV_TO_TESTPIN_SPACING" "5.00,5.00,5.00,5.00,5.00,5.00,5.00,5.00,5.00,5.00,5.00,5.00,5.00,5.00"
					( Origin gBackEnd )
				)
				( attribute "BONDPAD_TO_TESTPIN_SPACING" "5.00,5.00,5.00,5.00,5.00,5.00,5.00,5.00,5.00,5.00,5.00,5.00,5.00,5.00"
					( Origin gBackEnd )
				)
				( attribute "LINE_TO_TESTPIN_SPACING" "4.50,5.00,5.00,5.00,5.00,5.00,5.00,5.00,5.00,5.00,5.00,5.00,5.00,5.00"
					( Origin gBackEnd )
				)
				( attribute "SHAPE_TO_TESTPIN_SPACING" "4.50,4.00,4.00,4.00,4.00,4.00,4.00,4.00,4.00,4.00,4.00,4.00,4.00,4.00"
					( Origin gBackEnd )
				)
				( attribute "THRUVIA_TO_THRUVIA_SPACING" "5.00,5.00,5.00,5.00,5.00,5.00,5.00,5.00,5.00,5.00,5.00,5.00,5.00,5.00"
					( Origin gBackEnd )
				)
				( attribute "TESTVIA_TO_THRUVIA_SPACING" "5.00,5.00,5.00,5.00,5.00,5.00,5.00,5.00,5.00,5.00,5.00,5.00,5.00,5.00"
					( Origin gBackEnd )
				)
				( attribute "BBV_TO_THRUVIA_SPACING" "5.00,5.00,5.00,5.00,5.00,5.00,5.00,5.00,5.00,5.00,5.00,5.00,5.00,5.00"
					( Origin gBackEnd )
				)
				( attribute "BONDPAD_TO_THRUVIA_SPACING" "5.00,5.00,5.00,5.00,5.00,5.00,5.00,5.00,5.00,5.00,5.00,5.00,5.00,5.00"
					( Origin gBackEnd )
				)
				( attribute "LINE_TO_THRUVIA_SPACING" "9.40,5.00,12.00,5.00,12.00,5.00,5.00,5.00,5.00,12.00,5.00,12.00,5.00,12.00"
					( Origin gBackEnd )
				)
				( attribute "SHAPE_TO_THRUVIA_SPACING" "4.50,4.00,4.00,4.00,4.00,4.00,4.00,4.00,4.00,4.00,4.00,4.00,4.00,4.00"
					( Origin gBackEnd )
				)
				( attribute "TESTVIA_TO_TESTVIA_SPACING" "5.00,5.00,5.00,5.00,5.00,5.00,5.00,5.00,5.00,5.00,5.00,5.00,5.00,5.00"
					( Origin gBackEnd )
				)
				( attribute "BBV_TO_TESTVIA_SPACING" "5.00,5.00,5.00,5.00,5.00,5.00,5.00,5.00,5.00,5.00,5.00,5.00,5.00,5.00"
					( Origin gBackEnd )
				)
				( attribute "BONDPAD_TO_TESTVIA_SPACING" "5.00,5.00,5.00,5.00,5.00,5.00,5.00,5.00,5.00,5.00,5.00,5.00,5.00,5.00"
					( Origin gBackEnd )
				)
				( attribute "LINE_TO_TESTVIA_SPACING" "10.40,5.00,13.00,5.00,13.00,5.00,5.00,5.00,5.00,13.00,5.00,13.00,5.00,13.00"
					( Origin gBackEnd )
				)
				( attribute "SHAPE_TO_TESTVIA_SPACING" "4.50,4.00,4.00,4.00,4.00,4.00,4.00,4.00,4.00,4.00,4.00,4.00,4.00,4.00"
					( Origin gBackEnd )
				)
				( attribute "BBV_TO_BBV_SPACING" "5.00,5.00,5.00,5.00,5.00,5.00,5.00,5.00,5.00,5.00,5.00,5.00,5.00,5.00"
					( Origin gBackEnd )
				)
				( attribute "BONDPAD_TO_BBV_SPACING" "5.00,5.00,5.00,5.00,5.00,5.00,5.00,5.00,5.00,5.00,5.00,5.00,5.00,5.00"
					( Origin gBackEnd )
				)
				( attribute "BBV_TO_LINE_SPACING" "5.00,5.00,5.00,5.00,5.00,5.00,5.00,5.00,5.00,5.00,5.00,5.00,5.00,5.00"
					( Origin gBackEnd )
				)
				( attribute "BBV_TO_SHAPE_SPACING" "5.00,5.00,5.00,5.00,5.00,5.00,5.00,5.00,5.00,5.00,5.00,5.00,5.00,5.00"
					( Origin gBackEnd )
				)
				( attribute "BONDPAD_TO_BONDPAD_SPACING" "5.00,5.00,5.00,5.00,5.00,5.00,5.00,5.00,5.00,5.00,5.00,5.00,5.00,5.00"
					( Origin gBackEnd )
				)
				( attribute "BONDPAD_TO_LINE_SPACING" "5.00,5.00,5.00,5.00,5.00,5.00,5.00,5.00,5.00,5.00,5.00,5.00,5.00,5.00"
					( Origin gBackEnd )
				)
				( attribute "BONDPAD_TO_SHAPE_SPACING" "5.00,5.00,5.00,5.00,5.00,5.00,5.00,5.00,5.00,5.00,5.00,5.00,5.00,5.00"
					( Origin gBackEnd )
				)
				( attribute "LINE_TO_LINE_SPACING" "18.69,21.00,21.00,21.00,21.00,21.00,21.00,21.00,21.00,21.00,21.00,21.00,21.00,18.69"
					( Origin gBackEnd )
				)
				( attribute "LINE_TO_SHAPE_SPACING" "5.00,5.00,5.00,5.00,5.00,5.00,5.00,5.00,5.00,5.00,5.00,5.00,5.00,5.00"
					( Origin gBackEnd )
				)
				( attribute "SHAPE_TO_SHAPE_SPACING" "10.00,10.00,10.00,10.00,10.00,10.00,10.00,10.00,10.00,10.00,10.00,10.00,10.00,10.00"
					( Origin gBackEnd )
				)
				( attribute "HOLE_TO_PIN_SPACING" "8.00,8.00,8.00,8.00,8.00,8.00,8.00,8.00,8.00,8.00,8.00,8.00,8.00,8.00"
					( Origin gBackEnd )
				)
				( attribute "HOLE_TO_VIA_SPACING" "8.00,8.00,8.00,8.00,8.00,8.00,8.00,8.00,8.00,8.00,8.00,8.00,8.00,8.00"
					( Origin gBackEnd )
				)
				( attribute "HOLE_TO_LINE_SPACING" "8.00,8.00,8.00,8.00,8.00,8.00,8.00,8.00,8.00,8.00,8.00,8.00,8.00,8.00"
					( Origin gBackEnd )
				)
				( attribute "HOLE_TO_SHAPE_SPACING" "8.00,8.00,8.00,8.00,8.00,8.00,8.00,8.00,8.00,8.00,8.00,8.00,8.00,8.00"
					( Origin gBackEnd )
				)
				( attribute "HOLE_TO_HOLE_SPACING" "8.00,8.00,8.00,8.00,8.00,8.00,8.00,8.00,8.00,8.00,8.00,8.00,8.00,8.00"
					( Origin gBackEnd )
				)
				( attribute "MVIA_TO_MVIA_SPACING" "5.00,5.00,5.00,5.00,5.00,5.00,5.00,5.00,5.00,5.00,5.00,5.00,5.00,5.00"
					( Origin gBackEnd )
				)
				( attribute "MVIA_TO_THRUPIN_SPACING" "5.00,5.00,5.00,5.00,5.00,5.00,5.00,5.00,5.00,5.00,5.00,5.00,5.00,5.00"
					( Origin gBackEnd )
				)
				( attribute "MVIA_TO_SMDPIN_SPACING" "5.00,5.00,5.00,5.00,5.00,5.00,5.00,5.00,5.00,5.00,5.00,5.00,5.00,5.00"
					( Origin gBackEnd )
				)
				( attribute "MVIA_TO_THRUVIA_SPACING" "5.00,5.00,5.00,5.00,5.00,5.00,5.00,5.00,5.00,5.00,5.00,5.00,5.00,5.00"
					( Origin gBackEnd )
				)
				( attribute "MVIA_TO_BBV_SPACING" "5.00,5.00,5.00,5.00,5.00,5.00,5.00,5.00,5.00,5.00,5.00,5.00,5.00,5.00"
					( Origin gBackEnd )
				)
				( attribute "MVIA_TO_LINE_SPACING" "5.00,5.00,5.00,5.00,5.00,5.00,5.00,5.00,5.00,5.00,5.00,5.00,5.00,5.00"
					( Origin gBackEnd )
				)
				( attribute "MVIA_TO_SHAPE_SPACING" "5.00,5.00,5.00,5.00,5.00,5.00,5.00,5.00,5.00,5.00,5.00,5.00,5.00,5.00"
					( Origin gBackEnd )
				)
				( attribute "MVIA_TO_TESTPIN_SPACING" "5.00,5.00,5.00,5.00,5.00,5.00,5.00,5.00,5.00,5.00,5.00,5.00,5.00,5.00"
					( Origin gBackEnd )
				)
				( attribute "MVIA_TO_TESTVIA_SPACING" "5.00,5.00,5.00,5.00,5.00,5.00,5.00,5.00,5.00,5.00,5.00,5.00,5.00,5.00"
					( Origin gBackEnd )
				)
				( attribute "BONDPAD_TO_MVIA_SPACING" "5.00,5.00,5.00,5.00,5.00,5.00,5.00,5.00,5.00,5.00,5.00,5.00,5.00,5.00"
					( Origin gBackEnd )
				)
				( attribute "MIN_BVIA_GAP" "5.00"
					( Origin gBackEnd )
				)
				( attribute "BONDPAD_TO_BONDPAD_DIFFP_SPC" "5.00,5.00,5.00,5.00,5.00,5.00,5.00,5.00,5.00,5.00,5.00,5.00,5.00,5.00"
					( Origin gBackEnd )
				)
				( objectStatus "7H_VIA+2H" )
			)
			( spacingCSet "@sapphirecity_baseboard_lib.sapphirecity_baseboard(sch_1):\9H_US_AND_7H_SL_VIA+2H_A\"
				( attribute "THRUPIN_TO_THRUPIN_SPACING" "5.00,5.00,5.00,5.00,5.00,5.00,5.00,5.00,5.00,5.00,5.00,5.00,5.00,5.00"
					( Origin gBackEnd )
				)
				( attribute "THRUPIN_TO_SMDPIN_SPACING" "5.00,5.00,5.00,5.00,5.00,5.00,5.00,5.00,5.00,5.00,5.00,5.00,5.00,5.00"
					( Origin gBackEnd )
				)
				( attribute "TESTPIN_TO_THRUPIN_SPACING" "5.00,5.00,5.00,5.00,5.00,5.00,5.00,5.00,5.00,5.00,5.00,5.00,5.00,5.00"
					( Origin gBackEnd )
				)
				( attribute "THRUPIN_TO_THRUVIA_SPACING" "5.00,5.00,5.00,5.00,5.00,5.00,5.00,5.00,5.00,5.00,5.00,5.00,5.00,5.00"
					( Origin gBackEnd )
				)
				( attribute "TESTVIA_TO_THRUPIN_SPACING" "5.00,5.00,5.00,5.00,5.00,5.00,5.00,5.00,5.00,5.00,5.00,5.00,5.00,5.00"
					( Origin gBackEnd )
				)
				( attribute "BBV_TO_THRUPIN_SPACING" "5.00,5.00,5.00,5.00,5.00,5.00,5.00,5.00,5.00,5.00,5.00,5.00,5.00,5.00"
					( Origin gBackEnd )
				)
				( attribute "THRUPIN_TO_BONDPAD_SPACING" "5.00,5.00,5.00,5.00,5.00,5.00,5.00,5.00,5.00,5.00,5.00,5.00,5.00,5.00"
					( Origin gBackEnd )
				)
				( attribute "LINE_TO_THRUPIN_SPACING" "4.50,4.00,4.00,4.00,4.00,4.00,4.00,4.00,4.00,4.00,4.00,4.00,4.00,4.50"
					( Origin gBackEnd )
				)
				( attribute "THRUPIN_TO_SHAPE_SPACING" "4.50,4.00,4.00,4.00,4.00,4.00,4.00,4.00,4.00,4.00,4.00,4.00,4.00,4.00"
					( Origin gBackEnd )
				)
				( attribute "SMDPIN_TO_SMDPIN_SPACING" "5.00,5.00,5.00,5.00,5.00,5.00,5.00,5.00,5.00,5.00,5.00,5.00,5.00,5.00"
					( Origin gBackEnd )
				)
				( attribute "SMDPIN_TO_TESTPIN_SPACING" "5.00,5.00,5.00,5.00,5.00,5.00,5.00,5.00,5.00,5.00,5.00,5.00,5.00,5.00"
					( Origin gBackEnd )
				)
				( attribute "SMDPIN_TO_THRUVIA_SPACING" "5.00,5.00,5.00,5.00,5.00,5.00,5.00,5.00,5.00,5.00,5.00,5.00,5.00,5.00"
					( Origin gBackEnd )
				)
				( attribute "SMDPIN_TO_TESTVIA_SPACING" "5.00,5.00,5.00,5.00,5.00,5.00,5.00,5.00,5.00,5.00,5.00,5.00,5.00,5.00"
					( Origin gBackEnd )
				)
				( attribute "BBV_TO_SMDPIN_SPACING" "5.00,5.00,5.00,5.00,5.00,5.00,5.00,5.00,5.00,5.00,5.00,5.00,5.00,5.00"
					( Origin gBackEnd )
				)
				( attribute "SMDPIN_TO_BONDPAD_SPACING" "5.00,5.00,5.00,5.00,5.00,5.00,5.00,5.00,5.00,5.00,5.00,5.00,5.00,5.00"
					( Origin gBackEnd )
				)
				( attribute "LINE_TO_SMDPIN_SPACING" "4.50,4.50,4.50,4.50,4.50,4.50,4.50,4.50,4.50,4.50,4.50,4.50,4.50,4.50"
					( Origin gBackEnd )
				)
				( attribute "SHAPE_TO_SMDPIN_SPACING" "5.00,5.00,5.00,5.00,5.00,5.00,5.00,5.00,5.00,5.00,5.00,5.00,5.00,5.00"
					( Origin gBackEnd )
				)
				( attribute "TESTPIN_TO_TESTPIN_SPACING" "5.00,5.00,5.00,5.00,5.00,5.00,5.00,5.00,5.00,5.00,5.00,5.00,5.00,5.00"
					( Origin gBackEnd )
				)
				( attribute "TESTPIN_TO_THRUVIA_SPACING" "5.00,5.00,5.00,5.00,5.00,5.00,5.00,5.00,5.00,5.00,5.00,5.00,5.00,5.00"
					( Origin gBackEnd )
				)
				( attribute "TESTPIN_TO_TESTVIA_SPACING" "5.00,5.00,5.00,5.00,5.00,5.00,5.00,5.00,5.00,5.00,5.00,5.00,5.00,5.00"
					( Origin gBackEnd )
				)
				( attribute "BBV_TO_TESTPIN_SPACING" "5.00,5.00,5.00,5.00,5.00,5.00,5.00,5.00,5.00,5.00,5.00,5.00,5.00,5.00"
					( Origin gBackEnd )
				)
				( attribute "BONDPAD_TO_TESTPIN_SPACING" "5.00,5.00,5.00,5.00,5.00,5.00,5.00,5.00,5.00,5.00,5.00,5.00,5.00,5.00"
					( Origin gBackEnd )
				)
				( attribute "LINE_TO_TESTPIN_SPACING" "4.50,5.00,5.00,5.00,5.00,5.00,5.00,5.00,5.00,5.00,5.00,5.00,5.00,5.00"
					( Origin gBackEnd )
				)
				( attribute "SHAPE_TO_TESTPIN_SPACING" "4.50,4.00,4.00,4.00,4.00,4.00,4.00,4.00,4.00,4.00,4.00,4.00,4.00,4.00"
					( Origin gBackEnd )
				)
				( attribute "THRUVIA_TO_THRUVIA_SPACING" "5.00,5.00,5.00,5.00,5.00,5.00,5.00,5.00,5.00,5.00,5.00,5.00,5.00,5.00"
					( Origin gBackEnd )
				)
				( attribute "TESTVIA_TO_THRUVIA_SPACING" "5.00,5.00,5.00,5.00,5.00,5.00,5.00,5.00,5.00,5.00,5.00,5.00,5.00,5.00"
					( Origin gBackEnd )
				)
				( attribute "BBV_TO_THRUVIA_SPACING" "5.00,5.00,5.00,5.00,5.00,5.00,5.00,5.00,5.00,5.00,5.00,5.00,5.00,5.00"
					( Origin gBackEnd )
				)
				( attribute "BONDPAD_TO_THRUVIA_SPACING" "5.00,5.00,5.00,5.00,5.00,5.00,5.00,5.00,5.00,5.00,5.00,5.00,5.00,5.00"
					( Origin gBackEnd )
				)
				( attribute "LINE_TO_THRUVIA_SPACING" "9.40,5.00,10.00,5.00,10.00,5.00,5.00,5.00,5.00,10.00,5.00,10.00,5.00,9.40"
					( Origin gBackEnd )
				)
				( attribute "SHAPE_TO_THRUVIA_SPACING" "4.50,4.00,4.00,4.00,4.00,4.00,5.00,5.00,4.00,4.00,4.00,4.00,4.00,4.50"
					( Origin gBackEnd )
				)
				( attribute "TESTVIA_TO_TESTVIA_SPACING" "5.00,5.00,5.00,5.00,5.00,5.00,5.00,5.00,5.00,5.00,5.00,5.00,5.00,5.00"
					( Origin gBackEnd )
				)
				( attribute "BBV_TO_TESTVIA_SPACING" "5.00,5.00,5.00,5.00,5.00,5.00,5.00,5.00,5.00,5.00,5.00,5.00,5.00,5.00"
					( Origin gBackEnd )
				)
				( attribute "BONDPAD_TO_TESTVIA_SPACING" "5.00,5.00,5.00,5.00,5.00,5.00,5.00,5.00,5.00,5.00,5.00,5.00,5.00,5.00"
					( Origin gBackEnd )
				)
				( attribute "LINE_TO_TESTVIA_SPACING" "9.40,5.00,10.00,5.00,10.00,5.00,5.00,5.00,5.00,10.00,5.00,10.00,5.00,9.40"
					( Origin gBackEnd )
				)
				( attribute "SHAPE_TO_TESTVIA_SPACING" "4.50,4.00,4.00,4.00,4.00,4.00,4.00,4.00,4.00,4.00,4.00,4.00,4.00,4.00"
					( Origin gBackEnd )
				)
				( attribute "BBV_TO_BBV_SPACING" "5.00,5.00,5.00,5.00,5.00,5.00,5.00,5.00,5.00,5.00,5.00,5.00,5.00,5.00"
					( Origin gBackEnd )
				)
				( attribute "BONDPAD_TO_BBV_SPACING" "5.00,5.00,5.00,5.00,5.00,5.00,5.00,5.00,5.00,5.00,5.00,5.00,5.00,5.00"
					( Origin gBackEnd )
				)
				( attribute "BBV_TO_LINE_SPACING" "5.00,5.00,5.00,5.00,5.00,5.00,5.00,5.00,5.00,5.00,5.00,5.00,5.00,5.00"
					( Origin gBackEnd )
				)
				( attribute "BBV_TO_SHAPE_SPACING" "5.00,5.00,5.00,5.00,5.00,5.00,5.00,5.00,5.00,5.00,5.00,5.00,5.00,5.00"
					( Origin gBackEnd )
				)
				( attribute "BONDPAD_TO_BONDPAD_SPACING" "5.00,5.00,5.00,5.00,5.00,5.00,5.00,5.00,5.00,5.00,5.00,5.00,5.00,5.00"
					( Origin gBackEnd )
				)
				( attribute "BONDPAD_TO_LINE_SPACING" "5.00,5.00,5.00,5.00,5.00,5.00,5.00,5.00,5.00,5.00,5.00,5.00,5.00,5.00"
					( Origin gBackEnd )
				)
				( attribute "BONDPAD_TO_SHAPE_SPACING" "5.00,5.00,5.00,5.00,5.00,5.00,5.00,5.00,5.00,5.00,5.00,5.00,5.00,5.00"
					( Origin gBackEnd )
				)
				( attribute "LINE_TO_LINE_SPACING" "24.03,21.00,21.00,21.00,21.00,21.00,21.00,21.00,21.00,21.00,21.00,21.00,21.00,24.03"
					( Origin gBackEnd )
				)
				( attribute "LINE_TO_SHAPE_SPACING" "5.00,5.00,5.00,5.00,5.00,5.00,5.00,5.00,5.00,5.00,5.00,5.00,5.00,5.00"
					( Origin gBackEnd )
				)
				( attribute "SHAPE_TO_SHAPE_SPACING" "10.00,10.00,10.00,10.00,10.00,10.00,10.00,10.00,10.00,10.00,10.00,10.00,10.00,10.00"
					( Origin gBackEnd )
				)
				( attribute "HOLE_TO_PIN_SPACING" "8.00,8.00,8.00,8.00,8.00,8.00,8.00,8.00,8.00,8.00,8.00,8.00,8.00,8.00"
					( Origin gBackEnd )
				)
				( attribute "HOLE_TO_VIA_SPACING" "8.00,8.00,8.00,8.00,8.00,8.00,8.00,8.00,8.00,8.00,8.00,8.00,8.00,8.00"
					( Origin gBackEnd )
				)
				( attribute "HOLE_TO_LINE_SPACING" "8.00,8.00,8.00,8.00,8.00,8.00,8.00,8.00,8.00,8.00,8.00,8.00,8.00,8.00"
					( Origin gBackEnd )
				)
				( attribute "HOLE_TO_SHAPE_SPACING" "8.00,8.00,8.00,8.00,8.00,8.00,8.00,8.00,8.00,8.00,8.00,8.00,8.00,8.00"
					( Origin gBackEnd )
				)
				( attribute "HOLE_TO_HOLE_SPACING" "8.00,8.00,8.00,8.00,8.00,8.00,8.00,8.00,8.00,8.00,8.00,8.00,8.00,8.00"
					( Origin gBackEnd )
				)
				( attribute "MVIA_TO_MVIA_SPACING" "5.00,5.00,5.00,5.00,5.00,5.00,5.00,5.00,5.00,5.00,5.00,5.00,5.00,5.00"
					( Origin gBackEnd )
				)
				( attribute "MVIA_TO_THRUPIN_SPACING" "5.00,5.00,5.00,5.00,5.00,5.00,5.00,5.00,5.00,5.00,5.00,5.00,5.00,5.00"
					( Origin gBackEnd )
				)
				( attribute "MVIA_TO_SMDPIN_SPACING" "5.00,5.00,5.00,5.00,5.00,5.00,5.00,5.00,5.00,5.00,5.00,5.00,5.00,5.00"
					( Origin gBackEnd )
				)
				( attribute "MVIA_TO_THRUVIA_SPACING" "5.00,5.00,5.00,5.00,5.00,5.00,5.00,5.00,5.00,5.00,5.00,5.00,5.00,5.00"
					( Origin gBackEnd )
				)
				( attribute "MVIA_TO_BBV_SPACING" "5.00,5.00,5.00,5.00,5.00,5.00,5.00,5.00,5.00,5.00,5.00,5.00,5.00,5.00"
					( Origin gBackEnd )
				)
				( attribute "MVIA_TO_LINE_SPACING" "5.00,5.00,5.00,5.00,5.00,5.00,5.00,5.00,5.00,5.00,5.00,5.00,5.00,5.00"
					( Origin gBackEnd )
				)
				( attribute "MVIA_TO_SHAPE_SPACING" "5.00,5.00,5.00,5.00,5.00,5.00,5.00,5.00,5.00,5.00,5.00,5.00,5.00,5.00"
					( Origin gBackEnd )
				)
				( attribute "MVIA_TO_TESTPIN_SPACING" "5.00,5.00,5.00,5.00,5.00,5.00,5.00,5.00,5.00,5.00,5.00,5.00,5.00,5.00"
					( Origin gBackEnd )
				)
				( attribute "MVIA_TO_TESTVIA_SPACING" "5.00,5.00,5.00,5.00,5.00,5.00,5.00,5.00,5.00,5.00,5.00,5.00,5.00,5.00"
					( Origin gBackEnd )
				)
				( attribute "BONDPAD_TO_MVIA_SPACING" "5.00,5.00,5.00,5.00,5.00,5.00,5.00,5.00,5.00,5.00,5.00,5.00,5.00,5.00"
					( Origin gBackEnd )
				)
				( attribute "MIN_BVIA_GAP" "5.00"
					( Origin gBackEnd )
				)
				( attribute "BONDPAD_TO_BONDPAD_DIFFP_SPC" "5.00,5.00,5.00,5.00,5.00,5.00,5.00,5.00,5.00,5.00,5.00,5.00,5.00,5.00"
					( Origin gBackEnd )
				)
				( objectStatus "9H_US_&_7H_SL_VIA+2H_A" )
			)
			( spacingCSet "@sapphirecity_baseboard_lib.sapphirecity_baseboard(sch_1):\20_MILS\"
				( attribute "THRUPIN_TO_THRUPIN_SPACING" "5.00,5.00,5.00,5.00,5.00,5.00,5.00,5.00,5.00,5.00,5.00,5.00,5.00,5.00"
					( Origin gBackEnd )
				)
				( attribute "THRUPIN_TO_SMDPIN_SPACING" "5.00,5.00,5.00,5.00,5.00,5.00,5.00,5.00,5.00,5.00,5.00,5.00,5.00,5.00"
					( Origin gBackEnd )
				)
				( attribute "TESTPIN_TO_THRUPIN_SPACING" "5.00,5.00,5.00,5.00,5.00,5.00,5.00,5.00,5.00,5.00,5.00,5.00,5.00,5.00"
					( Origin gBackEnd )
				)
				( attribute "THRUPIN_TO_THRUVIA_SPACING" "5.00,5.00,5.00,5.00,5.00,5.00,5.00,5.00,5.00,5.00,5.00,5.00,5.00,5.00"
					( Origin gBackEnd )
				)
				( attribute "TESTVIA_TO_THRUPIN_SPACING" "5.00,5.00,5.00,5.00,5.00,5.00,5.00,5.00,5.00,5.00,5.00,5.00,5.00,5.00"
					( Origin gBackEnd )
				)
				( attribute "BBV_TO_THRUPIN_SPACING" "5.00,5.00,5.00,5.00,5.00,5.00,5.00,5.00,5.00,5.00,5.00,5.00,5.00,5.00"
					( Origin gBackEnd )
				)
				( attribute "THRUPIN_TO_BONDPAD_SPACING" "5.00,5.00,5.00,5.00,5.00,5.00,5.00,5.00,5.00,5.00,5.00,5.00,5.00,5.00"
					( Origin gBackEnd )
				)
				( attribute "LINE_TO_THRUPIN_SPACING" "4.50,4.00,4.00,4.00,4.00,4.00,4.00,4.00,4.00,4.00,4.00,4.00,4.00,4.50"
					( Origin gBackEnd )
				)
				( attribute "THRUPIN_TO_SHAPE_SPACING" "4.50,4.00,4.00,4.00,4.00,4.00,4.00,4.00,4.00,4.00,4.00,4.00,4.00,4.00"
					( Origin gBackEnd )
				)
				( attribute "SMDPIN_TO_SMDPIN_SPACING" "5.00,5.00,5.00,5.00,5.00,5.00,5.00,5.00,5.00,5.00,5.00,5.00,5.00,5.00"
					( Origin gBackEnd )
				)
				( attribute "SMDPIN_TO_TESTPIN_SPACING" "5.00,5.00,5.00,5.00,5.00,5.00,5.00,5.00,5.00,5.00,5.00,5.00,5.00,25.00"
					( Origin gBackEnd )
				)
				( attribute "SMDPIN_TO_THRUVIA_SPACING" "5.00,5.00,5.00,5.00,5.00,5.00,5.00,5.00,5.00,5.00,5.00,5.00,5.00,5.00"
					( Origin gBackEnd )
				)
				( attribute "SMDPIN_TO_TESTVIA_SPACING" "5.00,5.00,5.00,5.00,5.00,5.00,5.00,5.00,5.00,5.00,5.00,5.00,5.00,5.00"
					( Origin gBackEnd )
				)
				( attribute "BBV_TO_SMDPIN_SPACING" "5.00,5.00,5.00,5.00,5.00,5.00,5.00,5.00,5.00,5.00,5.00,5.00,5.00,5.00"
					( Origin gBackEnd )
				)
				( attribute "SMDPIN_TO_BONDPAD_SPACING" "5.00,5.00,5.00,5.00,5.00,5.00,5.00,5.00,5.00,5.00,5.00,5.00,5.00,5.00"
					( Origin gBackEnd )
				)
				( attribute "LINE_TO_SMDPIN_SPACING" "4.50,4.50,4.50,4.50,4.50,4.50,4.50,4.50,4.50,4.50,4.50,4.50,4.50,4.50"
					( Origin gBackEnd )
				)
				( attribute "SHAPE_TO_SMDPIN_SPACING" "5.00,5.00,5.00,5.00,5.00,5.00,5.00,5.00,5.00,5.00,5.00,5.00,5.00,5.00"
					( Origin gBackEnd )
				)
				( attribute "TESTPIN_TO_TESTPIN_SPACING" "5.00,5.00,5.00,5.00,5.00,5.00,5.00,5.00,5.00,5.00,5.00,5.00,5.00,5.00"
					( Origin gBackEnd )
				)
				( attribute "TESTPIN_TO_THRUVIA_SPACING" "5.00,5.00,5.00,5.00,5.00,5.00,5.00,5.00,5.00,5.00,5.00,5.00,5.00,5.00"
					( Origin gBackEnd )
				)
				( attribute "TESTPIN_TO_TESTVIA_SPACING" "5.00,5.00,5.00,5.00,5.00,5.00,5.00,5.00,5.00,5.00,5.00,5.00,5.00,5.00"
					( Origin gBackEnd )
				)
				( attribute "BBV_TO_TESTPIN_SPACING" "5.00,5.00,5.00,5.00,5.00,5.00,5.00,5.00,5.00,5.00,5.00,5.00,5.00,5.00"
					( Origin gBackEnd )
				)
				( attribute "BONDPAD_TO_TESTPIN_SPACING" "5.00,5.00,5.00,5.00,5.00,5.00,5.00,5.00,5.00,5.00,5.00,5.00,5.00,5.00"
					( Origin gBackEnd )
				)
				( attribute "LINE_TO_TESTPIN_SPACING" "4.50,5.00,5.00,5.00,5.00,5.00,5.00,5.00,5.00,5.00,5.00,5.00,5.00,5.00"
					( Origin gBackEnd )
				)
				( attribute "SHAPE_TO_TESTPIN_SPACING" "4.50,4.00,4.00,4.00,4.00,4.00,4.00,4.00,4.00,4.00,4.00,4.00,4.00,4.00"
					( Origin gBackEnd )
				)
				( attribute "THRUVIA_TO_THRUVIA_SPACING" "5.00,5.00,5.00,5.00,5.00,5.00,5.00,5.00,5.00,5.00,5.00,5.00,5.00,5.00"
					( Origin gBackEnd )
				)
				( attribute "TESTVIA_TO_THRUVIA_SPACING" "5.00,5.00,5.00,5.00,5.00,5.00,5.00,5.00,5.00,5.00,5.00,5.00,5.00,5.00"
					( Origin gBackEnd )
				)
				( attribute "BBV_TO_THRUVIA_SPACING" "5.00,5.00,5.00,5.00,5.00,5.00,5.00,5.00,5.00,5.00,5.00,5.00,5.00,5.00"
					( Origin gBackEnd )
				)
				( attribute "BONDPAD_TO_THRUVIA_SPACING" "5.00,5.00,5.00,5.00,5.00,5.00,5.00,5.00,5.00,5.00,5.00,5.00,5.00,5.00"
					( Origin gBackEnd )
				)
				( attribute "LINE_TO_THRUVIA_SPACING" "4.50,4.00,4.00,4.00,4.00,4.00,4.00,4.00,4.00,4.00,4.00,4.00,4.00,4.50"
					( Origin gBackEnd )
				)
				( attribute "SHAPE_TO_THRUVIA_SPACING" "4.50,4.00,4.00,4.00,4.00,4.00,4.00,4.00,4.00,4.00,4.00,4.00,4.00,4.00"
					( Origin gBackEnd )
				)
				( attribute "TESTVIA_TO_TESTVIA_SPACING" "5.00,5.00,5.00,5.00,5.00,5.00,5.00,5.00,5.00,5.00,5.00,5.00,5.00,5.00"
					( Origin gBackEnd )
				)
				( attribute "BBV_TO_TESTVIA_SPACING" "5.00,5.00,5.00,5.00,5.00,5.00,5.00,5.00,5.00,5.00,5.00,5.00,5.00,5.00"
					( Origin gBackEnd )
				)
				( attribute "BONDPAD_TO_TESTVIA_SPACING" "5.00,5.00,5.00,5.00,5.00,5.00,5.00,5.00,5.00,5.00,5.00,5.00,5.00,5.00"
					( Origin gBackEnd )
				)
				( attribute "LINE_TO_TESTVIA_SPACING" "4.50,5.00,4.00,5.00,4.00,5.00,5.00,5.00,5.00,4.00,5.00,4.00,5.00,4.50"
					( Origin gBackEnd )
				)
				( attribute "SHAPE_TO_TESTVIA_SPACING" "4.50,4.00,4.00,4.00,4.00,4.00,4.00,4.00,4.00,4.00,4.00,4.00,4.00,4.00"
					( Origin gBackEnd )
				)
				( attribute "BBV_TO_BBV_SPACING" "5.00,5.00,5.00,5.00,5.00,5.00,5.00,5.00,5.00,5.00,5.00,5.00,5.00,5.00"
					( Origin gBackEnd )
				)
				( attribute "BONDPAD_TO_BBV_SPACING" "5.00,5.00,5.00,5.00,5.00,5.00,5.00,5.00,5.00,5.00,5.00,5.00,5.00,5.00"
					( Origin gBackEnd )
				)
				( attribute "BBV_TO_LINE_SPACING" "5.00,5.00,5.00,5.00,5.00,5.00,5.00,5.00,5.00,5.00,5.00,5.00,5.00,5.00"
					( Origin gBackEnd )
				)
				( attribute "BBV_TO_SHAPE_SPACING" "5.00,5.00,5.00,5.00,5.00,5.00,5.00,5.00,5.00,5.00,5.00,5.00,5.00,5.00"
					( Origin gBackEnd )
				)
				( attribute "BONDPAD_TO_BONDPAD_SPACING" "5.00,5.00,5.00,5.00,5.00,5.00,5.00,5.00,5.00,5.00,5.00,5.00,5.00,5.00"
					( Origin gBackEnd )
				)
				( attribute "BONDPAD_TO_LINE_SPACING" "5.00,5.00,5.00,5.00,5.00,5.00,5.00,5.00,5.00,5.00,5.00,5.00,5.00,5.00"
					( Origin gBackEnd )
				)
				( attribute "BONDPAD_TO_SHAPE_SPACING" "5.00,5.00,5.00,5.00,5.00,5.00,5.00,5.00,5.00,5.00,5.00,5.00,5.00,5.00"
					( Origin gBackEnd )
				)
				( attribute "LINE_TO_LINE_SPACING" "20.00,20.00,20.00,20.00,20.00,20.00,20.00,20.00,20.00,20.00,20.00,20.00,20.00,20.00"
					( Origin gBackEnd )
				)
				( attribute "LINE_TO_SHAPE_SPACING" "5.00,5.00,5.00,5.00,5.00,5.00,5.00,5.00,5.00,5.00,5.00,5.00,5.00,5.00"
					( Origin gBackEnd )
				)
				( attribute "SHAPE_TO_SHAPE_SPACING" "10.00,10.00,10.00,10.00,10.00,10.00,10.00,10.00,10.00,10.00,10.00,10.00,10.00,10.00"
					( Origin gBackEnd )
				)
				( attribute "HOLE_TO_PIN_SPACING" "8.00,8.00,8.00,8.00,8.00,8.00,8.00,8.00,8.00,8.00,8.00,8.00,8.00,8.00"
					( Origin gBackEnd )
				)
				( attribute "HOLE_TO_VIA_SPACING" "8.00,8.00,8.00,8.00,8.00,8.00,8.00,8.00,8.00,8.00,8.00,8.00,8.00,8.00"
					( Origin gBackEnd )
				)
				( attribute "HOLE_TO_LINE_SPACING" "8.00,8.00,8.00,8.00,8.00,8.00,8.00,8.00,8.00,8.00,8.00,8.00,8.00,8.00"
					( Origin gBackEnd )
				)
				( attribute "HOLE_TO_SHAPE_SPACING" "8.00,8.00,8.00,8.00,8.00,8.00,8.00,8.00,8.00,8.00,8.00,8.00,8.00,8.00"
					( Origin gBackEnd )
				)
				( attribute "HOLE_TO_HOLE_SPACING" "8.00,8.00,8.00,8.00,8.00,8.00,8.00,8.00,8.00,8.00,8.00,8.00,8.00,8.00"
					( Origin gBackEnd )
				)
				( attribute "MVIA_TO_MVIA_SPACING" "5.00,5.00,5.00,5.00,5.00,5.00,5.00,5.00,5.00,5.00,5.00,5.00,5.00,5.00"
					( Origin gBackEnd )
				)
				( attribute "MVIA_TO_THRUPIN_SPACING" "5.00,5.00,5.00,5.00,5.00,5.00,5.00,5.00,5.00,5.00,5.00,5.00,5.00,5.00"
					( Origin gBackEnd )
				)
				( attribute "MVIA_TO_SMDPIN_SPACING" "5.00,5.00,5.00,5.00,5.00,5.00,5.00,5.00,5.00,5.00,5.00,5.00,5.00,5.00"
					( Origin gBackEnd )
				)
				( attribute "MVIA_TO_THRUVIA_SPACING" "5.00,5.00,5.00,5.00,5.00,5.00,5.00,5.00,5.00,5.00,5.00,5.00,5.00,5.00"
					( Origin gBackEnd )
				)
				( attribute "MVIA_TO_BBV_SPACING" "5.00,5.00,5.00,5.00,5.00,5.00,5.00,5.00,5.00,5.00,5.00,5.00,5.00,5.00"
					( Origin gBackEnd )
				)
				( attribute "MVIA_TO_LINE_SPACING" "5.00,5.00,5.00,5.00,5.00,5.00,5.00,5.00,5.00,5.00,5.00,5.00,5.00,5.00"
					( Origin gBackEnd )
				)
				( attribute "MVIA_TO_SHAPE_SPACING" "5.00,5.00,5.00,5.00,5.00,5.00,5.00,5.00,5.00,5.00,5.00,5.00,5.00,5.00"
					( Origin gBackEnd )
				)
				( attribute "MVIA_TO_TESTPIN_SPACING" "5.00,5.00,5.00,5.00,5.00,5.00,5.00,5.00,5.00,5.00,5.00,5.00,5.00,5.00"
					( Origin gBackEnd )
				)
				( attribute "MVIA_TO_TESTVIA_SPACING" "5.00,5.00,5.00,5.00,5.00,5.00,5.00,5.00,5.00,5.00,5.00,5.00,5.00,5.00"
					( Origin gBackEnd )
				)
				( attribute "BONDPAD_TO_MVIA_SPACING" "5.00,5.00,5.00,5.00,5.00,5.00,5.00,5.00,5.00,5.00,5.00,5.00,5.00,5.00"
					( Origin gBackEnd )
				)
				( attribute "MIN_BVIA_GAP" "5.00"
					( Origin gBackEnd )
				)
				( attribute "BONDPAD_TO_BONDPAD_DIFFP_SPC" "5.00,5.00,5.00,5.00,5.00,5.00,5.00,5.00,5.00,5.00,5.00,5.00,5.00,5.00"
					( Origin gBackEnd )
				)
				( objectStatus "20_MILS" )
			)
			( spacingCSet "@sapphirecity_baseboard_lib.sapphirecity_baseboard(sch_1):\8_MILS\"
				( attribute "THRUPIN_TO_THRUPIN_SPACING" "5.00,5.00,5.00,5.00,5.00,5.00,5.00,5.00,5.00,5.00,5.00,5.00,5.00,5.00"
					( Origin gBackEnd )
				)
				( attribute "THRUPIN_TO_SMDPIN_SPACING" "5.00,5.00,5.00,5.00,5.00,5.00,5.00,5.00,5.00,5.00,5.00,5.00,5.00,5.00"
					( Origin gBackEnd )
				)
				( attribute "TESTPIN_TO_THRUPIN_SPACING" "5.00,5.00,5.00,5.00,5.00,5.00,5.00,5.00,5.00,5.00,5.00,5.00,5.00,5.00"
					( Origin gBackEnd )
				)
				( attribute "THRUPIN_TO_THRUVIA_SPACING" "5.00,5.00,5.00,5.00,5.00,5.00,5.00,5.00,5.00,5.00,5.00,5.00,5.00,5.00"
					( Origin gBackEnd )
				)
				( attribute "TESTVIA_TO_THRUPIN_SPACING" "5.00,5.00,5.00,5.00,5.00,5.00,5.00,5.00,5.00,5.00,5.00,5.00,5.00,5.00"
					( Origin gBackEnd )
				)
				( attribute "BBV_TO_THRUPIN_SPACING" "5.00,5.00,5.00,5.00,5.00,5.00,5.00,5.00,5.00,5.00,5.00,5.00,5.00,5.00"
					( Origin gBackEnd )
				)
				( attribute "THRUPIN_TO_BONDPAD_SPACING" "5.00,5.00,5.00,5.00,5.00,5.00,5.00,5.00,5.00,5.00,5.00,5.00,5.00,5.00"
					( Origin gBackEnd )
				)
				( attribute "LINE_TO_THRUPIN_SPACING" "4.50,4.00,4.00,4.00,4.00,4.00,4.00,4.00,4.00,4.00,4.00,4.00,4.00,4.50"
					( Origin gBackEnd )
				)
				( attribute "THRUPIN_TO_SHAPE_SPACING" "4.50,4.00,4.00,4.00,4.00,4.00,4.00,4.00,4.00,4.00,4.00,4.00,4.00,4.00"
					( Origin gBackEnd )
				)
				( attribute "SMDPIN_TO_SMDPIN_SPACING" "5.00,5.00,5.00,5.00,5.00,5.00,5.00,5.00,5.00,5.00,5.00,5.00,5.00,5.00"
					( Origin gBackEnd )
				)
				( attribute "SMDPIN_TO_TESTPIN_SPACING" "5.00,5.00,5.00,5.00,5.00,5.00,5.00,5.00,5.00,5.00,5.00,5.00,5.00,5.00"
					( Origin gBackEnd )
				)
				( attribute "SMDPIN_TO_THRUVIA_SPACING" "5.00,5.00,5.00,5.00,5.00,5.00,5.00,5.00,5.00,5.00,5.00,5.00,5.00,5.00"
					( Origin gBackEnd )
				)
				( attribute "SMDPIN_TO_TESTVIA_SPACING" "5.00,5.00,5.00,5.00,5.00,5.00,5.00,5.00,5.00,5.00,5.00,5.00,5.00,5.00"
					( Origin gBackEnd )
				)
				( attribute "BBV_TO_SMDPIN_SPACING" "5.00,5.00,5.00,5.00,5.00,5.00,5.00,5.00,5.00,5.00,5.00,5.00,5.00,5.00"
					( Origin gBackEnd )
				)
				( attribute "SMDPIN_TO_BONDPAD_SPACING" "5.00,5.00,5.00,5.00,5.00,5.00,5.00,5.00,5.00,5.00,5.00,5.00,5.00,5.00"
					( Origin gBackEnd )
				)
				( attribute "LINE_TO_SMDPIN_SPACING" "4.50,4.50,4.50,4.50,4.50,4.50,4.50,4.50,4.50,4.50,4.50,4.50,4.50,4.50"
					( Origin gBackEnd )
				)
				( attribute "SHAPE_TO_SMDPIN_SPACING" "5.00,5.00,5.00,5.00,5.00,5.00,5.00,5.00,5.00,5.00,5.00,5.00,5.00,5.00"
					( Origin gBackEnd )
				)
				( attribute "TESTPIN_TO_TESTPIN_SPACING" "5.00,5.00,5.00,5.00,5.00,5.00,5.00,5.00,5.00,5.00,5.00,5.00,5.00,5.00"
					( Origin gBackEnd )
				)
				( attribute "TESTPIN_TO_THRUVIA_SPACING" "5.00,5.00,5.00,5.00,5.00,5.00,5.00,5.00,5.00,5.00,5.00,5.00,5.00,5.00"
					( Origin gBackEnd )
				)
				( attribute "TESTPIN_TO_TESTVIA_SPACING" "5.00,5.00,5.00,5.00,5.00,5.00,5.00,5.00,5.00,5.00,5.00,5.00,5.00,5.00"
					( Origin gBackEnd )
				)
				( attribute "BBV_TO_TESTPIN_SPACING" "5.00,5.00,5.00,5.00,5.00,5.00,5.00,5.00,5.00,5.00,5.00,5.00,5.00,5.00"
					( Origin gBackEnd )
				)
				( attribute "BONDPAD_TO_TESTPIN_SPACING" "5.00,5.00,5.00,5.00,5.00,5.00,5.00,5.00,5.00,5.00,5.00,5.00,5.00,5.00"
					( Origin gBackEnd )
				)
				( attribute "LINE_TO_TESTPIN_SPACING" "4.50,5.00,5.00,5.00,5.00,5.00,5.00,5.00,5.00,5.00,5.00,5.00,5.00,5.00"
					( Origin gBackEnd )
				)
				( attribute "SHAPE_TO_TESTPIN_SPACING" "4.50,4.00,4.00,4.00,4.00,4.00,4.00,4.00,4.00,4.00,4.00,4.00,4.00,4.00"
					( Origin gBackEnd )
				)
				( attribute "THRUVIA_TO_THRUVIA_SPACING" "5.00,5.00,5.00,5.00,5.00,5.00,5.00,5.00,5.00,5.00,5.00,5.00,5.00,5.00"
					( Origin gBackEnd )
				)
				( attribute "TESTVIA_TO_THRUVIA_SPACING" "5.00,5.00,5.00,5.00,5.00,5.00,5.00,5.00,5.00,5.00,5.00,5.00,5.00,5.00"
					( Origin gBackEnd )
				)
				( attribute "BBV_TO_THRUVIA_SPACING" "5.00,5.00,5.00,5.00,5.00,5.00,5.00,5.00,5.00,5.00,5.00,5.00,5.00,5.00"
					( Origin gBackEnd )
				)
				( attribute "BONDPAD_TO_THRUVIA_SPACING" "5.00,5.00,5.00,5.00,5.00,5.00,5.00,5.00,5.00,5.00,5.00,5.00,5.00,5.00"
					( Origin gBackEnd )
				)
				( attribute "LINE_TO_THRUVIA_SPACING" "4.50,4.00,4.00,4.00,4.00,4.00,4.00,4.00,4.00,4.00,4.00,4.00,4.00,4.50"
					( Origin gBackEnd )
				)
				( attribute "SHAPE_TO_THRUVIA_SPACING" "4.50,4.00,4.00,4.00,4.00,4.00,4.00,4.00,4.00,4.00,4.00,4.00,4.00,4.00"
					( Origin gBackEnd )
				)
				( attribute "TESTVIA_TO_TESTVIA_SPACING" "5.00,5.00,5.00,5.00,5.00,5.00,5.00,5.00,5.00,5.00,5.00,5.00,5.00,5.00"
					( Origin gBackEnd )
				)
				( attribute "BBV_TO_TESTVIA_SPACING" "5.00,5.00,5.00,5.00,5.00,5.00,5.00,5.00,5.00,5.00,5.00,5.00,5.00,5.00"
					( Origin gBackEnd )
				)
				( attribute "BONDPAD_TO_TESTVIA_SPACING" "5.00,5.00,5.00,5.00,5.00,5.00,5.00,5.00,5.00,5.00,5.00,5.00,5.00,5.00"
					( Origin gBackEnd )
				)
				( attribute "LINE_TO_TESTVIA_SPACING" "4.50,5.00,4.00,5.00,4.00,5.00,5.00,5.00,5.00,4.00,5.00,4.00,5.00,4.50"
					( Origin gBackEnd )
				)
				( attribute "SHAPE_TO_TESTVIA_SPACING" "4.50,4.00,4.00,4.00,4.00,4.00,4.00,4.00,4.00,4.00,4.00,4.00,4.00,4.00"
					( Origin gBackEnd )
				)
				( attribute "BBV_TO_BBV_SPACING" "5.00,5.00,5.00,5.00,5.00,5.00,5.00,5.00,5.00,5.00,5.00,5.00,5.00,5.00"
					( Origin gBackEnd )
				)
				( attribute "BONDPAD_TO_BBV_SPACING" "5.00,5.00,5.00,5.00,5.00,5.00,5.00,5.00,5.00,5.00,5.00,5.00,5.00,5.00"
					( Origin gBackEnd )
				)
				( attribute "BBV_TO_LINE_SPACING" "5.00,5.00,5.00,5.00,5.00,5.00,5.00,5.00,5.00,5.00,5.00,5.00,5.00,5.00"
					( Origin gBackEnd )
				)
				( attribute "BBV_TO_SHAPE_SPACING" "5.00,5.00,5.00,5.00,5.00,5.00,5.00,5.00,5.00,5.00,5.00,5.00,5.00,5.00"
					( Origin gBackEnd )
				)
				( attribute "BONDPAD_TO_BONDPAD_SPACING" "5.00,5.00,5.00,5.00,5.00,5.00,5.00,5.00,5.00,5.00,5.00,5.00,5.00,5.00"
					( Origin gBackEnd )
				)
				( attribute "BONDPAD_TO_LINE_SPACING" "5.00,5.00,5.00,5.00,5.00,5.00,5.00,5.00,5.00,5.00,5.00,5.00,5.00,5.00"
					( Origin gBackEnd )
				)
				( attribute "BONDPAD_TO_SHAPE_SPACING" "5.00,5.00,5.00,5.00,5.00,5.00,5.00,5.00,5.00,5.00,5.00,5.00,5.00,5.00"
					( Origin gBackEnd )
				)
				( attribute "LINE_TO_LINE_SPACING" "8.00,8.00,8.00,8.00,8.00,8.00,8.00,8.00,8.00,8.00,8.00,8.00,8.00,8.00"
					( Origin gBackEnd )
				)
				( attribute "LINE_TO_SHAPE_SPACING" "5.00,5.00,5.00,5.00,5.00,5.00,5.00,5.00,5.00,5.00,5.00,5.00,5.00,5.00"
					( Origin gBackEnd )
				)
				( attribute "SHAPE_TO_SHAPE_SPACING" "10.00,10.00,10.00,10.00,10.00,10.00,10.00,10.00,10.00,10.00,10.00,10.00,10.00,10.00"
					( Origin gBackEnd )
				)
				( attribute "HOLE_TO_PIN_SPACING" "8.00,8.00,8.00,8.00,8.00,8.00,8.00,8.00,8.00,8.00,8.00,8.00,8.00,8.00"
					( Origin gBackEnd )
				)
				( attribute "HOLE_TO_VIA_SPACING" "8.00,8.00,8.00,8.00,8.00,8.00,8.00,8.00,8.00,8.00,8.00,8.00,8.00,8.00"
					( Origin gBackEnd )
				)
				( attribute "HOLE_TO_LINE_SPACING" "8.00,8.00,8.00,8.00,8.00,8.00,8.00,8.00,8.00,8.00,8.00,8.00,8.00,8.00"
					( Origin gBackEnd )
				)
				( attribute "HOLE_TO_SHAPE_SPACING" "8.00,8.00,8.00,8.00,8.00,8.00,8.00,8.00,8.00,8.00,8.00,8.00,8.00,8.00"
					( Origin gBackEnd )
				)
				( attribute "HOLE_TO_HOLE_SPACING" "8.00,8.00,8.00,8.00,8.00,8.00,8.00,8.00,8.00,8.00,8.00,8.00,8.00,8.00"
					( Origin gBackEnd )
				)
				( attribute "MVIA_TO_MVIA_SPACING" "5.00,5.00,5.00,5.00,5.00,5.00,5.00,5.00,5.00,5.00,5.00,5.00,5.00,5.00"
					( Origin gBackEnd )
				)
				( attribute "MVIA_TO_THRUPIN_SPACING" "5.00,5.00,5.00,5.00,5.00,5.00,5.00,5.00,5.00,5.00,5.00,5.00,5.00,5.00"
					( Origin gBackEnd )
				)
				( attribute "MVIA_TO_SMDPIN_SPACING" "5.00,5.00,5.00,5.00,5.00,5.00,5.00,5.00,5.00,5.00,5.00,5.00,5.00,5.00"
					( Origin gBackEnd )
				)
				( attribute "MVIA_TO_THRUVIA_SPACING" "5.00,5.00,5.00,5.00,5.00,5.00,5.00,5.00,5.00,5.00,5.00,5.00,5.00,5.00"
					( Origin gBackEnd )
				)
				( attribute "MVIA_TO_BBV_SPACING" "5.00,5.00,5.00,5.00,5.00,5.00,5.00,5.00,5.00,5.00,5.00,5.00,5.00,5.00"
					( Origin gBackEnd )
				)
				( attribute "MVIA_TO_LINE_SPACING" "5.00,5.00,5.00,5.00,5.00,5.00,5.00,5.00,5.00,5.00,5.00,5.00,5.00,5.00"
					( Origin gBackEnd )
				)
				( attribute "MVIA_TO_SHAPE_SPACING" "5.00,5.00,5.00,5.00,5.00,5.00,5.00,5.00,5.00,5.00,5.00,5.00,5.00,5.00"
					( Origin gBackEnd )
				)
				( attribute "MVIA_TO_TESTPIN_SPACING" "5.00,5.00,5.00,5.00,5.00,5.00,5.00,5.00,5.00,5.00,5.00,5.00,5.00,5.00"
					( Origin gBackEnd )
				)
				( attribute "MVIA_TO_TESTVIA_SPACING" "5.00,5.00,5.00,5.00,5.00,5.00,5.00,5.00,5.00,5.00,5.00,5.00,5.00,5.00"
					( Origin gBackEnd )
				)
				( attribute "BONDPAD_TO_MVIA_SPACING" "5.00,5.00,5.00,5.00,5.00,5.00,5.00,5.00,5.00,5.00,5.00,5.00,5.00,5.00"
					( Origin gBackEnd )
				)
				( attribute "MIN_BVIA_GAP" "5.00"
					( Origin gBackEnd )
				)
				( attribute "BONDPAD_TO_BONDPAD_DIFFP_SPC" "5.00,5.00,5.00,5.00,5.00,5.00,5.00,5.00,5.00,5.00,5.00,5.00,5.00,5.00"
					( Origin gBackEnd )
				)
				( objectStatus "8_MILS" )
			)
			( spacingCSet "@sapphirecity_baseboard_lib.sapphirecity_baseboard(sch_1):\7H_US_AND_3H_SL\"
				( attribute "THRUPIN_TO_THRUPIN_SPACING" "5.00,5.00,5.00,5.00,5.00,5.00,5.00,5.00,5.00,5.00,5.00,5.00,5.00,5.00"
					( Origin gBackEnd )
				)
				( attribute "THRUPIN_TO_SMDPIN_SPACING" "5.00,5.00,5.00,5.00,5.00,5.00,5.00,5.00,5.00,5.00,5.00,5.00,5.00,5.00"
					( Origin gBackEnd )
				)
				( attribute "TESTPIN_TO_THRUPIN_SPACING" "5.00,5.00,5.00,5.00,5.00,5.00,5.00,5.00,5.00,5.00,5.00,5.00,5.00,5.00"
					( Origin gBackEnd )
				)
				( attribute "THRUPIN_TO_THRUVIA_SPACING" "5.00,5.00,5.00,5.00,5.00,5.00,5.00,5.00,5.00,5.00,5.00,5.00,5.00,5.00"
					( Origin gBackEnd )
				)
				( attribute "TESTVIA_TO_THRUPIN_SPACING" "5.00,5.00,5.00,5.00,5.00,5.00,5.00,5.00,5.00,5.00,5.00,5.00,5.00,5.00"
					( Origin gBackEnd )
				)
				( attribute "BBV_TO_THRUPIN_SPACING" "5.00,5.00,5.00,5.00,5.00,5.00,5.00,5.00,5.00,5.00,5.00,5.00,5.00,5.00"
					( Origin gBackEnd )
				)
				( attribute "THRUPIN_TO_BONDPAD_SPACING" "5.00,5.00,5.00,5.00,5.00,5.00,5.00,5.00,5.00,5.00,5.00,5.00,5.00,5.00"
					( Origin gBackEnd )
				)
				( attribute "LINE_TO_THRUPIN_SPACING" "4.50,4.00,4.00,4.00,4.00,4.00,4.00,4.00,4.00,4.00,4.00,4.00,4.00,4.50"
					( Origin gBackEnd )
				)
				( attribute "THRUPIN_TO_SHAPE_SPACING" "4.50,4.00,4.00,4.00,4.00,4.00,4.00,4.00,4.00,4.00,4.00,4.00,4.00,4.00"
					( Origin gBackEnd )
				)
				( attribute "SMDPIN_TO_SMDPIN_SPACING" "5.00,5.00,5.00,5.00,5.00,5.00,5.00,5.00,5.00,5.00,5.00,5.00,5.00,5.00"
					( Origin gBackEnd )
				)
				( attribute "SMDPIN_TO_TESTPIN_SPACING" "5.00,5.00,5.00,5.00,5.00,5.00,5.00,5.00,5.00,5.00,5.00,5.00,5.00,5.00"
					( Origin gBackEnd )
				)
				( attribute "SMDPIN_TO_THRUVIA_SPACING" "5.00,5.00,5.00,5.00,5.00,5.00,5.00,5.00,5.00,5.00,5.00,5.00,5.00,5.00"
					( Origin gBackEnd )
				)
				( attribute "SMDPIN_TO_TESTVIA_SPACING" "5.00,5.00,5.00,5.00,5.00,5.00,5.00,5.00,5.00,5.00,5.00,5.00,5.00,5.00"
					( Origin gBackEnd )
				)
				( attribute "BBV_TO_SMDPIN_SPACING" "5.00,5.00,5.00,5.00,5.00,5.00,5.00,5.00,5.00,5.00,5.00,5.00,5.00,5.00"
					( Origin gBackEnd )
				)
				( attribute "SMDPIN_TO_BONDPAD_SPACING" "5.00,5.00,5.00,5.00,5.00,5.00,5.00,5.00,5.00,5.00,5.00,5.00,5.00,5.00"
					( Origin gBackEnd )
				)
				( attribute "LINE_TO_SMDPIN_SPACING" "4.50,4.50,4.50,4.50,4.50,4.50,4.50,4.50,4.50,4.50,4.50,4.50,4.50,4.50"
					( Origin gBackEnd )
				)
				( attribute "SHAPE_TO_SMDPIN_SPACING" "5.00,5.00,5.00,5.00,5.00,5.00,5.00,5.00,5.00,5.00,5.00,5.00,5.00,5.00"
					( Origin gBackEnd )
				)
				( attribute "TESTPIN_TO_TESTPIN_SPACING" "5.00,5.00,5.00,5.00,5.00,5.00,5.00,5.00,5.00,5.00,5.00,5.00,5.00,5.00"
					( Origin gBackEnd )
				)
				( attribute "TESTPIN_TO_THRUVIA_SPACING" "5.00,5.00,5.00,5.00,5.00,5.00,5.00,5.00,5.00,5.00,5.00,5.00,5.00,5.00"
					( Origin gBackEnd )
				)
				( attribute "TESTPIN_TO_TESTVIA_SPACING" "5.00,5.00,5.00,5.00,5.00,5.00,5.00,5.00,5.00,5.00,5.00,5.00,5.00,5.00"
					( Origin gBackEnd )
				)
				( attribute "BBV_TO_TESTPIN_SPACING" "5.00,5.00,5.00,5.00,5.00,5.00,5.00,5.00,5.00,5.00,5.00,5.00,5.00,5.00"
					( Origin gBackEnd )
				)
				( attribute "BONDPAD_TO_TESTPIN_SPACING" "5.00,5.00,5.00,5.00,5.00,5.00,5.00,5.00,5.00,5.00,5.00,5.00,5.00,5.00"
					( Origin gBackEnd )
				)
				( attribute "LINE_TO_TESTPIN_SPACING" "4.50,5.00,5.00,5.00,5.00,5.00,5.00,5.00,5.00,5.00,5.00,5.00,5.00,5.00"
					( Origin gBackEnd )
				)
				( attribute "SHAPE_TO_TESTPIN_SPACING" "4.50,4.00,4.00,4.00,4.00,4.00,4.00,4.00,4.00,4.00,4.00,4.00,4.00,4.00"
					( Origin gBackEnd )
				)
				( attribute "THRUVIA_TO_THRUVIA_SPACING" "5.00,5.00,5.00,5.00,5.00,5.00,5.00,5.00,5.00,5.00,5.00,5.00,5.00,5.00"
					( Origin gBackEnd )
				)
				( attribute "TESTVIA_TO_THRUVIA_SPACING" "5.00,5.00,5.00,5.00,5.00,5.00,5.00,5.00,5.00,5.00,5.00,5.00,5.00,5.00"
					( Origin gBackEnd )
				)
				( attribute "BBV_TO_THRUVIA_SPACING" "5.00,5.00,5.00,5.00,5.00,5.00,5.00,5.00,5.00,5.00,5.00,5.00,5.00,5.00"
					( Origin gBackEnd )
				)
				( attribute "BONDPAD_TO_THRUVIA_SPACING" "5.00,5.00,5.00,5.00,5.00,5.00,5.00,5.00,5.00,5.00,5.00,5.00,5.00,5.00"
					( Origin gBackEnd )
				)
				( attribute "LINE_TO_THRUVIA_SPACING" "4.50,4.00,4.00,4.00,4.00,4.00,4.00,4.00,4.00,4.00,4.00,4.00,4.00,4.50"
					( Origin gBackEnd )
				)
				( attribute "SHAPE_TO_THRUVIA_SPACING" "4.50,4.00,4.00,4.00,4.00,4.00,4.00,4.00,4.00,4.00,4.00,4.00,4.00,4.00"
					( Origin gBackEnd )
				)
				( attribute "TESTVIA_TO_TESTVIA_SPACING" "5.00,5.00,5.00,5.00,5.00,5.00,5.00,5.00,5.00,5.00,5.00,5.00,5.00,5.00"
					( Origin gBackEnd )
				)
				( attribute "BBV_TO_TESTVIA_SPACING" "5.00,5.00,5.00,5.00,5.00,5.00,5.00,5.00,5.00,5.00,5.00,5.00,5.00,5.00"
					( Origin gBackEnd )
				)
				( attribute "BONDPAD_TO_TESTVIA_SPACING" "5.00,5.00,5.00,5.00,5.00,5.00,5.00,5.00,5.00,5.00,5.00,5.00,5.00,5.00"
					( Origin gBackEnd )
				)
				( attribute "LINE_TO_TESTVIA_SPACING" "4.50,5.00,4.00,5.00,4.00,5.00,5.00,5.00,5.00,4.00,5.00,4.00,5.00,4.50"
					( Origin gBackEnd )
				)
				( attribute "SHAPE_TO_TESTVIA_SPACING" "4.50,4.00,4.00,4.00,4.00,4.00,4.00,4.00,4.00,4.00,4.00,4.00,4.00,4.00"
					( Origin gBackEnd )
				)
				( attribute "BBV_TO_BBV_SPACING" "5.00,5.00,5.00,5.00,5.00,5.00,5.00,5.00,5.00,5.00,5.00,5.00,5.00,5.00"
					( Origin gBackEnd )
				)
				( attribute "BONDPAD_TO_BBV_SPACING" "5.00,5.00,5.00,5.00,5.00,5.00,5.00,5.00,5.00,5.00,5.00,5.00,5.00,5.00"
					( Origin gBackEnd )
				)
				( attribute "BBV_TO_LINE_SPACING" "5.00,5.00,5.00,5.00,5.00,5.00,5.00,5.00,5.00,5.00,5.00,5.00,5.00,5.00"
					( Origin gBackEnd )
				)
				( attribute "BBV_TO_SHAPE_SPACING" "5.00,5.00,5.00,5.00,5.00,5.00,5.00,5.00,5.00,5.00,5.00,5.00,5.00,5.00"
					( Origin gBackEnd )
				)
				( attribute "BONDPAD_TO_BONDPAD_SPACING" "5.00,5.00,5.00,5.00,5.00,5.00,5.00,5.00,5.00,5.00,5.00,5.00,5.00,5.00"
					( Origin gBackEnd )
				)
				( attribute "BONDPAD_TO_LINE_SPACING" "5.00,5.00,5.00,5.00,5.00,5.00,5.00,5.00,5.00,5.00,5.00,5.00,5.00,5.00"
					( Origin gBackEnd )
				)
				( attribute "BONDPAD_TO_SHAPE_SPACING" "5.00,5.00,5.00,5.00,5.00,5.00,5.00,5.00,5.00,5.00,5.00,5.00,5.00,5.00"
					( Origin gBackEnd )
				)
				( attribute "LINE_TO_LINE_SPACING" "18.69,9.00,9.00,9.00,9.00,9.00,9.00,9.00,9.00,9.00,9.00,9.00,9.00,18.69"
					( Origin gBackEnd )
				)
				( attribute "LINE_TO_SHAPE_SPACING" "5.00,5.00,5.00,5.00,5.00,5.00,5.00,5.00,5.00,5.00,5.00,5.00,5.00,5.00"
					( Origin gBackEnd )
				)
				( attribute "SHAPE_TO_SHAPE_SPACING" "10.00,10.00,10.00,10.00,10.00,10.00,10.00,10.00,10.00,10.00,10.00,10.00,10.00,10.00"
					( Origin gBackEnd )
				)
				( attribute "HOLE_TO_PIN_SPACING" "8.00,8.00,8.00,8.00,8.00,8.00,8.00,8.00,8.00,8.00,8.00,8.00,8.00,8.00"
					( Origin gBackEnd )
				)
				( attribute "HOLE_TO_VIA_SPACING" "8.00,8.00,8.00,8.00,8.00,8.00,8.00,8.00,8.00,8.00,8.00,8.00,8.00,8.00"
					( Origin gBackEnd )
				)
				( attribute "HOLE_TO_LINE_SPACING" "8.00,8.00,8.00,8.00,8.00,8.00,8.00,8.00,8.00,8.00,8.00,8.00,8.00,8.00"
					( Origin gBackEnd )
				)
				( attribute "HOLE_TO_SHAPE_SPACING" "8.00,8.00,8.00,8.00,8.00,8.00,8.00,8.00,8.00,8.00,8.00,8.00,8.00,8.00"
					( Origin gBackEnd )
				)
				( attribute "HOLE_TO_HOLE_SPACING" "8.00,8.00,8.00,8.00,8.00,8.00,8.00,8.00,8.00,8.00,8.00,8.00,8.00,8.00"
					( Origin gBackEnd )
				)
				( attribute "MVIA_TO_MVIA_SPACING" "5.00,5.00,5.00,5.00,5.00,5.00,5.00,5.00,5.00,5.00,5.00,5.00,5.00,5.00"
					( Origin gBackEnd )
				)
				( attribute "MVIA_TO_THRUPIN_SPACING" "5.00,5.00,5.00,5.00,5.00,5.00,5.00,5.00,5.00,5.00,5.00,5.00,5.00,5.00"
					( Origin gBackEnd )
				)
				( attribute "MVIA_TO_SMDPIN_SPACING" "5.00,5.00,5.00,5.00,5.00,5.00,5.00,5.00,5.00,5.00,5.00,5.00,5.00,5.00"
					( Origin gBackEnd )
				)
				( attribute "MVIA_TO_THRUVIA_SPACING" "5.00,5.00,5.00,5.00,5.00,5.00,5.00,5.00,5.00,5.00,5.00,5.00,5.00,5.00"
					( Origin gBackEnd )
				)
				( attribute "MVIA_TO_BBV_SPACING" "5.00,5.00,5.00,5.00,5.00,5.00,5.00,5.00,5.00,5.00,5.00,5.00,5.00,5.00"
					( Origin gBackEnd )
				)
				( attribute "MVIA_TO_LINE_SPACING" "5.00,5.00,5.00,5.00,5.00,5.00,5.00,5.00,5.00,5.00,5.00,5.00,5.00,5.00"
					( Origin gBackEnd )
				)
				( attribute "MVIA_TO_SHAPE_SPACING" "5.00,5.00,5.00,5.00,5.00,5.00,5.00,5.00,5.00,5.00,5.00,5.00,5.00,5.00"
					( Origin gBackEnd )
				)
				( attribute "MVIA_TO_TESTPIN_SPACING" "5.00,5.00,5.00,5.00,5.00,5.00,5.00,5.00,5.00,5.00,5.00,5.00,5.00,5.00"
					( Origin gBackEnd )
				)
				( attribute "MVIA_TO_TESTVIA_SPACING" "5.00,5.00,5.00,5.00,5.00,5.00,5.00,5.00,5.00,5.00,5.00,5.00,5.00,5.00"
					( Origin gBackEnd )
				)
				( attribute "BONDPAD_TO_MVIA_SPACING" "5.00,5.00,5.00,5.00,5.00,5.00,5.00,5.00,5.00,5.00,5.00,5.00,5.00,5.00"
					( Origin gBackEnd )
				)
				( attribute "MIN_BVIA_GAP" "5.00"
					( Origin gBackEnd )
				)
				( attribute "BONDPAD_TO_BONDPAD_DIFFP_SPC" "5.00,5.00,5.00,5.00,5.00,5.00,5.00,5.00,5.00,5.00,5.00,5.00,5.00,5.00"
					( Origin gBackEnd )
				)
				( objectStatus "7H_US_&_3H_SL" )
			)
			( spacingCSet "@sapphirecity_baseboard_lib.sapphirecity_baseboard(sch_1):\4H\"
				( attribute "THRUPIN_TO_THRUPIN_SPACING" "5.00,5.00,5.00,5.00,5.00,5.00,5.00,5.00,5.00,5.00,5.00,5.00,5.00,5.00"
					( Origin gBackEnd )
				)
				( attribute "THRUPIN_TO_SMDPIN_SPACING" "5.00,5.00,5.00,5.00,5.00,5.00,5.00,5.00,5.00,5.00,5.00,5.00,5.00,5.00"
					( Origin gBackEnd )
				)
				( attribute "TESTPIN_TO_THRUPIN_SPACING" "5.00,5.00,5.00,5.00,5.00,5.00,5.00,5.00,5.00,5.00,5.00,5.00,5.00,5.00"
					( Origin gBackEnd )
				)
				( attribute "THRUPIN_TO_THRUVIA_SPACING" "5.00,5.00,5.00,5.00,5.00,5.00,5.00,5.00,5.00,5.00,5.00,5.00,5.00,5.00"
					( Origin gBackEnd )
				)
				( attribute "TESTVIA_TO_THRUPIN_SPACING" "5.00,5.00,5.00,5.00,5.00,5.00,5.00,5.00,5.00,5.00,5.00,5.00,5.00,5.00"
					( Origin gBackEnd )
				)
				( attribute "BBV_TO_THRUPIN_SPACING" "5.00,5.00,5.00,5.00,5.00,5.00,5.00,5.00,5.00,5.00,5.00,5.00,5.00,5.00"
					( Origin gBackEnd )
				)
				( attribute "THRUPIN_TO_BONDPAD_SPACING" "5.00,5.00,5.00,5.00,5.00,5.00,5.00,5.00,5.00,5.00,5.00,5.00,5.00,5.00"
					( Origin gBackEnd )
				)
				( attribute "LINE_TO_THRUPIN_SPACING" "4.50,4.00,4.00,4.00,4.00,4.00,4.00,4.00,4.00,4.00,4.00,4.00,4.00,4.50"
					( Origin gBackEnd )
				)
				( attribute "THRUPIN_TO_SHAPE_SPACING" "4.50,4.00,4.00,4.00,4.00,4.00,4.00,4.00,4.00,4.00,4.00,4.00,4.00,4.00"
					( Origin gBackEnd )
				)
				( attribute "SMDPIN_TO_SMDPIN_SPACING" "5.00,5.00,5.00,5.00,5.00,5.00,5.00,5.00,5.00,5.00,5.00,5.00,5.00,5.00"
					( Origin gBackEnd )
				)
				( attribute "SMDPIN_TO_TESTPIN_SPACING" "5.00,5.00,5.00,5.00,5.00,5.00,5.00,5.00,5.00,5.00,5.00,5.00,5.00,5.00"
					( Origin gBackEnd )
				)
				( attribute "SMDPIN_TO_THRUVIA_SPACING" "5.00,5.00,5.00,5.00,5.00,5.00,5.00,5.00,5.00,5.00,5.00,5.00,5.00,5.00"
					( Origin gBackEnd )
				)
				( attribute "SMDPIN_TO_TESTVIA_SPACING" "5.00,5.00,5.00,5.00,5.00,5.00,5.00,5.00,5.00,5.00,5.00,5.00,5.00,5.00"
					( Origin gBackEnd )
				)
				( attribute "BBV_TO_SMDPIN_SPACING" "5.00,5.00,5.00,5.00,5.00,5.00,5.00,5.00,5.00,5.00,5.00,5.00,5.00,5.00"
					( Origin gBackEnd )
				)
				( attribute "SMDPIN_TO_BONDPAD_SPACING" "5.00,5.00,5.00,5.00,5.00,5.00,5.00,5.00,5.00,5.00,5.00,5.00,5.00,5.00"
					( Origin gBackEnd )
				)
				( attribute "LINE_TO_SMDPIN_SPACING" "4.50,4.50,4.50,4.50,4.50,4.50,4.50,4.50,4.50,4.50,4.50,4.50,4.50,4.50"
					( Origin gBackEnd )
				)
				( attribute "SHAPE_TO_SMDPIN_SPACING" "5.00,5.00,5.00,5.00,5.00,5.00,5.00,5.00,5.00,5.00,5.00,5.00,5.00,5.00"
					( Origin gBackEnd )
				)
				( attribute "TESTPIN_TO_TESTPIN_SPACING" "5.00,5.00,5.00,5.00,5.00,5.00,5.00,5.00,5.00,5.00,5.00,5.00,5.00,5.00"
					( Origin gBackEnd )
				)
				( attribute "TESTPIN_TO_THRUVIA_SPACING" "5.00,5.00,5.00,5.00,5.00,5.00,5.00,5.00,5.00,5.00,5.00,5.00,5.00,5.00"
					( Origin gBackEnd )
				)
				( attribute "TESTPIN_TO_TESTVIA_SPACING" "5.00,5.00,5.00,5.00,5.00,5.00,5.00,5.00,5.00,5.00,5.00,5.00,5.00,5.00"
					( Origin gBackEnd )
				)
				( attribute "BBV_TO_TESTPIN_SPACING" "5.00,5.00,5.00,5.00,5.00,5.00,5.00,5.00,5.00,5.00,5.00,5.00,5.00,5.00"
					( Origin gBackEnd )
				)
				( attribute "BONDPAD_TO_TESTPIN_SPACING" "5.00,5.00,5.00,5.00,5.00,5.00,5.00,5.00,5.00,5.00,5.00,5.00,5.00,5.00"
					( Origin gBackEnd )
				)
				( attribute "LINE_TO_TESTPIN_SPACING" "4.50,5.00,5.00,5.00,5.00,5.00,5.00,5.00,5.00,5.00,5.00,5.00,5.00,5.00"
					( Origin gBackEnd )
				)
				( attribute "SHAPE_TO_TESTPIN_SPACING" "4.50,4.00,4.00,4.00,4.00,4.00,4.00,4.00,4.00,4.00,4.00,4.00,4.00,4.00"
					( Origin gBackEnd )
				)
				( attribute "THRUVIA_TO_THRUVIA_SPACING" "5.00,5.00,5.00,5.00,5.00,5.00,5.00,5.00,5.00,5.00,5.00,5.00,5.00,5.00"
					( Origin gBackEnd )
				)
				( attribute "TESTVIA_TO_THRUVIA_SPACING" "5.00,5.00,5.00,5.00,5.00,5.00,5.00,5.00,5.00,5.00,5.00,5.00,5.00,5.00"
					( Origin gBackEnd )
				)
				( attribute "BBV_TO_THRUVIA_SPACING" "5.00,5.00,5.00,5.00,5.00,5.00,5.00,5.00,5.00,5.00,5.00,5.00,5.00,5.00"
					( Origin gBackEnd )
				)
				( attribute "BONDPAD_TO_THRUVIA_SPACING" "5.00,5.00,5.00,5.00,5.00,5.00,5.00,5.00,5.00,5.00,5.00,5.00,5.00,5.00"
					( Origin gBackEnd )
				)
				( attribute "LINE_TO_THRUVIA_SPACING" "4.50,4.00,4.00,4.00,4.00,4.00,4.00,4.00,4.00,4.00,4.00,4.00,4.00,4.50"
					( Origin gBackEnd )
				)
				( attribute "SHAPE_TO_THRUVIA_SPACING" "4.50,4.00,4.00,4.00,4.00,4.00,4.00,4.00,4.00,4.00,4.00,4.00,4.00,4.00"
					( Origin gBackEnd )
				)
				( attribute "TESTVIA_TO_TESTVIA_SPACING" "5.00,5.00,5.00,5.00,5.00,5.00,5.00,5.00,5.00,5.00,5.00,5.00,5.00,5.00"
					( Origin gBackEnd )
				)
				( attribute "BBV_TO_TESTVIA_SPACING" "5.00,5.00,5.00,5.00,5.00,5.00,5.00,5.00,5.00,5.00,5.00,5.00,5.00,5.00"
					( Origin gBackEnd )
				)
				( attribute "BONDPAD_TO_TESTVIA_SPACING" "5.00,5.00,5.00,5.00,5.00,5.00,5.00,5.00,5.00,5.00,5.00,5.00,5.00,5.00"
					( Origin gBackEnd )
				)
				( attribute "LINE_TO_TESTVIA_SPACING" "4.50,5.00,4.00,5.00,4.00,5.00,5.00,5.00,5.00,4.00,5.00,4.00,5.00,4.50"
					( Origin gBackEnd )
				)
				( attribute "SHAPE_TO_TESTVIA_SPACING" "4.50,4.00,4.00,4.00,4.00,4.00,4.00,4.00,4.00,4.00,4.00,4.00,4.00,4.00"
					( Origin gBackEnd )
				)
				( attribute "BBV_TO_BBV_SPACING" "5.00,5.00,5.00,5.00,5.00,5.00,5.00,5.00,5.00,5.00,5.00,5.00,5.00,5.00"
					( Origin gBackEnd )
				)
				( attribute "BONDPAD_TO_BBV_SPACING" "5.00,5.00,5.00,5.00,5.00,5.00,5.00,5.00,5.00,5.00,5.00,5.00,5.00,5.00"
					( Origin gBackEnd )
				)
				( attribute "BBV_TO_LINE_SPACING" "5.00,5.00,5.00,5.00,5.00,5.00,5.00,5.00,5.00,5.00,5.00,5.00,5.00,5.00"
					( Origin gBackEnd )
				)
				( attribute "BBV_TO_SHAPE_SPACING" "5.00,5.00,5.00,5.00,5.00,5.00,5.00,5.00,5.00,5.00,5.00,5.00,5.00,5.00"
					( Origin gBackEnd )
				)
				( attribute "BONDPAD_TO_BONDPAD_SPACING" "5.00,5.00,5.00,5.00,5.00,5.00,5.00,5.00,5.00,5.00,5.00,5.00,5.00,5.00"
					( Origin gBackEnd )
				)
				( attribute "BONDPAD_TO_LINE_SPACING" "5.00,5.00,5.00,5.00,5.00,5.00,5.00,5.00,5.00,5.00,5.00,5.00,5.00,5.00"
					( Origin gBackEnd )
				)
				( attribute "BONDPAD_TO_SHAPE_SPACING" "5.00,5.00,5.00,5.00,5.00,5.00,5.00,5.00,5.00,5.00,5.00,5.00,5.00,5.00"
					( Origin gBackEnd )
				)
				( attribute "LINE_TO_LINE_SPACING" "10.80,12.00,12.00,12.00,12.00,12.00,12.00,12.00,12.00,12.00,12.00,12.00,12.00,16.00"
					( Origin gBackEnd )
				)
				( attribute "LINE_TO_SHAPE_SPACING" "5.00,5.00,5.00,5.00,5.00,5.00,5.00,5.00,5.00,5.00,5.00,5.00,5.00,5.00"
					( Origin gBackEnd )
				)
				( attribute "SHAPE_TO_SHAPE_SPACING" "10.00,10.00,10.00,10.00,10.00,10.00,10.00,10.00,10.00,10.00,10.00,10.00,10.00,10.00"
					( Origin gBackEnd )
				)
				( attribute "HOLE_TO_PIN_SPACING" "8.00,8.00,8.00,8.00,8.00,8.00,8.00,8.00,8.00,8.00,8.00,8.00,8.00,8.00"
					( Origin gBackEnd )
				)
				( attribute "HOLE_TO_VIA_SPACING" "8.00,8.00,8.00,8.00,8.00,8.00,8.00,8.00,8.00,8.00,8.00,8.00,8.00,8.00"
					( Origin gBackEnd )
				)
				( attribute "HOLE_TO_LINE_SPACING" "8.00,8.00,8.00,8.00,8.00,8.00,8.00,8.00,8.00,8.00,8.00,8.00,8.00,8.00"
					( Origin gBackEnd )
				)
				( attribute "HOLE_TO_SHAPE_SPACING" "8.00,8.00,8.00,8.00,8.00,8.00,8.00,8.00,8.00,8.00,8.00,8.00,8.00,8.00"
					( Origin gBackEnd )
				)
				( attribute "HOLE_TO_HOLE_SPACING" "8.00,8.00,8.00,8.00,8.00,8.00,8.00,8.00,8.00,8.00,8.00,8.00,8.00,8.00"
					( Origin gBackEnd )
				)
				( attribute "MVIA_TO_MVIA_SPACING" "5.00,5.00,5.00,5.00,5.00,5.00,5.00,5.00,5.00,5.00,5.00,5.00,5.00,5.00"
					( Origin gBackEnd )
				)
				( attribute "MVIA_TO_THRUPIN_SPACING" "5.00,5.00,5.00,5.00,5.00,5.00,5.00,5.00,5.00,5.00,5.00,5.00,5.00,5.00"
					( Origin gBackEnd )
				)
				( attribute "MVIA_TO_SMDPIN_SPACING" "5.00,5.00,5.00,5.00,5.00,5.00,5.00,5.00,5.00,5.00,5.00,5.00,5.00,5.00"
					( Origin gBackEnd )
				)
				( attribute "MVIA_TO_THRUVIA_SPACING" "5.00,5.00,5.00,5.00,5.00,5.00,5.00,5.00,5.00,5.00,5.00,5.00,5.00,5.00"
					( Origin gBackEnd )
				)
				( attribute "MVIA_TO_BBV_SPACING" "5.00,5.00,5.00,5.00,5.00,5.00,5.00,5.00,5.00,5.00,5.00,5.00,5.00,5.00"
					( Origin gBackEnd )
				)
				( attribute "MVIA_TO_LINE_SPACING" "5.00,5.00,5.00,5.00,5.00,5.00,5.00,5.00,5.00,5.00,5.00,5.00,5.00,5.00"
					( Origin gBackEnd )
				)
				( attribute "MVIA_TO_SHAPE_SPACING" "5.00,5.00,5.00,5.00,5.00,5.00,5.00,5.00,5.00,5.00,5.00,5.00,5.00,5.00"
					( Origin gBackEnd )
				)
				( attribute "MVIA_TO_TESTPIN_SPACING" "5.00,5.00,5.00,5.00,5.00,5.00,5.00,5.00,5.00,5.00,5.00,5.00,5.00,5.00"
					( Origin gBackEnd )
				)
				( attribute "MVIA_TO_TESTVIA_SPACING" "5.00,5.00,5.00,5.00,5.00,5.00,5.00,5.00,5.00,5.00,5.00,5.00,5.00,5.00"
					( Origin gBackEnd )
				)
				( attribute "BONDPAD_TO_MVIA_SPACING" "5.00,5.00,5.00,5.00,5.00,5.00,5.00,5.00,5.00,5.00,5.00,5.00,5.00,5.00"
					( Origin gBackEnd )
				)
				( attribute "MIN_BVIA_GAP" "5.00"
					( Origin gBackEnd )
				)
				( attribute "BONDPAD_TO_BONDPAD_DIFFP_SPC" "5.00,5.00,5.00,5.00,5.00,5.00,5.00,5.00,5.00,5.00,5.00,5.00,5.00,5.00"
					( Origin gBackEnd )
				)
				( objectStatus "4H" )
			)
			( spacingCSet "@sapphirecity_baseboard_lib.sapphirecity_baseboard(sch_1):\11H_US_AND_5H_SL_VIA+3H_A\"
				( attribute "THRUPIN_TO_THRUPIN_SPACING" "5.00,5.00,5.00,5.00,5.00,5.00,5.00,5.00,5.00,5.00,5.00,5.00,5.00,5.00"
					( Origin gBackEnd )
				)
				( attribute "THRUPIN_TO_SMDPIN_SPACING" "5.00,5.00,5.00,5.00,5.00,5.00,5.00,5.00,5.00,5.00,5.00,5.00,5.00,5.00"
					( Origin gBackEnd )
				)
				( attribute "TESTPIN_TO_THRUPIN_SPACING" "5.00,5.00,5.00,5.00,5.00,5.00,5.00,5.00,5.00,5.00,5.00,5.00,5.00,5.00"
					( Origin gBackEnd )
				)
				( attribute "THRUPIN_TO_THRUVIA_SPACING" "5.00,5.00,5.00,5.00,5.00,5.00,5.00,5.00,5.00,5.00,5.00,5.00,5.00,5.00"
					( Origin gBackEnd )
				)
				( attribute "TESTVIA_TO_THRUPIN_SPACING" "5.00,5.00,5.00,5.00,5.00,5.00,5.00,5.00,5.00,5.00,5.00,5.00,5.00,5.00"
					( Origin gBackEnd )
				)
				( attribute "BBV_TO_THRUPIN_SPACING" "5.00,5.00,5.00,5.00,5.00,5.00,5.00,5.00,5.00,5.00,5.00,5.00,5.00,5.00"
					( Origin gBackEnd )
				)
				( attribute "THRUPIN_TO_BONDPAD_SPACING" "5.00,5.00,5.00,5.00,5.00,5.00,5.00,5.00,5.00,5.00,5.00,5.00,5.00,5.00"
					( Origin gBackEnd )
				)
				( attribute "LINE_TO_THRUPIN_SPACING" "4.50,4.00,4.00,4.00,4.00,4.00,4.00,4.00,4.00,4.00,4.00,4.00,4.00,4.50"
					( Origin gBackEnd )
				)
				( attribute "THRUPIN_TO_SHAPE_SPACING" "4.50,4.00,4.00,4.00,4.00,4.00,4.00,4.00,4.00,4.00,4.00,4.00,4.00,4.00"
					( Origin gBackEnd )
				)
				( attribute "SMDPIN_TO_SMDPIN_SPACING" "5.00,5.00,5.00,5.00,5.00,5.00,5.00,5.00,5.00,5.00,5.00,5.00,5.00,5.00"
					( Origin gBackEnd )
				)
				( attribute "SMDPIN_TO_TESTPIN_SPACING" "5.00,5.00,5.00,5.00,5.00,5.00,5.00,5.00,5.00,5.00,5.00,5.00,5.00,5.00"
					( Origin gBackEnd )
				)
				( attribute "SMDPIN_TO_THRUVIA_SPACING" "5.00,5.00,5.00,5.00,5.00,5.00,5.00,5.00,5.00,5.00,5.00,5.00,5.00,5.00"
					( Origin gBackEnd )
				)
				( attribute "SMDPIN_TO_TESTVIA_SPACING" "5.00,5.00,5.00,5.00,5.00,5.00,5.00,5.00,5.00,5.00,5.00,5.00,5.00,5.00"
					( Origin gBackEnd )
				)
				( attribute "BBV_TO_SMDPIN_SPACING" "5.00,5.00,5.00,5.00,5.00,5.00,5.00,5.00,5.00,5.00,5.00,5.00,5.00,5.00"
					( Origin gBackEnd )
				)
				( attribute "SMDPIN_TO_BONDPAD_SPACING" "5.00,5.00,5.00,5.00,5.00,5.00,5.00,5.00,5.00,5.00,5.00,5.00,5.00,5.00"
					( Origin gBackEnd )
				)
				( attribute "LINE_TO_SMDPIN_SPACING" "4.50,4.50,4.50,4.50,4.50,4.50,4.50,4.50,4.50,4.50,4.50,4.50,4.50,4.50"
					( Origin gBackEnd )
				)
				( attribute "SHAPE_TO_SMDPIN_SPACING" "5.00,5.00,5.00,5.00,5.00,5.00,5.00,5.00,5.00,5.00,5.00,5.00,5.00,5.00"
					( Origin gBackEnd )
				)
				( attribute "TESTPIN_TO_TESTPIN_SPACING" "5.00,5.00,5.00,5.00,5.00,5.00,5.00,5.00,5.00,5.00,5.00,5.00,5.00,5.00"
					( Origin gBackEnd )
				)
				( attribute "TESTPIN_TO_THRUVIA_SPACING" "5.00,5.00,5.00,5.00,5.00,5.00,5.00,5.00,5.00,5.00,5.00,5.00,5.00,5.00"
					( Origin gBackEnd )
				)
				( attribute "TESTPIN_TO_TESTVIA_SPACING" "5.00,5.00,5.00,5.00,5.00,5.00,5.00,5.00,5.00,5.00,5.00,5.00,5.00,5.00"
					( Origin gBackEnd )
				)
				( attribute "BBV_TO_TESTPIN_SPACING" "5.00,5.00,5.00,5.00,5.00,5.00,5.00,5.00,5.00,5.00,5.00,5.00,5.00,5.00"
					( Origin gBackEnd )
				)
				( attribute "BONDPAD_TO_TESTPIN_SPACING" "5.00,5.00,5.00,5.00,5.00,5.00,5.00,5.00,5.00,5.00,5.00,5.00,5.00,5.00"
					( Origin gBackEnd )
				)
				( attribute "LINE_TO_TESTPIN_SPACING" "4.50,5.00,5.00,5.00,5.00,5.00,5.00,5.00,5.00,5.00,5.00,5.00,5.00,5.00"
					( Origin gBackEnd )
				)
				( attribute "SHAPE_TO_TESTPIN_SPACING" "4.50,4.00,4.00,4.00,4.00,4.00,4.00,4.00,4.00,4.00,4.00,4.00,4.00,4.00"
					( Origin gBackEnd )
				)
				( attribute "THRUVIA_TO_THRUVIA_SPACING" "5.00,5.00,5.00,5.00,5.00,5.00,5.00,5.00,5.00,5.00,5.00,5.00,5.00,5.00"
					( Origin gBackEnd )
				)
				( attribute "TESTVIA_TO_THRUVIA_SPACING" "5.00,5.00,5.00,5.00,5.00,5.00,5.00,5.00,5.00,5.00,5.00,5.00,5.00,5.00"
					( Origin gBackEnd )
				)
				( attribute "BBV_TO_THRUVIA_SPACING" "5.00,5.00,5.00,5.00,5.00,5.00,5.00,5.00,5.00,5.00,5.00,5.00,5.00,5.00"
					( Origin gBackEnd )
				)
				( attribute "BONDPAD_TO_THRUVIA_SPACING" "5.00,5.00,5.00,5.00,5.00,5.00,5.00,5.00,5.00,5.00,5.00,5.00,5.00,5.00"
					( Origin gBackEnd )
				)
				( attribute "LINE_TO_THRUVIA_SPACING" "12.00,5.00,13.00,5.00,13.00,5.00,5.00,5.00,5.00,13.00,5.00,13.00,5.00,12.00"
					( Origin gBackEnd )
				)
				( attribute "SHAPE_TO_THRUVIA_SPACING" "4.50,4.00,4.00,4.00,4.00,4.00,4.00,4.00,4.00,4.00,4.00,4.00,4.00,4.00"
					( Origin gBackEnd )
				)
				( attribute "TESTVIA_TO_TESTVIA_SPACING" "5.00,5.00,5.00,5.00,5.00,5.00,5.00,5.00,5.00,5.00,5.00,5.00,5.00,5.00"
					( Origin gBackEnd )
				)
				( attribute "BBV_TO_TESTVIA_SPACING" "5.00,5.00,5.00,5.00,5.00,5.00,5.00,5.00,5.00,5.00,5.00,5.00,5.00,5.00"
					( Origin gBackEnd )
				)
				( attribute "BONDPAD_TO_TESTVIA_SPACING" "5.00,5.00,5.00,5.00,5.00,5.00,5.00,5.00,5.00,5.00,5.00,5.00,5.00,5.00"
					( Origin gBackEnd )
				)
				( attribute "LINE_TO_TESTVIA_SPACING" "12.00,5.00,13.00,5.00,13.00,5.00,5.00,5.00,5.00,13.00,5.00,13.00,5.00,12.00"
					( Origin gBackEnd )
				)
				( attribute "SHAPE_TO_TESTVIA_SPACING" "4.50,4.00,4.00,4.00,4.00,4.00,4.00,4.00,4.00,4.00,4.00,4.00,4.00,4.00"
					( Origin gBackEnd )
				)
				( attribute "BBV_TO_BBV_SPACING" "5.00,5.00,5.00,5.00,5.00,5.00,5.00,5.00,5.00,5.00,5.00,5.00,5.00,5.00"
					( Origin gBackEnd )
				)
				( attribute "BONDPAD_TO_BBV_SPACING" "5.00,5.00,5.00,5.00,5.00,5.00,5.00,5.00,5.00,5.00,5.00,5.00,5.00,5.00"
					( Origin gBackEnd )
				)
				( attribute "BBV_TO_LINE_SPACING" "5.00,5.00,5.00,5.00,5.00,5.00,5.00,5.00,5.00,5.00,5.00,5.00,5.00,5.00"
					( Origin gBackEnd )
				)
				( attribute "BBV_TO_SHAPE_SPACING" "5.00,5.00,5.00,5.00,5.00,5.00,5.00,5.00,5.00,5.00,5.00,5.00,5.00,5.00"
					( Origin gBackEnd )
				)
				( attribute "BONDPAD_TO_BONDPAD_SPACING" "5.00,5.00,5.00,5.00,5.00,5.00,5.00,5.00,5.00,5.00,5.00,5.00,5.00,5.00"
					( Origin gBackEnd )
				)
				( attribute "BONDPAD_TO_LINE_SPACING" "5.00,5.00,5.00,5.00,5.00,5.00,5.00,5.00,5.00,5.00,5.00,5.00,5.00,5.00"
					( Origin gBackEnd )
				)
				( attribute "BONDPAD_TO_SHAPE_SPACING" "5.00,5.00,5.00,5.00,5.00,5.00,5.00,5.00,5.00,5.00,5.00,5.00,5.00,5.00"
					( Origin gBackEnd )
				)
				( attribute "LINE_TO_LINE_SPACING" "29.37,15.00,15.00,15.00,15.00,15.00,15.00,15.00,15.00,15.00,15.00,15.00,15.00,29.37"
					( Origin gBackEnd )
				)
				( attribute "LINE_TO_SHAPE_SPACING" "5.00,5.00,5.00,5.00,5.00,5.00,5.00,5.00,5.00,5.00,5.00,5.00,5.00,5.00"
					( Origin gBackEnd )
				)
				( attribute "SHAPE_TO_SHAPE_SPACING" "10.00,10.00,10.00,10.00,10.00,10.00,10.00,10.00,10.00,10.00,10.00,10.00,10.00,10.00"
					( Origin gBackEnd )
				)
				( attribute "HOLE_TO_PIN_SPACING" "8.00,8.00,8.00,8.00,8.00,8.00,8.00,8.00,8.00,8.00,8.00,8.00,8.00,8.00"
					( Origin gBackEnd )
				)
				( attribute "HOLE_TO_VIA_SPACING" "8.00,8.00,8.00,8.00,8.00,8.00,8.00,8.00,8.00,8.00,8.00,8.00,8.00,8.00"
					( Origin gBackEnd )
				)
				( attribute "HOLE_TO_LINE_SPACING" "8.00,8.00,8.00,8.00,8.00,8.00,8.00,8.00,8.00,8.00,8.00,8.00,8.00,8.00"
					( Origin gBackEnd )
				)
				( attribute "HOLE_TO_SHAPE_SPACING" "8.00,8.00,8.00,8.00,8.00,8.00,8.00,8.00,8.00,8.00,8.00,8.00,8.00,8.00"
					( Origin gBackEnd )
				)
				( attribute "HOLE_TO_HOLE_SPACING" "8.00,8.00,8.00,8.00,8.00,8.00,8.00,8.00,8.00,8.00,8.00,8.00,8.00,8.00"
					( Origin gBackEnd )
				)
				( attribute "MVIA_TO_MVIA_SPACING" "5.00,5.00,5.00,5.00,5.00,5.00,5.00,5.00,5.00,5.00,5.00,5.00,5.00,5.00"
					( Origin gBackEnd )
				)
				( attribute "MVIA_TO_THRUPIN_SPACING" "5.00,5.00,5.00,5.00,5.00,5.00,5.00,5.00,5.00,5.00,5.00,5.00,5.00,5.00"
					( Origin gBackEnd )
				)
				( attribute "MVIA_TO_SMDPIN_SPACING" "5.00,5.00,5.00,5.00,5.00,5.00,5.00,5.00,5.00,5.00,5.00,5.00,5.00,5.00"
					( Origin gBackEnd )
				)
				( attribute "MVIA_TO_THRUVIA_SPACING" "5.00,5.00,5.00,5.00,5.00,5.00,5.00,5.00,5.00,5.00,5.00,5.00,5.00,5.00"
					( Origin gBackEnd )
				)
				( attribute "MVIA_TO_BBV_SPACING" "5.00,5.00,5.00,5.00,5.00,5.00,5.00,5.00,5.00,5.00,5.00,5.00,5.00,5.00"
					( Origin gBackEnd )
				)
				( attribute "MVIA_TO_LINE_SPACING" "5.00,5.00,5.00,5.00,5.00,5.00,5.00,5.00,5.00,5.00,5.00,5.00,5.00,5.00"
					( Origin gBackEnd )
				)
				( attribute "MVIA_TO_SHAPE_SPACING" "5.00,5.00,5.00,5.00,5.00,5.00,5.00,5.00,5.00,5.00,5.00,5.00,5.00,5.00"
					( Origin gBackEnd )
				)
				( attribute "MVIA_TO_TESTPIN_SPACING" "5.00,5.00,5.00,5.00,5.00,5.00,5.00,5.00,5.00,5.00,5.00,5.00,5.00,5.00"
					( Origin gBackEnd )
				)
				( attribute "MVIA_TO_TESTVIA_SPACING" "5.00,5.00,5.00,5.00,5.00,5.00,5.00,5.00,5.00,5.00,5.00,5.00,5.00,5.00"
					( Origin gBackEnd )
				)
				( attribute "BONDPAD_TO_MVIA_SPACING" "5.00,5.00,5.00,5.00,5.00,5.00,5.00,5.00,5.00,5.00,5.00,5.00,5.00,5.00"
					( Origin gBackEnd )
				)
				( attribute "MIN_BVIA_GAP" "5.00"
					( Origin gBackEnd )
				)
				( attribute "BONDPAD_TO_BONDPAD_DIFFP_SPC" "5.00,5.00,5.00,5.00,5.00,5.00,5.00,5.00,5.00,5.00,5.00,5.00,5.00,5.00"
					( Origin gBackEnd )
				)
				( objectStatus "11H_US_&_5H_SL_VIA_3H+A" )
			)
			( spacingCSet "@sapphirecity_baseboard_lib.sapphirecity_baseboard(sch_1):\2.5H_US_AND_2H_SL\"
				( attribute "THRUPIN_TO_THRUPIN_SPACING" "5.00,5.00,5.00,5.00,5.00,5.00,5.00,5.00,5.00,5.00,5.00,5.00,5.00,5.00"
					( Origin gBackEnd )
				)
				( attribute "THRUPIN_TO_SMDPIN_SPACING" "5.00,5.00,5.00,5.00,5.00,5.00,5.00,5.00,5.00,5.00,5.00,5.00,5.00,5.00"
					( Origin gBackEnd )
				)
				( attribute "TESTPIN_TO_THRUPIN_SPACING" "5.00,5.00,5.00,5.00,5.00,5.00,5.00,5.00,5.00,5.00,5.00,5.00,5.00,5.00"
					( Origin gBackEnd )
				)
				( attribute "THRUPIN_TO_THRUVIA_SPACING" "5.00,5.00,5.00,5.00,5.00,5.00,5.00,5.00,5.00,5.00,5.00,5.00,5.00,5.00"
					( Origin gBackEnd )
				)
				( attribute "TESTVIA_TO_THRUPIN_SPACING" "5.00,5.00,5.00,5.00,5.00,5.00,5.00,5.00,5.00,5.00,5.00,5.00,5.00,5.00"
					( Origin gBackEnd )
				)
				( attribute "BBV_TO_THRUPIN_SPACING" "5.00,5.00,5.00,5.00,5.00,5.00,5.00,5.00,5.00,5.00,5.00,5.00,5.00,5.00"
					( Origin gBackEnd )
				)
				( attribute "THRUPIN_TO_BONDPAD_SPACING" "5.00,5.00,5.00,5.00,5.00,5.00,5.00,5.00,5.00,5.00,5.00,5.00,5.00,5.00"
					( Origin gBackEnd )
				)
				( attribute "LINE_TO_THRUPIN_SPACING" "4.50,4.00,4.00,4.00,4.00,4.00,4.00,4.00,4.00,4.00,4.00,4.00,4.00,4.50"
					( Origin gBackEnd )
				)
				( attribute "THRUPIN_TO_SHAPE_SPACING" "4.50,4.00,4.00,4.00,4.00,4.00,4.00,4.00,4.00,4.00,4.00,4.00,4.00,4.00"
					( Origin gBackEnd )
				)
				( attribute "SMDPIN_TO_SMDPIN_SPACING" "5.00,5.00,5.00,5.00,5.00,5.00,5.00,5.00,5.00,5.00,5.00,5.00,5.00,5.00"
					( Origin gBackEnd )
				)
				( attribute "SMDPIN_TO_TESTPIN_SPACING" "5.00,5.00,5.00,5.00,5.00,5.00,5.00,5.00,5.00,5.00,5.00,5.00,5.00,5.00"
					( Origin gBackEnd )
				)
				( attribute "SMDPIN_TO_THRUVIA_SPACING" "5.00,5.00,5.00,5.00,5.00,5.00,5.00,5.00,5.00,5.00,5.00,5.00,5.00,5.00"
					( Origin gBackEnd )
				)
				( attribute "SMDPIN_TO_TESTVIA_SPACING" "5.00,5.00,5.00,5.00,5.00,5.00,5.00,5.00,5.00,5.00,5.00,5.00,5.00,5.00"
					( Origin gBackEnd )
				)
				( attribute "BBV_TO_SMDPIN_SPACING" "5.00,5.00,5.00,5.00,5.00,5.00,5.00,5.00,5.00,5.00,5.00,5.00,5.00,5.00"
					( Origin gBackEnd )
				)
				( attribute "SMDPIN_TO_BONDPAD_SPACING" "5.00,5.00,5.00,5.00,5.00,5.00,5.00,5.00,5.00,5.00,5.00,5.00,5.00,5.00"
					( Origin gBackEnd )
				)
				( attribute "LINE_TO_SMDPIN_SPACING" "4.50,4.50,4.50,4.50,4.50,4.50,4.50,4.50,4.50,4.50,4.50,4.50,4.50,4.50"
					( Origin gBackEnd )
				)
				( attribute "SHAPE_TO_SMDPIN_SPACING" "5.00,5.00,5.00,5.00,5.00,5.00,5.00,5.00,5.00,5.00,5.00,5.00,5.00,5.00"
					( Origin gBackEnd )
				)
				( attribute "TESTPIN_TO_TESTPIN_SPACING" "5.00,5.00,5.00,5.00,5.00,5.00,5.00,5.00,5.00,5.00,5.00,5.00,5.00,5.00"
					( Origin gBackEnd )
				)
				( attribute "TESTPIN_TO_THRUVIA_SPACING" "5.00,5.00,5.00,5.00,5.00,5.00,5.00,5.00,5.00,5.00,5.00,5.00,5.00,5.00"
					( Origin gBackEnd )
				)
				( attribute "TESTPIN_TO_TESTVIA_SPACING" "5.00,5.00,5.00,5.00,5.00,5.00,5.00,5.00,5.00,5.00,5.00,5.00,5.00,5.00"
					( Origin gBackEnd )
				)
				( attribute "BBV_TO_TESTPIN_SPACING" "5.00,5.00,5.00,5.00,5.00,5.00,5.00,5.00,5.00,5.00,5.00,5.00,5.00,5.00"
					( Origin gBackEnd )
				)
				( attribute "BONDPAD_TO_TESTPIN_SPACING" "5.00,5.00,5.00,5.00,5.00,5.00,5.00,5.00,5.00,5.00,5.00,5.00,5.00,5.00"
					( Origin gBackEnd )
				)
				( attribute "LINE_TO_TESTPIN_SPACING" "4.50,5.00,5.00,5.00,5.00,5.00,5.00,5.00,5.00,5.00,5.00,5.00,5.00,5.00"
					( Origin gBackEnd )
				)
				( attribute "SHAPE_TO_TESTPIN_SPACING" "4.50,4.00,4.00,4.00,4.00,4.00,4.00,4.00,4.00,4.00,4.00,4.00,4.00,4.00"
					( Origin gBackEnd )
				)
				( attribute "THRUVIA_TO_THRUVIA_SPACING" "5.00,5.00,5.00,5.00,5.00,5.00,5.00,5.00,5.00,5.00,5.00,5.00,5.00,5.00"
					( Origin gBackEnd )
				)
				( attribute "TESTVIA_TO_THRUVIA_SPACING" "5.00,5.00,5.00,5.00,5.00,5.00,5.00,5.00,5.00,5.00,5.00,5.00,5.00,5.00"
					( Origin gBackEnd )
				)
				( attribute "BBV_TO_THRUVIA_SPACING" "5.00,5.00,5.00,5.00,5.00,5.00,5.00,5.00,5.00,5.00,5.00,5.00,5.00,5.00"
					( Origin gBackEnd )
				)
				( attribute "BONDPAD_TO_THRUVIA_SPACING" "5.00,5.00,5.00,5.00,5.00,5.00,5.00,5.00,5.00,5.00,5.00,5.00,5.00,5.00"
					( Origin gBackEnd )
				)
				( attribute "LINE_TO_THRUVIA_SPACING" "4.50,4.00,4.00,4.00,4.00,4.00,4.00,4.00,4.00,4.00,4.00,4.00,4.00,4.50"
					( Origin gBackEnd )
				)
				( attribute "SHAPE_TO_THRUVIA_SPACING" "4.50,4.00,4.00,4.00,4.00,4.00,4.00,4.00,4.00,4.00,4.00,4.00,4.00,4.00"
					( Origin gBackEnd )
				)
				( attribute "TESTVIA_TO_TESTVIA_SPACING" "5.00,5.00,5.00,5.00,5.00,5.00,5.00,5.00,5.00,5.00,5.00,5.00,5.00,5.00"
					( Origin gBackEnd )
				)
				( attribute "BBV_TO_TESTVIA_SPACING" "5.00,5.00,5.00,5.00,5.00,5.00,5.00,5.00,5.00,5.00,5.00,5.00,5.00,5.00"
					( Origin gBackEnd )
				)
				( attribute "BONDPAD_TO_TESTVIA_SPACING" "5.00,5.00,5.00,5.00,5.00,5.00,5.00,5.00,5.00,5.00,5.00,5.00,5.00,5.00"
					( Origin gBackEnd )
				)
				( attribute "LINE_TO_TESTVIA_SPACING" "4.50,5.00,4.00,5.00,4.00,5.00,5.00,5.00,5.00,4.00,5.00,4.00,5.00,4.50"
					( Origin gBackEnd )
				)
				( attribute "SHAPE_TO_TESTVIA_SPACING" "4.50,4.00,4.00,4.00,4.00,4.00,4.00,4.00,4.00,4.00,4.00,4.00,4.00,4.00"
					( Origin gBackEnd )
				)
				( attribute "BBV_TO_BBV_SPACING" "5.00,5.00,5.00,5.00,5.00,5.00,5.00,5.00,5.00,5.00,5.00,5.00,5.00,5.00"
					( Origin gBackEnd )
				)
				( attribute "BONDPAD_TO_BBV_SPACING" "5.00,5.00,5.00,5.00,5.00,5.00,5.00,5.00,5.00,5.00,5.00,5.00,5.00,5.00"
					( Origin gBackEnd )
				)
				( attribute "BBV_TO_LINE_SPACING" "5.00,5.00,5.00,5.00,5.00,5.00,5.00,5.00,5.00,5.00,5.00,5.00,5.00,5.00"
					( Origin gBackEnd )
				)
				( attribute "BBV_TO_SHAPE_SPACING" "5.00,5.00,5.00,5.00,5.00,5.00,5.00,5.00,5.00,5.00,5.00,5.00,5.00,5.00"
					( Origin gBackEnd )
				)
				( attribute "BONDPAD_TO_BONDPAD_SPACING" "5.00,5.00,5.00,5.00,5.00,5.00,5.00,5.00,5.00,5.00,5.00,5.00,5.00,5.00"
					( Origin gBackEnd )
				)
				( attribute "BONDPAD_TO_LINE_SPACING" "5.00,5.00,5.00,5.00,5.00,5.00,5.00,5.00,5.00,5.00,5.00,5.00,5.00,5.00"
					( Origin gBackEnd )
				)
				( attribute "BONDPAD_TO_SHAPE_SPACING" "5.00,5.00,5.00,5.00,5.00,5.00,5.00,5.00,5.00,5.00,5.00,5.00,5.00,5.00"
					( Origin gBackEnd )
				)
				( attribute "LINE_TO_LINE_SPACING" "6.75,6.00,6.00,6.00,6.00,6.00,6.00,6.00,6.00,6.00,6.00,6.00,6.00,6.75"
					( Origin gBackEnd )
				)
				( attribute "LINE_TO_SHAPE_SPACING" "5.00,5.00,5.00,5.00,5.00,5.00,5.00,5.00,5.00,5.00,5.00,5.00,5.00,5.00"
					( Origin gBackEnd )
				)
				( attribute "SHAPE_TO_SHAPE_SPACING" "10.00,10.00,10.00,10.00,10.00,10.00,10.00,10.00,10.00,10.00,10.00,10.00,10.00,10.00"
					( Origin gBackEnd )
				)
				( attribute "HOLE_TO_PIN_SPACING" "8.00,8.00,8.00,8.00,8.00,8.00,8.00,8.00,8.00,8.00,8.00,8.00,8.00,8.00"
					( Origin gBackEnd )
				)
				( attribute "HOLE_TO_VIA_SPACING" "8.00,8.00,8.00,8.00,8.00,8.00,8.00,8.00,8.00,8.00,8.00,8.00,8.00,8.00"
					( Origin gBackEnd )
				)
				( attribute "HOLE_TO_LINE_SPACING" "8.00,8.00,8.00,8.00,8.00,8.00,8.00,8.00,8.00,8.00,8.00,8.00,8.00,8.00"
					( Origin gBackEnd )
				)
				( attribute "HOLE_TO_SHAPE_SPACING" "8.00,8.00,8.00,8.00,8.00,8.00,8.00,8.00,8.00,8.00,8.00,8.00,8.00,8.00"
					( Origin gBackEnd )
				)
				( attribute "HOLE_TO_HOLE_SPACING" "8.00,8.00,8.00,8.00,8.00,8.00,8.00,8.00,8.00,8.00,8.00,8.00,8.00,8.00"
					( Origin gBackEnd )
				)
				( attribute "MVIA_TO_MVIA_SPACING" "5.00,5.00,5.00,5.00,5.00,5.00,5.00,5.00,5.00,5.00,5.00,5.00,5.00,5.00"
					( Origin gBackEnd )
				)
				( attribute "MVIA_TO_THRUPIN_SPACING" "5.00,5.00,5.00,5.00,5.00,5.00,5.00,5.00,5.00,5.00,5.00,5.00,5.00,5.00"
					( Origin gBackEnd )
				)
				( attribute "MVIA_TO_SMDPIN_SPACING" "5.00,5.00,5.00,5.00,5.00,5.00,5.00,5.00,5.00,5.00,5.00,5.00,5.00,5.00"
					( Origin gBackEnd )
				)
				( attribute "MVIA_TO_THRUVIA_SPACING" "5.00,5.00,5.00,5.00,5.00,5.00,5.00,5.00,5.00,5.00,5.00,5.00,5.00,5.00"
					( Origin gBackEnd )
				)
				( attribute "MVIA_TO_BBV_SPACING" "5.00,5.00,5.00,5.00,5.00,5.00,5.00,5.00,5.00,5.00,5.00,5.00,5.00,5.00"
					( Origin gBackEnd )
				)
				( attribute "MVIA_TO_LINE_SPACING" "5.00,5.00,5.00,5.00,5.00,5.00,5.00,5.00,5.00,5.00,5.00,5.00,5.00,5.00"
					( Origin gBackEnd )
				)
				( attribute "MVIA_TO_SHAPE_SPACING" "5.00,5.00,5.00,5.00,5.00,5.00,5.00,5.00,5.00,5.00,5.00,5.00,5.00,5.00"
					( Origin gBackEnd )
				)
				( attribute "MVIA_TO_TESTPIN_SPACING" "5.00,5.00,5.00,5.00,5.00,5.00,5.00,5.00,5.00,5.00,5.00,5.00,5.00,5.00"
					( Origin gBackEnd )
				)
				( attribute "MVIA_TO_TESTVIA_SPACING" "5.00,5.00,5.00,5.00,5.00,5.00,5.00,5.00,5.00,5.00,5.00,5.00,5.00,5.00"
					( Origin gBackEnd )
				)
				( attribute "BONDPAD_TO_MVIA_SPACING" "5.00,5.00,5.00,5.00,5.00,5.00,5.00,5.00,5.00,5.00,5.00,5.00,5.00,5.00"
					( Origin gBackEnd )
				)
				( attribute "MIN_BVIA_GAP" "5.00"
					( Origin gBackEnd )
				)
				( attribute "BONDPAD_TO_BONDPAD_DIFFP_SPC" "5.00,5.00,5.00,5.00,5.00,5.00,5.00,5.00,5.00,5.00,5.00,5.00,5.00,5.00"
					( Origin gBackEnd )
				)
				( objectStatus "2.5H_US_&_2H_SL" )
			)
			( spacingCSet "@sapphirecity_baseboard_lib.sapphirecity_baseboard(sch_1):\DQ_TO_DQ\"
				( attribute "THRUPIN_TO_THRUPIN_SPACING" "5.00,5.00,5.00,5.00,5.00,5.00,5.00,5.00,5.00,5.00,5.00,5.00,5.00,5.00"
					( Origin gBackEnd )
				)
				( attribute "THRUPIN_TO_SMDPIN_SPACING" "5.00,5.00,5.00,5.00,5.00,5.00,5.00,5.00,5.00,5.00,5.00,5.00,5.00,5.00"
					( Origin gBackEnd )
				)
				( attribute "TESTPIN_TO_THRUPIN_SPACING" "5.00,5.00,5.00,5.00,5.00,5.00,5.00,5.00,5.00,5.00,5.00,5.00,5.00,5.00"
					( Origin gBackEnd )
				)
				( attribute "THRUPIN_TO_THRUVIA_SPACING" "6.00,6.00,6.00,6.00,6.00,6.00,6.00,6.00,6.00,6.00,6.00,6.00,6.00,6.00"
					( Origin gBackEnd )
				)
				( attribute "TESTVIA_TO_THRUPIN_SPACING" "5.00,5.00,5.00,5.00,5.00,5.00,5.00,5.00,5.00,5.00,5.00,5.00,5.00,5.00"
					( Origin gBackEnd )
				)
				( attribute "BBV_TO_THRUPIN_SPACING" "5.00,5.00,5.00,5.00,5.00,5.00,5.00,5.00,5.00,5.00,5.00,5.00,5.00,5.00"
					( Origin gBackEnd )
				)
				( attribute "THRUPIN_TO_BONDPAD_SPACING" "5.00,5.00,5.00,5.00,5.00,5.00,5.00,5.00,5.00,5.00,5.00,5.00,5.00,5.00"
					( Origin gBackEnd )
				)
				( attribute "LINE_TO_THRUPIN_SPACING" "4.50,4.00,4.00,4.00,4.00,4.00,4.00,4.00,4.00,4.00,4.00,4.00,4.00,4.50"
					( Origin gBackEnd )
				)
				( attribute "THRUPIN_TO_SHAPE_SPACING" "5.00,5.00,5.00,5.00,5.00,5.00,5.00,5.00,5.00,5.00,5.00,5.00,5.00,5.00"
					( Origin gBackEnd )
				)
				( attribute "SMDPIN_TO_SMDPIN_SPACING" "5.00,5.00,5.00,5.00,5.00,5.00,5.00,5.00,5.00,5.00,5.00,5.00,5.00,5.00"
					( Origin gBackEnd )
				)
				( attribute "SMDPIN_TO_TESTPIN_SPACING" "5.00,5.00,5.00,5.00,5.00,5.00,5.00,5.00,5.00,5.00,5.00,5.00,5.00,5.00"
					( Origin gBackEnd )
				)
				( attribute "SMDPIN_TO_THRUVIA_SPACING" "5.00,5.00,5.00,5.00,5.00,5.00,5.00,5.00,5.00,5.00,5.00,5.00,5.00,5.00"
					( Origin gBackEnd )
				)
				( attribute "SMDPIN_TO_TESTVIA_SPACING" "5.00,5.00,5.00,5.00,5.00,5.00,5.00,5.00,5.00,5.00,5.00,5.00,5.00,5.00"
					( Origin gBackEnd )
				)
				( attribute "BBV_TO_SMDPIN_SPACING" "5.00,5.00,5.00,5.00,5.00,5.00,5.00,5.00,5.00,5.00,5.00,5.00,5.00,5.00"
					( Origin gBackEnd )
				)
				( attribute "SMDPIN_TO_BONDPAD_SPACING" "5.00,5.00,5.00,5.00,5.00,5.00,5.00,5.00,5.00,5.00,5.00,5.00,5.00,5.00"
					( Origin gBackEnd )
				)
				( attribute "LINE_TO_SMDPIN_SPACING" "4.50,4.50,4.50,4.50,4.50,4.50,4.50,4.50,4.50,4.50,4.50,4.50,4.50,4.50"
					( Origin gBackEnd )
				)
				( attribute "SHAPE_TO_SMDPIN_SPACING" "5.00,5.00,5.00,5.00,5.00,5.00,5.00,5.00,5.00,5.00,5.00,5.00,5.00,5.00"
					( Origin gBackEnd )
				)
				( attribute "TESTPIN_TO_TESTPIN_SPACING" "5.00,5.00,5.00,5.00,5.00,5.00,5.00,5.00,5.00,5.00,5.00,5.00,5.00,5.00"
					( Origin gBackEnd )
				)
				( attribute "TESTPIN_TO_THRUVIA_SPACING" "6.00,6.00,6.00,6.00,6.00,6.00,6.00,6.00,6.00,6.00,6.00,6.00,6.00,6.00"
					( Origin gBackEnd )
				)
				( attribute "TESTPIN_TO_TESTVIA_SPACING" "5.00,5.00,5.00,5.00,5.00,5.00,5.00,5.00,5.00,5.00,5.00,5.00,5.00,5.00"
					( Origin gBackEnd )
				)
				( attribute "BBV_TO_TESTPIN_SPACING" "5.00,5.00,5.00,5.00,5.00,5.00,5.00,5.00,5.00,5.00,5.00,5.00,5.00,5.00"
					( Origin gBackEnd )
				)
				( attribute "BONDPAD_TO_TESTPIN_SPACING" "5.00,5.00,5.00,5.00,5.00,5.00,5.00,5.00,5.00,5.00,5.00,5.00,5.00,5.00"
					( Origin gBackEnd )
				)
				( attribute "LINE_TO_TESTPIN_SPACING" "5.00,4.00,4.00,4.00,4.00,4.00,4.00,4.00,4.00,4.00,4.00,4.00,4.00,5.00"
					( Origin gBackEnd )
				)
				( attribute "SHAPE_TO_TESTPIN_SPACING" "5.00,5.00,5.00,5.00,5.00,5.00,5.00,5.00,5.00,5.00,5.00,5.00,5.00,5.00"
					( Origin gBackEnd )
				)
				( attribute "THRUVIA_TO_THRUVIA_SPACING" "5.00,5.00,5.00,5.00,5.00,5.00,5.00,5.00,5.00,5.00,5.00,5.00,5.00,5.00"
					( Origin gBackEnd )
				)
				( attribute "TESTVIA_TO_THRUVIA_SPACING" "6.00,6.00,6.00,6.00,6.00,6.00,6.00,6.00,6.00,6.00,6.00,6.00,6.00,6.00"
					( Origin gBackEnd )
				)
				( attribute "BBV_TO_THRUVIA_SPACING" "5.00,5.00,5.00,5.00,5.00,5.00,5.00,5.00,5.00,5.00,5.00,5.00,5.00,5.00"
					( Origin gBackEnd )
				)
				( attribute "BONDPAD_TO_THRUVIA_SPACING" "5.00,5.00,5.00,5.00,5.00,5.00,5.00,5.00,5.00,5.00,5.00,5.00,5.00,5.00"
					( Origin gBackEnd )
				)
				( attribute "LINE_TO_THRUVIA_SPACING" "4.50,4.00,4.00,4.00,4.00,4.00,4.00,4.00,4.00,4.00,4.00,4.00,4.00,4.50"
					( Origin gBackEnd )
				)
				( attribute "SHAPE_TO_THRUVIA_SPACING" "4.50,4.00,4.00,4.00,4.00,4.00,5.00,5.00,4.00,4.00,4.00,4.00,4.00,4.50"
					( Origin gBackEnd )
				)
				( attribute "TESTVIA_TO_TESTVIA_SPACING" "6.00,6.00,6.00,6.00,6.00,6.00,6.00,6.00,6.00,6.00,6.00,6.00,6.00,6.00"
					( Origin gBackEnd )
				)
				( attribute "BBV_TO_TESTVIA_SPACING" "5.00,5.00,5.00,5.00,5.00,5.00,5.00,5.00,5.00,5.00,5.00,5.00,5.00,5.00"
					( Origin gBackEnd )
				)
				( attribute "BONDPAD_TO_TESTVIA_SPACING" "5.00,5.00,5.00,5.00,5.00,5.00,5.00,5.00,5.00,5.00,5.00,5.00,5.00,5.00"
					( Origin gBackEnd )
				)
				( attribute "LINE_TO_TESTVIA_SPACING" "4.50,4.00,4.00,4.00,4.00,4.00,4.00,4.00,4.00,4.00,4.00,4.00,4.00,4.50"
					( Origin gBackEnd )
				)
				( attribute "SHAPE_TO_TESTVIA_SPACING" "5.00,5.00,5.00,5.00,5.00,5.00,5.00,5.00,5.00,5.00,5.00,5.00,5.00,5.00"
					( Origin gBackEnd )
				)
				( attribute "BBV_TO_BBV_SPACING" "5.00,5.00,5.00,5.00,5.00,5.00,5.00,5.00,5.00,5.00,5.00,5.00,5.00,5.00"
					( Origin gBackEnd )
				)
				( attribute "BONDPAD_TO_BBV_SPACING" "5.00,5.00,5.00,5.00,5.00,5.00,5.00,5.00,5.00,5.00,5.00,5.00,5.00,5.00"
					( Origin gBackEnd )
				)
				( attribute "BBV_TO_LINE_SPACING" "5.00,5.00,5.00,5.00,5.00,5.00,5.00,5.00,5.00,5.00,5.00,5.00,5.00,5.00"
					( Origin gBackEnd )
				)
				( attribute "BBV_TO_SHAPE_SPACING" "5.00,5.00,5.00,5.00,5.00,5.00,5.00,5.00,5.00,5.00,5.00,5.00,5.00,5.00"
					( Origin gBackEnd )
				)
				( attribute "BONDPAD_TO_BONDPAD_SPACING" "5.00,5.00,5.00,5.00,5.00,5.00,5.00,5.00,5.00,5.00,5.00,5.00,5.00,5.00"
					( Origin gBackEnd )
				)
				( attribute "BONDPAD_TO_LINE_SPACING" "5.00,5.00,5.00,5.00,5.00,5.00,5.00,5.00,5.00,5.00,5.00,5.00,5.00,5.00"
					( Origin gBackEnd )
				)
				( attribute "BONDPAD_TO_SHAPE_SPACING" "5.00,5.00,5.00,5.00,5.00,5.00,5.00,5.00,5.00,5.00,5.00,5.00,5.00,5.00"
					( Origin gBackEnd )
				)
				( attribute "LINE_TO_LINE_SPACING" "26.70,24.00,24.00,24.00,24.00,24.00,24.00,24.00,24.00,24.00,24.00,24.00,24.00,26.70"
					( Origin gBackEnd )
				)
				( attribute "LINE_TO_SHAPE_SPACING" "10.00,10.00,10.00,10.00,10.00,10.00,10.00,10.00,10.00,10.00,10.00,10.00,10.00,10.00"
					( Origin gBackEnd )
				)
				( attribute "SHAPE_TO_SHAPE_SPACING" "10.00,10.00,10.00,10.00,10.00,10.00,10.00,10.00,10.00,10.00,10.00,10.00,10.00,10.00"
					( Origin gBackEnd )
				)
				( attribute "HOLE_TO_PIN_SPACING" "8.00,8.00,8.00,8.00,8.00,8.00,8.00,8.00,8.00,8.00,8.00,8.00,8.00,8.00"
					( Origin gBackEnd )
				)
				( attribute "HOLE_TO_VIA_SPACING" "8.00,8.00,8.00,8.00,8.00,8.00,8.00,8.00,8.00,8.00,8.00,8.00,8.00,8.00"
					( Origin gBackEnd )
				)
				( attribute "HOLE_TO_LINE_SPACING" "8.00,8.00,8.00,8.00,8.00,8.00,8.00,8.00,8.00,8.00,8.00,8.00,8.00,8.00"
					( Origin gBackEnd )
				)
				( attribute "HOLE_TO_SHAPE_SPACING" "8.00,8.00,8.00,8.00,8.00,8.00,8.00,8.00,8.00,8.00,8.00,8.00,8.00,8.00"
					( Origin gBackEnd )
				)
				( attribute "HOLE_TO_HOLE_SPACING" "8.00,8.00,8.00,8.00,8.00,8.00,8.00,8.00,8.00,8.00,8.00,8.00,8.00,8.00"
					( Origin gBackEnd )
				)
				( attribute "MVIA_TO_MVIA_SPACING" "5.00,5.00,5.00,5.00,5.00,5.00,5.00,5.00,5.00,5.00,5.00,5.00,5.00,5.00"
					( Origin gBackEnd )
				)
				( attribute "MVIA_TO_THRUPIN_SPACING" "5.00,5.00,5.00,5.00,5.00,5.00,5.00,5.00,5.00,5.00,5.00,5.00,5.00,5.00"
					( Origin gBackEnd )
				)
				( attribute "MVIA_TO_SMDPIN_SPACING" "5.00,5.00,5.00,5.00,5.00,5.00,5.00,5.00,5.00,5.00,5.00,5.00,5.00,5.00"
					( Origin gBackEnd )
				)
				( attribute "MVIA_TO_THRUVIA_SPACING" "5.00,5.00,5.00,5.00,5.00,5.00,5.00,5.00,5.00,5.00,5.00,5.00,5.00,5.00"
					( Origin gBackEnd )
				)
				( attribute "MVIA_TO_BBV_SPACING" "5.00,5.00,5.00,5.00,5.00,5.00,5.00,5.00,5.00,5.00,5.00,5.00,5.00,5.00"
					( Origin gBackEnd )
				)
				( attribute "MVIA_TO_LINE_SPACING" "5.00,5.00,5.00,5.00,5.00,5.00,5.00,5.00,5.00,5.00,5.00,5.00,5.00,5.00"
					( Origin gBackEnd )
				)
				( attribute "MVIA_TO_SHAPE_SPACING" "5.00,5.00,5.00,5.00,5.00,5.00,5.00,5.00,5.00,5.00,5.00,5.00,5.00,5.00"
					( Origin gBackEnd )
				)
				( attribute "MVIA_TO_TESTPIN_SPACING" "5.00,5.00,5.00,5.00,5.00,5.00,5.00,5.00,5.00,5.00,5.00,5.00,5.00,5.00"
					( Origin gBackEnd )
				)
				( attribute "MVIA_TO_TESTVIA_SPACING" "5.00,5.00,5.00,5.00,5.00,5.00,5.00,5.00,5.00,5.00,5.00,5.00,5.00,5.00"
					( Origin gBackEnd )
				)
				( attribute "BONDPAD_TO_MVIA_SPACING" "5.00,5.00,5.00,5.00,5.00,5.00,5.00,5.00,5.00,5.00,5.00,5.00,5.00,5.00"
					( Origin gBackEnd )
				)
				( attribute "MIN_BVIA_GAP" "5.00"
					( Origin gBackEnd )
				)
				( attribute "BONDPAD_TO_BONDPAD_DIFFP_SPC" "5.00,5.00,5.00,5.00,5.00,5.00,5.00,5.00,5.00,5.00,5.00,5.00,5.00,5.00"
					( Origin gBackEnd )
				)
				( objectStatus "10H_US_&_8H_SL" )
			)
			( spacingCSet "@sapphirecity_baseboard_lib.sapphirecity_baseboard(sch_1):\DDR4_2SPC_CAC\"
				( attribute "THRUPIN_TO_THRUPIN_SPACING" "5.00,5.00,5.00,5.00,5.00,5.00,5.00,5.00,5.00,5.00,5.00,5.00,5.00,5.00"
					( Origin gBackEnd )
				)
				( attribute "THRUPIN_TO_SMDPIN_SPACING" "5.00,5.00,5.00,5.00,5.00,5.00,5.00,5.00,5.00,5.00,5.00,5.00,5.00,5.00"
					( Origin gBackEnd )
				)
				( attribute "TESTPIN_TO_THRUPIN_SPACING" "5.00,5.00,5.00,5.00,5.00,5.00,5.00,5.00,5.00,5.00,5.00,5.00,5.00,5.00"
					( Origin gBackEnd )
				)
				( attribute "THRUPIN_TO_THRUVIA_SPACING" "5.00,5.00,5.00,5.00,5.00,5.00,5.00,5.00,5.00,5.00,5.00,5.00,5.00,5.00"
					( Origin gBackEnd )
				)
				( attribute "TESTVIA_TO_THRUPIN_SPACING" "5.00,5.00,5.00,5.00,5.00,5.00,5.00,5.00,5.00,5.00,5.00,5.00,5.00,5.00"
					( Origin gBackEnd )
				)
				( attribute "BBV_TO_THRUPIN_SPACING" "5.00,5.00,5.00,5.00,5.00,5.00,5.00,5.00,5.00,5.00,5.00,5.00,5.00,5.00"
					( Origin gBackEnd )
				)
				( attribute "THRUPIN_TO_BONDPAD_SPACING" "5.00,5.00,5.00,5.00,5.00,5.00,5.00,5.00,5.00,5.00,5.00,5.00,5.00,5.00"
					( Origin gBackEnd )
				)
				( attribute "LINE_TO_THRUPIN_SPACING" "4.50,4.00,4.00,4.00,4.00,4.00,4.00,4.00,4.00,4.00,4.00,4.00,4.00,4.50"
					( Origin gBackEnd )
				)
				( attribute "THRUPIN_TO_SHAPE_SPACING" "4.50,4.00,4.00,4.00,4.00,4.00,4.00,4.00,4.00,4.00,4.00,4.00,4.00,4.00"
					( Origin gBackEnd )
				)
				( attribute "SMDPIN_TO_SMDPIN_SPACING" "5.00,5.00,5.00,5.00,5.00,5.00,5.00,5.00,5.00,5.00,5.00,5.00,5.00,5.00"
					( Origin gBackEnd )
				)
				( attribute "SMDPIN_TO_TESTPIN_SPACING" "5.00,5.00,5.00,5.00,5.00,5.00,5.00,5.00,5.00,5.00,5.00,5.00,5.00,5.00"
					( Origin gBackEnd )
				)
				( attribute "SMDPIN_TO_THRUVIA_SPACING" "5.00,5.00,5.00,5.00,5.00,5.00,5.00,5.00,5.00,5.00,5.00,5.00,5.00,5.00"
					( Origin gBackEnd )
				)
				( attribute "SMDPIN_TO_TESTVIA_SPACING" "5.00,5.00,5.00,5.00,5.00,5.00,5.00,5.00,5.00,5.00,5.00,5.00,5.00,5.00"
					( Origin gBackEnd )
				)
				( attribute "BBV_TO_SMDPIN_SPACING" "5.00,5.00,5.00,5.00,5.00,5.00,5.00,5.00,5.00,5.00,5.00,5.00,5.00,5.00"
					( Origin gBackEnd )
				)
				( attribute "SMDPIN_TO_BONDPAD_SPACING" "5.00,5.00,5.00,5.00,5.00,5.00,5.00,5.00,5.00,5.00,5.00,5.00,5.00,5.00"
					( Origin gBackEnd )
				)
				( attribute "LINE_TO_SMDPIN_SPACING" "4.50,4.50,4.50,4.50,4.50,4.50,4.50,4.50,4.50,4.50,4.50,4.50,4.50,4.50"
					( Origin gBackEnd )
				)
				( attribute "SHAPE_TO_SMDPIN_SPACING" "5.00,5.00,5.00,5.00,5.00,5.00,5.00,5.00,5.00,5.00,5.00,5.00,5.00,5.00"
					( Origin gBackEnd )
				)
				( attribute "TESTPIN_TO_TESTPIN_SPACING" "5.00,5.00,5.00,5.00,5.00,5.00,5.00,5.00,5.00,5.00,5.00,5.00,5.00,5.00"
					( Origin gBackEnd )
				)
				( attribute "TESTPIN_TO_THRUVIA_SPACING" "5.00,5.00,5.00,5.00,5.00,5.00,5.00,5.00,5.00,5.00,5.00,5.00,5.00,5.00"
					( Origin gBackEnd )
				)
				( attribute "TESTPIN_TO_TESTVIA_SPACING" "5.00,5.00,5.00,5.00,5.00,5.00,5.00,5.00,5.00,5.00,5.00,5.00,5.00,5.00"
					( Origin gBackEnd )
				)
				( attribute "BBV_TO_TESTPIN_SPACING" "5.00,5.00,5.00,5.00,5.00,5.00,5.00,5.00,5.00,5.00,5.00,5.00,5.00,5.00"
					( Origin gBackEnd )
				)
				( attribute "BONDPAD_TO_TESTPIN_SPACING" "5.00,5.00,5.00,5.00,5.00,5.00,5.00,5.00,5.00,5.00,5.00,5.00,5.00,5.00"
					( Origin gBackEnd )
				)
				( attribute "LINE_TO_TESTPIN_SPACING" "4.50,5.00,5.00,5.00,5.00,5.00,5.00,5.00,5.00,5.00,5.00,5.00,5.00,5.00"
					( Origin gBackEnd )
				)
				( attribute "SHAPE_TO_TESTPIN_SPACING" "4.50,4.00,4.00,4.00,4.00,4.00,4.00,4.00,4.00,4.00,4.00,4.00,4.00,4.00"
					( Origin gBackEnd )
				)
				( attribute "THRUVIA_TO_THRUVIA_SPACING" "5.00,5.00,5.00,5.00,5.00,5.00,5.00,5.00,5.00,5.00,5.00,5.00,5.00,5.00"
					( Origin gBackEnd )
				)
				( attribute "TESTVIA_TO_THRUVIA_SPACING" "5.00,5.00,5.00,5.00,5.00,5.00,5.00,5.00,5.00,5.00,5.00,5.00,5.00,5.00"
					( Origin gBackEnd )
				)
				( attribute "BBV_TO_THRUVIA_SPACING" "5.00,5.00,5.00,5.00,5.00,5.00,5.00,5.00,5.00,5.00,5.00,5.00,5.00,5.00"
					( Origin gBackEnd )
				)
				( attribute "BONDPAD_TO_THRUVIA_SPACING" "5.00,5.00,5.00,5.00,5.00,5.00,5.00,5.00,5.00,5.00,5.00,5.00,5.00,5.00"
					( Origin gBackEnd )
				)
				( attribute "LINE_TO_THRUVIA_SPACING" "4.50,4.00,4.00,4.00,4.00,4.00,4.00,4.00,4.00,4.00,4.00,4.00,4.00,4.50"
					( Origin gBackEnd )
				)
				( attribute "SHAPE_TO_THRUVIA_SPACING" "4.50,4.00,4.00,4.00,4.00,4.00,4.00,4.00,4.00,4.00,4.00,4.00,4.00,4.00"
					( Origin gBackEnd )
				)
				( attribute "TESTVIA_TO_TESTVIA_SPACING" "5.00,5.00,5.00,5.00,5.00,5.00,5.00,5.00,5.00,5.00,5.00,5.00,5.00,5.00"
					( Origin gBackEnd )
				)
				( attribute "BBV_TO_TESTVIA_SPACING" "5.00,5.00,5.00,5.00,5.00,5.00,5.00,5.00,5.00,5.00,5.00,5.00,5.00,5.00"
					( Origin gBackEnd )
				)
				( attribute "BONDPAD_TO_TESTVIA_SPACING" "5.00,5.00,5.00,5.00,5.00,5.00,5.00,5.00,5.00,5.00,5.00,5.00,5.00,5.00"
					( Origin gBackEnd )
				)
				( attribute "LINE_TO_TESTVIA_SPACING" "4.50,5.00,4.00,5.00,4.00,5.00,5.00,5.00,5.00,4.00,5.00,4.00,5.00,4.50"
					( Origin gBackEnd )
				)
				( attribute "SHAPE_TO_TESTVIA_SPACING" "4.50,4.00,4.00,4.00,4.00,4.00,4.00,4.00,4.00,4.00,4.00,4.00,4.00,4.00"
					( Origin gBackEnd )
				)
				( attribute "BBV_TO_BBV_SPACING" "5.00,5.00,5.00,5.00,5.00,5.00,5.00,5.00,5.00,5.00,5.00,5.00,5.00,5.00"
					( Origin gBackEnd )
				)
				( attribute "BONDPAD_TO_BBV_SPACING" "5.00,5.00,5.00,5.00,5.00,5.00,5.00,5.00,5.00,5.00,5.00,5.00,5.00,5.00"
					( Origin gBackEnd )
				)
				( attribute "BBV_TO_LINE_SPACING" "5.00,5.00,5.00,5.00,5.00,5.00,5.00,5.00,5.00,5.00,5.00,5.00,5.00,5.00"
					( Origin gBackEnd )
				)
				( attribute "BBV_TO_SHAPE_SPACING" "5.00,5.00,5.00,5.00,5.00,5.00,5.00,5.00,5.00,5.00,5.00,5.00,5.00,5.00"
					( Origin gBackEnd )
				)
				( attribute "BONDPAD_TO_BONDPAD_SPACING" "5.00,5.00,5.00,5.00,5.00,5.00,5.00,5.00,5.00,5.00,5.00,5.00,5.00,5.00"
					( Origin gBackEnd )
				)
				( attribute "BONDPAD_TO_LINE_SPACING" "5.00,5.00,5.00,5.00,5.00,5.00,5.00,5.00,5.00,5.00,5.00,5.00,5.00,5.00"
					( Origin gBackEnd )
				)
				( attribute "BONDPAD_TO_SHAPE_SPACING" "5.00,5.00,5.00,5.00,5.00,5.00,5.00,5.00,5.00,5.00,5.00,5.00,5.00,5.00"
					( Origin gBackEnd )
				)
				( attribute "LINE_TO_LINE_SPACING" "13.35,9.00,9.00,9.00,9.00,9.00,9.00,9.00,9.00,9.00,9.00,9.00,9.00,13.35"
					( Origin gBackEnd )
				)
				( attribute "LINE_TO_SHAPE_SPACING" "5.00,5.00,5.00,5.00,5.00,5.00,5.00,5.00,5.00,5.00,5.00,5.00,5.00,5.00"
					( Origin gBackEnd )
				)
				( attribute "SHAPE_TO_SHAPE_SPACING" "10.00,10.00,10.00,10.00,10.00,10.00,10.00,10.00,10.00,10.00,10.00,10.00,10.00,10.00"
					( Origin gBackEnd )
				)
				( attribute "HOLE_TO_PIN_SPACING" "8.00,8.00,8.00,8.00,8.00,8.00,8.00,8.00,8.00,8.00,8.00,8.00,8.00,8.00"
					( Origin gBackEnd )
				)
				( attribute "HOLE_TO_VIA_SPACING" "8.00,8.00,8.00,8.00,8.00,8.00,8.00,8.00,8.00,8.00,8.00,8.00,8.00,8.00"
					( Origin gBackEnd )
				)
				( attribute "HOLE_TO_LINE_SPACING" "8.00,8.00,8.00,8.00,8.00,8.00,8.00,8.00,8.00,8.00,8.00,8.00,8.00,8.00"
					( Origin gBackEnd )
				)
				( attribute "HOLE_TO_SHAPE_SPACING" "8.00,8.00,8.00,8.00,8.00,8.00,8.00,8.00,8.00,8.00,8.00,8.00,8.00,8.00"
					( Origin gBackEnd )
				)
				( attribute "HOLE_TO_HOLE_SPACING" "8.00,8.00,8.00,8.00,8.00,8.00,8.00,8.00,8.00,8.00,8.00,8.00,8.00,8.00"
					( Origin gBackEnd )
				)
				( attribute "MVIA_TO_MVIA_SPACING" "5.00,5.00,5.00,5.00,5.00,5.00,5.00,5.00,5.00,5.00,5.00,5.00,5.00,5.00"
					( Origin gBackEnd )
				)
				( attribute "MVIA_TO_THRUPIN_SPACING" "5.00,5.00,5.00,5.00,5.00,5.00,5.00,5.00,5.00,5.00,5.00,5.00,5.00,5.00"
					( Origin gBackEnd )
				)
				( attribute "MVIA_TO_SMDPIN_SPACING" "5.00,5.00,5.00,5.00,5.00,5.00,5.00,5.00,5.00,5.00,5.00,5.00,5.00,5.00"
					( Origin gBackEnd )
				)
				( attribute "MVIA_TO_THRUVIA_SPACING" "5.00,5.00,5.00,5.00,5.00,5.00,5.00,5.00,5.00,5.00,5.00,5.00,5.00,5.00"
					( Origin gBackEnd )
				)
				( attribute "MVIA_TO_BBV_SPACING" "5.00,5.00,5.00,5.00,5.00,5.00,5.00,5.00,5.00,5.00,5.00,5.00,5.00,5.00"
					( Origin gBackEnd )
				)
				( attribute "MVIA_TO_LINE_SPACING" "5.00,5.00,5.00,5.00,5.00,5.00,5.00,5.00,5.00,5.00,5.00,5.00,5.00,5.00"
					( Origin gBackEnd )
				)
				( attribute "MVIA_TO_SHAPE_SPACING" "5.00,5.00,5.00,5.00,5.00,5.00,5.00,5.00,5.00,5.00,5.00,5.00,5.00,5.00"
					( Origin gBackEnd )
				)
				( attribute "MVIA_TO_TESTPIN_SPACING" "5.00,5.00,5.00,5.00,5.00,5.00,5.00,5.00,5.00,5.00,5.00,5.00,5.00,5.00"
					( Origin gBackEnd )
				)
				( attribute "MVIA_TO_TESTVIA_SPACING" "5.00,5.00,5.00,5.00,5.00,5.00,5.00,5.00,5.00,5.00,5.00,5.00,5.00,5.00"
					( Origin gBackEnd )
				)
				( attribute "BONDPAD_TO_MVIA_SPACING" "5.00,5.00,5.00,5.00,5.00,5.00,5.00,5.00,5.00,5.00,5.00,5.00,5.00,5.00"
					( Origin gBackEnd )
				)
				( attribute "MIN_BVIA_GAP" "5.00"
					( Origin gBackEnd )
				)
				( attribute "BONDPAD_TO_BONDPAD_DIFFP_SPC" "5.00,5.00,5.00,5.00,5.00,5.00,5.00,5.00,5.00,5.00,5.00,5.00,5.00,5.00"
					( Origin gBackEnd )
				)
				( objectStatus "5H_US_&_3H_SL" )
			)
			( spacingCSet "@crescent_city_bb_fab1_lib.crescent_city_bb_fab1(sch_1):\DEFAULT\"
				( attribute "THRUPIN_TO_THRUPIN_SPACING" "5.00,5.00,5.00,5.00,5.00,5.00,5.00,5.00,5.00,5.00,5.00,5.00,5.00,5.00"
					( Origin gBackEnd )
				)
				( attribute "THRUPIN_TO_SMDPIN_SPACING" "5.00,5.00,5.00,5.00,5.00,5.00,5.00,5.00,5.00,5.00,5.00,5.00,5.00,5.00"
					( Origin gBackEnd )
				)
				( attribute "TESTPIN_TO_THRUPIN_SPACING" "5.00,5.00,5.00,5.00,5.00,5.00,5.00,5.00,5.00,5.00,5.00,5.00,5.00,5.00"
					( Origin gBackEnd )
				)
				( attribute "THRUPIN_TO_THRUVIA_SPACING" "4.00,4.00,4.00,4.00,4.00,4.00,4.00,4.00,4.00,4.00,4.00,4.00,4.00,5.00"
					( Origin gBackEnd )
				)
				( attribute "TESTVIA_TO_THRUPIN_SPACING" "5.00,5.00,5.00,5.00,5.00,5.00,5.00,5.00,5.00,5.00,5.00,5.00,5.00,5.00"
					( Origin gBackEnd )
				)
				( attribute "BBV_TO_THRUPIN_SPACING" "5.00,5.00,5.00,5.00,5.00,5.00,5.00,5.00,5.00,5.00,5.00,5.00,5.00,5.00"
					( Origin gBackEnd )
				)
				( attribute "THRUPIN_TO_BONDPAD_SPACING" "5.00,5.00,5.00,5.00,5.00,5.00,5.00,5.00,5.00,5.00,5.00,5.00,5.00,5.00"
					( Origin gBackEnd )
				)
				( attribute "LINE_TO_THRUPIN_SPACING" "5.00,5.00,5.00,5.00,5.00,5.00,5.00,5.00,5.00,5.00,5.00,5.00,5.00,5.00"
					( Origin gBackEnd )
				)
				( attribute "THRUPIN_TO_SHAPE_SPACING" "4.50,4.00,4.00,4.00,4.00,4.00,4.00,4.00,4.00,4.00,4.00,4.00,4.00,5.00"
					( Origin gBackEnd )
				)
				( attribute "SMDPIN_TO_SMDPIN_SPACING" "5.00,5.00,5.00,5.00,5.00,5.00,5.00,5.00,5.00,5.00,5.00,5.00,5.00,5.00"
					( Origin gBackEnd )
				)
				( attribute "SMDPIN_TO_TESTPIN_SPACING" "5.00,5.00,5.00,5.00,5.00,5.00,5.00,5.00,5.00,5.00,5.00,5.00,5.00,25.00"
					( Origin gBackEnd )
				)
				( attribute "SMDPIN_TO_THRUVIA_SPACING" "4.00,4.00,4.00,4.00,4.00,4.00,4.00,4.00,4.00,4.00,4.00,4.00,4.00,5.00"
					( Origin gBackEnd )
				)
				( attribute "SMDPIN_TO_TESTVIA_SPACING" "4.50,4.50,4.50,4.50,4.50,4.50,4.50,4.50,4.50,4.50,4.50,4.50,4.50,5.00"
					( Origin gBackEnd )
				)
				( attribute "BBV_TO_SMDPIN_SPACING" "5.00,5.00,5.00,5.00,5.00,5.00,5.00,5.00,5.00,5.00,5.00,5.00,5.00,5.00"
					( Origin gBackEnd )
				)
				( attribute "SMDPIN_TO_BONDPAD_SPACING" "5.00,5.00,5.00,5.00,5.00,5.00,5.00,5.00,5.00,5.00,5.00,5.00,5.00,5.00"
					( Origin gBackEnd )
				)
				( attribute "LINE_TO_SMDPIN_SPACING" "4.50,4.50,4.50,4.50,4.50,4.50,4.50,4.50,4.50,4.50,4.50,4.50,4.50,4.50"
					( Origin gBackEnd )
				)
				( attribute "SHAPE_TO_SMDPIN_SPACING" "5.00,5.00,5.00,5.00,5.00,5.00,5.00,5.00,5.00,5.00,5.00,5.00,5.00,5.00"
					( Origin gBackEnd )
				)
				( attribute "TESTPIN_TO_TESTPIN_SPACING" "5.00,5.00,5.00,5.00,5.00,5.00,5.00,5.00,5.00,5.00,5.00,5.00,5.00,5.00"
					( Origin gBackEnd )
				)
				( attribute "TESTPIN_TO_THRUVIA_SPACING" "5.00,5.00,5.00,5.00,5.00,5.00,5.00,5.00,5.00,5.00,5.00,5.00,5.00,5.00"
					( Origin gBackEnd )
				)
				( attribute "TESTPIN_TO_TESTVIA_SPACING" "5.00,5.00,5.00,5.00,5.00,5.00,5.00,5.00,5.00,5.00,5.00,5.00,5.00,5.00"
					( Origin gBackEnd )
				)
				( attribute "BBV_TO_TESTPIN_SPACING" "5.00,5.00,5.00,5.00,5.00,5.00,5.00,5.00,5.00,5.00,5.00,5.00,5.00,5.00"
					( Origin gBackEnd )
				)
				( attribute "BONDPAD_TO_TESTPIN_SPACING" "5.00,5.00,5.00,5.00,5.00,5.00,5.00,5.00,5.00,5.00,5.00,5.00,5.00,5.00"
					( Origin gBackEnd )
				)
				( attribute "LINE_TO_TESTPIN_SPACING" "4.50,5.00,5.00,5.00,5.00,5.00,5.00,5.00,5.00,5.00,5.00,5.00,5.00,5.00"
					( Origin gBackEnd )
				)
				( attribute "SHAPE_TO_TESTPIN_SPACING" "4.50,4.00,4.00,4.00,4.00,4.00,4.00,4.00,4.00,4.00,4.00,4.00,4.00,5.00"
					( Origin gBackEnd )
				)
				( attribute "THRUVIA_TO_THRUVIA_SPACING" "5.00,5.00,5.00,5.00,5.00,5.00,5.00,5.00,5.00,5.00,5.00,5.00,5.00,5.00"
					( Origin gBackEnd )
				)
				( attribute "TESTVIA_TO_THRUVIA_SPACING" "5.00,5.00,5.00,5.00,5.00,5.00,5.00,5.00,5.00,5.00,5.00,5.00,5.00,5.00"
					( Origin gBackEnd )
				)
				( attribute "BBV_TO_THRUVIA_SPACING" "5.00,5.00,5.00,5.00,5.00,5.00,5.00,5.00,5.00,5.00,5.00,5.00,5.00,5.00"
					( Origin gBackEnd )
				)
				( attribute "BONDPAD_TO_THRUVIA_SPACING" "5.00,5.00,5.00,5.00,5.00,5.00,5.00,5.00,5.00,5.00,5.00,5.00,5.00,5.00"
					( Origin gBackEnd )
				)
				( attribute "LINE_TO_THRUVIA_SPACING" "4.50,4.00,4.00,4.00,4.00,4.00,4.00,4.00,4.00,4.00,4.00,4.00,4.00,4.50"
					( Origin gBackEnd )
				)
				( attribute "SHAPE_TO_THRUVIA_SPACING" "4.50,4.00,4.00,4.00,4.00,4.00,4.00,4.00,4.00,4.00,4.00,4.00,4.00,5.00"
					( Origin gBackEnd )
				)
				( attribute "TESTVIA_TO_TESTVIA_SPACING" "5.00,5.00,5.00,5.00,5.00,5.00,5.00,5.00,5.00,5.00,5.00,5.00,5.00,6.00"
					( Origin gBackEnd )
				)
				( attribute "BBV_TO_TESTVIA_SPACING" "5.00,5.00,5.00,5.00,5.00,5.00,5.00,5.00,5.00,5.00,5.00,5.00,5.00,5.00"
					( Origin gBackEnd )
				)
				( attribute "BONDPAD_TO_TESTVIA_SPACING" "5.00,5.00,5.00,5.00,5.00,5.00,5.00,5.00,5.00,5.00,5.00,5.00,5.00,5.00"
					( Origin gBackEnd )
				)
				( attribute "LINE_TO_TESTVIA_SPACING" "4.50,5.00,4.00,5.00,4.00,5.00,5.00,5.00,5.00,4.00,5.00,4.00,5.00,4.50"
					( Origin gBackEnd )
				)
				( attribute "SHAPE_TO_TESTVIA_SPACING" "4.50,4.00,4.00,4.00,4.00,4.00,4.00,4.00,4.00,4.00,4.00,4.00,4.00,5.00"
					( Origin gBackEnd )
				)
				( attribute "BBV_TO_BBV_SPACING" "5.00,5.00,5.00,5.00,5.00,5.00,5.00,5.00,5.00,5.00,5.00,5.00,5.00,5.00"
					( Origin gBackEnd )
				)
				( attribute "BONDPAD_TO_BBV_SPACING" "5.00,5.00,5.00,5.00,5.00,5.00,5.00,5.00,5.00,5.00,5.00,5.00,5.00,5.00"
					( Origin gBackEnd )
				)
				( attribute "BBV_TO_LINE_SPACING" "5.00,5.00,5.00,5.00,5.00,5.00,5.00,5.00,5.00,5.00,5.00,5.00,5.00,5.00"
					( Origin gBackEnd )
				)
				( attribute "BBV_TO_SHAPE_SPACING" "5.00,5.00,5.00,5.00,5.00,5.00,5.00,5.00,5.00,5.00,5.00,5.00,5.00,5.00"
					( Origin gBackEnd )
				)
				( attribute "BONDPAD_TO_BONDPAD_SPACING" "5.00,5.00,5.00,5.00,5.00,5.00,5.00,5.00,5.00,5.00,5.00,5.00,5.00,5.00"
					( Origin gBackEnd )
				)
				( attribute "BONDPAD_TO_LINE_SPACING" "5.00,5.00,5.00,5.00,5.00,5.00,5.00,5.00,5.00,5.00,5.00,5.00,5.00,5.00"
					( Origin gBackEnd )
				)
				( attribute "BONDPAD_TO_SHAPE_SPACING" "5.00,5.00,5.00,5.00,5.00,5.00,5.00,5.00,5.00,5.00,5.00,5.00,5.00,5.00"
					( Origin gBackEnd )
				)
				( attribute "LINE_TO_LINE_SPACING" "4.00,4.00,4.00,4.00,4.00,4.00,4.00,4.00,4.00,4.00,4.00,4.00,4.00,4.00"
					( Origin gBackEnd )
				)
				( attribute "LINE_TO_SHAPE_SPACING" "5.00,5.00,5.00,5.00,5.00,5.00,5.00,5.00,5.00,5.00,5.00,5.00,5.00,10.00"
					( Origin gBackEnd )
				)
				( attribute "SHAPE_TO_SHAPE_SPACING" "10.00,10.00,10.00,10.00,10.00,10.00,10.00,10.00,10.00,10.00,10.00,10.00,10.00,10.00"
					( Origin gBackEnd )
				)
				( attribute "HOLE_TO_PIN_SPACING" "8.00,8.00,8.00,8.00,8.00,8.00,8.00,8.00,8.00,8.00,8.00,8.00,8.00,8.00"
					( Origin gBackEnd )
				)
				( attribute "HOLE_TO_VIA_SPACING" "8.00,8.00,8.00,8.00,8.00,8.00,8.00,8.00,8.00,8.00,8.00,8.00,8.00,8.00"
					( Origin gBackEnd )
				)
				( attribute "HOLE_TO_LINE_SPACING" "8.00,8.00,8.00,8.00,8.00,8.00,8.00,8.00,8.00,8.00,8.00,8.00,8.00,8.00"
					( Origin gBackEnd )
				)
				( attribute "HOLE_TO_SHAPE_SPACING" "8.00,8.00,8.00,8.00,8.00,8.00,8.00,8.00,8.00,8.00,8.00,8.00,8.00,8.00"
					( Origin gBackEnd )
				)
				( attribute "HOLE_TO_HOLE_SPACING" "8.00,8.00,8.00,8.00,8.00,8.00,8.00,8.00,8.00,8.00,8.00,8.00,8.00,8.00"
					( Origin gBackEnd )
				)
				( attribute "MVIA_TO_MVIA_SPACING" "5.00,5.00,5.00,5.00,5.00,5.00,5.00,5.00,5.00,5.00,5.00,5.00,5.00,5.00"
					( Origin gBackEnd )
				)
				( attribute "MVIA_TO_THRUPIN_SPACING" "5.00,5.00,5.00,5.00,5.00,5.00,5.00,5.00,5.00,5.00,5.00,5.00,5.00,5.00"
					( Origin gBackEnd )
				)
				( attribute "MVIA_TO_SMDPIN_SPACING" "5.00,5.00,5.00,5.00,5.00,5.00,5.00,5.00,5.00,5.00,5.00,5.00,5.00,5.00"
					( Origin gBackEnd )
				)
				( attribute "MVIA_TO_THRUVIA_SPACING" "5.00,5.00,5.00,5.00,5.00,5.00,5.00,5.00,5.00,5.00,5.00,5.00,5.00,5.00"
					( Origin gBackEnd )
				)
				( attribute "MVIA_TO_BBV_SPACING" "5.00,5.00,5.00,5.00,5.00,5.00,5.00,5.00,5.00,5.00,5.00,5.00,5.00,5.00"
					( Origin gBackEnd )
				)
				( attribute "MVIA_TO_LINE_SPACING" "5.00,5.00,5.00,5.00,5.00,5.00,5.00,5.00,5.00,5.00,5.00,5.00,5.00,5.00"
					( Origin gBackEnd )
				)
				( attribute "MVIA_TO_SHAPE_SPACING" "5.00,5.00,5.00,5.00,5.00,5.00,5.00,5.00,5.00,5.00,5.00,5.00,5.00,5.00"
					( Origin gBackEnd )
				)
				( attribute "MVIA_TO_TESTPIN_SPACING" "5.00,5.00,5.00,5.00,5.00,5.00,5.00,5.00,5.00,5.00,5.00,5.00,5.00,5.00"
					( Origin gBackEnd )
				)
				( attribute "MVIA_TO_TESTVIA_SPACING" "5.00,5.00,5.00,5.00,5.00,5.00,5.00,5.00,5.00,5.00,5.00,5.00,5.00,5.00"
					( Origin gBackEnd )
				)
				( attribute "BONDPAD_TO_MVIA_SPACING" "5.00,5.00,5.00,5.00,5.00,5.00,5.00,5.00,5.00,5.00,5.00,5.00,5.00,5.00"
					( Origin gBackEnd )
				)
				( attribute "MIN_BVIA_GAP" "5.00"
					( Origin gBackEnd )
				)
				( attribute "BONDPAD_TO_BONDPAD_DIFFP_SPC" "5.00,5.00,5.00,5.00,5.00,5.00,5.00,5.00,5.00,5.00,5.00,5.00,5.00,5.00"
					( Origin gBackEnd )
				)
				( objectStatus "DEFAULT" )
			)
			( sameNetSpacingCSet "@crescent_city_bb_fab1_lib.crescent_city_bb_fab1(sch_1):\20_MILS_US_&_15_MILS_SL\"
				( attribute "SAME_NET" "TRUE,TRUE,TRUE,TRUE,TRUE,TRUE,TRUE,TRUE,TRUE,TRUE,TRUE,TRUE,TRUE,TRUE"
					( Origin gBackEnd )
				)
				( attribute "SN_THRUPIN_TO_THRUPIN_SPACING" "5.00,5.00,5.00,5.00,5.00,5.00,5.00,5.00,5.00,5.00,5.00,5.00,5.00,5.00"
					( Origin gBackEnd )
				)
				( attribute "SN_THRUPIN_TO_SMDPIN_SPACING" "5.00,5.00,5.00,5.00,5.00,5.00,5.00,5.00,5.00,5.00,5.00,5.00,5.00,5.00"
					( Origin gBackEnd )
				)
				( attribute "SN_TESTPIN_TO_THRUPIN_SPACING" "5.00,5.00,5.00,5.00,5.00,5.00,5.00,5.00,5.00,5.00,5.00,5.00,5.00,5.00"
					( Origin gBackEnd )
				)
				( attribute "SN_THRUPIN_TO_THRUVIA_SPACING" "5.00,5.00,5.00,5.00,5.00,5.00,5.00,5.00,5.00,5.00,5.00,5.00,5.00,5.00"
					( Origin gBackEnd )
				)
				( attribute "SN_TESTVIA_TO_THRUPIN_SPACING" "5.00,5.00,5.00,5.00,5.00,5.00,5.00,5.00,5.00,5.00,5.00,5.00,5.00,5.00"
					( Origin gBackEnd )
				)
				( attribute "SN_BBV_TO_THRUPIN_SPACING" "5.00,5.00,5.00,5.00,5.00,5.00,5.00,5.00,5.00,5.00,5.00,5.00,5.00,5.00"
					( Origin gBackEnd )
				)
				( attribute "SN_THRUPIN_TO_BONDPAD_SPACING" "5.00,5.00,5.00,5.00,5.00,5.00,5.00,5.00,5.00,5.00,5.00,5.00,5.00,5.00"
					( Origin gBackEnd )
				)
				( attribute "SN_LINE_TO_THRUPIN_SPACING" "4.50,4.00,4.00,4.00,4.00,4.00,4.00,4.00,4.00,4.00,4.00,4.00,4.00,4.50"
					( Origin gBackEnd )
				)
				( attribute "SN_THRUPIN_TO_SHAPE_SPACING" "5.00,5.00,5.00,5.00,5.00,5.00,5.00,5.00,5.00,5.00,5.00,5.00,5.00,5.00"
					( Origin gBackEnd )
				)
				( attribute "SN_SMDPIN_TO_SMDPIN_SPACING" "5.00,5.00,5.00,5.00,5.00,5.00,5.00,5.00,5.00,5.00,5.00,5.00,5.00,5.00"
					( Origin gBackEnd )
				)
				( attribute "SN_SMDPIN_TO_TESTPIN_SPACING" "5.00,5.00,5.00,5.00,5.00,5.00,5.00,5.00,5.00,5.00,5.00,5.00,5.00,5.00"
					( Origin gBackEnd )
				)
				( attribute "SN_SMDPIN_TO_THRUVIA_SPACING" "5.00,5.00,5.00,5.00,5.00,5.00,5.00,5.00,5.00,5.00,5.00,5.00,5.00,5.00"
					( Origin gBackEnd )
				)
				( attribute "SN_SMDPIN_TO_TESTVIA_SPACING" "5.00,5.00,5.00,5.00,5.00,5.00,5.00,5.00,5.00,5.00,5.00,5.00,5.00,5.00"
					( Origin gBackEnd )
				)
				( attribute "SN_BBV_TO_SMDPIN_SPACING" "5.00,5.00,5.00,5.00,5.00,5.00,5.00,5.00,5.00,5.00,5.00,5.00,5.00,5.00"
					( Origin gBackEnd )
				)
				( attribute "SN_SMDPIN_TO_BONDPAD_SPACING" "5.00,5.00,5.00,5.00,5.00,5.00,5.00,5.00,5.00,5.00,5.00,5.00,5.00,5.00"
					( Origin gBackEnd )
				)
				( attribute "SN_LINE_TO_SMDPIN_SPACING" "4.50,4.50,4.50,4.50,4.50,4.50,4.50,4.50,4.50,4.50,4.50,4.50,4.50,4.50"
					( Origin gBackEnd )
				)
				( attribute "SN_SHAPE_TO_SMDPIN_SPACING" "5.00,5.00,5.00,5.00,5.00,5.00,5.00,5.00,5.00,5.00,5.00,5.00,5.00,5.00"
					( Origin gBackEnd )
				)
				( attribute "SN_TESTPIN_TO_TESTPIN_SPACING" "5.00,5.00,5.00,5.00,5.00,5.00,5.00,5.00,5.00,5.00,5.00,5.00,5.00,5.00"
					( Origin gBackEnd )
				)
				( attribute "SN_TESTPIN_TO_THRUVIA_SPACING" "5.00,5.00,5.00,5.00,5.00,5.00,5.00,5.00,5.00,5.00,5.00,5.00,5.00,5.00"
					( Origin gBackEnd )
				)
				( attribute "SN_TESTPIN_TO_TESTVIA_SPACING" "5.00,5.00,5.00,5.00,5.00,5.00,5.00,5.00,5.00,5.00,5.00,5.00,5.00,5.00"
					( Origin gBackEnd )
				)
				( attribute "SN_BBV_TO_TESTPIN_SPACING" "5.00,5.00,5.00,5.00,5.00,5.00,5.00,5.00,5.00,5.00,5.00,5.00,5.00,5.00"
					( Origin gBackEnd )
				)
				( attribute "SN_BONDPAD_TO_TESTPIN_SPACING" "5.00,5.00,5.00,5.00,5.00,5.00,5.00,5.00,5.00,5.00,5.00,5.00,5.00,5.00"
					( Origin gBackEnd )
				)
				( attribute "SN_LINE_TO_TESTPIN_SPACING" "5.00,4.00,4.00,4.00,4.00,4.00,4.00,4.00,4.00,4.00,4.00,4.00,4.00,5.00"
					( Origin gBackEnd )
				)
				( attribute "SN_SHAPE_TO_TESTPIN_SPACING" "5.00,5.00,5.00,5.00,5.00,5.00,5.00,5.00,5.00,5.00,5.00,5.00,5.00,5.00"
					( Origin gBackEnd )
				)
				( attribute "SN_THRUVIA_TO_THRUVIA_SPACING" "4.50,4.00,4.00,4.00,4.00,4.00,4.00,4.00,4.00,4.00,4.00,4.00,4.00,4.50"
					( Origin gBackEnd )
				)
				( attribute "SN_TESTVIA_TO_THRUVIA_SPACING" "5.00,5.00,5.00,5.00,5.00,5.00,5.00,5.00,5.00,5.00,5.00,5.00,5.00,5.00"
					( Origin gBackEnd )
				)
				( attribute "SN_BBV_TO_THRUVIA_SPACING" "5.00,5.00,5.00,5.00,5.00,5.00,5.00,5.00,5.00,5.00,5.00,5.00,5.00,5.00"
					( Origin gBackEnd )
				)
				( attribute "SN_BONDPAD_TO_THRUVIA_SPACING" "5.00,5.00,5.00,5.00,5.00,5.00,5.00,5.00,5.00,5.00,5.00,5.00,5.00,5.00"
					( Origin gBackEnd )
				)
				( attribute "SN_LINE_TO_THRUVIA_SPACING" "4.50,4.00,4.00,4.00,4.00,4.00,4.00,4.00,4.00,4.00,4.00,4.00,4.00,4.50"
					( Origin gBackEnd )
				)
				( attribute "SN_SHAPE_TO_THRUVIA_SPACING" "5.00,5.00,5.00,5.00,5.00,5.00,5.00,5.00,5.00,5.00,5.00,5.00,5.00,5.00"
					( Origin gBackEnd )
				)
				( attribute "SN_TESTVIA_TO_TESTVIA_SPACING" "5.00,5.00,5.00,5.00,5.00,5.00,5.00,5.00,5.00,5.00,5.00,5.00,5.00,5.00"
					( Origin gBackEnd )
				)
				( attribute "SN_BBV_TO_TESTVIA_SPACING" "5.00,5.00,5.00,5.00,5.00,5.00,5.00,5.00,5.00,5.00,5.00,5.00,5.00,5.00"
					( Origin gBackEnd )
				)
				( attribute "SN_BONDPAD_TO_TESTVIA_SPACING" "5.00,5.00,5.00,5.00,5.00,5.00,5.00,5.00,5.00,5.00,5.00,5.00,5.00,5.00"
					( Origin gBackEnd )
				)
				( attribute "SN_LINE_TO_TESTVIA_SPACING" "5.00,4.00,4.00,4.00,4.00,4.00,4.00,4.00,4.00,4.00,4.00,4.00,4.00,5.00"
					( Origin gBackEnd )
				)
				( attribute "SN_SHAPE_TO_TESTVIA_SPACING" "5.00,5.00,5.00,5.00,5.00,5.00,5.00,5.00,5.00,5.00,5.00,5.00,5.00,5.00"
					( Origin gBackEnd )
				)
				( attribute "SN_BBV_TO_BBV_SPACING" "5.00,5.00,5.00,5.00,5.00,5.00,5.00,5.00,5.00,5.00,5.00,5.00,5.00,5.00"
					( Origin gBackEnd )
				)
				( attribute "SN_BONDPAD_TO_BBV_SPACING" "5.00,5.00,5.00,5.00,5.00,5.00,5.00,5.00,5.00,5.00,5.00,5.00,5.00,5.00"
					( Origin gBackEnd )
				)
				( attribute "SN_BBV_TO_LINE_SPACING" "5.00,5.00,5.00,5.00,5.00,5.00,5.00,5.00,5.00,5.00,5.00,5.00,5.00,5.00"
					( Origin gBackEnd )
				)
				( attribute "SN_BBV_TO_SHAPE_SPACING" "5.00,5.00,5.00,5.00,5.00,5.00,5.00,5.00,5.00,5.00,5.00,5.00,5.00,5.00"
					( Origin gBackEnd )
				)
				( attribute "SN_BONDPAD_TO_BONDPAD_SPACING" "5.00,5.00,5.00,5.00,5.00,5.00,5.00,5.00,5.00,5.00,5.00,5.00,5.00,5.00"
					( Origin gBackEnd )
				)
				( attribute "SN_BONDPAD_TO_LINE_SPACING" "5.00,5.00,5.00,5.00,5.00,5.00,5.00,5.00,5.00,5.00,5.00,5.00,5.00,5.00"
					( Origin gBackEnd )
				)
				( attribute "SN_BONDPAD_TO_SHAPE_SPACING" "5.00,5.00,5.00,5.00,5.00,5.00,5.00,5.00,5.00,5.00,5.00,5.00,5.00,5.00"
					( Origin gBackEnd )
				)
				( attribute "SN_LINE_TO_LINE_SPACING" "20.00,20.00,15.00,20.00,15.00,20.00,20.00,20.00,20.00,15.00,20.00,15.00,20.00,20.00"
					( Origin gBackEnd )
				)
				( attribute "SN_LINE_TO_SHAPE_SPACING" "0.00,0.00,0.00,0.00,0.00,0.00,0.00,0.00,0.00,0.00,0.00,0.00,0.00,0.00"
					( Origin gBackEnd )
				)
				( attribute "SN_SHAPE_TO_SHAPE_SPACING" "5.00,5.00,5.00,5.00,5.00,5.00,5.00,5.00,5.00,5.00,5.00,5.00,5.00,5.00"
					( Origin gBackEnd )
				)
				( attribute "SN_HOLE_TO_PIN_SPACING" "8.00,8.00,8.00,8.00,8.00,8.00,8.00,8.00,8.00,8.00,8.00,8.00,8.00,8.00"
					( Origin gBackEnd )
				)
				( attribute "SN_HOLE_TO_VIA_SPACING" "8.00,8.00,8.00,8.00,8.00,8.00,8.00,8.00,8.00,8.00,8.00,8.00,8.00,8.00"
					( Origin gBackEnd )
				)
				( attribute "SN_HOLE_TO_LINE_SPACING" "8.00,8.00,8.00,8.00,8.00,8.00,8.00,8.00,8.00,8.00,8.00,8.00,8.00,8.00"
					( Origin gBackEnd )
				)
				( attribute "SN_HOLE_TO_SHAPE_SPACING" "8.00,8.00,8.00,8.00,8.00,8.00,8.00,8.00,8.00,8.00,8.00,8.00,8.00,8.00"
					( Origin gBackEnd )
				)
				( attribute "SN_HOLE_TO_HOLE_SPACING" "8.00,8.00,8.00,8.00,8.00,8.00,8.00,8.00,8.00,8.00,8.00,8.00,8.00,8.00"
					( Origin gBackEnd )
				)
				( attribute "SN_MVIA_TO_MVIA_SPACING" "5.00,5.00,5.00,5.00,5.00,5.00,5.00,5.00,5.00,5.00,5.00,5.00,5.00,5.00"
					( Origin gBackEnd )
				)
				( attribute "SN_MVIA_TO_THRUPIN_SPACING" "5.00,5.00,5.00,5.00,5.00,5.00,5.00,5.00,5.00,5.00,5.00,5.00,5.00,5.00"
					( Origin gBackEnd )
				)
				( attribute "SN_MVIA_TO_SMDPIN_SPACING" "5.00,5.00,5.00,5.00,5.00,5.00,5.00,5.00,5.00,5.00,5.00,5.00,5.00,5.00"
					( Origin gBackEnd )
				)
				( attribute "SN_MVIA_TO_THRUVIA_SPACING" "5.00,5.00,5.00,5.00,5.00,5.00,5.00,5.00,5.00,5.00,5.00,5.00,5.00,5.00"
					( Origin gBackEnd )
				)
				( attribute "SN_MVIA_TO_BBV_SPACING" "5.00,5.00,5.00,5.00,5.00,5.00,5.00,5.00,5.00,5.00,5.00,5.00,5.00,5.00"
					( Origin gBackEnd )
				)
				( attribute "SN_MVIA_TO_LINE_SPACING" "5.00,5.00,5.00,5.00,5.00,5.00,5.00,5.00,5.00,5.00,5.00,5.00,5.00,5.00"
					( Origin gBackEnd )
				)
				( attribute "SN_MVIA_TO_SHAPE_SPACING" "5.00,5.00,5.00,5.00,5.00,5.00,5.00,5.00,5.00,5.00,5.00,5.00,5.00,5.00"
					( Origin gBackEnd )
				)
				( attribute "SN_MVIA_TO_TESTPIN_SPACING" "5.00,5.00,5.00,5.00,5.00,5.00,5.00,5.00,5.00,5.00,5.00,5.00,5.00,5.00"
					( Origin gBackEnd )
				)
				( attribute "SN_MVIA_TO_TESTVIA_SPACING" "5.00,5.00,5.00,5.00,5.00,5.00,5.00,5.00,5.00,5.00,5.00,5.00,5.00,5.00"
					( Origin gBackEnd )
				)
				( attribute "SN_BONDPAD_TO_MVIA_SPACING" "5.00,5.00,5.00,5.00,5.00,5.00,5.00,5.00,5.00,5.00,5.00,5.00,5.00,5.00"
					( Origin gBackEnd )
				)
				( objectStatus "20_MILS_US_&_15_MILS_SL" )
			)
			( sameNetSpacingCSet "@crescent_city_bb_fab1_lib.crescent_city_bb_fab1(sch_1):\24MIL_US&15MIL_SL\"
				( attribute "SAME_NET" "TRUE,TRUE,TRUE,TRUE,TRUE,TRUE,TRUE,TRUE,TRUE,TRUE,TRUE,TRUE,TRUE,TRUE"
					( Origin gBackEnd )
				)
				( attribute "SN_THRUPIN_TO_THRUPIN_SPACING" "5.00,5.00,5.00,5.00,5.00,5.00,5.00,5.00,5.00,5.00,5.00,5.00,5.00,5.00"
					( Origin gBackEnd )
				)
				( attribute "SN_THRUPIN_TO_SMDPIN_SPACING" "5.00,5.00,5.00,5.00,5.00,5.00,5.00,5.00,5.00,5.00,5.00,5.00,5.00,5.00"
					( Origin gBackEnd )
				)
				( attribute "SN_TESTPIN_TO_THRUPIN_SPACING" "5.00,5.00,5.00,5.00,5.00,5.00,5.00,5.00,5.00,5.00,5.00,5.00,5.00,5.00"
					( Origin gBackEnd )
				)
				( attribute "SN_THRUPIN_TO_THRUVIA_SPACING" "5.00,5.00,5.00,5.00,5.00,5.00,5.00,5.00,5.00,5.00,5.00,5.00,5.00,5.00"
					( Origin gBackEnd )
				)
				( attribute "SN_TESTVIA_TO_THRUPIN_SPACING" "5.00,5.00,5.00,5.00,5.00,5.00,5.00,5.00,5.00,5.00,5.00,5.00,5.00,5.00"
					( Origin gBackEnd )
				)
				( attribute "SN_BBV_TO_THRUPIN_SPACING" "5.00,5.00,5.00,5.00,5.00,5.00,5.00,5.00,5.00,5.00,5.00,5.00,5.00,5.00"
					( Origin gBackEnd )
				)
				( attribute "SN_THRUPIN_TO_BONDPAD_SPACING" "5.00,5.00,5.00,5.00,5.00,5.00,5.00,5.00,5.00,5.00,5.00,5.00,5.00,5.00"
					( Origin gBackEnd )
				)
				( attribute "SN_LINE_TO_THRUPIN_SPACING" "5.00,5.00,5.00,5.00,5.00,5.00,5.00,5.00,5.00,5.00,5.00,5.00,5.00,5.00"
					( Origin gBackEnd )
				)
				( attribute "SN_THRUPIN_TO_SHAPE_SPACING" "5.00,5.00,5.00,5.00,5.00,5.00,5.00,5.00,5.00,5.00,5.00,5.00,5.00,5.00"
					( Origin gBackEnd )
				)
				( attribute "SN_SMDPIN_TO_SMDPIN_SPACING" "5.00,5.00,5.00,5.00,5.00,5.00,5.00,5.00,5.00,5.00,5.00,5.00,5.00,5.00"
					( Origin gBackEnd )
				)
				( attribute "SN_SMDPIN_TO_TESTPIN_SPACING" "5.00,5.00,5.00,5.00,5.00,5.00,5.00,5.00,5.00,5.00,5.00,5.00,5.00,5.00"
					( Origin gBackEnd )
				)
				( attribute "SN_SMDPIN_TO_THRUVIA_SPACING" "4.00,4.00,4.00,4.00,4.00,4.00,4.00,4.00,4.00,4.00,4.00,4.00,4.00,4.00"
					( Origin gBackEnd )
				)
				( attribute "SN_SMDPIN_TO_TESTVIA_SPACING" "4.00,4.00,4.00,4.00,4.00,4.00,4.00,4.00,4.00,4.00,4.00,4.00,4.00,4.00"
					( Origin gBackEnd )
				)
				( attribute "SN_BBV_TO_SMDPIN_SPACING" "5.00,5.00,5.00,5.00,5.00,5.00,5.00,5.00,5.00,5.00,5.00,5.00,5.00,5.00"
					( Origin gBackEnd )
				)
				( attribute "SN_SMDPIN_TO_BONDPAD_SPACING" "5.00,5.00,5.00,5.00,5.00,5.00,5.00,5.00,5.00,5.00,5.00,5.00,5.00,5.00"
					( Origin gBackEnd )
				)
				( attribute "SN_LINE_TO_SMDPIN_SPACING" "4.50,4.50,4.50,4.50,4.50,4.50,4.50,4.50,4.50,4.50,4.50,4.50,4.50,4.50"
					( Origin gBackEnd )
				)
				( attribute "SN_SHAPE_TO_SMDPIN_SPACING" "5.00,5.00,5.00,5.00,5.00,5.00,5.00,5.00,5.00,5.00,5.00,5.00,5.00,5.00"
					( Origin gBackEnd )
				)
				( attribute "SN_TESTPIN_TO_TESTPIN_SPACING" "5.00,5.00,5.00,5.00,5.00,5.00,5.00,5.00,5.00,5.00,5.00,5.00,5.00,5.00"
					( Origin gBackEnd )
				)
				( attribute "SN_TESTPIN_TO_THRUVIA_SPACING" "5.00,5.00,5.00,5.00,5.00,5.00,5.00,5.00,5.00,5.00,5.00,5.00,5.00,5.00"
					( Origin gBackEnd )
				)
				( attribute "SN_TESTPIN_TO_TESTVIA_SPACING" "5.00,5.00,5.00,5.00,5.00,5.00,5.00,5.00,5.00,5.00,5.00,5.00,5.00,5.00"
					( Origin gBackEnd )
				)
				( attribute "SN_BBV_TO_TESTPIN_SPACING" "5.00,5.00,5.00,5.00,5.00,5.00,5.00,5.00,5.00,5.00,5.00,5.00,5.00,5.00"
					( Origin gBackEnd )
				)
				( attribute "SN_BONDPAD_TO_TESTPIN_SPACING" "5.00,5.00,5.00,5.00,5.00,5.00,5.00,5.00,5.00,5.00,5.00,5.00,5.00,5.00"
					( Origin gBackEnd )
				)
				( attribute "SN_LINE_TO_TESTPIN_SPACING" "5.00,5.00,5.00,5.00,5.00,5.00,5.00,5.00,5.00,5.00,5.00,5.00,5.00,5.00"
					( Origin gBackEnd )
				)
				( attribute "SN_SHAPE_TO_TESTPIN_SPACING" "5.00,5.00,5.00,5.00,5.00,5.00,5.00,5.00,5.00,5.00,5.00,5.00,5.00,5.00"
					( Origin gBackEnd )
				)
				( attribute "SN_THRUVIA_TO_THRUVIA_SPACING" "4.50,4.00,4.00,4.00,4.00,4.00,4.00,4.00,4.00,4.00,4.00,4.00,4.00,4.50"
					( Origin gBackEnd )
				)
				( attribute "SN_TESTVIA_TO_THRUVIA_SPACING" "5.00,5.00,5.00,5.00,5.00,5.00,5.00,5.00,5.00,5.00,5.00,5.00,5.00,5.00"
					( Origin gBackEnd )
				)
				( attribute "SN_BBV_TO_THRUVIA_SPACING" "5.00,5.00,5.00,5.00,5.00,5.00,5.00,5.00,5.00,5.00,5.00,5.00,5.00,5.00"
					( Origin gBackEnd )
				)
				( attribute "SN_BONDPAD_TO_THRUVIA_SPACING" "5.00,5.00,5.00,5.00,5.00,5.00,5.00,5.00,5.00,5.00,5.00,5.00,5.00,5.00"
					( Origin gBackEnd )
				)
				( attribute "SN_LINE_TO_THRUVIA_SPACING" "4.50,4.00,4.00,4.00,4.00,4.00,4.00,4.00,4.00,4.00,4.00,4.00,4.00,4.50"
					( Origin gBackEnd )
				)
				( attribute "SN_SHAPE_TO_THRUVIA_SPACING" "5.00,5.00,5.00,5.00,5.00,5.00,5.00,5.00,5.00,5.00,5.00,5.00,5.00,5.00"
					( Origin gBackEnd )
				)
				( attribute "SN_TESTVIA_TO_TESTVIA_SPACING" "5.00,5.00,5.00,5.00,5.00,5.00,5.00,5.00,5.00,5.00,5.00,5.00,5.00,5.00"
					( Origin gBackEnd )
				)
				( attribute "SN_BBV_TO_TESTVIA_SPACING" "5.00,5.00,5.00,5.00,5.00,5.00,5.00,5.00,5.00,5.00,5.00,5.00,5.00,5.00"
					( Origin gBackEnd )
				)
				( attribute "SN_BONDPAD_TO_TESTVIA_SPACING" "5.00,5.00,5.00,5.00,5.00,5.00,5.00,5.00,5.00,5.00,5.00,5.00,5.00,5.00"
					( Origin gBackEnd )
				)
				( attribute "SN_LINE_TO_TESTVIA_SPACING" "5.00,5.00,5.00,5.00,5.00,5.00,5.00,5.00,5.00,5.00,5.00,5.00,5.00,5.00"
					( Origin gBackEnd )
				)
				( attribute "SN_SHAPE_TO_TESTVIA_SPACING" "5.00,5.00,5.00,5.00,5.00,5.00,5.00,5.00,5.00,5.00,5.00,5.00,5.00,5.00"
					( Origin gBackEnd )
				)
				( attribute "SN_BBV_TO_BBV_SPACING" "5.00,5.00,5.00,5.00,5.00,5.00,5.00,5.00,5.00,5.00,5.00,5.00,5.00,5.00"
					( Origin gBackEnd )
				)
				( attribute "SN_BONDPAD_TO_BBV_SPACING" "5.00,5.00,5.00,5.00,5.00,5.00,5.00,5.00,5.00,5.00,5.00,5.00,5.00,5.00"
					( Origin gBackEnd )
				)
				( attribute "SN_BBV_TO_LINE_SPACING" "5.00,5.00,5.00,5.00,5.00,5.00,5.00,5.00,5.00,5.00,5.00,5.00,5.00,5.00"
					( Origin gBackEnd )
				)
				( attribute "SN_BBV_TO_SHAPE_SPACING" "5.00,5.00,5.00,5.00,5.00,5.00,5.00,5.00,5.00,5.00,5.00,5.00,5.00,5.00"
					( Origin gBackEnd )
				)
				( attribute "SN_BONDPAD_TO_BONDPAD_SPACING" "5.00,5.00,5.00,5.00,5.00,5.00,5.00,5.00,5.00,5.00,5.00,5.00,5.00,5.00"
					( Origin gBackEnd )
				)
				( attribute "SN_BONDPAD_TO_LINE_SPACING" "5.00,5.00,5.00,5.00,5.00,5.00,5.00,5.00,5.00,5.00,5.00,5.00,5.00,5.00"
					( Origin gBackEnd )
				)
				( attribute "SN_BONDPAD_TO_SHAPE_SPACING" "5.00,5.00,5.00,5.00,5.00,5.00,5.00,5.00,5.00,5.00,5.00,5.00,5.00,5.00"
					( Origin gBackEnd )
				)
				( attribute "SN_LINE_TO_LINE_SPACING" "24.00,15.00,15.00,15.00,15.00,15.00,15.00,15.00,15.00,15.00,15.00,15.00,15.00,24.00"
					( Origin gBackEnd )
				)
				( attribute "SN_LINE_TO_SHAPE_SPACING" "5.00,5.00,5.00,5.00,5.00,5.00,5.00,5.00,5.00,5.00,5.00,5.00,5.00,5.00"
					( Origin gBackEnd )
				)
				( attribute "SN_SHAPE_TO_SHAPE_SPACING" "5.00,5.00,5.00,5.00,5.00,5.00,5.00,5.00,5.00,5.00,5.00,5.00,5.00,5.00"
					( Origin gBackEnd )
				)
				( attribute "SN_HOLE_TO_PIN_SPACING" "8.00,8.00,8.00,8.00,8.00,8.00,8.00,8.00,8.00,8.00,8.00,8.00,8.00,8.00"
					( Origin gBackEnd )
				)
				( attribute "SN_HOLE_TO_VIA_SPACING" "8.00,8.00,8.00,8.00,8.00,8.00,8.00,8.00,8.00,8.00,8.00,8.00,8.00,8.00"
					( Origin gBackEnd )
				)
				( attribute "SN_HOLE_TO_LINE_SPACING" "8.00,8.00,8.00,8.00,8.00,8.00,8.00,8.00,8.00,8.00,8.00,8.00,8.00,8.00"
					( Origin gBackEnd )
				)
				( attribute "SN_HOLE_TO_SHAPE_SPACING" "8.00,8.00,8.00,8.00,8.00,8.00,8.00,8.00,8.00,8.00,8.00,8.00,8.00,8.00"
					( Origin gBackEnd )
				)
				( attribute "SN_HOLE_TO_HOLE_SPACING" "8.00,8.00,8.00,8.00,8.00,8.00,8.00,8.00,8.00,8.00,8.00,8.00,8.00,8.00"
					( Origin gBackEnd )
				)
				( attribute "SN_MVIA_TO_MVIA_SPACING" "5.00,5.00,5.00,5.00,5.00,5.00,5.00,5.00,5.00,5.00,5.00,5.00,5.00,5.00"
					( Origin gBackEnd )
				)
				( attribute "SN_MVIA_TO_THRUPIN_SPACING" "5.00,5.00,5.00,5.00,5.00,5.00,5.00,5.00,5.00,5.00,5.00,5.00,5.00,5.00"
					( Origin gBackEnd )
				)
				( attribute "SN_MVIA_TO_SMDPIN_SPACING" "5.00,5.00,5.00,5.00,5.00,5.00,5.00,5.00,5.00,5.00,5.00,5.00,5.00,5.00"
					( Origin gBackEnd )
				)
				( attribute "SN_MVIA_TO_THRUVIA_SPACING" "5.00,5.00,5.00,5.00,5.00,5.00,5.00,5.00,5.00,5.00,5.00,5.00,5.00,5.00"
					( Origin gBackEnd )
				)
				( attribute "SN_MVIA_TO_BBV_SPACING" "5.00,5.00,5.00,5.00,5.00,5.00,5.00,5.00,5.00,5.00,5.00,5.00,5.00,5.00"
					( Origin gBackEnd )
				)
				( attribute "SN_MVIA_TO_LINE_SPACING" "5.00,5.00,5.00,5.00,5.00,5.00,5.00,5.00,5.00,5.00,5.00,5.00,5.00,5.00"
					( Origin gBackEnd )
				)
				( attribute "SN_MVIA_TO_SHAPE_SPACING" "5.00,5.00,5.00,5.00,5.00,5.00,5.00,5.00,5.00,5.00,5.00,5.00,5.00,5.00"
					( Origin gBackEnd )
				)
				( attribute "SN_MVIA_TO_TESTPIN_SPACING" "5.00,5.00,5.00,5.00,5.00,5.00,5.00,5.00,5.00,5.00,5.00,5.00,5.00,5.00"
					( Origin gBackEnd )
				)
				( attribute "SN_MVIA_TO_TESTVIA_SPACING" "5.00,5.00,5.00,5.00,5.00,5.00,5.00,5.00,5.00,5.00,5.00,5.00,5.00,5.00"
					( Origin gBackEnd )
				)
				( attribute "SN_BONDPAD_TO_MVIA_SPACING" "5.00,5.00,5.00,5.00,5.00,5.00,5.00,5.00,5.00,5.00,5.00,5.00,5.00,5.00"
					( Origin gBackEnd )
				)
				( objectStatus "24MIL_US_&_15MIL_SL" )
			)
			( sameNetSpacingCSet "@crescent_city_bb_fab1_lib.crescent_city_bb_fab1(sch_1):\2.2H_US_AND_2H_SL\"
				( attribute "SAME_NET" "TRUE,TRUE,TRUE,TRUE,TRUE,TRUE,TRUE,TRUE,TRUE,TRUE,TRUE,TRUE,TRUE,TRUE"
					( Origin gBackEnd )
				)
				( attribute "SN_THRUPIN_TO_THRUPIN_SPACING" "5.00,5.00,5.00,5.00,5.00,5.00,5.00,5.00,5.00,5.00,5.00,5.00,5.00,5.00"
					( Origin gBackEnd )
				)
				( attribute "SN_THRUPIN_TO_SMDPIN_SPACING" "5.00,5.00,5.00,5.00,5.00,5.00,5.00,5.00,5.00,5.00,5.00,5.00,5.00,5.00"
					( Origin gBackEnd )
				)
				( attribute "SN_TESTPIN_TO_THRUPIN_SPACING" "5.00,5.00,5.00,5.00,5.00,5.00,5.00,5.00,5.00,5.00,5.00,5.00,5.00,5.00"
					( Origin gBackEnd )
				)
				( attribute "SN_THRUPIN_TO_THRUVIA_SPACING" "5.00,5.00,5.00,5.00,5.00,5.00,5.00,5.00,5.00,5.00,5.00,5.00,5.00,5.00"
					( Origin gBackEnd )
				)
				( attribute "SN_TESTVIA_TO_THRUPIN_SPACING" "5.00,5.00,5.00,5.00,5.00,5.00,5.00,5.00,5.00,5.00,5.00,5.00,5.00,5.00"
					( Origin gBackEnd )
				)
				( attribute "SN_BBV_TO_THRUPIN_SPACING" "5.00,5.00,5.00,5.00,5.00,5.00,5.00,5.00,5.00,5.00,5.00,5.00,5.00,5.00"
					( Origin gBackEnd )
				)
				( attribute "SN_THRUPIN_TO_BONDPAD_SPACING" "5.00,5.00,5.00,5.00,5.00,5.00,5.00,5.00,5.00,5.00,5.00,5.00,5.00,5.00"
					( Origin gBackEnd )
				)
				( attribute "SN_LINE_TO_THRUPIN_SPACING" "5.00,5.00,5.00,5.00,5.00,5.00,5.00,5.00,5.00,5.00,5.00,5.00,5.00,5.00"
					( Origin gBackEnd )
				)
				( attribute "SN_THRUPIN_TO_SHAPE_SPACING" "5.00,5.00,5.00,5.00,5.00,5.00,5.00,5.00,5.00,5.00,5.00,5.00,5.00,5.00"
					( Origin gBackEnd )
				)
				( attribute "SN_SMDPIN_TO_SMDPIN_SPACING" "5.00,5.00,5.00,5.00,5.00,5.00,5.00,5.00,5.00,5.00,5.00,5.00,5.00,5.00"
					( Origin gBackEnd )
				)
				( attribute "SN_SMDPIN_TO_TESTPIN_SPACING" "5.00,5.00,5.00,5.00,5.00,5.00,5.00,5.00,5.00,5.00,5.00,5.00,5.00,5.00"
					( Origin gBackEnd )
				)
				( attribute "SN_SMDPIN_TO_THRUVIA_SPACING" "4.00,4.00,4.00,4.00,4.00,4.00,4.00,4.00,4.00,4.00,4.00,4.00,4.00,4.00"
					( Origin gBackEnd )
				)
				( attribute "SN_SMDPIN_TO_TESTVIA_SPACING" "4.00,4.00,4.00,4.00,4.00,4.00,4.00,4.00,4.00,4.00,4.00,4.00,4.00,4.00"
					( Origin gBackEnd )
				)
				( attribute "SN_BBV_TO_SMDPIN_SPACING" "5.00,5.00,5.00,5.00,5.00,5.00,5.00,5.00,5.00,5.00,5.00,5.00,5.00,5.00"
					( Origin gBackEnd )
				)
				( attribute "SN_SMDPIN_TO_BONDPAD_SPACING" "5.00,5.00,5.00,5.00,5.00,5.00,5.00,5.00,5.00,5.00,5.00,5.00,5.00,5.00"
					( Origin gBackEnd )
				)
				( attribute "SN_LINE_TO_SMDPIN_SPACING" "4.50,4.50,4.50,4.50,4.50,4.50,4.50,4.50,4.50,4.50,4.50,4.50,4.50,4.50"
					( Origin gBackEnd )
				)
				( attribute "SN_SHAPE_TO_SMDPIN_SPACING" "5.00,5.00,5.00,5.00,5.00,5.00,5.00,5.00,5.00,5.00,5.00,5.00,5.00,5.00"
					( Origin gBackEnd )
				)
				( attribute "SN_TESTPIN_TO_TESTPIN_SPACING" "5.00,5.00,5.00,5.00,5.00,5.00,5.00,5.00,5.00,5.00,5.00,5.00,5.00,5.00"
					( Origin gBackEnd )
				)
				( attribute "SN_TESTPIN_TO_THRUVIA_SPACING" "5.00,5.00,5.00,5.00,5.00,5.00,5.00,5.00,5.00,5.00,5.00,5.00,5.00,5.00"
					( Origin gBackEnd )
				)
				( attribute "SN_TESTPIN_TO_TESTVIA_SPACING" "5.00,5.00,5.00,5.00,5.00,5.00,5.00,5.00,5.00,5.00,5.00,5.00,5.00,5.00"
					( Origin gBackEnd )
				)
				( attribute "SN_BBV_TO_TESTPIN_SPACING" "5.00,5.00,5.00,5.00,5.00,5.00,5.00,5.00,5.00,5.00,5.00,5.00,5.00,5.00"
					( Origin gBackEnd )
				)
				( attribute "SN_BONDPAD_TO_TESTPIN_SPACING" "5.00,5.00,5.00,5.00,5.00,5.00,5.00,5.00,5.00,5.00,5.00,5.00,5.00,5.00"
					( Origin gBackEnd )
				)
				( attribute "SN_LINE_TO_TESTPIN_SPACING" "5.00,5.00,5.00,5.00,5.00,5.00,5.00,5.00,5.00,5.00,5.00,5.00,5.00,5.00"
					( Origin gBackEnd )
				)
				( attribute "SN_SHAPE_TO_TESTPIN_SPACING" "5.00,5.00,5.00,5.00,5.00,5.00,5.00,5.00,5.00,5.00,5.00,5.00,5.00,5.00"
					( Origin gBackEnd )
				)
				( attribute "SN_THRUVIA_TO_THRUVIA_SPACING" "4.50,4.00,4.00,4.00,4.00,4.00,4.00,4.00,4.00,4.00,4.00,4.00,4.00,4.50"
					( Origin gBackEnd )
				)
				( attribute "SN_TESTVIA_TO_THRUVIA_SPACING" "5.00,5.00,5.00,5.00,5.00,5.00,5.00,5.00,5.00,5.00,5.00,5.00,5.00,5.00"
					( Origin gBackEnd )
				)
				( attribute "SN_BBV_TO_THRUVIA_SPACING" "5.00,5.00,5.00,5.00,5.00,5.00,5.00,5.00,5.00,5.00,5.00,5.00,5.00,5.00"
					( Origin gBackEnd )
				)
				( attribute "SN_BONDPAD_TO_THRUVIA_SPACING" "5.00,5.00,5.00,5.00,5.00,5.00,5.00,5.00,5.00,5.00,5.00,5.00,5.00,5.00"
					( Origin gBackEnd )
				)
				( attribute "SN_LINE_TO_THRUVIA_SPACING" "4.50,4.00,4.00,4.00,4.00,4.00,4.00,4.00,4.00,4.00,4.00,4.00,4.00,4.50"
					( Origin gBackEnd )
				)
				( attribute "SN_SHAPE_TO_THRUVIA_SPACING" "5.00,5.00,5.00,5.00,5.00,5.00,5.00,5.00,5.00,5.00,5.00,5.00,5.00,5.00"
					( Origin gBackEnd )
				)
				( attribute "SN_TESTVIA_TO_TESTVIA_SPACING" "5.00,5.00,5.00,5.00,5.00,5.00,5.00,5.00,5.00,5.00,5.00,5.00,5.00,5.00"
					( Origin gBackEnd )
				)
				( attribute "SN_BBV_TO_TESTVIA_SPACING" "5.00,5.00,5.00,5.00,5.00,5.00,5.00,5.00,5.00,5.00,5.00,5.00,5.00,5.00"
					( Origin gBackEnd )
				)
				( attribute "SN_BONDPAD_TO_TESTVIA_SPACING" "5.00,5.00,5.00,5.00,5.00,5.00,5.00,5.00,5.00,5.00,5.00,5.00,5.00,5.00"
					( Origin gBackEnd )
				)
				( attribute "SN_LINE_TO_TESTVIA_SPACING" "5.00,5.00,5.00,5.00,5.00,5.00,5.00,5.00,5.00,5.00,5.00,5.00,5.00,5.00"
					( Origin gBackEnd )
				)
				( attribute "SN_SHAPE_TO_TESTVIA_SPACING" "5.00,5.00,5.00,5.00,5.00,5.00,5.00,5.00,5.00,5.00,5.00,5.00,5.00,5.00"
					( Origin gBackEnd )
				)
				( attribute "SN_BBV_TO_BBV_SPACING" "5.00,5.00,5.00,5.00,5.00,5.00,5.00,5.00,5.00,5.00,5.00,5.00,5.00,5.00"
					( Origin gBackEnd )
				)
				( attribute "SN_BONDPAD_TO_BBV_SPACING" "5.00,5.00,5.00,5.00,5.00,5.00,5.00,5.00,5.00,5.00,5.00,5.00,5.00,5.00"
					( Origin gBackEnd )
				)
				( attribute "SN_BBV_TO_LINE_SPACING" "5.00,5.00,5.00,5.00,5.00,5.00,5.00,5.00,5.00,5.00,5.00,5.00,5.00,5.00"
					( Origin gBackEnd )
				)
				( attribute "SN_BBV_TO_SHAPE_SPACING" "5.00,5.00,5.00,5.00,5.00,5.00,5.00,5.00,5.00,5.00,5.00,5.00,5.00,5.00"
					( Origin gBackEnd )
				)
				( attribute "SN_BONDPAD_TO_BONDPAD_SPACING" "5.00,5.00,5.00,5.00,5.00,5.00,5.00,5.00,5.00,5.00,5.00,5.00,5.00,5.00"
					( Origin gBackEnd )
				)
				( attribute "SN_BONDPAD_TO_LINE_SPACING" "5.00,5.00,5.00,5.00,5.00,5.00,5.00,5.00,5.00,5.00,5.00,5.00,5.00,5.00"
					( Origin gBackEnd )
				)
				( attribute "SN_BONDPAD_TO_SHAPE_SPACING" "5.00,5.00,5.00,5.00,5.00,5.00,5.00,5.00,5.00,5.00,5.00,5.00,5.00,5.00"
					( Origin gBackEnd )
				)
				( attribute "SN_LINE_TO_LINE_SPACING" "5.94,6.00,6.00,6.00,6.00,6.00,6.00,6.00,6.00,6.00,6.00,6.00,6.00,5.94"
					( Origin gBackEnd )
				)
				( attribute "SN_LINE_TO_SHAPE_SPACING" "5.00,5.00,5.00,5.00,5.00,5.00,5.00,5.00,5.00,5.00,5.00,5.00,5.00,5.00"
					( Origin gBackEnd )
				)
				( attribute "SN_SHAPE_TO_SHAPE_SPACING" "5.00,5.00,5.00,5.00,5.00,5.00,5.00,5.00,5.00,5.00,5.00,5.00,5.00,5.00"
					( Origin gBackEnd )
				)
				( attribute "SN_HOLE_TO_PIN_SPACING" "8.00,8.00,8.00,8.00,8.00,8.00,8.00,8.00,8.00,8.00,8.00,8.00,8.00,8.00"
					( Origin gBackEnd )
				)
				( attribute "SN_HOLE_TO_VIA_SPACING" "8.00,8.00,8.00,8.00,8.00,8.00,8.00,8.00,8.00,8.00,8.00,8.00,8.00,8.00"
					( Origin gBackEnd )
				)
				( attribute "SN_HOLE_TO_LINE_SPACING" "8.00,8.00,8.00,8.00,8.00,8.00,8.00,8.00,8.00,8.00,8.00,8.00,8.00,8.00"
					( Origin gBackEnd )
				)
				( attribute "SN_HOLE_TO_SHAPE_SPACING" "8.00,8.00,8.00,8.00,8.00,8.00,8.00,8.00,8.00,8.00,8.00,8.00,8.00,8.00"
					( Origin gBackEnd )
				)
				( attribute "SN_HOLE_TO_HOLE_SPACING" "8.00,8.00,8.00,8.00,8.00,8.00,8.00,8.00,8.00,8.00,8.00,8.00,8.00,8.00"
					( Origin gBackEnd )
				)
				( attribute "SN_MVIA_TO_MVIA_SPACING" "5.00,5.00,5.00,5.00,5.00,5.00,5.00,5.00,5.00,5.00,5.00,5.00,5.00,5.00"
					( Origin gBackEnd )
				)
				( attribute "SN_MVIA_TO_THRUPIN_SPACING" "5.00,5.00,5.00,5.00,5.00,5.00,5.00,5.00,5.00,5.00,5.00,5.00,5.00,5.00"
					( Origin gBackEnd )
				)
				( attribute "SN_MVIA_TO_SMDPIN_SPACING" "5.00,5.00,5.00,5.00,5.00,5.00,5.00,5.00,5.00,5.00,5.00,5.00,5.00,5.00"
					( Origin gBackEnd )
				)
				( attribute "SN_MVIA_TO_THRUVIA_SPACING" "5.00,5.00,5.00,5.00,5.00,5.00,5.00,5.00,5.00,5.00,5.00,5.00,5.00,5.00"
					( Origin gBackEnd )
				)
				( attribute "SN_MVIA_TO_BBV_SPACING" "5.00,5.00,5.00,5.00,5.00,5.00,5.00,5.00,5.00,5.00,5.00,5.00,5.00,5.00"
					( Origin gBackEnd )
				)
				( attribute "SN_MVIA_TO_LINE_SPACING" "5.00,5.00,5.00,5.00,5.00,5.00,5.00,5.00,5.00,5.00,5.00,5.00,5.00,5.00"
					( Origin gBackEnd )
				)
				( attribute "SN_MVIA_TO_SHAPE_SPACING" "5.00,5.00,5.00,5.00,5.00,5.00,5.00,5.00,5.00,5.00,5.00,5.00,5.00,5.00"
					( Origin gBackEnd )
				)
				( attribute "SN_MVIA_TO_TESTPIN_SPACING" "5.00,5.00,5.00,5.00,5.00,5.00,5.00,5.00,5.00,5.00,5.00,5.00,5.00,5.00"
					( Origin gBackEnd )
				)
				( attribute "SN_MVIA_TO_TESTVIA_SPACING" "5.00,5.00,5.00,5.00,5.00,5.00,5.00,5.00,5.00,5.00,5.00,5.00,5.00,5.00"
					( Origin gBackEnd )
				)
				( attribute "SN_BONDPAD_TO_MVIA_SPACING" "5.00,5.00,5.00,5.00,5.00,5.00,5.00,5.00,5.00,5.00,5.00,5.00,5.00,5.00"
					( Origin gBackEnd )
				)
				( objectStatus "2.2H_US_&_2H_SL" )
			)
			( sameNetSpacingCSet "@crescent_city_bb_fab1_lib.crescent_city_bb_fab1(sch_1):\4H\"
				( attribute "SAME_NET" "TRUE,TRUE,TRUE,TRUE,TRUE,TRUE,TRUE,TRUE,TRUE,TRUE,TRUE,TRUE,TRUE,TRUE"
					( Origin gBackEnd )
				)
				( attribute "SN_THRUPIN_TO_THRUPIN_SPACING" "5.00,5.00,5.00,5.00,5.00,5.00,5.00,5.00,5.00,5.00,5.00,5.00,5.00,5.00"
					( Origin gBackEnd )
				)
				( attribute "SN_THRUPIN_TO_SMDPIN_SPACING" "5.00,5.00,5.00,5.00,5.00,5.00,5.00,5.00,5.00,5.00,5.00,5.00,5.00,5.00"
					( Origin gBackEnd )
				)
				( attribute "SN_TESTPIN_TO_THRUPIN_SPACING" "5.00,5.00,5.00,5.00,5.00,5.00,5.00,5.00,5.00,5.00,5.00,5.00,5.00,5.00"
					( Origin gBackEnd )
				)
				( attribute "SN_THRUPIN_TO_THRUVIA_SPACING" "5.00,5.00,5.00,5.00,5.00,5.00,5.00,5.00,5.00,5.00,5.00,5.00,5.00,5.00"
					( Origin gBackEnd )
				)
				( attribute "SN_TESTVIA_TO_THRUPIN_SPACING" "5.00,5.00,5.00,5.00,5.00,5.00,5.00,5.00,5.00,5.00,5.00,5.00,5.00,5.00"
					( Origin gBackEnd )
				)
				( attribute "SN_BBV_TO_THRUPIN_SPACING" "5.00,5.00,5.00,5.00,5.00,5.00,5.00,5.00,5.00,5.00,5.00,5.00,5.00,5.00"
					( Origin gBackEnd )
				)
				( attribute "SN_THRUPIN_TO_BONDPAD_SPACING" "5.00,5.00,5.00,5.00,5.00,5.00,5.00,5.00,5.00,5.00,5.00,5.00,5.00,5.00"
					( Origin gBackEnd )
				)
				( attribute "SN_LINE_TO_THRUPIN_SPACING" "5.00,5.00,5.00,5.00,5.00,5.00,5.00,5.00,5.00,5.00,5.00,5.00,5.00,5.00"
					( Origin gBackEnd )
				)
				( attribute "SN_THRUPIN_TO_SHAPE_SPACING" "5.00,5.00,5.00,5.00,5.00,5.00,5.00,5.00,5.00,5.00,5.00,5.00,5.00,5.00"
					( Origin gBackEnd )
				)
				( attribute "SN_SMDPIN_TO_SMDPIN_SPACING" "5.00,5.00,5.00,5.00,5.00,5.00,5.00,5.00,5.00,5.00,5.00,5.00,5.00,5.00"
					( Origin gBackEnd )
				)
				( attribute "SN_SMDPIN_TO_TESTPIN_SPACING" "5.00,5.00,5.00,5.00,5.00,5.00,5.00,5.00,5.00,5.00,5.00,5.00,5.00,5.00"
					( Origin gBackEnd )
				)
				( attribute "SN_SMDPIN_TO_THRUVIA_SPACING" "4.00,4.00,4.00,4.00,4.00,4.00,4.00,4.00,4.00,4.00,4.00,4.00,4.00,4.00"
					( Origin gBackEnd )
				)
				( attribute "SN_SMDPIN_TO_TESTVIA_SPACING" "4.00,4.00,4.00,4.00,4.00,4.00,4.00,4.00,4.00,4.00,4.00,4.00,4.00,4.00"
					( Origin gBackEnd )
				)
				( attribute "SN_BBV_TO_SMDPIN_SPACING" "5.00,5.00,5.00,5.00,5.00,5.00,5.00,5.00,5.00,5.00,5.00,5.00,5.00,5.00"
					( Origin gBackEnd )
				)
				( attribute "SN_SMDPIN_TO_BONDPAD_SPACING" "5.00,5.00,5.00,5.00,5.00,5.00,5.00,5.00,5.00,5.00,5.00,5.00,5.00,5.00"
					( Origin gBackEnd )
				)
				( attribute "SN_LINE_TO_SMDPIN_SPACING" "4.50,4.50,4.50,4.50,4.50,4.50,4.50,4.50,4.50,4.50,4.50,4.50,4.50,4.50"
					( Origin gBackEnd )
				)
				( attribute "SN_SHAPE_TO_SMDPIN_SPACING" "5.00,5.00,5.00,5.00,5.00,5.00,5.00,5.00,5.00,5.00,5.00,5.00,5.00,5.00"
					( Origin gBackEnd )
				)
				( attribute "SN_TESTPIN_TO_TESTPIN_SPACING" "5.00,5.00,5.00,5.00,5.00,5.00,5.00,5.00,5.00,5.00,5.00,5.00,5.00,5.00"
					( Origin gBackEnd )
				)
				( attribute "SN_TESTPIN_TO_THRUVIA_SPACING" "5.00,5.00,5.00,5.00,5.00,5.00,5.00,5.00,5.00,5.00,5.00,5.00,5.00,5.00"
					( Origin gBackEnd )
				)
				( attribute "SN_TESTPIN_TO_TESTVIA_SPACING" "5.00,5.00,5.00,5.00,5.00,5.00,5.00,5.00,5.00,5.00,5.00,5.00,5.00,5.00"
					( Origin gBackEnd )
				)
				( attribute "SN_BBV_TO_TESTPIN_SPACING" "5.00,5.00,5.00,5.00,5.00,5.00,5.00,5.00,5.00,5.00,5.00,5.00,5.00,5.00"
					( Origin gBackEnd )
				)
				( attribute "SN_BONDPAD_TO_TESTPIN_SPACING" "5.00,5.00,5.00,5.00,5.00,5.00,5.00,5.00,5.00,5.00,5.00,5.00,5.00,5.00"
					( Origin gBackEnd )
				)
				( attribute "SN_LINE_TO_TESTPIN_SPACING" "5.00,5.00,5.00,5.00,5.00,5.00,5.00,5.00,5.00,5.00,5.00,5.00,5.00,5.00"
					( Origin gBackEnd )
				)
				( attribute "SN_SHAPE_TO_TESTPIN_SPACING" "5.00,5.00,5.00,5.00,5.00,5.00,5.00,5.00,5.00,5.00,5.00,5.00,5.00,5.00"
					( Origin gBackEnd )
				)
				( attribute "SN_THRUVIA_TO_THRUVIA_SPACING" "4.50,4.00,4.00,4.00,4.00,4.00,4.00,4.00,4.00,4.00,4.00,4.00,4.00,4.50"
					( Origin gBackEnd )
				)
				( attribute "SN_TESTVIA_TO_THRUVIA_SPACING" "5.00,5.00,5.00,5.00,5.00,5.00,5.00,5.00,5.00,5.00,5.00,5.00,5.00,5.00"
					( Origin gBackEnd )
				)
				( attribute "SN_BBV_TO_THRUVIA_SPACING" "5.00,5.00,5.00,5.00,5.00,5.00,5.00,5.00,5.00,5.00,5.00,5.00,5.00,5.00"
					( Origin gBackEnd )
				)
				( attribute "SN_BONDPAD_TO_THRUVIA_SPACING" "5.00,5.00,5.00,5.00,5.00,5.00,5.00,5.00,5.00,5.00,5.00,5.00,5.00,5.00"
					( Origin gBackEnd )
				)
				( attribute "SN_LINE_TO_THRUVIA_SPACING" "4.50,4.00,4.00,4.00,4.00,4.00,4.00,4.00,4.00,4.00,4.00,4.00,4.00,4.50"
					( Origin gBackEnd )
				)
				( attribute "SN_SHAPE_TO_THRUVIA_SPACING" "5.00,5.00,5.00,5.00,5.00,5.00,5.00,5.00,5.00,5.00,5.00,5.00,5.00,5.00"
					( Origin gBackEnd )
				)
				( attribute "SN_TESTVIA_TO_TESTVIA_SPACING" "5.00,5.00,5.00,5.00,5.00,5.00,5.00,5.00,5.00,5.00,5.00,5.00,5.00,5.00"
					( Origin gBackEnd )
				)
				( attribute "SN_BBV_TO_TESTVIA_SPACING" "5.00,5.00,5.00,5.00,5.00,5.00,5.00,5.00,5.00,5.00,5.00,5.00,5.00,5.00"
					( Origin gBackEnd )
				)
				( attribute "SN_BONDPAD_TO_TESTVIA_SPACING" "5.00,5.00,5.00,5.00,5.00,5.00,5.00,5.00,5.00,5.00,5.00,5.00,5.00,5.00"
					( Origin gBackEnd )
				)
				( attribute "SN_LINE_TO_TESTVIA_SPACING" "5.00,5.00,5.00,5.00,5.00,5.00,5.00,5.00,5.00,5.00,5.00,5.00,5.00,5.00"
					( Origin gBackEnd )
				)
				( attribute "SN_SHAPE_TO_TESTVIA_SPACING" "5.00,5.00,5.00,5.00,5.00,5.00,5.00,5.00,5.00,5.00,5.00,5.00,5.00,5.00"
					( Origin gBackEnd )
				)
				( attribute "SN_BBV_TO_BBV_SPACING" "5.00,5.00,5.00,5.00,5.00,5.00,5.00,5.00,5.00,5.00,5.00,5.00,5.00,5.00"
					( Origin gBackEnd )
				)
				( attribute "SN_BONDPAD_TO_BBV_SPACING" "5.00,5.00,5.00,5.00,5.00,5.00,5.00,5.00,5.00,5.00,5.00,5.00,5.00,5.00"
					( Origin gBackEnd )
				)
				( attribute "SN_BBV_TO_LINE_SPACING" "5.00,5.00,5.00,5.00,5.00,5.00,5.00,5.00,5.00,5.00,5.00,5.00,5.00,5.00"
					( Origin gBackEnd )
				)
				( attribute "SN_BBV_TO_SHAPE_SPACING" "5.00,5.00,5.00,5.00,5.00,5.00,5.00,5.00,5.00,5.00,5.00,5.00,5.00,5.00"
					( Origin gBackEnd )
				)
				( attribute "SN_BONDPAD_TO_BONDPAD_SPACING" "5.00,5.00,5.00,5.00,5.00,5.00,5.00,5.00,5.00,5.00,5.00,5.00,5.00,5.00"
					( Origin gBackEnd )
				)
				( attribute "SN_BONDPAD_TO_LINE_SPACING" "5.00,5.00,5.00,5.00,5.00,5.00,5.00,5.00,5.00,5.00,5.00,5.00,5.00,5.00"
					( Origin gBackEnd )
				)
				( attribute "SN_BONDPAD_TO_SHAPE_SPACING" "5.00,5.00,5.00,5.00,5.00,5.00,5.00,5.00,5.00,5.00,5.00,5.00,5.00,5.00"
					( Origin gBackEnd )
				)
				( attribute "SN_LINE_TO_LINE_SPACING" "10.80,12.00,12.00,12.00,12.00,12.00,12.00,12.00,12.00,12.00,12.00,12.00,12.00,10.80"
					( Origin gBackEnd )
				)
				( attribute "SN_LINE_TO_SHAPE_SPACING" "5.00,5.00,5.00,5.00,5.00,5.00,5.00,5.00,5.00,5.00,5.00,5.00,5.00,5.00"
					( Origin gBackEnd )
				)
				( attribute "SN_SHAPE_TO_SHAPE_SPACING" "5.00,5.00,5.00,5.00,5.00,5.00,5.00,5.00,5.00,5.00,5.00,5.00,5.00,5.00"
					( Origin gBackEnd )
				)
				( attribute "SN_HOLE_TO_PIN_SPACING" "8.00,8.00,8.00,8.00,8.00,8.00,8.00,8.00,8.00,8.00,8.00,8.00,8.00,8.00"
					( Origin gBackEnd )
				)
				( attribute "SN_HOLE_TO_VIA_SPACING" "8.00,8.00,8.00,8.00,8.00,8.00,8.00,8.00,8.00,8.00,8.00,8.00,8.00,8.00"
					( Origin gBackEnd )
				)
				( attribute "SN_HOLE_TO_LINE_SPACING" "8.00,8.00,8.00,8.00,8.00,8.00,8.00,8.00,8.00,8.00,8.00,8.00,8.00,8.00"
					( Origin gBackEnd )
				)
				( attribute "SN_HOLE_TO_SHAPE_SPACING" "8.00,8.00,8.00,8.00,8.00,8.00,8.00,8.00,8.00,8.00,8.00,8.00,8.00,8.00"
					( Origin gBackEnd )
				)
				( attribute "SN_HOLE_TO_HOLE_SPACING" "8.00,8.00,8.00,8.00,8.00,8.00,8.00,8.00,8.00,8.00,8.00,8.00,8.00,8.00"
					( Origin gBackEnd )
				)
				( attribute "SN_MVIA_TO_MVIA_SPACING" "5.00,5.00,5.00,5.00,5.00,5.00,5.00,5.00,5.00,5.00,5.00,5.00,5.00,5.00"
					( Origin gBackEnd )
				)
				( attribute "SN_MVIA_TO_THRUPIN_SPACING" "5.00,5.00,5.00,5.00,5.00,5.00,5.00,5.00,5.00,5.00,5.00,5.00,5.00,5.00"
					( Origin gBackEnd )
				)
				( attribute "SN_MVIA_TO_SMDPIN_SPACING" "5.00,5.00,5.00,5.00,5.00,5.00,5.00,5.00,5.00,5.00,5.00,5.00,5.00,5.00"
					( Origin gBackEnd )
				)
				( attribute "SN_MVIA_TO_THRUVIA_SPACING" "5.00,5.00,5.00,5.00,5.00,5.00,5.00,5.00,5.00,5.00,5.00,5.00,5.00,5.00"
					( Origin gBackEnd )
				)
				( attribute "SN_MVIA_TO_BBV_SPACING" "5.00,5.00,5.00,5.00,5.00,5.00,5.00,5.00,5.00,5.00,5.00,5.00,5.00,5.00"
					( Origin gBackEnd )
				)
				( attribute "SN_MVIA_TO_LINE_SPACING" "5.00,5.00,5.00,5.00,5.00,5.00,5.00,5.00,5.00,5.00,5.00,5.00,5.00,5.00"
					( Origin gBackEnd )
				)
				( attribute "SN_MVIA_TO_SHAPE_SPACING" "5.00,5.00,5.00,5.00,5.00,5.00,5.00,5.00,5.00,5.00,5.00,5.00,5.00,5.00"
					( Origin gBackEnd )
				)
				( attribute "SN_MVIA_TO_TESTPIN_SPACING" "5.00,5.00,5.00,5.00,5.00,5.00,5.00,5.00,5.00,5.00,5.00,5.00,5.00,5.00"
					( Origin gBackEnd )
				)
				( attribute "SN_MVIA_TO_TESTVIA_SPACING" "5.00,5.00,5.00,5.00,5.00,5.00,5.00,5.00,5.00,5.00,5.00,5.00,5.00,5.00"
					( Origin gBackEnd )
				)
				( attribute "SN_BONDPAD_TO_MVIA_SPACING" "5.00,5.00,5.00,5.00,5.00,5.00,5.00,5.00,5.00,5.00,5.00,5.00,5.00,5.00"
					( Origin gBackEnd )
				)
				( objectStatus "4H" )
			)
			( sameNetSpacingCSet "@crescent_city_bb_fab1_lib.crescent_city_bb_fab1(sch_1):\5_MILS\"
				( attribute "SAME_NET" "TRUE,TRUE,TRUE,TRUE,TRUE,TRUE,TRUE,TRUE,TRUE,TRUE,TRUE,TRUE,TRUE,TRUE"
					( Origin gBackEnd )
				)
				( attribute "SN_THRUPIN_TO_THRUPIN_SPACING" "5.00,5.00,5.00,5.00,5.00,5.00,5.00,5.00,5.00,5.00,5.00,5.00,5.00,5.00"
					( Origin gBackEnd )
				)
				( attribute "SN_THRUPIN_TO_SMDPIN_SPACING" "5.00,5.00,5.00,5.00,5.00,5.00,5.00,5.00,5.00,5.00,5.00,5.00,5.00,5.00"
					( Origin gBackEnd )
				)
				( attribute "SN_TESTPIN_TO_THRUPIN_SPACING" "5.00,5.00,5.00,5.00,5.00,5.00,5.00,5.00,5.00,5.00,5.00,5.00,5.00,5.00"
					( Origin gBackEnd )
				)
				( attribute "SN_THRUPIN_TO_THRUVIA_SPACING" "5.00,5.00,5.00,5.00,5.00,5.00,5.00,5.00,5.00,5.00,5.00,5.00,5.00,5.00"
					( Origin gBackEnd )
				)
				( attribute "SN_TESTVIA_TO_THRUPIN_SPACING" "5.00,5.00,5.00,5.00,5.00,5.00,5.00,5.00,5.00,5.00,5.00,5.00,5.00,5.00"
					( Origin gBackEnd )
				)
				( attribute "SN_BBV_TO_THRUPIN_SPACING" "5.00,5.00,5.00,5.00,5.00,5.00,5.00,5.00,5.00,5.00,5.00,5.00,5.00,5.00"
					( Origin gBackEnd )
				)
				( attribute "SN_THRUPIN_TO_BONDPAD_SPACING" "5.00,5.00,5.00,5.00,5.00,5.00,5.00,5.00,5.00,5.00,5.00,5.00,5.00,5.00"
					( Origin gBackEnd )
				)
				( attribute "SN_LINE_TO_THRUPIN_SPACING" "5.00,5.00,5.00,5.00,5.00,5.00,5.00,5.00,5.00,5.00,5.00,5.00,5.00,5.00"
					( Origin gBackEnd )
				)
				( attribute "SN_THRUPIN_TO_SHAPE_SPACING" "5.00,5.00,5.00,5.00,5.00,5.00,5.00,5.00,5.00,5.00,5.00,5.00,5.00,5.00"
					( Origin gBackEnd )
				)
				( attribute "SN_SMDPIN_TO_SMDPIN_SPACING" "5.00,5.00,5.00,5.00,5.00,5.00,5.00,5.00,5.00,5.00,5.00,5.00,5.00,5.00"
					( Origin gBackEnd )
				)
				( attribute "SN_SMDPIN_TO_TESTPIN_SPACING" "5.00,5.00,5.00,5.00,5.00,5.00,5.00,5.00,5.00,5.00,5.00,5.00,5.00,5.00"
					( Origin gBackEnd )
				)
				( attribute "SN_SMDPIN_TO_THRUVIA_SPACING" "4.00,4.00,4.00,4.00,4.00,4.00,4.00,4.00,4.00,4.00,4.00,4.00,4.00,4.00"
					( Origin gBackEnd )
				)
				( attribute "SN_SMDPIN_TO_TESTVIA_SPACING" "4.00,4.00,4.00,4.00,4.00,4.00,4.00,4.00,4.00,4.00,4.00,4.00,4.00,4.00"
					( Origin gBackEnd )
				)
				( attribute "SN_BBV_TO_SMDPIN_SPACING" "5.00,5.00,5.00,5.00,5.00,5.00,5.00,5.00,5.00,5.00,5.00,5.00,5.00,5.00"
					( Origin gBackEnd )
				)
				( attribute "SN_SMDPIN_TO_BONDPAD_SPACING" "5.00,5.00,5.00,5.00,5.00,5.00,5.00,5.00,5.00,5.00,5.00,5.00,5.00,5.00"
					( Origin gBackEnd )
				)
				( attribute "SN_LINE_TO_SMDPIN_SPACING" "4.50,4.50,4.50,4.50,4.50,4.50,4.50,4.50,4.50,4.50,4.50,4.50,4.50,4.50"
					( Origin gBackEnd )
				)
				( attribute "SN_SHAPE_TO_SMDPIN_SPACING" "5.00,5.00,5.00,5.00,5.00,5.00,5.00,5.00,5.00,5.00,5.00,5.00,5.00,5.00"
					( Origin gBackEnd )
				)
				( attribute "SN_TESTPIN_TO_TESTPIN_SPACING" "5.00,5.00,5.00,5.00,5.00,5.00,5.00,5.00,5.00,5.00,5.00,5.00,5.00,5.00"
					( Origin gBackEnd )
				)
				( attribute "SN_TESTPIN_TO_THRUVIA_SPACING" "5.00,5.00,5.00,5.00,5.00,5.00,5.00,5.00,5.00,5.00,5.00,5.00,5.00,5.00"
					( Origin gBackEnd )
				)
				( attribute "SN_TESTPIN_TO_TESTVIA_SPACING" "5.00,5.00,5.00,5.00,5.00,5.00,5.00,5.00,5.00,5.00,5.00,5.00,5.00,5.00"
					( Origin gBackEnd )
				)
				( attribute "SN_BBV_TO_TESTPIN_SPACING" "5.00,5.00,5.00,5.00,5.00,5.00,5.00,5.00,5.00,5.00,5.00,5.00,5.00,5.00"
					( Origin gBackEnd )
				)
				( attribute "SN_BONDPAD_TO_TESTPIN_SPACING" "5.00,5.00,5.00,5.00,5.00,5.00,5.00,5.00,5.00,5.00,5.00,5.00,5.00,5.00"
					( Origin gBackEnd )
				)
				( attribute "SN_LINE_TO_TESTPIN_SPACING" "5.00,5.00,5.00,5.00,5.00,5.00,5.00,5.00,5.00,5.00,5.00,5.00,5.00,5.00"
					( Origin gBackEnd )
				)
				( attribute "SN_SHAPE_TO_TESTPIN_SPACING" "5.00,5.00,5.00,5.00,5.00,5.00,5.00,5.00,5.00,5.00,5.00,5.00,5.00,5.00"
					( Origin gBackEnd )
				)
				( attribute "SN_THRUVIA_TO_THRUVIA_SPACING" "4.50,4.00,4.00,4.00,4.00,4.00,4.00,4.00,4.00,4.00,4.00,4.00,4.00,4.50"
					( Origin gBackEnd )
				)
				( attribute "SN_TESTVIA_TO_THRUVIA_SPACING" "5.00,5.00,5.00,5.00,5.00,5.00,5.00,5.00,5.00,5.00,5.00,5.00,5.00,5.00"
					( Origin gBackEnd )
				)
				( attribute "SN_BBV_TO_THRUVIA_SPACING" "5.00,5.00,5.00,5.00,5.00,5.00,5.00,5.00,5.00,5.00,5.00,5.00,5.00,5.00"
					( Origin gBackEnd )
				)
				( attribute "SN_BONDPAD_TO_THRUVIA_SPACING" "5.00,5.00,5.00,5.00,5.00,5.00,5.00,5.00,5.00,5.00,5.00,5.00,5.00,5.00"
					( Origin gBackEnd )
				)
				( attribute "SN_LINE_TO_THRUVIA_SPACING" "4.50,4.00,4.00,4.00,4.00,4.00,4.00,4.00,4.00,4.00,4.00,4.00,4.00,4.50"
					( Origin gBackEnd )
				)
				( attribute "SN_SHAPE_TO_THRUVIA_SPACING" "5.00,5.00,5.00,5.00,5.00,5.00,5.00,5.00,5.00,5.00,5.00,5.00,5.00,5.00"
					( Origin gBackEnd )
				)
				( attribute "SN_TESTVIA_TO_TESTVIA_SPACING" "5.00,5.00,5.00,5.00,5.00,5.00,5.00,5.00,5.00,5.00,5.00,5.00,5.00,5.00"
					( Origin gBackEnd )
				)
				( attribute "SN_BBV_TO_TESTVIA_SPACING" "5.00,5.00,5.00,5.00,5.00,5.00,5.00,5.00,5.00,5.00,5.00,5.00,5.00,5.00"
					( Origin gBackEnd )
				)
				( attribute "SN_BONDPAD_TO_TESTVIA_SPACING" "5.00,5.00,5.00,5.00,5.00,5.00,5.00,5.00,5.00,5.00,5.00,5.00,5.00,5.00"
					( Origin gBackEnd )
				)
				( attribute "SN_LINE_TO_TESTVIA_SPACING" "5.00,5.00,5.00,5.00,5.00,5.00,5.00,5.00,5.00,5.00,5.00,5.00,5.00,5.00"
					( Origin gBackEnd )
				)
				( attribute "SN_SHAPE_TO_TESTVIA_SPACING" "5.00,5.00,5.00,5.00,5.00,5.00,5.00,5.00,5.00,5.00,5.00,5.00,5.00,5.00"
					( Origin gBackEnd )
				)
				( attribute "SN_BBV_TO_BBV_SPACING" "5.00,5.00,5.00,5.00,5.00,5.00,5.00,5.00,5.00,5.00,5.00,5.00,5.00,5.00"
					( Origin gBackEnd )
				)
				( attribute "SN_BONDPAD_TO_BBV_SPACING" "5.00,5.00,5.00,5.00,5.00,5.00,5.00,5.00,5.00,5.00,5.00,5.00,5.00,5.00"
					( Origin gBackEnd )
				)
				( attribute "SN_BBV_TO_LINE_SPACING" "5.00,5.00,5.00,5.00,5.00,5.00,5.00,5.00,5.00,5.00,5.00,5.00,5.00,5.00"
					( Origin gBackEnd )
				)
				( attribute "SN_BBV_TO_SHAPE_SPACING" "5.00,5.00,5.00,5.00,5.00,5.00,5.00,5.00,5.00,5.00,5.00,5.00,5.00,5.00"
					( Origin gBackEnd )
				)
				( attribute "SN_BONDPAD_TO_BONDPAD_SPACING" "5.00,5.00,5.00,5.00,5.00,5.00,5.00,5.00,5.00,5.00,5.00,5.00,5.00,5.00"
					( Origin gBackEnd )
				)
				( attribute "SN_BONDPAD_TO_LINE_SPACING" "5.00,5.00,5.00,5.00,5.00,5.00,5.00,5.00,5.00,5.00,5.00,5.00,5.00,5.00"
					( Origin gBackEnd )
				)
				( attribute "SN_BONDPAD_TO_SHAPE_SPACING" "5.00,5.00,5.00,5.00,5.00,5.00,5.00,5.00,5.00,5.00,5.00,5.00,5.00,5.00"
					( Origin gBackEnd )
				)
				( attribute "SN_LINE_TO_LINE_SPACING" "5.00,5.00,5.00,5.00,5.00,5.00,5.00,5.00,5.00,5.00,5.00,5.00,5.00,5.00"
					( Origin gBackEnd )
				)
				( attribute "SN_LINE_TO_SHAPE_SPACING" "5.00,5.00,5.00,5.00,5.00,5.00,5.00,5.00,5.00,5.00,5.00,5.00,5.00,5.00"
					( Origin gBackEnd )
				)
				( attribute "SN_SHAPE_TO_SHAPE_SPACING" "5.00,5.00,5.00,5.00,5.00,5.00,5.00,5.00,5.00,5.00,5.00,5.00,5.00,5.00"
					( Origin gBackEnd )
				)
				( attribute "SN_HOLE_TO_PIN_SPACING" "8.00,8.00,8.00,8.00,8.00,8.00,8.00,8.00,8.00,8.00,8.00,8.00,8.00,8.00"
					( Origin gBackEnd )
				)
				( attribute "SN_HOLE_TO_VIA_SPACING" "8.00,8.00,8.00,8.00,8.00,8.00,8.00,8.00,8.00,8.00,8.00,8.00,8.00,8.00"
					( Origin gBackEnd )
				)
				( attribute "SN_HOLE_TO_LINE_SPACING" "8.00,8.00,8.00,8.00,8.00,8.00,8.00,8.00,8.00,8.00,8.00,8.00,8.00,8.00"
					( Origin gBackEnd )
				)
				( attribute "SN_HOLE_TO_SHAPE_SPACING" "8.00,8.00,8.00,8.00,8.00,8.00,8.00,8.00,8.00,8.00,8.00,8.00,8.00,8.00"
					( Origin gBackEnd )
				)
				( attribute "SN_HOLE_TO_HOLE_SPACING" "8.00,8.00,8.00,8.00,8.00,8.00,8.00,8.00,8.00,8.00,8.00,8.00,8.00,8.00"
					( Origin gBackEnd )
				)
				( attribute "SN_MVIA_TO_MVIA_SPACING" "5.00,5.00,5.00,5.00,5.00,5.00,5.00,5.00,5.00,5.00,5.00,5.00,5.00,5.00"
					( Origin gBackEnd )
				)
				( attribute "SN_MVIA_TO_THRUPIN_SPACING" "5.00,5.00,5.00,5.00,5.00,5.00,5.00,5.00,5.00,5.00,5.00,5.00,5.00,5.00"
					( Origin gBackEnd )
				)
				( attribute "SN_MVIA_TO_SMDPIN_SPACING" "5.00,5.00,5.00,5.00,5.00,5.00,5.00,5.00,5.00,5.00,5.00,5.00,5.00,5.00"
					( Origin gBackEnd )
				)
				( attribute "SN_MVIA_TO_THRUVIA_SPACING" "5.00,5.00,5.00,5.00,5.00,5.00,5.00,5.00,5.00,5.00,5.00,5.00,5.00,5.00"
					( Origin gBackEnd )
				)
				( attribute "SN_MVIA_TO_BBV_SPACING" "5.00,5.00,5.00,5.00,5.00,5.00,5.00,5.00,5.00,5.00,5.00,5.00,5.00,5.00"
					( Origin gBackEnd )
				)
				( attribute "SN_MVIA_TO_LINE_SPACING" "5.00,5.00,5.00,5.00,5.00,5.00,5.00,5.00,5.00,5.00,5.00,5.00,5.00,5.00"
					( Origin gBackEnd )
				)
				( attribute "SN_MVIA_TO_SHAPE_SPACING" "5.00,5.00,5.00,5.00,5.00,5.00,5.00,5.00,5.00,5.00,5.00,5.00,5.00,5.00"
					( Origin gBackEnd )
				)
				( attribute "SN_MVIA_TO_TESTPIN_SPACING" "5.00,5.00,5.00,5.00,5.00,5.00,5.00,5.00,5.00,5.00,5.00,5.00,5.00,5.00"
					( Origin gBackEnd )
				)
				( attribute "SN_MVIA_TO_TESTVIA_SPACING" "5.00,5.00,5.00,5.00,5.00,5.00,5.00,5.00,5.00,5.00,5.00,5.00,5.00,5.00"
					( Origin gBackEnd )
				)
				( attribute "SN_BONDPAD_TO_MVIA_SPACING" "5.00,5.00,5.00,5.00,5.00,5.00,5.00,5.00,5.00,5.00,5.00,5.00,5.00,5.00"
					( Origin gBackEnd )
				)
				( objectStatus "5_MILS" )
			)
			( sameNetSpacingCSet "@crescent_city_bb_fab1_lib.crescent_city_bb_fab1(sch_1):\3.7H_US_AND_2H_SL\"
				( attribute "SAME_NET" "TRUE,TRUE,TRUE,TRUE,TRUE,TRUE,TRUE,TRUE,TRUE,TRUE,TRUE,TRUE,TRUE,TRUE"
					( Origin gBackEnd )
				)
				( attribute "SN_THRUPIN_TO_THRUPIN_SPACING" "5.00,5.00,5.00,5.00,5.00,5.00,5.00,5.00,5.00,5.00,5.00,5.00,5.00,5.00"
					( Origin gBackEnd )
				)
				( attribute "SN_THRUPIN_TO_SMDPIN_SPACING" "5.00,5.00,5.00,5.00,5.00,5.00,5.00,5.00,5.00,5.00,5.00,5.00,5.00,5.00"
					( Origin gBackEnd )
				)
				( attribute "SN_TESTPIN_TO_THRUPIN_SPACING" "5.00,5.00,5.00,5.00,5.00,5.00,5.00,5.00,5.00,5.00,5.00,5.00,5.00,5.00"
					( Origin gBackEnd )
				)
				( attribute "SN_THRUPIN_TO_THRUVIA_SPACING" "5.00,5.00,5.00,5.00,5.00,5.00,5.00,5.00,5.00,5.00,5.00,5.00,5.00,5.00"
					( Origin gBackEnd )
				)
				( attribute "SN_TESTVIA_TO_THRUPIN_SPACING" "5.00,5.00,5.00,5.00,5.00,5.00,5.00,5.00,5.00,5.00,5.00,5.00,5.00,5.00"
					( Origin gBackEnd )
				)
				( attribute "SN_BBV_TO_THRUPIN_SPACING" "5.00,5.00,5.00,5.00,5.00,5.00,5.00,5.00,5.00,5.00,5.00,5.00,5.00,5.00"
					( Origin gBackEnd )
				)
				( attribute "SN_THRUPIN_TO_BONDPAD_SPACING" "5.00,5.00,5.00,5.00,5.00,5.00,5.00,5.00,5.00,5.00,5.00,5.00,5.00,5.00"
					( Origin gBackEnd )
				)
				( attribute "SN_LINE_TO_THRUPIN_SPACING" "5.00,5.00,5.00,5.00,5.00,5.00,5.00,5.00,5.00,5.00,5.00,5.00,5.00,5.00"
					( Origin gBackEnd )
				)
				( attribute "SN_THRUPIN_TO_SHAPE_SPACING" "5.00,5.00,5.00,5.00,5.00,5.00,5.00,5.00,5.00,5.00,5.00,5.00,5.00,5.00"
					( Origin gBackEnd )
				)
				( attribute "SN_SMDPIN_TO_SMDPIN_SPACING" "5.00,5.00,5.00,5.00,5.00,5.00,5.00,5.00,5.00,5.00,5.00,5.00,5.00,5.00"
					( Origin gBackEnd )
				)
				( attribute "SN_SMDPIN_TO_TESTPIN_SPACING" "5.00,5.00,5.00,5.00,5.00,5.00,5.00,5.00,5.00,5.00,5.00,5.00,5.00,5.00"
					( Origin gBackEnd )
				)
				( attribute "SN_SMDPIN_TO_THRUVIA_SPACING" "4.00,4.00,4.00,4.00,4.00,4.00,4.00,4.00,4.00,4.00,4.00,4.00,4.00,4.00"
					( Origin gBackEnd )
				)
				( attribute "SN_SMDPIN_TO_TESTVIA_SPACING" "4.00,4.00,4.00,4.00,4.00,4.00,4.00,4.00,4.00,4.00,4.00,4.00,4.00,4.00"
					( Origin gBackEnd )
				)
				( attribute "SN_BBV_TO_SMDPIN_SPACING" "5.00,5.00,5.00,5.00,5.00,5.00,5.00,5.00,5.00,5.00,5.00,5.00,5.00,5.00"
					( Origin gBackEnd )
				)
				( attribute "SN_SMDPIN_TO_BONDPAD_SPACING" "5.00,5.00,5.00,5.00,5.00,5.00,5.00,5.00,5.00,5.00,5.00,5.00,5.00,5.00"
					( Origin gBackEnd )
				)
				( attribute "SN_LINE_TO_SMDPIN_SPACING" "4.50,4.50,4.50,4.50,4.50,4.50,4.50,4.50,4.50,4.50,4.50,4.50,4.50,4.50"
					( Origin gBackEnd )
				)
				( attribute "SN_SHAPE_TO_SMDPIN_SPACING" "5.00,5.00,5.00,5.00,5.00,5.00,5.00,5.00,5.00,5.00,5.00,5.00,5.00,5.00"
					( Origin gBackEnd )
				)
				( attribute "SN_TESTPIN_TO_TESTPIN_SPACING" "5.00,5.00,5.00,5.00,5.00,5.00,5.00,5.00,5.00,5.00,5.00,5.00,5.00,5.00"
					( Origin gBackEnd )
				)
				( attribute "SN_TESTPIN_TO_THRUVIA_SPACING" "5.00,5.00,5.00,5.00,5.00,5.00,5.00,5.00,5.00,5.00,5.00,5.00,5.00,5.00"
					( Origin gBackEnd )
				)
				( attribute "SN_TESTPIN_TO_TESTVIA_SPACING" "5.00,5.00,5.00,5.00,5.00,5.00,5.00,5.00,5.00,5.00,5.00,5.00,5.00,5.00"
					( Origin gBackEnd )
				)
				( attribute "SN_BBV_TO_TESTPIN_SPACING" "5.00,5.00,5.00,5.00,5.00,5.00,5.00,5.00,5.00,5.00,5.00,5.00,5.00,5.00"
					( Origin gBackEnd )
				)
				( attribute "SN_BONDPAD_TO_TESTPIN_SPACING" "5.00,5.00,5.00,5.00,5.00,5.00,5.00,5.00,5.00,5.00,5.00,5.00,5.00,5.00"
					( Origin gBackEnd )
				)
				( attribute "SN_LINE_TO_TESTPIN_SPACING" "5.00,5.00,5.00,5.00,5.00,5.00,5.00,5.00,5.00,5.00,5.00,5.00,5.00,5.00"
					( Origin gBackEnd )
				)
				( attribute "SN_SHAPE_TO_TESTPIN_SPACING" "5.00,5.00,5.00,5.00,5.00,5.00,5.00,5.00,5.00,5.00,5.00,5.00,5.00,5.00"
					( Origin gBackEnd )
				)
				( attribute "SN_THRUVIA_TO_THRUVIA_SPACING" "4.50,4.00,4.00,4.00,4.00,4.00,4.00,4.00,4.00,4.00,4.00,4.00,4.00,4.50"
					( Origin gBackEnd )
				)
				( attribute "SN_TESTVIA_TO_THRUVIA_SPACING" "5.00,5.00,5.00,5.00,5.00,5.00,5.00,5.00,5.00,5.00,5.00,5.00,5.00,5.00"
					( Origin gBackEnd )
				)
				( attribute "SN_BBV_TO_THRUVIA_SPACING" "5.00,5.00,5.00,5.00,5.00,5.00,5.00,5.00,5.00,5.00,5.00,5.00,5.00,5.00"
					( Origin gBackEnd )
				)
				( attribute "SN_BONDPAD_TO_THRUVIA_SPACING" "5.00,5.00,5.00,5.00,5.00,5.00,5.00,5.00,5.00,5.00,5.00,5.00,5.00,5.00"
					( Origin gBackEnd )
				)
				( attribute "SN_LINE_TO_THRUVIA_SPACING" "4.50,4.00,4.00,4.00,4.00,4.00,4.00,4.00,4.00,4.00,4.00,4.00,4.00,4.50"
					( Origin gBackEnd )
				)
				( attribute "SN_SHAPE_TO_THRUVIA_SPACING" "5.00,5.00,5.00,5.00,5.00,5.00,5.00,5.00,5.00,5.00,5.00,5.00,5.00,5.00"
					( Origin gBackEnd )
				)
				( attribute "SN_TESTVIA_TO_TESTVIA_SPACING" "5.00,5.00,5.00,5.00,5.00,5.00,5.00,5.00,5.00,5.00,5.00,5.00,5.00,5.00"
					( Origin gBackEnd )
				)
				( attribute "SN_BBV_TO_TESTVIA_SPACING" "5.00,5.00,5.00,5.00,5.00,5.00,5.00,5.00,5.00,5.00,5.00,5.00,5.00,5.00"
					( Origin gBackEnd )
				)
				( attribute "SN_BONDPAD_TO_TESTVIA_SPACING" "5.00,5.00,5.00,5.00,5.00,5.00,5.00,5.00,5.00,5.00,5.00,5.00,5.00,5.00"
					( Origin gBackEnd )
				)
				( attribute "SN_LINE_TO_TESTVIA_SPACING" "5.00,5.00,5.00,5.00,5.00,5.00,5.00,5.00,5.00,5.00,5.00,5.00,5.00,5.00"
					( Origin gBackEnd )
				)
				( attribute "SN_SHAPE_TO_TESTVIA_SPACING" "5.00,5.00,5.00,5.00,5.00,5.00,5.00,5.00,5.00,5.00,5.00,5.00,5.00,5.00"
					( Origin gBackEnd )
				)
				( attribute "SN_BBV_TO_BBV_SPACING" "5.00,5.00,5.00,5.00,5.00,5.00,5.00,5.00,5.00,5.00,5.00,5.00,5.00,5.00"
					( Origin gBackEnd )
				)
				( attribute "SN_BONDPAD_TO_BBV_SPACING" "5.00,5.00,5.00,5.00,5.00,5.00,5.00,5.00,5.00,5.00,5.00,5.00,5.00,5.00"
					( Origin gBackEnd )
				)
				( attribute "SN_BBV_TO_LINE_SPACING" "5.00,5.00,5.00,5.00,5.00,5.00,5.00,5.00,5.00,5.00,5.00,5.00,5.00,5.00"
					( Origin gBackEnd )
				)
				( attribute "SN_BBV_TO_SHAPE_SPACING" "5.00,5.00,5.00,5.00,5.00,5.00,5.00,5.00,5.00,5.00,5.00,5.00,5.00,5.00"
					( Origin gBackEnd )
				)
				( attribute "SN_BONDPAD_TO_BONDPAD_SPACING" "5.00,5.00,5.00,5.00,5.00,5.00,5.00,5.00,5.00,5.00,5.00,5.00,5.00,5.00"
					( Origin gBackEnd )
				)
				( attribute "SN_BONDPAD_TO_LINE_SPACING" "5.00,5.00,5.00,5.00,5.00,5.00,5.00,5.00,5.00,5.00,5.00,5.00,5.00,5.00"
					( Origin gBackEnd )
				)
				( attribute "SN_BONDPAD_TO_SHAPE_SPACING" "5.00,5.00,5.00,5.00,5.00,5.00,5.00,5.00,5.00,5.00,5.00,5.00,5.00,5.00"
					( Origin gBackEnd )
				)
				( attribute "SN_LINE_TO_LINE_SPACING" "10.00,6.00,6.00,6.00,6.00,6.00,6.00,6.00,6.00,6.00,6.00,6.00,6.00,10.00"
					( Origin gBackEnd )
				)
				( attribute "SN_LINE_TO_SHAPE_SPACING" "5.00,5.00,5.00,5.00,5.00,5.00,5.00,5.00,5.00,5.00,5.00,5.00,5.00,5.00"
					( Origin gBackEnd )
				)
				( attribute "SN_SHAPE_TO_SHAPE_SPACING" "5.00,5.00,5.00,5.00,5.00,5.00,5.00,5.00,5.00,5.00,5.00,5.00,5.00,5.00"
					( Origin gBackEnd )
				)
				( attribute "SN_HOLE_TO_PIN_SPACING" "8.00,8.00,8.00,8.00,8.00,8.00,8.00,8.00,8.00,8.00,8.00,8.00,8.00,8.00"
					( Origin gBackEnd )
				)
				( attribute "SN_HOLE_TO_VIA_SPACING" "8.00,8.00,8.00,8.00,8.00,8.00,8.00,8.00,8.00,8.00,8.00,8.00,8.00,8.00"
					( Origin gBackEnd )
				)
				( attribute "SN_HOLE_TO_LINE_SPACING" "8.00,8.00,8.00,8.00,8.00,8.00,8.00,8.00,8.00,8.00,8.00,8.00,8.00,8.00"
					( Origin gBackEnd )
				)
				( attribute "SN_HOLE_TO_SHAPE_SPACING" "8.00,8.00,8.00,8.00,8.00,8.00,8.00,8.00,8.00,8.00,8.00,8.00,8.00,8.00"
					( Origin gBackEnd )
				)
				( attribute "SN_HOLE_TO_HOLE_SPACING" "8.00,8.00,8.00,8.00,8.00,8.00,8.00,8.00,8.00,8.00,8.00,8.00,8.00,8.00"
					( Origin gBackEnd )
				)
				( attribute "SN_MVIA_TO_MVIA_SPACING" "5.00,5.00,5.00,5.00,5.00,5.00,5.00,5.00,5.00,5.00,5.00,5.00,5.00,5.00"
					( Origin gBackEnd )
				)
				( attribute "SN_MVIA_TO_THRUPIN_SPACING" "5.00,5.00,5.00,5.00,5.00,5.00,5.00,5.00,5.00,5.00,5.00,5.00,5.00,5.00"
					( Origin gBackEnd )
				)
				( attribute "SN_MVIA_TO_SMDPIN_SPACING" "5.00,5.00,5.00,5.00,5.00,5.00,5.00,5.00,5.00,5.00,5.00,5.00,5.00,5.00"
					( Origin gBackEnd )
				)
				( attribute "SN_MVIA_TO_THRUVIA_SPACING" "5.00,5.00,5.00,5.00,5.00,5.00,5.00,5.00,5.00,5.00,5.00,5.00,5.00,5.00"
					( Origin gBackEnd )
				)
				( attribute "SN_MVIA_TO_BBV_SPACING" "5.00,5.00,5.00,5.00,5.00,5.00,5.00,5.00,5.00,5.00,5.00,5.00,5.00,5.00"
					( Origin gBackEnd )
				)
				( attribute "SN_MVIA_TO_LINE_SPACING" "5.00,5.00,5.00,5.00,5.00,5.00,5.00,5.00,5.00,5.00,5.00,5.00,5.00,5.00"
					( Origin gBackEnd )
				)
				( attribute "SN_MVIA_TO_SHAPE_SPACING" "5.00,5.00,5.00,5.00,5.00,5.00,5.00,5.00,5.00,5.00,5.00,5.00,5.00,5.00"
					( Origin gBackEnd )
				)
				( attribute "SN_MVIA_TO_TESTPIN_SPACING" "5.00,5.00,5.00,5.00,5.00,5.00,5.00,5.00,5.00,5.00,5.00,5.00,5.00,5.00"
					( Origin gBackEnd )
				)
				( attribute "SN_MVIA_TO_TESTVIA_SPACING" "5.00,5.00,5.00,5.00,5.00,5.00,5.00,5.00,5.00,5.00,5.00,5.00,5.00,5.00"
					( Origin gBackEnd )
				)
				( attribute "SN_BONDPAD_TO_MVIA_SPACING" "5.00,5.00,5.00,5.00,5.00,5.00,5.00,5.00,5.00,5.00,5.00,5.00,5.00,5.00"
					( Origin gBackEnd )
				)
				( objectStatus "3.7H_US_&_2H_SL" )
			)
			( sameNetSpacingCSet "@crescent_city_bb_fab1_lib.crescent_city_bb_fab1(sch_1):\25_MILS\"
				( attribute "SAME_NET" "TRUE,TRUE,TRUE,TRUE,TRUE,TRUE,TRUE,TRUE,TRUE,TRUE,TRUE,TRUE,TRUE,TRUE"
					( Origin gBackEnd )
				)
				( attribute "SN_THRUPIN_TO_THRUPIN_SPACING" "5.00,5.00,5.00,5.00,5.00,5.00,5.00,5.00,5.00,5.00,5.00,5.00,5.00,5.00"
					( Origin gBackEnd )
				)
				( attribute "SN_THRUPIN_TO_SMDPIN_SPACING" "5.00,5.00,5.00,5.00,5.00,5.00,5.00,5.00,5.00,5.00,5.00,5.00,5.00,5.00"
					( Origin gBackEnd )
				)
				( attribute "SN_TESTPIN_TO_THRUPIN_SPACING" "5.00,5.00,5.00,5.00,5.00,5.00,5.00,5.00,5.00,5.00,5.00,5.00,5.00,5.00"
					( Origin gBackEnd )
				)
				( attribute "SN_THRUPIN_TO_THRUVIA_SPACING" "5.00,5.00,5.00,5.00,5.00,5.00,5.00,5.00,5.00,5.00,5.00,5.00,5.00,5.00"
					( Origin gBackEnd )
				)
				( attribute "SN_TESTVIA_TO_THRUPIN_SPACING" "5.00,5.00,5.00,5.00,5.00,5.00,5.00,5.00,5.00,5.00,5.00,5.00,5.00,5.00"
					( Origin gBackEnd )
				)
				( attribute "SN_BBV_TO_THRUPIN_SPACING" "5.00,5.00,5.00,5.00,5.00,5.00,5.00,5.00,5.00,5.00,5.00,5.00,5.00,5.00"
					( Origin gBackEnd )
				)
				( attribute "SN_THRUPIN_TO_BONDPAD_SPACING" "5.00,5.00,5.00,5.00,5.00,5.00,5.00,5.00,5.00,5.00,5.00,5.00,5.00,5.00"
					( Origin gBackEnd )
				)
				( attribute "SN_LINE_TO_THRUPIN_SPACING" "5.00,5.00,5.00,5.00,5.00,5.00,5.00,5.00,5.00,5.00,5.00,5.00,5.00,5.00"
					( Origin gBackEnd )
				)
				( attribute "SN_THRUPIN_TO_SHAPE_SPACING" "5.00,5.00,5.00,5.00,5.00,5.00,5.00,5.00,5.00,5.00,5.00,5.00,5.00,5.00"
					( Origin gBackEnd )
				)
				( attribute "SN_SMDPIN_TO_SMDPIN_SPACING" "5.00,5.00,5.00,5.00,5.00,5.00,5.00,5.00,5.00,5.00,5.00,5.00,5.00,5.00"
					( Origin gBackEnd )
				)
				( attribute "SN_SMDPIN_TO_TESTPIN_SPACING" "5.00,5.00,5.00,5.00,5.00,5.00,5.00,5.00,5.00,5.00,5.00,5.00,5.00,5.00"
					( Origin gBackEnd )
				)
				( attribute "SN_SMDPIN_TO_THRUVIA_SPACING" "4.00,4.00,4.00,4.00,4.00,4.00,4.00,4.00,4.00,4.00,4.00,4.00,4.00,4.00"
					( Origin gBackEnd )
				)
				( attribute "SN_SMDPIN_TO_TESTVIA_SPACING" "4.00,4.00,4.00,4.00,4.00,4.00,4.00,4.00,4.00,4.00,4.00,4.00,4.00,4.00"
					( Origin gBackEnd )
				)
				( attribute "SN_BBV_TO_SMDPIN_SPACING" "5.00,5.00,5.00,5.00,5.00,5.00,5.00,5.00,5.00,5.00,5.00,5.00,5.00,5.00"
					( Origin gBackEnd )
				)
				( attribute "SN_SMDPIN_TO_BONDPAD_SPACING" "5.00,5.00,5.00,5.00,5.00,5.00,5.00,5.00,5.00,5.00,5.00,5.00,5.00,5.00"
					( Origin gBackEnd )
				)
				( attribute "SN_LINE_TO_SMDPIN_SPACING" "4.50,4.50,4.50,4.50,4.50,4.50,4.50,4.50,4.50,4.50,4.50,4.50,4.50,4.50"
					( Origin gBackEnd )
				)
				( attribute "SN_SHAPE_TO_SMDPIN_SPACING" "5.00,5.00,5.00,5.00,5.00,5.00,5.00,5.00,5.00,5.00,5.00,5.00,5.00,5.00"
					( Origin gBackEnd )
				)
				( attribute "SN_TESTPIN_TO_TESTPIN_SPACING" "5.00,5.00,5.00,5.00,5.00,5.00,5.00,5.00,5.00,5.00,5.00,5.00,5.00,5.00"
					( Origin gBackEnd )
				)
				( attribute "SN_TESTPIN_TO_THRUVIA_SPACING" "5.00,5.00,5.00,5.00,5.00,5.00,5.00,5.00,5.00,5.00,5.00,5.00,5.00,5.00"
					( Origin gBackEnd )
				)
				( attribute "SN_TESTPIN_TO_TESTVIA_SPACING" "5.00,5.00,5.00,5.00,5.00,5.00,5.00,5.00,5.00,5.00,5.00,5.00,5.00,5.00"
					( Origin gBackEnd )
				)
				( attribute "SN_BBV_TO_TESTPIN_SPACING" "5.00,5.00,5.00,5.00,5.00,5.00,5.00,5.00,5.00,5.00,5.00,5.00,5.00,5.00"
					( Origin gBackEnd )
				)
				( attribute "SN_BONDPAD_TO_TESTPIN_SPACING" "5.00,5.00,5.00,5.00,5.00,5.00,5.00,5.00,5.00,5.00,5.00,5.00,5.00,5.00"
					( Origin gBackEnd )
				)
				( attribute "SN_LINE_TO_TESTPIN_SPACING" "5.00,5.00,5.00,5.00,5.00,5.00,5.00,5.00,5.00,5.00,5.00,5.00,5.00,5.00"
					( Origin gBackEnd )
				)
				( attribute "SN_SHAPE_TO_TESTPIN_SPACING" "5.00,5.00,5.00,5.00,5.00,5.00,5.00,5.00,5.00,5.00,5.00,5.00,5.00,5.00"
					( Origin gBackEnd )
				)
				( attribute "SN_THRUVIA_TO_THRUVIA_SPACING" "4.50,4.00,4.00,4.00,4.00,4.00,4.00,4.00,4.00,4.00,4.00,4.00,4.00,4.50"
					( Origin gBackEnd )
				)
				( attribute "SN_TESTVIA_TO_THRUVIA_SPACING" "5.00,5.00,5.00,5.00,5.00,5.00,5.00,5.00,5.00,5.00,5.00,5.00,5.00,5.00"
					( Origin gBackEnd )
				)
				( attribute "SN_BBV_TO_THRUVIA_SPACING" "5.00,5.00,5.00,5.00,5.00,5.00,5.00,5.00,5.00,5.00,5.00,5.00,5.00,5.00"
					( Origin gBackEnd )
				)
				( attribute "SN_BONDPAD_TO_THRUVIA_SPACING" "5.00,5.00,5.00,5.00,5.00,5.00,5.00,5.00,5.00,5.00,5.00,5.00,5.00,5.00"
					( Origin gBackEnd )
				)
				( attribute "SN_LINE_TO_THRUVIA_SPACING" "4.50,4.00,4.00,4.00,4.00,4.00,4.00,4.00,4.00,4.00,4.00,4.00,4.00,4.50"
					( Origin gBackEnd )
				)
				( attribute "SN_SHAPE_TO_THRUVIA_SPACING" "5.00,5.00,5.00,5.00,5.00,5.00,5.00,5.00,5.00,5.00,5.00,5.00,5.00,5.00"
					( Origin gBackEnd )
				)
				( attribute "SN_TESTVIA_TO_TESTVIA_SPACING" "5.00,5.00,5.00,5.00,5.00,5.00,5.00,5.00,5.00,5.00,5.00,5.00,5.00,5.00"
					( Origin gBackEnd )
				)
				( attribute "SN_BBV_TO_TESTVIA_SPACING" "5.00,5.00,5.00,5.00,5.00,5.00,5.00,5.00,5.00,5.00,5.00,5.00,5.00,5.00"
					( Origin gBackEnd )
				)
				( attribute "SN_BONDPAD_TO_TESTVIA_SPACING" "5.00,5.00,5.00,5.00,5.00,5.00,5.00,5.00,5.00,5.00,5.00,5.00,5.00,5.00"
					( Origin gBackEnd )
				)
				( attribute "SN_LINE_TO_TESTVIA_SPACING" "5.00,5.00,5.00,5.00,5.00,5.00,5.00,5.00,5.00,5.00,5.00,5.00,5.00,5.00"
					( Origin gBackEnd )
				)
				( attribute "SN_SHAPE_TO_TESTVIA_SPACING" "5.00,5.00,5.00,5.00,5.00,5.00,5.00,5.00,5.00,5.00,5.00,5.00,5.00,5.00"
					( Origin gBackEnd )
				)
				( attribute "SN_BBV_TO_BBV_SPACING" "5.00,5.00,5.00,5.00,5.00,5.00,5.00,5.00,5.00,5.00,5.00,5.00,5.00,5.00"
					( Origin gBackEnd )
				)
				( attribute "SN_BONDPAD_TO_BBV_SPACING" "5.00,5.00,5.00,5.00,5.00,5.00,5.00,5.00,5.00,5.00,5.00,5.00,5.00,5.00"
					( Origin gBackEnd )
				)
				( attribute "SN_BBV_TO_LINE_SPACING" "5.00,5.00,5.00,5.00,5.00,5.00,5.00,5.00,5.00,5.00,5.00,5.00,5.00,5.00"
					( Origin gBackEnd )
				)
				( attribute "SN_BBV_TO_SHAPE_SPACING" "5.00,5.00,5.00,5.00,5.00,5.00,5.00,5.00,5.00,5.00,5.00,5.00,5.00,5.00"
					( Origin gBackEnd )
				)
				( attribute "SN_BONDPAD_TO_BONDPAD_SPACING" "5.00,5.00,5.00,5.00,5.00,5.00,5.00,5.00,5.00,5.00,5.00,5.00,5.00,5.00"
					( Origin gBackEnd )
				)
				( attribute "SN_BONDPAD_TO_LINE_SPACING" "5.00,5.00,5.00,5.00,5.00,5.00,5.00,5.00,5.00,5.00,5.00,5.00,5.00,5.00"
					( Origin gBackEnd )
				)
				( attribute "SN_BONDPAD_TO_SHAPE_SPACING" "5.00,5.00,5.00,5.00,5.00,5.00,5.00,5.00,5.00,5.00,5.00,5.00,5.00,5.00"
					( Origin gBackEnd )
				)
				( attribute "SN_LINE_TO_LINE_SPACING" "25.00,25.00,25.00,25.00,25.00,25.00,25.00,25.00,25.00,25.00,25.00,25.00,25.00,25.00"
					( Origin gBackEnd )
				)
				( attribute "SN_LINE_TO_SHAPE_SPACING" "5.00,5.00,5.00,5.00,5.00,5.00,5.00,5.00,5.00,5.00,5.00,5.00,5.00,5.00"
					( Origin gBackEnd )
				)
				( attribute "SN_SHAPE_TO_SHAPE_SPACING" "5.00,5.00,5.00,5.00,5.00,5.00,5.00,5.00,5.00,5.00,5.00,5.00,5.00,5.00"
					( Origin gBackEnd )
				)
				( attribute "SN_HOLE_TO_PIN_SPACING" "8.00,8.00,8.00,8.00,8.00,8.00,8.00,8.00,8.00,8.00,8.00,8.00,8.00,8.00"
					( Origin gBackEnd )
				)
				( attribute "SN_HOLE_TO_VIA_SPACING" "8.00,8.00,8.00,8.00,8.00,8.00,8.00,8.00,8.00,8.00,8.00,8.00,8.00,8.00"
					( Origin gBackEnd )
				)
				( attribute "SN_HOLE_TO_LINE_SPACING" "8.00,8.00,8.00,8.00,8.00,8.00,8.00,8.00,8.00,8.00,8.00,8.00,8.00,8.00"
					( Origin gBackEnd )
				)
				( attribute "SN_HOLE_TO_SHAPE_SPACING" "8.00,8.00,8.00,8.00,8.00,8.00,8.00,8.00,8.00,8.00,8.00,8.00,8.00,8.00"
					( Origin gBackEnd )
				)
				( attribute "SN_HOLE_TO_HOLE_SPACING" "8.00,8.00,8.00,8.00,8.00,8.00,8.00,8.00,8.00,8.00,8.00,8.00,8.00,8.00"
					( Origin gBackEnd )
				)
				( attribute "SN_MVIA_TO_MVIA_SPACING" "5.00,5.00,5.00,5.00,5.00,5.00,5.00,5.00,5.00,5.00,5.00,5.00,5.00,5.00"
					( Origin gBackEnd )
				)
				( attribute "SN_MVIA_TO_THRUPIN_SPACING" "5.00,5.00,5.00,5.00,5.00,5.00,5.00,5.00,5.00,5.00,5.00,5.00,5.00,5.00"
					( Origin gBackEnd )
				)
				( attribute "SN_MVIA_TO_SMDPIN_SPACING" "5.00,5.00,5.00,5.00,5.00,5.00,5.00,5.00,5.00,5.00,5.00,5.00,5.00,5.00"
					( Origin gBackEnd )
				)
				( attribute "SN_MVIA_TO_THRUVIA_SPACING" "5.00,5.00,5.00,5.00,5.00,5.00,5.00,5.00,5.00,5.00,5.00,5.00,5.00,5.00"
					( Origin gBackEnd )
				)
				( attribute "SN_MVIA_TO_BBV_SPACING" "5.00,5.00,5.00,5.00,5.00,5.00,5.00,5.00,5.00,5.00,5.00,5.00,5.00,5.00"
					( Origin gBackEnd )
				)
				( attribute "SN_MVIA_TO_LINE_SPACING" "5.00,5.00,5.00,5.00,5.00,5.00,5.00,5.00,5.00,5.00,5.00,5.00,5.00,5.00"
					( Origin gBackEnd )
				)
				( attribute "SN_MVIA_TO_SHAPE_SPACING" "5.00,5.00,5.00,5.00,5.00,5.00,5.00,5.00,5.00,5.00,5.00,5.00,5.00,5.00"
					( Origin gBackEnd )
				)
				( attribute "SN_MVIA_TO_TESTPIN_SPACING" "5.00,5.00,5.00,5.00,5.00,5.00,5.00,5.00,5.00,5.00,5.00,5.00,5.00,5.00"
					( Origin gBackEnd )
				)
				( attribute "SN_MVIA_TO_TESTVIA_SPACING" "5.00,5.00,5.00,5.00,5.00,5.00,5.00,5.00,5.00,5.00,5.00,5.00,5.00,5.00"
					( Origin gBackEnd )
				)
				( attribute "SN_BONDPAD_TO_MVIA_SPACING" "5.00,5.00,5.00,5.00,5.00,5.00,5.00,5.00,5.00,5.00,5.00,5.00,5.00,5.00"
					( Origin gBackEnd )
				)
				( objectStatus "25_MILS" )
			)
			( sameNetSpacingCSet "@crescent_city_bb_fab1_lib.crescent_city_bb_fab1(sch_1):\12_MILS\"
				( attribute "SAME_NET" "TRUE,TRUE,TRUE,TRUE,TRUE,TRUE,TRUE,TRUE,TRUE,TRUE,TRUE,TRUE,TRUE,TRUE"
					( Origin gBackEnd )
				)
				( attribute "SN_THRUPIN_TO_THRUPIN_SPACING" "5.00,5.00,5.00,5.00,5.00,5.00,5.00,5.00,5.00,5.00,5.00,5.00,5.00,5.00"
					( Origin gBackEnd )
				)
				( attribute "SN_THRUPIN_TO_SMDPIN_SPACING" "5.00,5.00,5.00,5.00,5.00,5.00,5.00,5.00,5.00,5.00,5.00,5.00,5.00,5.00"
					( Origin gBackEnd )
				)
				( attribute "SN_TESTPIN_TO_THRUPIN_SPACING" "5.00,5.00,5.00,5.00,5.00,5.00,5.00,5.00,5.00,5.00,5.00,5.00,5.00,5.00"
					( Origin gBackEnd )
				)
				( attribute "SN_THRUPIN_TO_THRUVIA_SPACING" "5.00,5.00,5.00,5.00,5.00,5.00,5.00,5.00,5.00,5.00,5.00,5.00,5.00,5.00"
					( Origin gBackEnd )
				)
				( attribute "SN_TESTVIA_TO_THRUPIN_SPACING" "5.00,5.00,5.00,5.00,5.00,5.00,5.00,5.00,5.00,5.00,5.00,5.00,5.00,5.00"
					( Origin gBackEnd )
				)
				( attribute "SN_BBV_TO_THRUPIN_SPACING" "5.00,5.00,5.00,5.00,5.00,5.00,5.00,5.00,5.00,5.00,5.00,5.00,5.00,5.00"
					( Origin gBackEnd )
				)
				( attribute "SN_THRUPIN_TO_BONDPAD_SPACING" "5.00,5.00,5.00,5.00,5.00,5.00,5.00,5.00,5.00,5.00,5.00,5.00,5.00,5.00"
					( Origin gBackEnd )
				)
				( attribute "SN_LINE_TO_THRUPIN_SPACING" "5.00,5.00,5.00,5.00,5.00,5.00,5.00,5.00,5.00,5.00,5.00,5.00,5.00,5.00"
					( Origin gBackEnd )
				)
				( attribute "SN_THRUPIN_TO_SHAPE_SPACING" "5.00,5.00,5.00,5.00,5.00,5.00,5.00,5.00,5.00,5.00,5.00,5.00,5.00,5.00"
					( Origin gBackEnd )
				)
				( attribute "SN_SMDPIN_TO_SMDPIN_SPACING" "5.00,5.00,5.00,5.00,5.00,5.00,5.00,5.00,5.00,5.00,5.00,5.00,5.00,5.00"
					( Origin gBackEnd )
				)
				( attribute "SN_SMDPIN_TO_TESTPIN_SPACING" "5.00,5.00,5.00,5.00,5.00,5.00,5.00,5.00,5.00,5.00,5.00,5.00,5.00,5.00"
					( Origin gBackEnd )
				)
				( attribute "SN_SMDPIN_TO_THRUVIA_SPACING" "4.00,4.00,4.00,4.00,4.00,4.00,4.00,4.00,4.00,4.00,4.00,4.00,4.00,4.00"
					( Origin gBackEnd )
				)
				( attribute "SN_SMDPIN_TO_TESTVIA_SPACING" "4.00,4.00,4.00,4.00,4.00,4.00,4.00,4.00,4.00,4.00,4.00,4.00,4.00,4.00"
					( Origin gBackEnd )
				)
				( attribute "SN_BBV_TO_SMDPIN_SPACING" "5.00,5.00,5.00,5.00,5.00,5.00,5.00,5.00,5.00,5.00,5.00,5.00,5.00,5.00"
					( Origin gBackEnd )
				)
				( attribute "SN_SMDPIN_TO_BONDPAD_SPACING" "5.00,5.00,5.00,5.00,5.00,5.00,5.00,5.00,5.00,5.00,5.00,5.00,5.00,5.00"
					( Origin gBackEnd )
				)
				( attribute "SN_LINE_TO_SMDPIN_SPACING" "4.50,4.50,4.50,4.50,4.50,4.50,4.50,4.50,4.50,4.50,4.50,4.50,4.50,4.50"
					( Origin gBackEnd )
				)
				( attribute "SN_SHAPE_TO_SMDPIN_SPACING" "5.00,5.00,5.00,5.00,5.00,5.00,5.00,5.00,5.00,5.00,5.00,5.00,5.00,5.00"
					( Origin gBackEnd )
				)
				( attribute "SN_TESTPIN_TO_TESTPIN_SPACING" "5.00,5.00,5.00,5.00,5.00,5.00,5.00,5.00,5.00,5.00,5.00,5.00,5.00,5.00"
					( Origin gBackEnd )
				)
				( attribute "SN_TESTPIN_TO_THRUVIA_SPACING" "5.00,5.00,5.00,5.00,5.00,5.00,5.00,5.00,5.00,5.00,5.00,5.00,5.00,5.00"
					( Origin gBackEnd )
				)
				( attribute "SN_TESTPIN_TO_TESTVIA_SPACING" "5.00,5.00,5.00,5.00,5.00,5.00,5.00,5.00,5.00,5.00,5.00,5.00,5.00,5.00"
					( Origin gBackEnd )
				)
				( attribute "SN_BBV_TO_TESTPIN_SPACING" "5.00,5.00,5.00,5.00,5.00,5.00,5.00,5.00,5.00,5.00,5.00,5.00,5.00,5.00"
					( Origin gBackEnd )
				)
				( attribute "SN_BONDPAD_TO_TESTPIN_SPACING" "5.00,5.00,5.00,5.00,5.00,5.00,5.00,5.00,5.00,5.00,5.00,5.00,5.00,5.00"
					( Origin gBackEnd )
				)
				( attribute "SN_LINE_TO_TESTPIN_SPACING" "5.00,5.00,5.00,5.00,5.00,5.00,5.00,5.00,5.00,5.00,5.00,5.00,5.00,5.00"
					( Origin gBackEnd )
				)
				( attribute "SN_SHAPE_TO_TESTPIN_SPACING" "5.00,5.00,5.00,5.00,5.00,5.00,5.00,5.00,5.00,5.00,5.00,5.00,5.00,5.00"
					( Origin gBackEnd )
				)
				( attribute "SN_THRUVIA_TO_THRUVIA_SPACING" "4.50,4.00,4.00,4.00,4.00,4.00,4.00,4.00,4.00,4.00,4.00,4.00,4.00,4.50"
					( Origin gBackEnd )
				)
				( attribute "SN_TESTVIA_TO_THRUVIA_SPACING" "5.00,5.00,5.00,5.00,5.00,5.00,5.00,5.00,5.00,5.00,5.00,5.00,5.00,5.00"
					( Origin gBackEnd )
				)
				( attribute "SN_BBV_TO_THRUVIA_SPACING" "5.00,5.00,5.00,5.00,5.00,5.00,5.00,5.00,5.00,5.00,5.00,5.00,5.00,5.00"
					( Origin gBackEnd )
				)
				( attribute "SN_BONDPAD_TO_THRUVIA_SPACING" "5.00,5.00,5.00,5.00,5.00,5.00,5.00,5.00,5.00,5.00,5.00,5.00,5.00,5.00"
					( Origin gBackEnd )
				)
				( attribute "SN_LINE_TO_THRUVIA_SPACING" "4.50,4.00,4.00,4.00,4.00,4.00,4.00,4.00,4.00,4.00,4.00,4.00,4.00,4.50"
					( Origin gBackEnd )
				)
				( attribute "SN_SHAPE_TO_THRUVIA_SPACING" "5.00,5.00,5.00,5.00,5.00,5.00,5.00,5.00,5.00,5.00,5.00,5.00,5.00,5.00"
					( Origin gBackEnd )
				)
				( attribute "SN_TESTVIA_TO_TESTVIA_SPACING" "5.00,5.00,5.00,5.00,5.00,5.00,5.00,5.00,5.00,5.00,5.00,5.00,5.00,5.00"
					( Origin gBackEnd )
				)
				( attribute "SN_BBV_TO_TESTVIA_SPACING" "5.00,5.00,5.00,5.00,5.00,5.00,5.00,5.00,5.00,5.00,5.00,5.00,5.00,5.00"
					( Origin gBackEnd )
				)
				( attribute "SN_BONDPAD_TO_TESTVIA_SPACING" "5.00,5.00,5.00,5.00,5.00,5.00,5.00,5.00,5.00,5.00,5.00,5.00,5.00,5.00"
					( Origin gBackEnd )
				)
				( attribute "SN_LINE_TO_TESTVIA_SPACING" "5.00,5.00,5.00,5.00,5.00,5.00,5.00,5.00,5.00,5.00,5.00,5.00,5.00,5.00"
					( Origin gBackEnd )
				)
				( attribute "SN_SHAPE_TO_TESTVIA_SPACING" "5.00,5.00,5.00,5.00,5.00,5.00,5.00,5.00,5.00,5.00,5.00,5.00,5.00,5.00"
					( Origin gBackEnd )
				)
				( attribute "SN_BBV_TO_BBV_SPACING" "5.00,5.00,5.00,5.00,5.00,5.00,5.00,5.00,5.00,5.00,5.00,5.00,5.00,5.00"
					( Origin gBackEnd )
				)
				( attribute "SN_BONDPAD_TO_BBV_SPACING" "5.00,5.00,5.00,5.00,5.00,5.00,5.00,5.00,5.00,5.00,5.00,5.00,5.00,5.00"
					( Origin gBackEnd )
				)
				( attribute "SN_BBV_TO_LINE_SPACING" "5.00,5.00,5.00,5.00,5.00,5.00,5.00,5.00,5.00,5.00,5.00,5.00,5.00,5.00"
					( Origin gBackEnd )
				)
				( attribute "SN_BBV_TO_SHAPE_SPACING" "5.00,5.00,5.00,5.00,5.00,5.00,5.00,5.00,5.00,5.00,5.00,5.00,5.00,5.00"
					( Origin gBackEnd )
				)
				( attribute "SN_BONDPAD_TO_BONDPAD_SPACING" "5.00,5.00,5.00,5.00,5.00,5.00,5.00,5.00,5.00,5.00,5.00,5.00,5.00,5.00"
					( Origin gBackEnd )
				)
				( attribute "SN_BONDPAD_TO_LINE_SPACING" "5.00,5.00,5.00,5.00,5.00,5.00,5.00,5.00,5.00,5.00,5.00,5.00,5.00,5.00"
					( Origin gBackEnd )
				)
				( attribute "SN_BONDPAD_TO_SHAPE_SPACING" "5.00,5.00,5.00,5.00,5.00,5.00,5.00,5.00,5.00,5.00,5.00,5.00,5.00,5.00"
					( Origin gBackEnd )
				)
				( attribute "SN_LINE_TO_LINE_SPACING" "12.00,12.00,12.00,12.00,12.00,12.00,12.00,12.00,12.00,12.00,12.00,12.00,12.00,12.00"
					( Origin gBackEnd )
				)
				( attribute "SN_LINE_TO_SHAPE_SPACING" "5.00,5.00,5.00,5.00,5.00,5.00,5.00,5.00,5.00,5.00,5.00,5.00,5.00,5.00"
					( Origin gBackEnd )
				)
				( attribute "SN_SHAPE_TO_SHAPE_SPACING" "5.00,5.00,5.00,5.00,5.00,5.00,5.00,5.00,5.00,5.00,5.00,5.00,5.00,5.00"
					( Origin gBackEnd )
				)
				( attribute "SN_HOLE_TO_PIN_SPACING" "8.00,8.00,8.00,8.00,8.00,8.00,8.00,8.00,8.00,8.00,8.00,8.00,8.00,8.00"
					( Origin gBackEnd )
				)
				( attribute "SN_HOLE_TO_VIA_SPACING" "8.00,8.00,8.00,8.00,8.00,8.00,8.00,8.00,8.00,8.00,8.00,8.00,8.00,8.00"
					( Origin gBackEnd )
				)
				( attribute "SN_HOLE_TO_LINE_SPACING" "8.00,8.00,8.00,8.00,8.00,8.00,8.00,8.00,8.00,8.00,8.00,8.00,8.00,8.00"
					( Origin gBackEnd )
				)
				( attribute "SN_HOLE_TO_SHAPE_SPACING" "8.00,8.00,8.00,8.00,8.00,8.00,8.00,8.00,8.00,8.00,8.00,8.00,8.00,8.00"
					( Origin gBackEnd )
				)
				( attribute "SN_HOLE_TO_HOLE_SPACING" "8.00,8.00,8.00,8.00,8.00,8.00,8.00,8.00,8.00,8.00,8.00,8.00,8.00,8.00"
					( Origin gBackEnd )
				)
				( attribute "SN_MVIA_TO_MVIA_SPACING" "5.00,5.00,5.00,5.00,5.00,5.00,5.00,5.00,5.00,5.00,5.00,5.00,5.00,5.00"
					( Origin gBackEnd )
				)
				( attribute "SN_MVIA_TO_THRUPIN_SPACING" "5.00,5.00,5.00,5.00,5.00,5.00,5.00,5.00,5.00,5.00,5.00,5.00,5.00,5.00"
					( Origin gBackEnd )
				)
				( attribute "SN_MVIA_TO_SMDPIN_SPACING" "5.00,5.00,5.00,5.00,5.00,5.00,5.00,5.00,5.00,5.00,5.00,5.00,5.00,5.00"
					( Origin gBackEnd )
				)
				( attribute "SN_MVIA_TO_THRUVIA_SPACING" "5.00,5.00,5.00,5.00,5.00,5.00,5.00,5.00,5.00,5.00,5.00,5.00,5.00,5.00"
					( Origin gBackEnd )
				)
				( attribute "SN_MVIA_TO_BBV_SPACING" "5.00,5.00,5.00,5.00,5.00,5.00,5.00,5.00,5.00,5.00,5.00,5.00,5.00,5.00"
					( Origin gBackEnd )
				)
				( attribute "SN_MVIA_TO_LINE_SPACING" "5.00,5.00,5.00,5.00,5.00,5.00,5.00,5.00,5.00,5.00,5.00,5.00,5.00,5.00"
					( Origin gBackEnd )
				)
				( attribute "SN_MVIA_TO_SHAPE_SPACING" "5.00,5.00,5.00,5.00,5.00,5.00,5.00,5.00,5.00,5.00,5.00,5.00,5.00,5.00"
					( Origin gBackEnd )
				)
				( attribute "SN_MVIA_TO_TESTPIN_SPACING" "5.00,5.00,5.00,5.00,5.00,5.00,5.00,5.00,5.00,5.00,5.00,5.00,5.00,5.00"
					( Origin gBackEnd )
				)
				( attribute "SN_MVIA_TO_TESTVIA_SPACING" "5.00,5.00,5.00,5.00,5.00,5.00,5.00,5.00,5.00,5.00,5.00,5.00,5.00,5.00"
					( Origin gBackEnd )
				)
				( attribute "SN_BONDPAD_TO_MVIA_SPACING" "5.00,5.00,5.00,5.00,5.00,5.00,5.00,5.00,5.00,5.00,5.00,5.00,5.00,5.00"
					( Origin gBackEnd )
				)
				( objectStatus "12_MILS" )
			)
			( sameNetSpacingCSet "@crescent_city_bb_fab1_lib.crescent_city_bb_fab1(sch_1):\2.5H_US_AND_2H_SL\"
				( attribute "SAME_NET" "TRUE,TRUE,TRUE,TRUE,TRUE,TRUE,TRUE,TRUE,TRUE,TRUE,TRUE,TRUE,TRUE,TRUE"
					( Origin gBackEnd )
				)
				( attribute "SN_THRUPIN_TO_THRUPIN_SPACING" "5.00,5.00,5.00,5.00,5.00,5.00,5.00,5.00,5.00,5.00,5.00,5.00,5.00,5.00"
					( Origin gBackEnd )
				)
				( attribute "SN_THRUPIN_TO_SMDPIN_SPACING" "5.00,5.00,5.00,5.00,5.00,5.00,5.00,5.00,5.00,5.00,5.00,5.00,5.00,5.00"
					( Origin gBackEnd )
				)
				( attribute "SN_TESTPIN_TO_THRUPIN_SPACING" "5.00,5.00,5.00,5.00,5.00,5.00,5.00,5.00,5.00,5.00,5.00,5.00,5.00,5.00"
					( Origin gBackEnd )
				)
				( attribute "SN_THRUPIN_TO_THRUVIA_SPACING" "5.00,5.00,5.00,5.00,5.00,5.00,5.00,5.00,5.00,5.00,5.00,5.00,5.00,5.00"
					( Origin gBackEnd )
				)
				( attribute "SN_TESTVIA_TO_THRUPIN_SPACING" "5.00,5.00,5.00,5.00,5.00,5.00,5.00,5.00,5.00,5.00,5.00,5.00,5.00,5.00"
					( Origin gBackEnd )
				)
				( attribute "SN_BBV_TO_THRUPIN_SPACING" "5.00,5.00,5.00,5.00,5.00,5.00,5.00,5.00,5.00,5.00,5.00,5.00,5.00,5.00"
					( Origin gBackEnd )
				)
				( attribute "SN_THRUPIN_TO_BONDPAD_SPACING" "5.00,5.00,5.00,5.00,5.00,5.00,5.00,5.00,5.00,5.00,5.00,5.00,5.00,5.00"
					( Origin gBackEnd )
				)
				( attribute "SN_LINE_TO_THRUPIN_SPACING" "5.00,5.00,5.00,5.00,5.00,5.00,5.00,5.00,5.00,5.00,5.00,5.00,5.00,5.00"
					( Origin gBackEnd )
				)
				( attribute "SN_THRUPIN_TO_SHAPE_SPACING" "5.00,5.00,5.00,5.00,5.00,5.00,5.00,5.00,5.00,5.00,5.00,5.00,5.00,5.00"
					( Origin gBackEnd )
				)
				( attribute "SN_SMDPIN_TO_SMDPIN_SPACING" "5.00,5.00,5.00,5.00,5.00,5.00,5.00,5.00,5.00,5.00,5.00,5.00,5.00,5.00"
					( Origin gBackEnd )
				)
				( attribute "SN_SMDPIN_TO_TESTPIN_SPACING" "5.00,5.00,5.00,5.00,5.00,5.00,5.00,5.00,5.00,5.00,5.00,5.00,5.00,5.00"
					( Origin gBackEnd )
				)
				( attribute "SN_SMDPIN_TO_THRUVIA_SPACING" "4.00,4.00,4.00,4.00,4.00,4.00,4.00,4.00,4.00,4.00,4.00,4.00,4.00,4.00"
					( Origin gBackEnd )
				)
				( attribute "SN_SMDPIN_TO_TESTVIA_SPACING" "4.00,4.00,4.00,4.00,4.00,4.00,4.00,4.00,4.00,4.00,4.00,4.00,4.00,4.00"
					( Origin gBackEnd )
				)
				( attribute "SN_BBV_TO_SMDPIN_SPACING" "5.00,5.00,5.00,5.00,5.00,5.00,5.00,5.00,5.00,5.00,5.00,5.00,5.00,5.00"
					( Origin gBackEnd )
				)
				( attribute "SN_SMDPIN_TO_BONDPAD_SPACING" "5.00,5.00,5.00,5.00,5.00,5.00,5.00,5.00,5.00,5.00,5.00,5.00,5.00,5.00"
					( Origin gBackEnd )
				)
				( attribute "SN_LINE_TO_SMDPIN_SPACING" "4.50,4.50,4.50,4.50,4.50,4.50,4.50,4.50,4.50,4.50,4.50,4.50,4.50,4.50"
					( Origin gBackEnd )
				)
				( attribute "SN_SHAPE_TO_SMDPIN_SPACING" "5.00,5.00,5.00,5.00,5.00,5.00,5.00,5.00,5.00,5.00,5.00,5.00,5.00,5.00"
					( Origin gBackEnd )
				)
				( attribute "SN_TESTPIN_TO_TESTPIN_SPACING" "5.00,5.00,5.00,5.00,5.00,5.00,5.00,5.00,5.00,5.00,5.00,5.00,5.00,5.00"
					( Origin gBackEnd )
				)
				( attribute "SN_TESTPIN_TO_THRUVIA_SPACING" "5.00,5.00,5.00,5.00,5.00,5.00,5.00,5.00,5.00,5.00,5.00,5.00,5.00,5.00"
					( Origin gBackEnd )
				)
				( attribute "SN_TESTPIN_TO_TESTVIA_SPACING" "5.00,5.00,5.00,5.00,5.00,5.00,5.00,5.00,5.00,5.00,5.00,5.00,5.00,5.00"
					( Origin gBackEnd )
				)
				( attribute "SN_BBV_TO_TESTPIN_SPACING" "5.00,5.00,5.00,5.00,5.00,5.00,5.00,5.00,5.00,5.00,5.00,5.00,5.00,5.00"
					( Origin gBackEnd )
				)
				( attribute "SN_BONDPAD_TO_TESTPIN_SPACING" "5.00,5.00,5.00,5.00,5.00,5.00,5.00,5.00,5.00,5.00,5.00,5.00,5.00,5.00"
					( Origin gBackEnd )
				)
				( attribute "SN_LINE_TO_TESTPIN_SPACING" "5.00,5.00,5.00,5.00,5.00,5.00,5.00,5.00,5.00,5.00,5.00,5.00,5.00,5.00"
					( Origin gBackEnd )
				)
				( attribute "SN_SHAPE_TO_TESTPIN_SPACING" "5.00,5.00,5.00,5.00,5.00,5.00,5.00,5.00,5.00,5.00,5.00,5.00,5.00,5.00"
					( Origin gBackEnd )
				)
				( attribute "SN_THRUVIA_TO_THRUVIA_SPACING" "4.50,4.00,4.00,4.00,4.00,4.00,4.00,4.00,4.00,4.00,4.00,4.00,4.00,4.50"
					( Origin gBackEnd )
				)
				( attribute "SN_TESTVIA_TO_THRUVIA_SPACING" "5.00,5.00,5.00,5.00,5.00,5.00,5.00,5.00,5.00,5.00,5.00,5.00,5.00,5.00"
					( Origin gBackEnd )
				)
				( attribute "SN_BBV_TO_THRUVIA_SPACING" "5.00,5.00,5.00,5.00,5.00,5.00,5.00,5.00,5.00,5.00,5.00,5.00,5.00,5.00"
					( Origin gBackEnd )
				)
				( attribute "SN_BONDPAD_TO_THRUVIA_SPACING" "5.00,5.00,5.00,5.00,5.00,5.00,5.00,5.00,5.00,5.00,5.00,5.00,5.00,5.00"
					( Origin gBackEnd )
				)
				( attribute "SN_LINE_TO_THRUVIA_SPACING" "4.50,4.00,4.00,4.00,4.00,4.00,4.00,4.00,4.00,4.00,4.00,4.00,4.00,4.50"
					( Origin gBackEnd )
				)
				( attribute "SN_SHAPE_TO_THRUVIA_SPACING" "5.00,5.00,5.00,5.00,5.00,5.00,5.00,5.00,5.00,5.00,5.00,5.00,5.00,5.00"
					( Origin gBackEnd )
				)
				( attribute "SN_TESTVIA_TO_TESTVIA_SPACING" "5.00,5.00,5.00,5.00,5.00,5.00,5.00,5.00,5.00,5.00,5.00,5.00,5.00,5.00"
					( Origin gBackEnd )
				)
				( attribute "SN_BBV_TO_TESTVIA_SPACING" "5.00,5.00,5.00,5.00,5.00,5.00,5.00,5.00,5.00,5.00,5.00,5.00,5.00,5.00"
					( Origin gBackEnd )
				)
				( attribute "SN_BONDPAD_TO_TESTVIA_SPACING" "5.00,5.00,5.00,5.00,5.00,5.00,5.00,5.00,5.00,5.00,5.00,5.00,5.00,5.00"
					( Origin gBackEnd )
				)
				( attribute "SN_LINE_TO_TESTVIA_SPACING" "5.00,5.00,5.00,5.00,5.00,5.00,5.00,5.00,5.00,5.00,5.00,5.00,5.00,5.00"
					( Origin gBackEnd )
				)
				( attribute "SN_SHAPE_TO_TESTVIA_SPACING" "5.00,5.00,5.00,5.00,5.00,5.00,5.00,5.00,5.00,5.00,5.00,5.00,5.00,5.00"
					( Origin gBackEnd )
				)
				( attribute "SN_BBV_TO_BBV_SPACING" "5.00,5.00,5.00,5.00,5.00,5.00,5.00,5.00,5.00,5.00,5.00,5.00,5.00,5.00"
					( Origin gBackEnd )
				)
				( attribute "SN_BONDPAD_TO_BBV_SPACING" "5.00,5.00,5.00,5.00,5.00,5.00,5.00,5.00,5.00,5.00,5.00,5.00,5.00,5.00"
					( Origin gBackEnd )
				)
				( attribute "SN_BBV_TO_LINE_SPACING" "5.00,5.00,5.00,5.00,5.00,5.00,5.00,5.00,5.00,5.00,5.00,5.00,5.00,5.00"
					( Origin gBackEnd )
				)
				( attribute "SN_BBV_TO_SHAPE_SPACING" "5.00,5.00,5.00,5.00,5.00,5.00,5.00,5.00,5.00,5.00,5.00,5.00,5.00,5.00"
					( Origin gBackEnd )
				)
				( attribute "SN_BONDPAD_TO_BONDPAD_SPACING" "5.00,5.00,5.00,5.00,5.00,5.00,5.00,5.00,5.00,5.00,5.00,5.00,5.00,5.00"
					( Origin gBackEnd )
				)
				( attribute "SN_BONDPAD_TO_LINE_SPACING" "5.00,5.00,5.00,5.00,5.00,5.00,5.00,5.00,5.00,5.00,5.00,5.00,5.00,5.00"
					( Origin gBackEnd )
				)
				( attribute "SN_BONDPAD_TO_SHAPE_SPACING" "5.00,5.00,5.00,5.00,5.00,5.00,5.00,5.00,5.00,5.00,5.00,5.00,5.00,5.00"
					( Origin gBackEnd )
				)
				( attribute "SN_LINE_TO_LINE_SPACING" "6.75,6.00,6.00,6.00,6.00,6.00,6.00,6.00,6.00,6.00,6.00,6.00,6.00,6.75"
					( Origin gBackEnd )
				)
				( attribute "SN_LINE_TO_SHAPE_SPACING" "5.00,5.00,5.00,5.00,5.00,5.00,5.00,5.00,5.00,5.00,5.00,5.00,5.00,5.00"
					( Origin gBackEnd )
				)
				( attribute "SN_SHAPE_TO_SHAPE_SPACING" "5.00,5.00,5.00,5.00,5.00,5.00,5.00,5.00,5.00,5.00,5.00,5.00,5.00,5.00"
					( Origin gBackEnd )
				)
				( attribute "SN_HOLE_TO_PIN_SPACING" "8.00,8.00,8.00,8.00,8.00,8.00,8.00,8.00,8.00,8.00,8.00,8.00,8.00,8.00"
					( Origin gBackEnd )
				)
				( attribute "SN_HOLE_TO_VIA_SPACING" "8.00,8.00,8.00,8.00,8.00,8.00,8.00,8.00,8.00,8.00,8.00,8.00,8.00,8.00"
					( Origin gBackEnd )
				)
				( attribute "SN_HOLE_TO_LINE_SPACING" "8.00,8.00,8.00,8.00,8.00,8.00,8.00,8.00,8.00,8.00,8.00,8.00,8.00,8.00"
					( Origin gBackEnd )
				)
				( attribute "SN_HOLE_TO_SHAPE_SPACING" "8.00,8.00,8.00,8.00,8.00,8.00,8.00,8.00,8.00,8.00,8.00,8.00,8.00,8.00"
					( Origin gBackEnd )
				)
				( attribute "SN_HOLE_TO_HOLE_SPACING" "8.00,8.00,8.00,8.00,8.00,8.00,8.00,8.00,8.00,8.00,8.00,8.00,8.00,8.00"
					( Origin gBackEnd )
				)
				( attribute "SN_MVIA_TO_MVIA_SPACING" "5.00,5.00,5.00,5.00,5.00,5.00,5.00,5.00,5.00,5.00,5.00,5.00,5.00,5.00"
					( Origin gBackEnd )
				)
				( attribute "SN_MVIA_TO_THRUPIN_SPACING" "5.00,5.00,5.00,5.00,5.00,5.00,5.00,5.00,5.00,5.00,5.00,5.00,5.00,5.00"
					( Origin gBackEnd )
				)
				( attribute "SN_MVIA_TO_SMDPIN_SPACING" "5.00,5.00,5.00,5.00,5.00,5.00,5.00,5.00,5.00,5.00,5.00,5.00,5.00,5.00"
					( Origin gBackEnd )
				)
				( attribute "SN_MVIA_TO_THRUVIA_SPACING" "5.00,5.00,5.00,5.00,5.00,5.00,5.00,5.00,5.00,5.00,5.00,5.00,5.00,5.00"
					( Origin gBackEnd )
				)
				( attribute "SN_MVIA_TO_BBV_SPACING" "5.00,5.00,5.00,5.00,5.00,5.00,5.00,5.00,5.00,5.00,5.00,5.00,5.00,5.00"
					( Origin gBackEnd )
				)
				( attribute "SN_MVIA_TO_LINE_SPACING" "5.00,5.00,5.00,5.00,5.00,5.00,5.00,5.00,5.00,5.00,5.00,5.00,5.00,5.00"
					( Origin gBackEnd )
				)
				( attribute "SN_MVIA_TO_SHAPE_SPACING" "5.00,5.00,5.00,5.00,5.00,5.00,5.00,5.00,5.00,5.00,5.00,5.00,5.00,5.00"
					( Origin gBackEnd )
				)
				( attribute "SN_MVIA_TO_TESTPIN_SPACING" "5.00,5.00,5.00,5.00,5.00,5.00,5.00,5.00,5.00,5.00,5.00,5.00,5.00,5.00"
					( Origin gBackEnd )
				)
				( attribute "SN_MVIA_TO_TESTVIA_SPACING" "5.00,5.00,5.00,5.00,5.00,5.00,5.00,5.00,5.00,5.00,5.00,5.00,5.00,5.00"
					( Origin gBackEnd )
				)
				( attribute "SN_BONDPAD_TO_MVIA_SPACING" "5.00,5.00,5.00,5.00,5.00,5.00,5.00,5.00,5.00,5.00,5.00,5.00,5.00,5.00"
					( Origin gBackEnd )
				)
				( objectStatus "2.5H_US_&_2H_SL" )
			)
			( sameNetSpacingCSet "@crescent_city_bb_fab1_lib.crescent_city_bb_fab1(sch_1):\15_MILS\"
				( attribute "SAME_NET" "TRUE,TRUE,TRUE,TRUE,TRUE,TRUE,TRUE,TRUE,TRUE,TRUE,TRUE,TRUE,TRUE,TRUE"
					( Origin gBackEnd )
				)
				( attribute "SN_THRUPIN_TO_THRUPIN_SPACING" "5.00,5.00,5.00,5.00,5.00,5.00,5.00,5.00,5.00,5.00,5.00,5.00,5.00,5.00"
					( Origin gBackEnd )
				)
				( attribute "SN_THRUPIN_TO_SMDPIN_SPACING" "5.00,5.00,5.00,5.00,5.00,5.00,5.00,5.00,5.00,5.00,5.00,5.00,5.00,5.00"
					( Origin gBackEnd )
				)
				( attribute "SN_TESTPIN_TO_THRUPIN_SPACING" "5.00,5.00,5.00,5.00,5.00,5.00,5.00,5.00,5.00,5.00,5.00,5.00,5.00,5.00"
					( Origin gBackEnd )
				)
				( attribute "SN_THRUPIN_TO_THRUVIA_SPACING" "5.00,5.00,5.00,5.00,5.00,5.00,5.00,5.00,5.00,5.00,5.00,5.00,5.00,5.00"
					( Origin gBackEnd )
				)
				( attribute "SN_TESTVIA_TO_THRUPIN_SPACING" "5.00,5.00,5.00,5.00,5.00,5.00,5.00,5.00,5.00,5.00,5.00,5.00,5.00,5.00"
					( Origin gBackEnd )
				)
				( attribute "SN_BBV_TO_THRUPIN_SPACING" "5.00,5.00,5.00,5.00,5.00,5.00,5.00,5.00,5.00,5.00,5.00,5.00,5.00,5.00"
					( Origin gBackEnd )
				)
				( attribute "SN_THRUPIN_TO_BONDPAD_SPACING" "5.00,5.00,5.00,5.00,5.00,5.00,5.00,5.00,5.00,5.00,5.00,5.00,5.00,5.00"
					( Origin gBackEnd )
				)
				( attribute "SN_LINE_TO_THRUPIN_SPACING" "5.00,5.00,5.00,5.00,5.00,5.00,5.00,5.00,5.00,5.00,5.00,5.00,5.00,5.00"
					( Origin gBackEnd )
				)
				( attribute "SN_THRUPIN_TO_SHAPE_SPACING" "5.00,5.00,5.00,5.00,5.00,5.00,5.00,5.00,5.00,5.00,5.00,5.00,5.00,5.00"
					( Origin gBackEnd )
				)
				( attribute "SN_SMDPIN_TO_SMDPIN_SPACING" "5.00,5.00,5.00,5.00,5.00,5.00,5.00,5.00,5.00,5.00,5.00,5.00,5.00,5.00"
					( Origin gBackEnd )
				)
				( attribute "SN_SMDPIN_TO_TESTPIN_SPACING" "5.00,5.00,5.00,5.00,5.00,5.00,5.00,5.00,5.00,5.00,5.00,5.00,5.00,5.00"
					( Origin gBackEnd )
				)
				( attribute "SN_SMDPIN_TO_THRUVIA_SPACING" "4.00,4.00,4.00,4.00,4.00,4.00,4.00,4.00,4.00,4.00,4.00,4.00,4.00,4.00"
					( Origin gBackEnd )
				)
				( attribute "SN_SMDPIN_TO_TESTVIA_SPACING" "4.00,4.00,4.00,4.00,4.00,4.00,4.00,4.00,4.00,4.00,4.00,4.00,4.00,4.00"
					( Origin gBackEnd )
				)
				( attribute "SN_BBV_TO_SMDPIN_SPACING" "5.00,5.00,5.00,5.00,5.00,5.00,5.00,5.00,5.00,5.00,5.00,5.00,5.00,5.00"
					( Origin gBackEnd )
				)
				( attribute "SN_SMDPIN_TO_BONDPAD_SPACING" "5.00,5.00,5.00,5.00,5.00,5.00,5.00,5.00,5.00,5.00,5.00,5.00,5.00,5.00"
					( Origin gBackEnd )
				)
				( attribute "SN_LINE_TO_SMDPIN_SPACING" "4.50,4.50,4.50,4.50,4.50,4.50,4.50,4.50,4.50,4.50,4.50,4.50,4.50,4.50"
					( Origin gBackEnd )
				)
				( attribute "SN_SHAPE_TO_SMDPIN_SPACING" "5.00,5.00,5.00,5.00,5.00,5.00,5.00,5.00,5.00,5.00,5.00,5.00,5.00,5.00"
					( Origin gBackEnd )
				)
				( attribute "SN_TESTPIN_TO_TESTPIN_SPACING" "5.00,5.00,5.00,5.00,5.00,5.00,5.00,5.00,5.00,5.00,5.00,5.00,5.00,5.00"
					( Origin gBackEnd )
				)
				( attribute "SN_TESTPIN_TO_THRUVIA_SPACING" "5.00,5.00,5.00,5.00,5.00,5.00,5.00,5.00,5.00,5.00,5.00,5.00,5.00,5.00"
					( Origin gBackEnd )
				)
				( attribute "SN_TESTPIN_TO_TESTVIA_SPACING" "5.00,5.00,5.00,5.00,5.00,5.00,5.00,5.00,5.00,5.00,5.00,5.00,5.00,5.00"
					( Origin gBackEnd )
				)
				( attribute "SN_BBV_TO_TESTPIN_SPACING" "5.00,5.00,5.00,5.00,5.00,5.00,5.00,5.00,5.00,5.00,5.00,5.00,5.00,5.00"
					( Origin gBackEnd )
				)
				( attribute "SN_BONDPAD_TO_TESTPIN_SPACING" "5.00,5.00,5.00,5.00,5.00,5.00,5.00,5.00,5.00,5.00,5.00,5.00,5.00,5.00"
					( Origin gBackEnd )
				)
				( attribute "SN_LINE_TO_TESTPIN_SPACING" "5.00,5.00,5.00,5.00,5.00,5.00,5.00,5.00,5.00,5.00,5.00,5.00,5.00,5.00"
					( Origin gBackEnd )
				)
				( attribute "SN_SHAPE_TO_TESTPIN_SPACING" "5.00,5.00,5.00,5.00,5.00,5.00,5.00,5.00,5.00,5.00,5.00,5.00,5.00,5.00"
					( Origin gBackEnd )
				)
				( attribute "SN_THRUVIA_TO_THRUVIA_SPACING" "4.50,4.00,4.00,4.00,4.00,4.00,4.00,4.00,4.00,4.00,4.00,4.00,4.00,4.50"
					( Origin gBackEnd )
				)
				( attribute "SN_TESTVIA_TO_THRUVIA_SPACING" "5.00,5.00,5.00,5.00,5.00,5.00,5.00,5.00,5.00,5.00,5.00,5.00,5.00,5.00"
					( Origin gBackEnd )
				)
				( attribute "SN_BBV_TO_THRUVIA_SPACING" "5.00,5.00,5.00,5.00,5.00,5.00,5.00,5.00,5.00,5.00,5.00,5.00,5.00,5.00"
					( Origin gBackEnd )
				)
				( attribute "SN_BONDPAD_TO_THRUVIA_SPACING" "5.00,5.00,5.00,5.00,5.00,5.00,5.00,5.00,5.00,5.00,5.00,5.00,5.00,5.00"
					( Origin gBackEnd )
				)
				( attribute "SN_LINE_TO_THRUVIA_SPACING" "4.50,4.00,4.00,4.00,4.00,4.00,4.00,4.00,4.00,4.00,4.00,4.00,4.00,4.50"
					( Origin gBackEnd )
				)
				( attribute "SN_SHAPE_TO_THRUVIA_SPACING" "5.00,5.00,5.00,5.00,5.00,5.00,5.00,5.00,5.00,5.00,5.00,5.00,5.00,5.00"
					( Origin gBackEnd )
				)
				( attribute "SN_TESTVIA_TO_TESTVIA_SPACING" "5.00,5.00,5.00,5.00,5.00,5.00,5.00,5.00,5.00,5.00,5.00,5.00,5.00,5.00"
					( Origin gBackEnd )
				)
				( attribute "SN_BBV_TO_TESTVIA_SPACING" "5.00,5.00,5.00,5.00,5.00,5.00,5.00,5.00,5.00,5.00,5.00,5.00,5.00,5.00"
					( Origin gBackEnd )
				)
				( attribute "SN_BONDPAD_TO_TESTVIA_SPACING" "5.00,5.00,5.00,5.00,5.00,5.00,5.00,5.00,5.00,5.00,5.00,5.00,5.00,5.00"
					( Origin gBackEnd )
				)
				( attribute "SN_LINE_TO_TESTVIA_SPACING" "5.00,5.00,5.00,5.00,5.00,5.00,5.00,5.00,5.00,5.00,5.00,5.00,5.00,5.00"
					( Origin gBackEnd )
				)
				( attribute "SN_SHAPE_TO_TESTVIA_SPACING" "5.00,5.00,5.00,5.00,5.00,5.00,5.00,5.00,5.00,5.00,5.00,5.00,5.00,5.00"
					( Origin gBackEnd )
				)
				( attribute "SN_BBV_TO_BBV_SPACING" "5.00,5.00,5.00,5.00,5.00,5.00,5.00,5.00,5.00,5.00,5.00,5.00,5.00,5.00"
					( Origin gBackEnd )
				)
				( attribute "SN_BONDPAD_TO_BBV_SPACING" "5.00,5.00,5.00,5.00,5.00,5.00,5.00,5.00,5.00,5.00,5.00,5.00,5.00,5.00"
					( Origin gBackEnd )
				)
				( attribute "SN_BBV_TO_LINE_SPACING" "5.00,5.00,5.00,5.00,5.00,5.00,5.00,5.00,5.00,5.00,5.00,5.00,5.00,5.00"
					( Origin gBackEnd )
				)
				( attribute "SN_BBV_TO_SHAPE_SPACING" "5.00,5.00,5.00,5.00,5.00,5.00,5.00,5.00,5.00,5.00,5.00,5.00,5.00,5.00"
					( Origin gBackEnd )
				)
				( attribute "SN_BONDPAD_TO_BONDPAD_SPACING" "5.00,5.00,5.00,5.00,5.00,5.00,5.00,5.00,5.00,5.00,5.00,5.00,5.00,5.00"
					( Origin gBackEnd )
				)
				( attribute "SN_BONDPAD_TO_LINE_SPACING" "5.00,5.00,5.00,5.00,5.00,5.00,5.00,5.00,5.00,5.00,5.00,5.00,5.00,5.00"
					( Origin gBackEnd )
				)
				( attribute "SN_BONDPAD_TO_SHAPE_SPACING" "5.00,5.00,5.00,5.00,5.00,5.00,5.00,5.00,5.00,5.00,5.00,5.00,5.00,5.00"
					( Origin gBackEnd )
				)
				( attribute "SN_LINE_TO_LINE_SPACING" "15.00,15.00,15.00,15.00,15.00,15.00,15.00,15.00,15.00,15.00,15.00,15.00,15.00,15.00"
					( Origin gBackEnd )
				)
				( attribute "SN_LINE_TO_SHAPE_SPACING" "5.00,5.00,5.00,5.00,5.00,5.00,5.00,5.00,5.00,5.00,5.00,5.00,5.00,5.00"
					( Origin gBackEnd )
				)
				( attribute "SN_SHAPE_TO_SHAPE_SPACING" "5.00,5.00,5.00,5.00,5.00,5.00,5.00,5.00,5.00,5.00,5.00,5.00,5.00,5.00"
					( Origin gBackEnd )
				)
				( attribute "SN_HOLE_TO_PIN_SPACING" "8.00,8.00,8.00,8.00,8.00,8.00,8.00,8.00,8.00,8.00,8.00,8.00,8.00,8.00"
					( Origin gBackEnd )
				)
				( attribute "SN_HOLE_TO_VIA_SPACING" "8.00,8.00,8.00,8.00,8.00,8.00,8.00,8.00,8.00,8.00,8.00,8.00,8.00,8.00"
					( Origin gBackEnd )
				)
				( attribute "SN_HOLE_TO_LINE_SPACING" "8.00,8.00,8.00,8.00,8.00,8.00,8.00,8.00,8.00,8.00,8.00,8.00,8.00,8.00"
					( Origin gBackEnd )
				)
				( attribute "SN_HOLE_TO_SHAPE_SPACING" "8.00,8.00,8.00,8.00,8.00,8.00,8.00,8.00,8.00,8.00,8.00,8.00,8.00,8.00"
					( Origin gBackEnd )
				)
				( attribute "SN_HOLE_TO_HOLE_SPACING" "8.00,8.00,8.00,8.00,8.00,8.00,8.00,8.00,8.00,8.00,8.00,8.00,8.00,8.00"
					( Origin gBackEnd )
				)
				( attribute "SN_MVIA_TO_MVIA_SPACING" "5.00,5.00,5.00,5.00,5.00,5.00,5.00,5.00,5.00,5.00,5.00,5.00,5.00,5.00"
					( Origin gBackEnd )
				)
				( attribute "SN_MVIA_TO_THRUPIN_SPACING" "5.00,5.00,5.00,5.00,5.00,5.00,5.00,5.00,5.00,5.00,5.00,5.00,5.00,5.00"
					( Origin gBackEnd )
				)
				( attribute "SN_MVIA_TO_SMDPIN_SPACING" "5.00,5.00,5.00,5.00,5.00,5.00,5.00,5.00,5.00,5.00,5.00,5.00,5.00,5.00"
					( Origin gBackEnd )
				)
				( attribute "SN_MVIA_TO_THRUVIA_SPACING" "5.00,5.00,5.00,5.00,5.00,5.00,5.00,5.00,5.00,5.00,5.00,5.00,5.00,5.00"
					( Origin gBackEnd )
				)
				( attribute "SN_MVIA_TO_BBV_SPACING" "5.00,5.00,5.00,5.00,5.00,5.00,5.00,5.00,5.00,5.00,5.00,5.00,5.00,5.00"
					( Origin gBackEnd )
				)
				( attribute "SN_MVIA_TO_LINE_SPACING" "5.00,5.00,5.00,5.00,5.00,5.00,5.00,5.00,5.00,5.00,5.00,5.00,5.00,5.00"
					( Origin gBackEnd )
				)
				( attribute "SN_MVIA_TO_SHAPE_SPACING" "5.00,5.00,5.00,5.00,5.00,5.00,5.00,5.00,5.00,5.00,5.00,5.00,5.00,5.00"
					( Origin gBackEnd )
				)
				( attribute "SN_MVIA_TO_TESTPIN_SPACING" "5.00,5.00,5.00,5.00,5.00,5.00,5.00,5.00,5.00,5.00,5.00,5.00,5.00,5.00"
					( Origin gBackEnd )
				)
				( attribute "SN_MVIA_TO_TESTVIA_SPACING" "5.00,5.00,5.00,5.00,5.00,5.00,5.00,5.00,5.00,5.00,5.00,5.00,5.00,5.00"
					( Origin gBackEnd )
				)
				( attribute "SN_BONDPAD_TO_MVIA_SPACING" "5.00,5.00,5.00,5.00,5.00,5.00,5.00,5.00,5.00,5.00,5.00,5.00,5.00,5.00"
					( Origin gBackEnd )
				)
				( objectStatus "15_MILS" )
			)
			( sameNetSpacingCSet "@crescent_city_bb_fab1_lib.crescent_city_bb_fab1(sch_1):\16_MILS\"
				( attribute "SAME_NET" "TRUE,TRUE,TRUE,TRUE,TRUE,TRUE,TRUE,TRUE,TRUE,TRUE,TRUE,TRUE,TRUE,TRUE"
					( Origin gBackEnd )
				)
				( attribute "SN_THRUPIN_TO_THRUPIN_SPACING" "5.00,5.00,5.00,5.00,5.00,5.00,5.00,5.00,5.00,5.00,5.00,5.00,5.00,5.00"
					( Origin gBackEnd )
				)
				( attribute "SN_THRUPIN_TO_SMDPIN_SPACING" "5.00,5.00,5.00,5.00,5.00,5.00,5.00,5.00,5.00,5.00,5.00,5.00,5.00,5.00"
					( Origin gBackEnd )
				)
				( attribute "SN_TESTPIN_TO_THRUPIN_SPACING" "5.00,5.00,5.00,5.00,5.00,5.00,5.00,5.00,5.00,5.00,5.00,5.00,5.00,5.00"
					( Origin gBackEnd )
				)
				( attribute "SN_THRUPIN_TO_THRUVIA_SPACING" "5.00,5.00,5.00,5.00,5.00,5.00,5.00,5.00,5.00,5.00,5.00,5.00,5.00,5.00"
					( Origin gBackEnd )
				)
				( attribute "SN_TESTVIA_TO_THRUPIN_SPACING" "5.00,5.00,5.00,5.00,5.00,5.00,5.00,5.00,5.00,5.00,5.00,5.00,5.00,5.00"
					( Origin gBackEnd )
				)
				( attribute "SN_BBV_TO_THRUPIN_SPACING" "5.00,5.00,5.00,5.00,5.00,5.00,5.00,5.00,5.00,5.00,5.00,5.00,5.00,5.00"
					( Origin gBackEnd )
				)
				( attribute "SN_THRUPIN_TO_BONDPAD_SPACING" "5.00,5.00,5.00,5.00,5.00,5.00,5.00,5.00,5.00,5.00,5.00,5.00,5.00,5.00"
					( Origin gBackEnd )
				)
				( attribute "SN_LINE_TO_THRUPIN_SPACING" "5.00,5.00,5.00,5.00,5.00,5.00,5.00,5.00,5.00,5.00,5.00,5.00,5.00,5.00"
					( Origin gBackEnd )
				)
				( attribute "SN_THRUPIN_TO_SHAPE_SPACING" "5.00,5.00,5.00,5.00,5.00,5.00,5.00,5.00,5.00,5.00,5.00,5.00,5.00,5.00"
					( Origin gBackEnd )
				)
				( attribute "SN_SMDPIN_TO_SMDPIN_SPACING" "5.00,5.00,5.00,5.00,5.00,5.00,5.00,5.00,5.00,5.00,5.00,5.00,5.00,5.00"
					( Origin gBackEnd )
				)
				( attribute "SN_SMDPIN_TO_TESTPIN_SPACING" "5.00,5.00,5.00,5.00,5.00,5.00,5.00,5.00,5.00,5.00,5.00,5.00,5.00,5.00"
					( Origin gBackEnd )
				)
				( attribute "SN_SMDPIN_TO_THRUVIA_SPACING" "4.00,4.00,4.00,4.00,4.00,4.00,4.00,4.00,4.00,4.00,4.00,4.00,4.00,4.00"
					( Origin gBackEnd )
				)
				( attribute "SN_SMDPIN_TO_TESTVIA_SPACING" "4.00,4.00,4.00,4.00,4.00,4.00,4.00,4.00,4.00,4.00,4.00,4.00,4.00,4.00"
					( Origin gBackEnd )
				)
				( attribute "SN_BBV_TO_SMDPIN_SPACING" "5.00,5.00,5.00,5.00,5.00,5.00,5.00,5.00,5.00,5.00,5.00,5.00,5.00,5.00"
					( Origin gBackEnd )
				)
				( attribute "SN_SMDPIN_TO_BONDPAD_SPACING" "5.00,5.00,5.00,5.00,5.00,5.00,5.00,5.00,5.00,5.00,5.00,5.00,5.00,5.00"
					( Origin gBackEnd )
				)
				( attribute "SN_LINE_TO_SMDPIN_SPACING" "4.50,4.50,4.50,4.50,4.50,4.50,4.50,4.50,4.50,4.50,4.50,4.50,4.50,4.50"
					( Origin gBackEnd )
				)
				( attribute "SN_SHAPE_TO_SMDPIN_SPACING" "5.00,5.00,5.00,5.00,5.00,5.00,5.00,5.00,5.00,5.00,5.00,5.00,5.00,5.00"
					( Origin gBackEnd )
				)
				( attribute "SN_TESTPIN_TO_TESTPIN_SPACING" "5.00,5.00,5.00,5.00,5.00,5.00,5.00,5.00,5.00,5.00,5.00,5.00,5.00,5.00"
					( Origin gBackEnd )
				)
				( attribute "SN_TESTPIN_TO_THRUVIA_SPACING" "5.00,5.00,5.00,5.00,5.00,5.00,5.00,5.00,5.00,5.00,5.00,5.00,5.00,5.00"
					( Origin gBackEnd )
				)
				( attribute "SN_TESTPIN_TO_TESTVIA_SPACING" "5.00,5.00,5.00,5.00,5.00,5.00,5.00,5.00,5.00,5.00,5.00,5.00,5.00,5.00"
					( Origin gBackEnd )
				)
				( attribute "SN_BBV_TO_TESTPIN_SPACING" "5.00,5.00,5.00,5.00,5.00,5.00,5.00,5.00,5.00,5.00,5.00,5.00,5.00,5.00"
					( Origin gBackEnd )
				)
				( attribute "SN_BONDPAD_TO_TESTPIN_SPACING" "5.00,5.00,5.00,5.00,5.00,5.00,5.00,5.00,5.00,5.00,5.00,5.00,5.00,5.00"
					( Origin gBackEnd )
				)
				( attribute "SN_LINE_TO_TESTPIN_SPACING" "5.00,5.00,5.00,5.00,5.00,5.00,5.00,5.00,5.00,5.00,5.00,5.00,5.00,5.00"
					( Origin gBackEnd )
				)
				( attribute "SN_SHAPE_TO_TESTPIN_SPACING" "5.00,5.00,5.00,5.00,5.00,5.00,5.00,5.00,5.00,5.00,5.00,5.00,5.00,5.00"
					( Origin gBackEnd )
				)
				( attribute "SN_THRUVIA_TO_THRUVIA_SPACING" "4.50,4.00,4.00,4.00,4.00,4.00,4.00,4.00,4.00,4.00,4.00,4.00,4.00,4.50"
					( Origin gBackEnd )
				)
				( attribute "SN_TESTVIA_TO_THRUVIA_SPACING" "5.00,5.00,5.00,5.00,5.00,5.00,5.00,5.00,5.00,5.00,5.00,5.00,5.00,5.00"
					( Origin gBackEnd )
				)
				( attribute "SN_BBV_TO_THRUVIA_SPACING" "5.00,5.00,5.00,5.00,5.00,5.00,5.00,5.00,5.00,5.00,5.00,5.00,5.00,5.00"
					( Origin gBackEnd )
				)
				( attribute "SN_BONDPAD_TO_THRUVIA_SPACING" "5.00,5.00,5.00,5.00,5.00,5.00,5.00,5.00,5.00,5.00,5.00,5.00,5.00,5.00"
					( Origin gBackEnd )
				)
				( attribute "SN_LINE_TO_THRUVIA_SPACING" "4.50,4.00,4.00,4.00,4.00,4.00,4.00,4.00,4.00,4.00,4.00,4.00,4.00,4.50"
					( Origin gBackEnd )
				)
				( attribute "SN_SHAPE_TO_THRUVIA_SPACING" "5.00,5.00,5.00,5.00,5.00,5.00,5.00,5.00,5.00,5.00,5.00,5.00,5.00,5.00"
					( Origin gBackEnd )
				)
				( attribute "SN_TESTVIA_TO_TESTVIA_SPACING" "5.00,5.00,5.00,5.00,5.00,5.00,5.00,5.00,5.00,5.00,5.00,5.00,5.00,5.00"
					( Origin gBackEnd )
				)
				( attribute "SN_BBV_TO_TESTVIA_SPACING" "5.00,5.00,5.00,5.00,5.00,5.00,5.00,5.00,5.00,5.00,5.00,5.00,5.00,5.00"
					( Origin gBackEnd )
				)
				( attribute "SN_BONDPAD_TO_TESTVIA_SPACING" "5.00,5.00,5.00,5.00,5.00,5.00,5.00,5.00,5.00,5.00,5.00,5.00,5.00,5.00"
					( Origin gBackEnd )
				)
				( attribute "SN_LINE_TO_TESTVIA_SPACING" "5.00,5.00,5.00,5.00,5.00,5.00,5.00,5.00,5.00,5.00,5.00,5.00,5.00,5.00"
					( Origin gBackEnd )
				)
				( attribute "SN_SHAPE_TO_TESTVIA_SPACING" "5.00,5.00,5.00,5.00,5.00,5.00,5.00,5.00,5.00,5.00,5.00,5.00,5.00,5.00"
					( Origin gBackEnd )
				)
				( attribute "SN_BBV_TO_BBV_SPACING" "5.00,5.00,5.00,5.00,5.00,5.00,5.00,5.00,5.00,5.00,5.00,5.00,5.00,5.00"
					( Origin gBackEnd )
				)
				( attribute "SN_BONDPAD_TO_BBV_SPACING" "5.00,5.00,5.00,5.00,5.00,5.00,5.00,5.00,5.00,5.00,5.00,5.00,5.00,5.00"
					( Origin gBackEnd )
				)
				( attribute "SN_BBV_TO_LINE_SPACING" "5.00,5.00,5.00,5.00,5.00,5.00,5.00,5.00,5.00,5.00,5.00,5.00,5.00,5.00"
					( Origin gBackEnd )
				)
				( attribute "SN_BBV_TO_SHAPE_SPACING" "5.00,5.00,5.00,5.00,5.00,5.00,5.00,5.00,5.00,5.00,5.00,5.00,5.00,5.00"
					( Origin gBackEnd )
				)
				( attribute "SN_BONDPAD_TO_BONDPAD_SPACING" "5.00,5.00,5.00,5.00,5.00,5.00,5.00,5.00,5.00,5.00,5.00,5.00,5.00,5.00"
					( Origin gBackEnd )
				)
				( attribute "SN_BONDPAD_TO_LINE_SPACING" "5.00,5.00,5.00,5.00,5.00,5.00,5.00,5.00,5.00,5.00,5.00,5.00,5.00,5.00"
					( Origin gBackEnd )
				)
				( attribute "SN_BONDPAD_TO_SHAPE_SPACING" "5.00,5.00,5.00,5.00,5.00,5.00,5.00,5.00,5.00,5.00,5.00,5.00,5.00,5.00"
					( Origin gBackEnd )
				)
				( attribute "SN_LINE_TO_LINE_SPACING" "16.00,16.00,16.00,16.00,16.00,16.00,16.00,16.00,16.00,16.00,16.00,16.00,16.00,16.00"
					( Origin gBackEnd )
				)
				( attribute "SN_LINE_TO_SHAPE_SPACING" "5.00,5.00,5.00,5.00,5.00,5.00,5.00,5.00,5.00,5.00,5.00,5.00,5.00,5.00"
					( Origin gBackEnd )
				)
				( attribute "SN_SHAPE_TO_SHAPE_SPACING" "5.00,5.00,5.00,5.00,5.00,5.00,5.00,5.00,5.00,5.00,5.00,5.00,5.00,5.00"
					( Origin gBackEnd )
				)
				( attribute "SN_HOLE_TO_PIN_SPACING" "8.00,8.00,8.00,8.00,8.00,8.00,8.00,8.00,8.00,8.00,8.00,8.00,8.00,8.00"
					( Origin gBackEnd )
				)
				( attribute "SN_HOLE_TO_VIA_SPACING" "8.00,8.00,8.00,8.00,8.00,8.00,8.00,8.00,8.00,8.00,8.00,8.00,8.00,8.00"
					( Origin gBackEnd )
				)
				( attribute "SN_HOLE_TO_LINE_SPACING" "8.00,8.00,8.00,8.00,8.00,8.00,8.00,8.00,8.00,8.00,8.00,8.00,8.00,8.00"
					( Origin gBackEnd )
				)
				( attribute "SN_HOLE_TO_SHAPE_SPACING" "8.00,8.00,8.00,8.00,8.00,8.00,8.00,8.00,8.00,8.00,8.00,8.00,8.00,8.00"
					( Origin gBackEnd )
				)
				( attribute "SN_HOLE_TO_HOLE_SPACING" "8.00,8.00,8.00,8.00,8.00,8.00,8.00,8.00,8.00,8.00,8.00,8.00,8.00,8.00"
					( Origin gBackEnd )
				)
				( attribute "SN_MVIA_TO_MVIA_SPACING" "5.00,5.00,5.00,5.00,5.00,5.00,5.00,5.00,5.00,5.00,5.00,5.00,5.00,5.00"
					( Origin gBackEnd )
				)
				( attribute "SN_MVIA_TO_THRUPIN_SPACING" "5.00,5.00,5.00,5.00,5.00,5.00,5.00,5.00,5.00,5.00,5.00,5.00,5.00,5.00"
					( Origin gBackEnd )
				)
				( attribute "SN_MVIA_TO_SMDPIN_SPACING" "5.00,5.00,5.00,5.00,5.00,5.00,5.00,5.00,5.00,5.00,5.00,5.00,5.00,5.00"
					( Origin gBackEnd )
				)
				( attribute "SN_MVIA_TO_THRUVIA_SPACING" "5.00,5.00,5.00,5.00,5.00,5.00,5.00,5.00,5.00,5.00,5.00,5.00,5.00,5.00"
					( Origin gBackEnd )
				)
				( attribute "SN_MVIA_TO_BBV_SPACING" "5.00,5.00,5.00,5.00,5.00,5.00,5.00,5.00,5.00,5.00,5.00,5.00,5.00,5.00"
					( Origin gBackEnd )
				)
				( attribute "SN_MVIA_TO_LINE_SPACING" "5.00,5.00,5.00,5.00,5.00,5.00,5.00,5.00,5.00,5.00,5.00,5.00,5.00,5.00"
					( Origin gBackEnd )
				)
				( attribute "SN_MVIA_TO_SHAPE_SPACING" "5.00,5.00,5.00,5.00,5.00,5.00,5.00,5.00,5.00,5.00,5.00,5.00,5.00,5.00"
					( Origin gBackEnd )
				)
				( attribute "SN_MVIA_TO_TESTPIN_SPACING" "5.00,5.00,5.00,5.00,5.00,5.00,5.00,5.00,5.00,5.00,5.00,5.00,5.00,5.00"
					( Origin gBackEnd )
				)
				( attribute "SN_MVIA_TO_TESTVIA_SPACING" "5.00,5.00,5.00,5.00,5.00,5.00,5.00,5.00,5.00,5.00,5.00,5.00,5.00,5.00"
					( Origin gBackEnd )
				)
				( attribute "SN_BONDPAD_TO_MVIA_SPACING" "5.00,5.00,5.00,5.00,5.00,5.00,5.00,5.00,5.00,5.00,5.00,5.00,5.00,5.00"
					( Origin gBackEnd )
				)
				( objectStatus "16_MILS" )
			)
			( sameNetSpacingCSet "@crescent_city_bb_fab1_lib.crescent_city_bb_fab1(sch_1):\30_MILS\"
				( attribute "SAME_NET" "TRUE,TRUE,TRUE,TRUE,TRUE,TRUE,TRUE,TRUE,TRUE,TRUE,TRUE,TRUE,TRUE,TRUE"
					( Origin gBackEnd )
				)
				( attribute "SN_THRUPIN_TO_THRUPIN_SPACING" "5.00,5.00,5.00,5.00,5.00,5.00,5.00,5.00,5.00,5.00,5.00,5.00,5.00,5.00"
					( Origin gBackEnd )
				)
				( attribute "SN_THRUPIN_TO_SMDPIN_SPACING" "5.00,5.00,5.00,5.00,5.00,5.00,5.00,5.00,5.00,5.00,5.00,5.00,5.00,5.00"
					( Origin gBackEnd )
				)
				( attribute "SN_TESTPIN_TO_THRUPIN_SPACING" "5.00,5.00,5.00,5.00,5.00,5.00,5.00,5.00,5.00,5.00,5.00,5.00,5.00,5.00"
					( Origin gBackEnd )
				)
				( attribute "SN_THRUPIN_TO_THRUVIA_SPACING" "5.00,5.00,5.00,5.00,5.00,5.00,5.00,5.00,5.00,5.00,5.00,5.00,5.00,5.00"
					( Origin gBackEnd )
				)
				( attribute "SN_TESTVIA_TO_THRUPIN_SPACING" "5.00,5.00,5.00,5.00,5.00,5.00,5.00,5.00,5.00,5.00,5.00,5.00,5.00,5.00"
					( Origin gBackEnd )
				)
				( attribute "SN_BBV_TO_THRUPIN_SPACING" "5.00,5.00,5.00,5.00,5.00,5.00,5.00,5.00,5.00,5.00,5.00,5.00,5.00,5.00"
					( Origin gBackEnd )
				)
				( attribute "SN_THRUPIN_TO_BONDPAD_SPACING" "5.00,5.00,5.00,5.00,5.00,5.00,5.00,5.00,5.00,5.00,5.00,5.00,5.00,5.00"
					( Origin gBackEnd )
				)
				( attribute "SN_LINE_TO_THRUPIN_SPACING" "5.00,5.00,5.00,5.00,5.00,5.00,5.00,5.00,5.00,5.00,5.00,5.00,5.00,5.00"
					( Origin gBackEnd )
				)
				( attribute "SN_THRUPIN_TO_SHAPE_SPACING" "5.00,5.00,5.00,5.00,5.00,5.00,5.00,5.00,5.00,5.00,5.00,5.00,5.00,5.00"
					( Origin gBackEnd )
				)
				( attribute "SN_SMDPIN_TO_SMDPIN_SPACING" "5.00,5.00,5.00,5.00,5.00,5.00,5.00,5.00,5.00,5.00,5.00,5.00,5.00,5.00"
					( Origin gBackEnd )
				)
				( attribute "SN_SMDPIN_TO_TESTPIN_SPACING" "5.00,5.00,5.00,5.00,5.00,5.00,5.00,5.00,5.00,5.00,5.00,5.00,5.00,5.00"
					( Origin gBackEnd )
				)
				( attribute "SN_SMDPIN_TO_THRUVIA_SPACING" "4.00,4.00,4.00,4.00,4.00,4.00,4.00,4.00,4.00,4.00,4.00,4.00,4.00,4.00"
					( Origin gBackEnd )
				)
				( attribute "SN_SMDPIN_TO_TESTVIA_SPACING" "4.00,4.00,4.00,4.00,4.00,4.00,4.00,4.00,4.00,4.00,4.00,4.00,4.00,4.00"
					( Origin gBackEnd )
				)
				( attribute "SN_BBV_TO_SMDPIN_SPACING" "5.00,5.00,5.00,5.00,5.00,5.00,5.00,5.00,5.00,5.00,5.00,5.00,5.00,5.00"
					( Origin gBackEnd )
				)
				( attribute "SN_SMDPIN_TO_BONDPAD_SPACING" "5.00,5.00,5.00,5.00,5.00,5.00,5.00,5.00,5.00,5.00,5.00,5.00,5.00,5.00"
					( Origin gBackEnd )
				)
				( attribute "SN_LINE_TO_SMDPIN_SPACING" "4.50,4.50,4.50,4.50,4.50,4.50,4.50,4.50,4.50,4.50,4.50,4.50,4.50,4.50"
					( Origin gBackEnd )
				)
				( attribute "SN_SHAPE_TO_SMDPIN_SPACING" "5.00,5.00,5.00,5.00,5.00,5.00,5.00,5.00,5.00,5.00,5.00,5.00,5.00,5.00"
					( Origin gBackEnd )
				)
				( attribute "SN_TESTPIN_TO_TESTPIN_SPACING" "5.00,5.00,5.00,5.00,5.00,5.00,5.00,5.00,5.00,5.00,5.00,5.00,5.00,5.00"
					( Origin gBackEnd )
				)
				( attribute "SN_TESTPIN_TO_THRUVIA_SPACING" "5.00,5.00,5.00,5.00,5.00,5.00,5.00,5.00,5.00,5.00,5.00,5.00,5.00,5.00"
					( Origin gBackEnd )
				)
				( attribute "SN_TESTPIN_TO_TESTVIA_SPACING" "5.00,5.00,5.00,5.00,5.00,5.00,5.00,5.00,5.00,5.00,5.00,5.00,5.00,5.00"
					( Origin gBackEnd )
				)
				( attribute "SN_BBV_TO_TESTPIN_SPACING" "5.00,5.00,5.00,5.00,5.00,5.00,5.00,5.00,5.00,5.00,5.00,5.00,5.00,5.00"
					( Origin gBackEnd )
				)
				( attribute "SN_BONDPAD_TO_TESTPIN_SPACING" "5.00,5.00,5.00,5.00,5.00,5.00,5.00,5.00,5.00,5.00,5.00,5.00,5.00,5.00"
					( Origin gBackEnd )
				)
				( attribute "SN_LINE_TO_TESTPIN_SPACING" "5.00,5.00,5.00,5.00,5.00,5.00,5.00,5.00,5.00,5.00,5.00,5.00,5.00,5.00"
					( Origin gBackEnd )
				)
				( attribute "SN_SHAPE_TO_TESTPIN_SPACING" "5.00,5.00,5.00,5.00,5.00,5.00,5.00,5.00,5.00,5.00,5.00,5.00,5.00,5.00"
					( Origin gBackEnd )
				)
				( attribute "SN_THRUVIA_TO_THRUVIA_SPACING" "4.50,4.00,4.00,4.00,4.00,4.00,4.00,4.00,4.00,4.00,4.00,4.00,4.00,4.50"
					( Origin gBackEnd )
				)
				( attribute "SN_TESTVIA_TO_THRUVIA_SPACING" "5.00,5.00,5.00,5.00,5.00,5.00,5.00,5.00,5.00,5.00,5.00,5.00,5.00,5.00"
					( Origin gBackEnd )
				)
				( attribute "SN_BBV_TO_THRUVIA_SPACING" "5.00,5.00,5.00,5.00,5.00,5.00,5.00,5.00,5.00,5.00,5.00,5.00,5.00,5.00"
					( Origin gBackEnd )
				)
				( attribute "SN_BONDPAD_TO_THRUVIA_SPACING" "5.00,5.00,5.00,5.00,5.00,5.00,5.00,5.00,5.00,5.00,5.00,5.00,5.00,5.00"
					( Origin gBackEnd )
				)
				( attribute "SN_LINE_TO_THRUVIA_SPACING" "4.50,4.00,4.00,4.00,4.00,4.00,4.00,4.00,4.00,4.00,4.00,4.00,4.00,4.50"
					( Origin gBackEnd )
				)
				( attribute "SN_SHAPE_TO_THRUVIA_SPACING" "5.00,5.00,5.00,5.00,5.00,5.00,5.00,5.00,5.00,5.00,5.00,5.00,5.00,5.00"
					( Origin gBackEnd )
				)
				( attribute "SN_TESTVIA_TO_TESTVIA_SPACING" "5.00,5.00,5.00,5.00,5.00,5.00,5.00,5.00,5.00,5.00,5.00,5.00,5.00,5.00"
					( Origin gBackEnd )
				)
				( attribute "SN_BBV_TO_TESTVIA_SPACING" "5.00,5.00,5.00,5.00,5.00,5.00,5.00,5.00,5.00,5.00,5.00,5.00,5.00,5.00"
					( Origin gBackEnd )
				)
				( attribute "SN_BONDPAD_TO_TESTVIA_SPACING" "5.00,5.00,5.00,5.00,5.00,5.00,5.00,5.00,5.00,5.00,5.00,5.00,5.00,5.00"
					( Origin gBackEnd )
				)
				( attribute "SN_LINE_TO_TESTVIA_SPACING" "5.00,5.00,5.00,5.00,5.00,5.00,5.00,5.00,5.00,5.00,5.00,5.00,5.00,5.00"
					( Origin gBackEnd )
				)
				( attribute "SN_SHAPE_TO_TESTVIA_SPACING" "5.00,5.00,5.00,5.00,5.00,5.00,5.00,5.00,5.00,5.00,5.00,5.00,5.00,5.00"
					( Origin gBackEnd )
				)
				( attribute "SN_BBV_TO_BBV_SPACING" "5.00,5.00,5.00,5.00,5.00,5.00,5.00,5.00,5.00,5.00,5.00,5.00,5.00,5.00"
					( Origin gBackEnd )
				)
				( attribute "SN_BONDPAD_TO_BBV_SPACING" "5.00,5.00,5.00,5.00,5.00,5.00,5.00,5.00,5.00,5.00,5.00,5.00,5.00,5.00"
					( Origin gBackEnd )
				)
				( attribute "SN_BBV_TO_LINE_SPACING" "5.00,5.00,5.00,5.00,5.00,5.00,5.00,5.00,5.00,5.00,5.00,5.00,5.00,5.00"
					( Origin gBackEnd )
				)
				( attribute "SN_BBV_TO_SHAPE_SPACING" "5.00,5.00,5.00,5.00,5.00,5.00,5.00,5.00,5.00,5.00,5.00,5.00,5.00,5.00"
					( Origin gBackEnd )
				)
				( attribute "SN_BONDPAD_TO_BONDPAD_SPACING" "5.00,5.00,5.00,5.00,5.00,5.00,5.00,5.00,5.00,5.00,5.00,5.00,5.00,5.00"
					( Origin gBackEnd )
				)
				( attribute "SN_BONDPAD_TO_LINE_SPACING" "5.00,5.00,5.00,5.00,5.00,5.00,5.00,5.00,5.00,5.00,5.00,5.00,5.00,5.00"
					( Origin gBackEnd )
				)
				( attribute "SN_BONDPAD_TO_SHAPE_SPACING" "5.00,5.00,5.00,5.00,5.00,5.00,5.00,5.00,5.00,5.00,5.00,5.00,5.00,5.00"
					( Origin gBackEnd )
				)
				( attribute "SN_LINE_TO_LINE_SPACING" "30.00,30.00,30.00,30.00,30.00,30.00,30.00,30.00,30.00,30.00,30.00,30.00,30.00,30.00"
					( Origin gBackEnd )
				)
				( attribute "SN_LINE_TO_SHAPE_SPACING" "5.00,5.00,5.00,5.00,5.00,5.00,5.00,5.00,5.00,5.00,5.00,5.00,5.00,5.00"
					( Origin gBackEnd )
				)
				( attribute "SN_SHAPE_TO_SHAPE_SPACING" "5.00,5.00,5.00,5.00,5.00,5.00,5.00,5.00,5.00,5.00,5.00,5.00,5.00,5.00"
					( Origin gBackEnd )
				)
				( attribute "SN_HOLE_TO_PIN_SPACING" "8.00,8.00,8.00,8.00,8.00,8.00,8.00,8.00,8.00,8.00,8.00,8.00,8.00,8.00"
					( Origin gBackEnd )
				)
				( attribute "SN_HOLE_TO_VIA_SPACING" "8.00,8.00,8.00,8.00,8.00,8.00,8.00,8.00,8.00,8.00,8.00,8.00,8.00,8.00"
					( Origin gBackEnd )
				)
				( attribute "SN_HOLE_TO_LINE_SPACING" "8.00,8.00,8.00,8.00,8.00,8.00,8.00,8.00,8.00,8.00,8.00,8.00,8.00,8.00"
					( Origin gBackEnd )
				)
				( attribute "SN_HOLE_TO_SHAPE_SPACING" "8.00,8.00,8.00,8.00,8.00,8.00,8.00,8.00,8.00,8.00,8.00,8.00,8.00,8.00"
					( Origin gBackEnd )
				)
				( attribute "SN_HOLE_TO_HOLE_SPACING" "8.00,8.00,8.00,8.00,8.00,8.00,8.00,8.00,8.00,8.00,8.00,8.00,8.00,8.00"
					( Origin gBackEnd )
				)
				( attribute "SN_MVIA_TO_MVIA_SPACING" "5.00,5.00,5.00,5.00,5.00,5.00,5.00,5.00,5.00,5.00,5.00,5.00,5.00,5.00"
					( Origin gBackEnd )
				)
				( attribute "SN_MVIA_TO_THRUPIN_SPACING" "5.00,5.00,5.00,5.00,5.00,5.00,5.00,5.00,5.00,5.00,5.00,5.00,5.00,5.00"
					( Origin gBackEnd )
				)
				( attribute "SN_MVIA_TO_SMDPIN_SPACING" "5.00,5.00,5.00,5.00,5.00,5.00,5.00,5.00,5.00,5.00,5.00,5.00,5.00,5.00"
					( Origin gBackEnd )
				)
				( attribute "SN_MVIA_TO_THRUVIA_SPACING" "5.00,5.00,5.00,5.00,5.00,5.00,5.00,5.00,5.00,5.00,5.00,5.00,5.00,5.00"
					( Origin gBackEnd )
				)
				( attribute "SN_MVIA_TO_BBV_SPACING" "5.00,5.00,5.00,5.00,5.00,5.00,5.00,5.00,5.00,5.00,5.00,5.00,5.00,5.00"
					( Origin gBackEnd )
				)
				( attribute "SN_MVIA_TO_LINE_SPACING" "5.00,5.00,5.00,5.00,5.00,5.00,5.00,5.00,5.00,5.00,5.00,5.00,5.00,5.00"
					( Origin gBackEnd )
				)
				( attribute "SN_MVIA_TO_SHAPE_SPACING" "5.00,5.00,5.00,5.00,5.00,5.00,5.00,5.00,5.00,5.00,5.00,5.00,5.00,5.00"
					( Origin gBackEnd )
				)
				( attribute "SN_MVIA_TO_TESTPIN_SPACING" "5.00,5.00,5.00,5.00,5.00,5.00,5.00,5.00,5.00,5.00,5.00,5.00,5.00,5.00"
					( Origin gBackEnd )
				)
				( attribute "SN_MVIA_TO_TESTVIA_SPACING" "5.00,5.00,5.00,5.00,5.00,5.00,5.00,5.00,5.00,5.00,5.00,5.00,5.00,5.00"
					( Origin gBackEnd )
				)
				( attribute "SN_BONDPAD_TO_MVIA_SPACING" "5.00,5.00,5.00,5.00,5.00,5.00,5.00,5.00,5.00,5.00,5.00,5.00,5.00,5.00"
					( Origin gBackEnd )
				)
				( objectStatus "30_MILS" )
			)
			( sameNetSpacingCSet "@crescent_city_bb_fab1_lib.crescent_city_bb_fab1(sch_1):\8_MILS\"
				( attribute "SAME_NET" "TRUE,TRUE,TRUE,TRUE,TRUE,TRUE,TRUE,TRUE,TRUE,TRUE,TRUE,TRUE,TRUE,TRUE"
					( Origin gBackEnd )
				)
				( attribute "SN_THRUPIN_TO_THRUPIN_SPACING" "5.00,5.00,5.00,5.00,5.00,5.00,5.00,5.00,5.00,5.00,5.00,5.00,5.00,5.00"
					( Origin gBackEnd )
				)
				( attribute "SN_THRUPIN_TO_SMDPIN_SPACING" "5.00,5.00,5.00,5.00,5.00,5.00,5.00,5.00,5.00,5.00,5.00,5.00,5.00,5.00"
					( Origin gBackEnd )
				)
				( attribute "SN_TESTPIN_TO_THRUPIN_SPACING" "5.00,5.00,5.00,5.00,5.00,5.00,5.00,5.00,5.00,5.00,5.00,5.00,5.00,5.00"
					( Origin gBackEnd )
				)
				( attribute "SN_THRUPIN_TO_THRUVIA_SPACING" "5.00,5.00,5.00,5.00,5.00,5.00,5.00,5.00,5.00,5.00,5.00,5.00,5.00,5.00"
					( Origin gBackEnd )
				)
				( attribute "SN_TESTVIA_TO_THRUPIN_SPACING" "5.00,5.00,5.00,5.00,5.00,5.00,5.00,5.00,5.00,5.00,5.00,5.00,5.00,5.00"
					( Origin gBackEnd )
				)
				( attribute "SN_BBV_TO_THRUPIN_SPACING" "5.00,5.00,5.00,5.00,5.00,5.00,5.00,5.00,5.00,5.00,5.00,5.00,5.00,5.00"
					( Origin gBackEnd )
				)
				( attribute "SN_THRUPIN_TO_BONDPAD_SPACING" "5.00,5.00,5.00,5.00,5.00,5.00,5.00,5.00,5.00,5.00,5.00,5.00,5.00,5.00"
					( Origin gBackEnd )
				)
				( attribute "SN_LINE_TO_THRUPIN_SPACING" "5.00,5.00,5.00,5.00,5.00,5.00,5.00,5.00,5.00,5.00,5.00,5.00,5.00,5.00"
					( Origin gBackEnd )
				)
				( attribute "SN_THRUPIN_TO_SHAPE_SPACING" "5.00,5.00,5.00,5.00,5.00,5.00,5.00,5.00,5.00,5.00,5.00,5.00,5.00,5.00"
					( Origin gBackEnd )
				)
				( attribute "SN_SMDPIN_TO_SMDPIN_SPACING" "5.00,5.00,5.00,5.00,5.00,5.00,5.00,5.00,5.00,5.00,5.00,5.00,5.00,5.00"
					( Origin gBackEnd )
				)
				( attribute "SN_SMDPIN_TO_TESTPIN_SPACING" "5.00,5.00,5.00,5.00,5.00,5.00,5.00,5.00,5.00,5.00,5.00,5.00,5.00,5.00"
					( Origin gBackEnd )
				)
				( attribute "SN_SMDPIN_TO_THRUVIA_SPACING" "4.00,4.00,4.00,4.00,4.00,4.00,4.00,4.00,4.00,4.00,4.00,4.00,4.00,4.00"
					( Origin gBackEnd )
				)
				( attribute "SN_SMDPIN_TO_TESTVIA_SPACING" "4.00,4.00,4.00,4.00,4.00,4.00,4.00,4.00,4.00,4.00,4.00,4.00,4.00,4.00"
					( Origin gBackEnd )
				)
				( attribute "SN_BBV_TO_SMDPIN_SPACING" "5.00,5.00,5.00,5.00,5.00,5.00,5.00,5.00,5.00,5.00,5.00,5.00,5.00,5.00"
					( Origin gBackEnd )
				)
				( attribute "SN_SMDPIN_TO_BONDPAD_SPACING" "5.00,5.00,5.00,5.00,5.00,5.00,5.00,5.00,5.00,5.00,5.00,5.00,5.00,5.00"
					( Origin gBackEnd )
				)
				( attribute "SN_LINE_TO_SMDPIN_SPACING" "4.50,4.50,4.50,4.50,4.50,4.50,4.50,4.50,4.50,4.50,4.50,4.50,4.50,4.50"
					( Origin gBackEnd )
				)
				( attribute "SN_SHAPE_TO_SMDPIN_SPACING" "5.00,5.00,5.00,5.00,5.00,5.00,5.00,5.00,5.00,5.00,5.00,5.00,5.00,5.00"
					( Origin gBackEnd )
				)
				( attribute "SN_TESTPIN_TO_TESTPIN_SPACING" "5.00,5.00,5.00,5.00,5.00,5.00,5.00,5.00,5.00,5.00,5.00,5.00,5.00,5.00"
					( Origin gBackEnd )
				)
				( attribute "SN_TESTPIN_TO_THRUVIA_SPACING" "5.00,5.00,5.00,5.00,5.00,5.00,5.00,5.00,5.00,5.00,5.00,5.00,5.00,5.00"
					( Origin gBackEnd )
				)
				( attribute "SN_TESTPIN_TO_TESTVIA_SPACING" "5.00,5.00,5.00,5.00,5.00,5.00,5.00,5.00,5.00,5.00,5.00,5.00,5.00,5.00"
					( Origin gBackEnd )
				)
				( attribute "SN_BBV_TO_TESTPIN_SPACING" "5.00,5.00,5.00,5.00,5.00,5.00,5.00,5.00,5.00,5.00,5.00,5.00,5.00,5.00"
					( Origin gBackEnd )
				)
				( attribute "SN_BONDPAD_TO_TESTPIN_SPACING" "5.00,5.00,5.00,5.00,5.00,5.00,5.00,5.00,5.00,5.00,5.00,5.00,5.00,5.00"
					( Origin gBackEnd )
				)
				( attribute "SN_LINE_TO_TESTPIN_SPACING" "5.00,5.00,5.00,5.00,5.00,5.00,5.00,5.00,5.00,5.00,5.00,5.00,5.00,5.00"
					( Origin gBackEnd )
				)
				( attribute "SN_SHAPE_TO_TESTPIN_SPACING" "5.00,5.00,5.00,5.00,5.00,5.00,5.00,5.00,5.00,5.00,5.00,5.00,5.00,5.00"
					( Origin gBackEnd )
				)
				( attribute "SN_THRUVIA_TO_THRUVIA_SPACING" "4.50,4.00,4.00,4.00,4.00,4.00,4.00,4.00,4.00,4.00,4.00,4.00,4.00,4.50"
					( Origin gBackEnd )
				)
				( attribute "SN_TESTVIA_TO_THRUVIA_SPACING" "5.00,5.00,5.00,5.00,5.00,5.00,5.00,5.00,5.00,5.00,5.00,5.00,5.00,5.00"
					( Origin gBackEnd )
				)
				( attribute "SN_BBV_TO_THRUVIA_SPACING" "5.00,5.00,5.00,5.00,5.00,5.00,5.00,5.00,5.00,5.00,5.00,5.00,5.00,5.00"
					( Origin gBackEnd )
				)
				( attribute "SN_BONDPAD_TO_THRUVIA_SPACING" "5.00,5.00,5.00,5.00,5.00,5.00,5.00,5.00,5.00,5.00,5.00,5.00,5.00,5.00"
					( Origin gBackEnd )
				)
				( attribute "SN_LINE_TO_THRUVIA_SPACING" "4.50,4.00,4.00,4.00,4.00,4.00,4.00,4.00,4.00,4.00,4.00,4.00,4.00,4.50"
					( Origin gBackEnd )
				)
				( attribute "SN_SHAPE_TO_THRUVIA_SPACING" "5.00,5.00,5.00,5.00,5.00,5.00,5.00,5.00,5.00,5.00,5.00,5.00,5.00,5.00"
					( Origin gBackEnd )
				)
				( attribute "SN_TESTVIA_TO_TESTVIA_SPACING" "5.00,5.00,5.00,5.00,5.00,5.00,5.00,5.00,5.00,5.00,5.00,5.00,5.00,5.00"
					( Origin gBackEnd )
				)
				( attribute "SN_BBV_TO_TESTVIA_SPACING" "5.00,5.00,5.00,5.00,5.00,5.00,5.00,5.00,5.00,5.00,5.00,5.00,5.00,5.00"
					( Origin gBackEnd )
				)
				( attribute "SN_BONDPAD_TO_TESTVIA_SPACING" "5.00,5.00,5.00,5.00,5.00,5.00,5.00,5.00,5.00,5.00,5.00,5.00,5.00,5.00"
					( Origin gBackEnd )
				)
				( attribute "SN_LINE_TO_TESTVIA_SPACING" "5.00,5.00,5.00,5.00,5.00,5.00,5.00,5.00,5.00,5.00,5.00,5.00,5.00,5.00"
					( Origin gBackEnd )
				)
				( attribute "SN_SHAPE_TO_TESTVIA_SPACING" "5.00,5.00,5.00,5.00,5.00,5.00,5.00,5.00,5.00,5.00,5.00,5.00,5.00,5.00"
					( Origin gBackEnd )
				)
				( attribute "SN_BBV_TO_BBV_SPACING" "5.00,5.00,5.00,5.00,5.00,5.00,5.00,5.00,5.00,5.00,5.00,5.00,5.00,5.00"
					( Origin gBackEnd )
				)
				( attribute "SN_BONDPAD_TO_BBV_SPACING" "5.00,5.00,5.00,5.00,5.00,5.00,5.00,5.00,5.00,5.00,5.00,5.00,5.00,5.00"
					( Origin gBackEnd )
				)
				( attribute "SN_BBV_TO_LINE_SPACING" "5.00,5.00,5.00,5.00,5.00,5.00,5.00,5.00,5.00,5.00,5.00,5.00,5.00,5.00"
					( Origin gBackEnd )
				)
				( attribute "SN_BBV_TO_SHAPE_SPACING" "5.00,5.00,5.00,5.00,5.00,5.00,5.00,5.00,5.00,5.00,5.00,5.00,5.00,5.00"
					( Origin gBackEnd )
				)
				( attribute "SN_BONDPAD_TO_BONDPAD_SPACING" "5.00,5.00,5.00,5.00,5.00,5.00,5.00,5.00,5.00,5.00,5.00,5.00,5.00,5.00"
					( Origin gBackEnd )
				)
				( attribute "SN_BONDPAD_TO_LINE_SPACING" "5.00,5.00,5.00,5.00,5.00,5.00,5.00,5.00,5.00,5.00,5.00,5.00,5.00,5.00"
					( Origin gBackEnd )
				)
				( attribute "SN_BONDPAD_TO_SHAPE_SPACING" "5.00,5.00,5.00,5.00,5.00,5.00,5.00,5.00,5.00,5.00,5.00,5.00,5.00,5.00"
					( Origin gBackEnd )
				)
				( attribute "SN_LINE_TO_LINE_SPACING" "8.00,8.00,8.00,8.00,8.00,8.00,8.00,8.00,8.00,8.00,8.00,8.00,8.00,8.00"
					( Origin gBackEnd )
				)
				( attribute "SN_LINE_TO_SHAPE_SPACING" "5.00,5.00,5.00,5.00,5.00,5.00,5.00,5.00,5.00,5.00,5.00,5.00,5.00,5.00"
					( Origin gBackEnd )
				)
				( attribute "SN_SHAPE_TO_SHAPE_SPACING" "5.00,5.00,5.00,5.00,5.00,5.00,5.00,5.00,5.00,5.00,5.00,5.00,5.00,5.00"
					( Origin gBackEnd )
				)
				( attribute "SN_HOLE_TO_PIN_SPACING" "8.00,8.00,8.00,8.00,8.00,8.00,8.00,8.00,8.00,8.00,8.00,8.00,8.00,8.00"
					( Origin gBackEnd )
				)
				( attribute "SN_HOLE_TO_VIA_SPACING" "8.00,8.00,8.00,8.00,8.00,8.00,8.00,8.00,8.00,8.00,8.00,8.00,8.00,8.00"
					( Origin gBackEnd )
				)
				( attribute "SN_HOLE_TO_LINE_SPACING" "8.00,8.00,8.00,8.00,8.00,8.00,8.00,8.00,8.00,8.00,8.00,8.00,8.00,8.00"
					( Origin gBackEnd )
				)
				( attribute "SN_HOLE_TO_SHAPE_SPACING" "8.00,8.00,8.00,8.00,8.00,8.00,8.00,8.00,8.00,8.00,8.00,8.00,8.00,8.00"
					( Origin gBackEnd )
				)
				( attribute "SN_HOLE_TO_HOLE_SPACING" "8.00,8.00,8.00,8.00,8.00,8.00,8.00,8.00,8.00,8.00,8.00,8.00,8.00,8.00"
					( Origin gBackEnd )
				)
				( attribute "SN_MVIA_TO_MVIA_SPACING" "5.00,5.00,5.00,5.00,5.00,5.00,5.00,5.00,5.00,5.00,5.00,5.00,5.00,5.00"
					( Origin gBackEnd )
				)
				( attribute "SN_MVIA_TO_THRUPIN_SPACING" "5.00,5.00,5.00,5.00,5.00,5.00,5.00,5.00,5.00,5.00,5.00,5.00,5.00,5.00"
					( Origin gBackEnd )
				)
				( attribute "SN_MVIA_TO_SMDPIN_SPACING" "5.00,5.00,5.00,5.00,5.00,5.00,5.00,5.00,5.00,5.00,5.00,5.00,5.00,5.00"
					( Origin gBackEnd )
				)
				( attribute "SN_MVIA_TO_THRUVIA_SPACING" "5.00,5.00,5.00,5.00,5.00,5.00,5.00,5.00,5.00,5.00,5.00,5.00,5.00,5.00"
					( Origin gBackEnd )
				)
				( attribute "SN_MVIA_TO_BBV_SPACING" "5.00,5.00,5.00,5.00,5.00,5.00,5.00,5.00,5.00,5.00,5.00,5.00,5.00,5.00"
					( Origin gBackEnd )
				)
				( attribute "SN_MVIA_TO_LINE_SPACING" "5.00,5.00,5.00,5.00,5.00,5.00,5.00,5.00,5.00,5.00,5.00,5.00,5.00,5.00"
					( Origin gBackEnd )
				)
				( attribute "SN_MVIA_TO_SHAPE_SPACING" "5.00,5.00,5.00,5.00,5.00,5.00,5.00,5.00,5.00,5.00,5.00,5.00,5.00,5.00"
					( Origin gBackEnd )
				)
				( attribute "SN_MVIA_TO_TESTPIN_SPACING" "5.00,5.00,5.00,5.00,5.00,5.00,5.00,5.00,5.00,5.00,5.00,5.00,5.00,5.00"
					( Origin gBackEnd )
				)
				( attribute "SN_MVIA_TO_TESTVIA_SPACING" "5.00,5.00,5.00,5.00,5.00,5.00,5.00,5.00,5.00,5.00,5.00,5.00,5.00,5.00"
					( Origin gBackEnd )
				)
				( attribute "SN_BONDPAD_TO_MVIA_SPACING" "5.00,5.00,5.00,5.00,5.00,5.00,5.00,5.00,5.00,5.00,5.00,5.00,5.00,5.00"
					( Origin gBackEnd )
				)
				( objectStatus "8_MILS" )
			)
			( sameNetSpacingCSet "@crescent_city_bb_fab1_lib.crescent_city_bb_fab1(sch_1):\10_MILS\"
				( attribute "SAME_NET" "TRUE,TRUE,TRUE,TRUE,TRUE,TRUE,TRUE,TRUE,TRUE,TRUE,TRUE,TRUE,TRUE,TRUE"
					( Origin gBackEnd )
				)
				( attribute "SN_THRUPIN_TO_THRUPIN_SPACING" "5.00,5.00,5.00,5.00,5.00,5.00,5.00,5.00,5.00,5.00,5.00,5.00,5.00,5.00"
					( Origin gBackEnd )
				)
				( attribute "SN_THRUPIN_TO_SMDPIN_SPACING" "5.00,5.00,5.00,5.00,5.00,5.00,5.00,5.00,5.00,5.00,5.00,5.00,5.00,5.00"
					( Origin gBackEnd )
				)
				( attribute "SN_TESTPIN_TO_THRUPIN_SPACING" "5.00,5.00,5.00,5.00,5.00,5.00,5.00,5.00,5.00,5.00,5.00,5.00,5.00,5.00"
					( Origin gBackEnd )
				)
				( attribute "SN_THRUPIN_TO_THRUVIA_SPACING" "5.00,5.00,5.00,5.00,5.00,5.00,5.00,5.00,5.00,5.00,5.00,5.00,5.00,5.00"
					( Origin gBackEnd )
				)
				( attribute "SN_TESTVIA_TO_THRUPIN_SPACING" "5.00,5.00,5.00,5.00,5.00,5.00,5.00,5.00,5.00,5.00,5.00,5.00,5.00,5.00"
					( Origin gBackEnd )
				)
				( attribute "SN_BBV_TO_THRUPIN_SPACING" "5.00,5.00,5.00,5.00,5.00,5.00,5.00,5.00,5.00,5.00,5.00,5.00,5.00,5.00"
					( Origin gBackEnd )
				)
				( attribute "SN_THRUPIN_TO_BONDPAD_SPACING" "5.00,5.00,5.00,5.00,5.00,5.00,5.00,5.00,5.00,5.00,5.00,5.00,5.00,5.00"
					( Origin gBackEnd )
				)
				( attribute "SN_LINE_TO_THRUPIN_SPACING" "5.00,5.00,5.00,5.00,5.00,5.00,5.00,5.00,5.00,5.00,5.00,5.00,5.00,5.00"
					( Origin gBackEnd )
				)
				( attribute "SN_THRUPIN_TO_SHAPE_SPACING" "5.00,5.00,5.00,5.00,5.00,5.00,5.00,5.00,5.00,5.00,5.00,5.00,5.00,5.00"
					( Origin gBackEnd )
				)
				( attribute "SN_SMDPIN_TO_SMDPIN_SPACING" "5.00,5.00,5.00,5.00,5.00,5.00,5.00,5.00,5.00,5.00,5.00,5.00,5.00,5.00"
					( Origin gBackEnd )
				)
				( attribute "SN_SMDPIN_TO_TESTPIN_SPACING" "5.00,5.00,5.00,5.00,5.00,5.00,5.00,5.00,5.00,5.00,5.00,5.00,5.00,5.00"
					( Origin gBackEnd )
				)
				( attribute "SN_SMDPIN_TO_THRUVIA_SPACING" "4.00,4.00,4.00,4.00,4.00,4.00,4.00,4.00,4.00,4.00,4.00,4.00,4.00,4.00"
					( Origin gBackEnd )
				)
				( attribute "SN_SMDPIN_TO_TESTVIA_SPACING" "4.00,4.00,4.00,4.00,4.00,4.00,4.00,4.00,4.00,4.00,4.00,4.00,4.00,4.00"
					( Origin gBackEnd )
				)
				( attribute "SN_BBV_TO_SMDPIN_SPACING" "5.00,5.00,5.00,5.00,5.00,5.00,5.00,5.00,5.00,5.00,5.00,5.00,5.00,5.00"
					( Origin gBackEnd )
				)
				( attribute "SN_SMDPIN_TO_BONDPAD_SPACING" "5.00,5.00,5.00,5.00,5.00,5.00,5.00,5.00,5.00,5.00,5.00,5.00,5.00,5.00"
					( Origin gBackEnd )
				)
				( attribute "SN_LINE_TO_SMDPIN_SPACING" "4.50,4.50,4.50,4.50,4.50,4.50,4.50,4.50,4.50,4.50,4.50,4.50,4.50,4.50"
					( Origin gBackEnd )
				)
				( attribute "SN_SHAPE_TO_SMDPIN_SPACING" "5.00,5.00,5.00,5.00,5.00,5.00,5.00,5.00,5.00,5.00,5.00,5.00,5.00,5.00"
					( Origin gBackEnd )
				)
				( attribute "SN_TESTPIN_TO_TESTPIN_SPACING" "5.00,5.00,5.00,5.00,5.00,5.00,5.00,5.00,5.00,5.00,5.00,5.00,5.00,5.00"
					( Origin gBackEnd )
				)
				( attribute "SN_TESTPIN_TO_THRUVIA_SPACING" "5.00,5.00,5.00,5.00,5.00,5.00,5.00,5.00,5.00,5.00,5.00,5.00,5.00,5.00"
					( Origin gBackEnd )
				)
				( attribute "SN_TESTPIN_TO_TESTVIA_SPACING" "5.00,5.00,5.00,5.00,5.00,5.00,5.00,5.00,5.00,5.00,5.00,5.00,5.00,5.00"
					( Origin gBackEnd )
				)
				( attribute "SN_BBV_TO_TESTPIN_SPACING" "5.00,5.00,5.00,5.00,5.00,5.00,5.00,5.00,5.00,5.00,5.00,5.00,5.00,5.00"
					( Origin gBackEnd )
				)
				( attribute "SN_BONDPAD_TO_TESTPIN_SPACING" "5.00,5.00,5.00,5.00,5.00,5.00,5.00,5.00,5.00,5.00,5.00,5.00,5.00,5.00"
					( Origin gBackEnd )
				)
				( attribute "SN_LINE_TO_TESTPIN_SPACING" "5.00,5.00,5.00,5.00,5.00,5.00,5.00,5.00,5.00,5.00,5.00,5.00,5.00,5.00"
					( Origin gBackEnd )
				)
				( attribute "SN_SHAPE_TO_TESTPIN_SPACING" "5.00,5.00,5.00,5.00,5.00,5.00,5.00,5.00,5.00,5.00,5.00,5.00,5.00,5.00"
					( Origin gBackEnd )
				)
				( attribute "SN_THRUVIA_TO_THRUVIA_SPACING" "4.00,4.00,4.00,4.00,4.00,4.00,4.00,4.00,4.00,4.00,4.00,4.00,4.00,4.00"
					( Origin gBackEnd )
				)
				( attribute "SN_TESTVIA_TO_THRUVIA_SPACING" "5.00,5.00,5.00,5.00,5.00,5.00,5.00,5.00,5.00,5.00,5.00,5.00,5.00,5.00"
					( Origin gBackEnd )
				)
				( attribute "SN_BBV_TO_THRUVIA_SPACING" "5.00,5.00,5.00,5.00,5.00,5.00,5.00,5.00,5.00,5.00,5.00,5.00,5.00,5.00"
					( Origin gBackEnd )
				)
				( attribute "SN_BONDPAD_TO_THRUVIA_SPACING" "5.00,5.00,5.00,5.00,5.00,5.00,5.00,5.00,5.00,5.00,5.00,5.00,5.00,5.00"
					( Origin gBackEnd )
				)
				( attribute "SN_LINE_TO_THRUVIA_SPACING" "4.00,4.00,4.00,4.00,4.00,4.00,4.00,4.00,4.00,4.00,4.00,4.00,4.00,4.00"
					( Origin gBackEnd )
				)
				( attribute "SN_SHAPE_TO_THRUVIA_SPACING" "5.00,5.00,5.00,5.00,5.00,5.00,5.00,5.00,5.00,5.00,5.00,5.00,5.00,5.00"
					( Origin gBackEnd )
				)
				( attribute "SN_TESTVIA_TO_TESTVIA_SPACING" "5.00,5.00,5.00,5.00,5.00,5.00,5.00,5.00,5.00,5.00,5.00,5.00,5.00,5.00"
					( Origin gBackEnd )
				)
				( attribute "SN_BBV_TO_TESTVIA_SPACING" "5.00,5.00,5.00,5.00,5.00,5.00,5.00,5.00,5.00,5.00,5.00,5.00,5.00,5.00"
					( Origin gBackEnd )
				)
				( attribute "SN_BONDPAD_TO_TESTVIA_SPACING" "5.00,5.00,5.00,5.00,5.00,5.00,5.00,5.00,5.00,5.00,5.00,5.00,5.00,5.00"
					( Origin gBackEnd )
				)
				( attribute "SN_LINE_TO_TESTVIA_SPACING" "5.00,5.00,5.00,5.00,5.00,5.00,5.00,5.00,5.00,5.00,5.00,5.00,5.00,5.00"
					( Origin gBackEnd )
				)
				( attribute "SN_SHAPE_TO_TESTVIA_SPACING" "5.00,5.00,5.00,5.00,5.00,5.00,5.00,5.00,5.00,5.00,5.00,5.00,5.00,5.00"
					( Origin gBackEnd )
				)
				( attribute "SN_BBV_TO_BBV_SPACING" "5.00,5.00,5.00,5.00,5.00,5.00,5.00,5.00,5.00,5.00,5.00,5.00,5.00,5.00"
					( Origin gBackEnd )
				)
				( attribute "SN_BONDPAD_TO_BBV_SPACING" "5.00,5.00,5.00,5.00,5.00,5.00,5.00,5.00,5.00,5.00,5.00,5.00,5.00,5.00"
					( Origin gBackEnd )
				)
				( attribute "SN_BBV_TO_LINE_SPACING" "5.00,5.00,5.00,5.00,5.00,5.00,5.00,5.00,5.00,5.00,5.00,5.00,5.00,5.00"
					( Origin gBackEnd )
				)
				( attribute "SN_BBV_TO_SHAPE_SPACING" "5.00,5.00,5.00,5.00,5.00,5.00,5.00,5.00,5.00,5.00,5.00,5.00,5.00,5.00"
					( Origin gBackEnd )
				)
				( attribute "SN_BONDPAD_TO_BONDPAD_SPACING" "5.00,5.00,5.00,5.00,5.00,5.00,5.00,5.00,5.00,5.00,5.00,5.00,5.00,5.00"
					( Origin gBackEnd )
				)
				( attribute "SN_BONDPAD_TO_LINE_SPACING" "5.00,5.00,5.00,5.00,5.00,5.00,5.00,5.00,5.00,5.00,5.00,5.00,5.00,5.00"
					( Origin gBackEnd )
				)
				( attribute "SN_BONDPAD_TO_SHAPE_SPACING" "5.00,5.00,5.00,5.00,5.00,5.00,5.00,5.00,5.00,5.00,5.00,5.00,5.00,5.00"
					( Origin gBackEnd )
				)
				( attribute "SN_LINE_TO_LINE_SPACING" "10.00,10.00,10.00,10.00,10.00,10.00,10.00,10.00,10.00,10.00,10.00,10.00,10.00,10.00"
					( Origin gBackEnd )
				)
				( attribute "SN_LINE_TO_SHAPE_SPACING" "5.00,5.00,5.00,5.00,5.00,5.00,5.00,5.00,5.00,5.00,5.00,5.00,5.00,5.00"
					( Origin gBackEnd )
				)
				( attribute "SN_SHAPE_TO_SHAPE_SPACING" "5.00,5.00,5.00,5.00,5.00,5.00,5.00,5.00,5.00,5.00,5.00,5.00,5.00,5.00"
					( Origin gBackEnd )
				)
				( attribute "SN_HOLE_TO_PIN_SPACING" "8.00,8.00,8.00,8.00,8.00,8.00,8.00,8.00,8.00,8.00,8.00,8.00,8.00,8.00"
					( Origin gBackEnd )
				)
				( attribute "SN_HOLE_TO_VIA_SPACING" "8.00,8.00,8.00,8.00,8.00,8.00,8.00,8.00,8.00,8.00,8.00,8.00,8.00,8.00"
					( Origin gBackEnd )
				)
				( attribute "SN_HOLE_TO_LINE_SPACING" "8.00,8.00,8.00,8.00,8.00,8.00,8.00,8.00,8.00,8.00,8.00,8.00,8.00,8.00"
					( Origin gBackEnd )
				)
				( attribute "SN_HOLE_TO_SHAPE_SPACING" "8.00,8.00,8.00,8.00,8.00,8.00,8.00,8.00,8.00,8.00,8.00,8.00,8.00,8.00"
					( Origin gBackEnd )
				)
				( attribute "SN_HOLE_TO_HOLE_SPACING" "8.00,8.00,8.00,8.00,8.00,8.00,8.00,8.00,8.00,8.00,8.00,8.00,8.00,8.00"
					( Origin gBackEnd )
				)
				( attribute "SN_MVIA_TO_MVIA_SPACING" "5.00,5.00,5.00,5.00,5.00,5.00,5.00,5.00,5.00,5.00,5.00,5.00,5.00,5.00"
					( Origin gBackEnd )
				)
				( attribute "SN_MVIA_TO_THRUPIN_SPACING" "5.00,5.00,5.00,5.00,5.00,5.00,5.00,5.00,5.00,5.00,5.00,5.00,5.00,5.00"
					( Origin gBackEnd )
				)
				( attribute "SN_MVIA_TO_SMDPIN_SPACING" "5.00,5.00,5.00,5.00,5.00,5.00,5.00,5.00,5.00,5.00,5.00,5.00,5.00,5.00"
					( Origin gBackEnd )
				)
				( attribute "SN_MVIA_TO_THRUVIA_SPACING" "5.00,5.00,5.00,5.00,5.00,5.00,5.00,5.00,5.00,5.00,5.00,5.00,5.00,5.00"
					( Origin gBackEnd )
				)
				( attribute "SN_MVIA_TO_BBV_SPACING" "5.00,5.00,5.00,5.00,5.00,5.00,5.00,5.00,5.00,5.00,5.00,5.00,5.00,5.00"
					( Origin gBackEnd )
				)
				( attribute "SN_MVIA_TO_LINE_SPACING" "5.00,5.00,5.00,5.00,5.00,5.00,5.00,5.00,5.00,5.00,5.00,5.00,5.00,5.00"
					( Origin gBackEnd )
				)
				( attribute "SN_MVIA_TO_SHAPE_SPACING" "5.00,5.00,5.00,5.00,5.00,5.00,5.00,5.00,5.00,5.00,5.00,5.00,5.00,5.00"
					( Origin gBackEnd )
				)
				( attribute "SN_MVIA_TO_TESTPIN_SPACING" "5.00,5.00,5.00,5.00,5.00,5.00,5.00,5.00,5.00,5.00,5.00,5.00,5.00,5.00"
					( Origin gBackEnd )
				)
				( attribute "SN_MVIA_TO_TESTVIA_SPACING" "5.00,5.00,5.00,5.00,5.00,5.00,5.00,5.00,5.00,5.00,5.00,5.00,5.00,5.00"
					( Origin gBackEnd )
				)
				( attribute "SN_BONDPAD_TO_MVIA_SPACING" "5.00,5.00,5.00,5.00,5.00,5.00,5.00,5.00,5.00,5.00,5.00,5.00,5.00,5.00"
					( Origin gBackEnd )
				)
				( objectStatus "10_MILS" )
			)
			( sameNetSpacingCSet "@crescent_city_bb_fab1_lib.crescent_city_bb_fab1(sch_1):\3H\"
				( attribute "SAME_NET" "TRUE,TRUE,TRUE,TRUE,TRUE,TRUE,TRUE,TRUE,TRUE,TRUE,TRUE,TRUE,TRUE,TRUE"
					( Origin gBackEnd )
				)
				( attribute "SN_THRUPIN_TO_THRUPIN_SPACING" "5.00,5.00,5.00,5.00,5.00,5.00,5.00,5.00,5.00,5.00,5.00,5.00,5.00,5.00"
					( Origin gBackEnd )
				)
				( attribute "SN_THRUPIN_TO_SMDPIN_SPACING" "5.00,5.00,5.00,5.00,5.00,5.00,5.00,5.00,5.00,5.00,5.00,5.00,5.00,5.00"
					( Origin gBackEnd )
				)
				( attribute "SN_TESTPIN_TO_THRUPIN_SPACING" "5.00,5.00,5.00,5.00,5.00,5.00,5.00,5.00,5.00,5.00,5.00,5.00,5.00,5.00"
					( Origin gBackEnd )
				)
				( attribute "SN_THRUPIN_TO_THRUVIA_SPACING" "5.00,5.00,5.00,5.00,5.00,5.00,5.00,5.00,5.00,5.00,5.00,5.00,5.00,5.00"
					( Origin gBackEnd )
				)
				( attribute "SN_TESTVIA_TO_THRUPIN_SPACING" "5.00,5.00,5.00,5.00,5.00,5.00,5.00,5.00,5.00,5.00,5.00,5.00,5.00,5.00"
					( Origin gBackEnd )
				)
				( attribute "SN_BBV_TO_THRUPIN_SPACING" "5.00,5.00,5.00,5.00,5.00,5.00,5.00,5.00,5.00,5.00,5.00,5.00,5.00,5.00"
					( Origin gBackEnd )
				)
				( attribute "SN_THRUPIN_TO_BONDPAD_SPACING" "5.00,5.00,5.00,5.00,5.00,5.00,5.00,5.00,5.00,5.00,5.00,5.00,5.00,5.00"
					( Origin gBackEnd )
				)
				( attribute "SN_LINE_TO_THRUPIN_SPACING" "5.00,5.00,5.00,5.00,5.00,5.00,5.00,5.00,5.00,5.00,5.00,5.00,5.00,5.00"
					( Origin gBackEnd )
				)
				( attribute "SN_THRUPIN_TO_SHAPE_SPACING" "5.00,5.00,5.00,5.00,5.00,5.00,5.00,5.00,5.00,5.00,5.00,5.00,5.00,5.00"
					( Origin gBackEnd )
				)
				( attribute "SN_SMDPIN_TO_SMDPIN_SPACING" "5.00,5.00,5.00,5.00,5.00,5.00,5.00,5.00,5.00,5.00,5.00,5.00,5.00,5.00"
					( Origin gBackEnd )
				)
				( attribute "SN_SMDPIN_TO_TESTPIN_SPACING" "5.00,5.00,5.00,5.00,5.00,5.00,5.00,5.00,5.00,5.00,5.00,5.00,5.00,5.00"
					( Origin gBackEnd )
				)
				( attribute "SN_SMDPIN_TO_THRUVIA_SPACING" "4.00,4.00,4.00,4.00,4.00,4.00,4.00,4.00,4.00,4.00,4.00,4.00,4.00,4.00"
					( Origin gBackEnd )
				)
				( attribute "SN_SMDPIN_TO_TESTVIA_SPACING" "4.00,4.00,4.00,4.00,4.00,4.00,4.00,4.00,4.00,4.00,4.00,4.00,4.00,4.00"
					( Origin gBackEnd )
				)
				( attribute "SN_BBV_TO_SMDPIN_SPACING" "5.00,5.00,5.00,5.00,5.00,5.00,5.00,5.00,5.00,5.00,5.00,5.00,5.00,5.00"
					( Origin gBackEnd )
				)
				( attribute "SN_SMDPIN_TO_BONDPAD_SPACING" "5.00,5.00,5.00,5.00,5.00,5.00,5.00,5.00,5.00,5.00,5.00,5.00,5.00,5.00"
					( Origin gBackEnd )
				)
				( attribute "SN_LINE_TO_SMDPIN_SPACING" "4.50,4.50,4.50,4.50,4.50,4.50,4.50,4.50,4.50,4.50,4.50,4.50,4.50,4.50"
					( Origin gBackEnd )
				)
				( attribute "SN_SHAPE_TO_SMDPIN_SPACING" "5.00,5.00,5.00,5.00,5.00,5.00,5.00,5.00,5.00,5.00,5.00,5.00,5.00,5.00"
					( Origin gBackEnd )
				)
				( attribute "SN_TESTPIN_TO_TESTPIN_SPACING" "5.00,5.00,5.00,5.00,5.00,5.00,5.00,5.00,5.00,5.00,5.00,5.00,5.00,5.00"
					( Origin gBackEnd )
				)
				( attribute "SN_TESTPIN_TO_THRUVIA_SPACING" "5.00,5.00,5.00,5.00,5.00,5.00,5.00,5.00,5.00,5.00,5.00,5.00,5.00,5.00"
					( Origin gBackEnd )
				)
				( attribute "SN_TESTPIN_TO_TESTVIA_SPACING" "5.00,5.00,5.00,5.00,5.00,5.00,5.00,5.00,5.00,5.00,5.00,5.00,5.00,5.00"
					( Origin gBackEnd )
				)
				( attribute "SN_BBV_TO_TESTPIN_SPACING" "5.00,5.00,5.00,5.00,5.00,5.00,5.00,5.00,5.00,5.00,5.00,5.00,5.00,5.00"
					( Origin gBackEnd )
				)
				( attribute "SN_BONDPAD_TO_TESTPIN_SPACING" "5.00,5.00,5.00,5.00,5.00,5.00,5.00,5.00,5.00,5.00,5.00,5.00,5.00,5.00"
					( Origin gBackEnd )
				)
				( attribute "SN_LINE_TO_TESTPIN_SPACING" "5.00,5.00,5.00,5.00,5.00,5.00,5.00,5.00,5.00,5.00,5.00,5.00,5.00,5.00"
					( Origin gBackEnd )
				)
				( attribute "SN_SHAPE_TO_TESTPIN_SPACING" "5.00,5.00,5.00,5.00,5.00,5.00,5.00,5.00,5.00,5.00,5.00,5.00,5.00,5.00"
					( Origin gBackEnd )
				)
				( attribute "SN_THRUVIA_TO_THRUVIA_SPACING" "4.50,4.00,4.00,4.00,4.00,4.00,4.00,4.00,4.00,4.00,4.00,4.00,4.00,4.50"
					( Origin gBackEnd )
				)
				( attribute "SN_TESTVIA_TO_THRUVIA_SPACING" "5.00,5.00,5.00,5.00,5.00,5.00,5.00,5.00,5.00,5.00,5.00,5.00,5.00,5.00"
					( Origin gBackEnd )
				)
				( attribute "SN_BBV_TO_THRUVIA_SPACING" "5.00,5.00,5.00,5.00,5.00,5.00,5.00,5.00,5.00,5.00,5.00,5.00,5.00,5.00"
					( Origin gBackEnd )
				)
				( attribute "SN_BONDPAD_TO_THRUVIA_SPACING" "5.00,5.00,5.00,5.00,5.00,5.00,5.00,5.00,5.00,5.00,5.00,5.00,5.00,5.00"
					( Origin gBackEnd )
				)
				( attribute "SN_LINE_TO_THRUVIA_SPACING" "4.50,4.00,4.00,4.00,4.00,4.00,4.00,4.00,4.00,4.00,4.00,4.00,4.00,4.50"
					( Origin gBackEnd )
				)
				( attribute "SN_SHAPE_TO_THRUVIA_SPACING" "5.00,5.00,5.00,5.00,5.00,5.00,5.00,5.00,5.00,5.00,5.00,5.00,5.00,5.00"
					( Origin gBackEnd )
				)
				( attribute "SN_TESTVIA_TO_TESTVIA_SPACING" "5.00,5.00,5.00,5.00,5.00,5.00,5.00,5.00,5.00,5.00,5.00,5.00,5.00,5.00"
					( Origin gBackEnd )
				)
				( attribute "SN_BBV_TO_TESTVIA_SPACING" "5.00,5.00,5.00,5.00,5.00,5.00,5.00,5.00,5.00,5.00,5.00,5.00,5.00,5.00"
					( Origin gBackEnd )
				)
				( attribute "SN_BONDPAD_TO_TESTVIA_SPACING" "5.00,5.00,5.00,5.00,5.00,5.00,5.00,5.00,5.00,5.00,5.00,5.00,5.00,5.00"
					( Origin gBackEnd )
				)
				( attribute "SN_LINE_TO_TESTVIA_SPACING" "5.00,5.00,5.00,5.00,5.00,5.00,5.00,5.00,5.00,5.00,5.00,5.00,5.00,5.00"
					( Origin gBackEnd )
				)
				( attribute "SN_SHAPE_TO_TESTVIA_SPACING" "5.00,5.00,5.00,5.00,5.00,5.00,5.00,5.00,5.00,5.00,5.00,5.00,5.00,5.00"
					( Origin gBackEnd )
				)
				( attribute "SN_BBV_TO_BBV_SPACING" "5.00,5.00,5.00,5.00,5.00,5.00,5.00,5.00,5.00,5.00,5.00,5.00,5.00,5.00"
					( Origin gBackEnd )
				)
				( attribute "SN_BONDPAD_TO_BBV_SPACING" "5.00,5.00,5.00,5.00,5.00,5.00,5.00,5.00,5.00,5.00,5.00,5.00,5.00,5.00"
					( Origin gBackEnd )
				)
				( attribute "SN_BBV_TO_LINE_SPACING" "5.00,5.00,5.00,5.00,5.00,5.00,5.00,5.00,5.00,5.00,5.00,5.00,5.00,5.00"
					( Origin gBackEnd )
				)
				( attribute "SN_BBV_TO_SHAPE_SPACING" "5.00,5.00,5.00,5.00,5.00,5.00,5.00,5.00,5.00,5.00,5.00,5.00,5.00,5.00"
					( Origin gBackEnd )
				)
				( attribute "SN_BONDPAD_TO_BONDPAD_SPACING" "5.00,5.00,5.00,5.00,5.00,5.00,5.00,5.00,5.00,5.00,5.00,5.00,5.00,5.00"
					( Origin gBackEnd )
				)
				( attribute "SN_BONDPAD_TO_LINE_SPACING" "5.00,5.00,5.00,5.00,5.00,5.00,5.00,5.00,5.00,5.00,5.00,5.00,5.00,5.00"
					( Origin gBackEnd )
				)
				( attribute "SN_BONDPAD_TO_SHAPE_SPACING" "5.00,5.00,5.00,5.00,5.00,5.00,5.00,5.00,5.00,5.00,5.00,5.00,5.00,5.00"
					( Origin gBackEnd )
				)
				( attribute "SN_LINE_TO_LINE_SPACING" "8.10,9.00,9.00,9.00,9.00,9.00,9.00,9.00,9.00,9.00,9.00,9.00,9.00,8.10"
					( Origin gBackEnd )
				)
				( attribute "SN_LINE_TO_SHAPE_SPACING" "5.00,5.00,5.00,5.00,5.00,5.00,5.00,5.00,5.00,5.00,5.00,5.00,5.00,5.00"
					( Origin gBackEnd )
				)
				( attribute "SN_SHAPE_TO_SHAPE_SPACING" "5.00,5.00,5.00,5.00,5.00,5.00,5.00,5.00,5.00,5.00,5.00,5.00,5.00,5.00"
					( Origin gBackEnd )
				)
				( attribute "SN_HOLE_TO_PIN_SPACING" "8.00,8.00,8.00,8.00,8.00,8.00,8.00,8.00,8.00,8.00,8.00,8.00,8.00,8.00"
					( Origin gBackEnd )
				)
				( attribute "SN_HOLE_TO_VIA_SPACING" "8.00,8.00,8.00,8.00,8.00,8.00,8.00,8.00,8.00,8.00,8.00,8.00,8.00,8.00"
					( Origin gBackEnd )
				)
				( attribute "SN_HOLE_TO_LINE_SPACING" "8.00,8.00,8.00,8.00,8.00,8.00,8.00,8.00,8.00,8.00,8.00,8.00,8.00,8.00"
					( Origin gBackEnd )
				)
				( attribute "SN_HOLE_TO_SHAPE_SPACING" "8.00,8.00,8.00,8.00,8.00,8.00,8.00,8.00,8.00,8.00,8.00,8.00,8.00,8.00"
					( Origin gBackEnd )
				)
				( attribute "SN_HOLE_TO_HOLE_SPACING" "8.00,8.00,8.00,8.00,8.00,8.00,8.00,8.00,8.00,8.00,8.00,8.00,8.00,8.00"
					( Origin gBackEnd )
				)
				( attribute "SN_MVIA_TO_MVIA_SPACING" "5.00,5.00,5.00,5.00,5.00,5.00,5.00,5.00,5.00,5.00,5.00,5.00,5.00,5.00"
					( Origin gBackEnd )
				)
				( attribute "SN_MVIA_TO_THRUPIN_SPACING" "5.00,5.00,5.00,5.00,5.00,5.00,5.00,5.00,5.00,5.00,5.00,5.00,5.00,5.00"
					( Origin gBackEnd )
				)
				( attribute "SN_MVIA_TO_SMDPIN_SPACING" "5.00,5.00,5.00,5.00,5.00,5.00,5.00,5.00,5.00,5.00,5.00,5.00,5.00,5.00"
					( Origin gBackEnd )
				)
				( attribute "SN_MVIA_TO_THRUVIA_SPACING" "5.00,5.00,5.00,5.00,5.00,5.00,5.00,5.00,5.00,5.00,5.00,5.00,5.00,5.00"
					( Origin gBackEnd )
				)
				( attribute "SN_MVIA_TO_BBV_SPACING" "5.00,5.00,5.00,5.00,5.00,5.00,5.00,5.00,5.00,5.00,5.00,5.00,5.00,5.00"
					( Origin gBackEnd )
				)
				( attribute "SN_MVIA_TO_LINE_SPACING" "5.00,5.00,5.00,5.00,5.00,5.00,5.00,5.00,5.00,5.00,5.00,5.00,5.00,5.00"
					( Origin gBackEnd )
				)
				( attribute "SN_MVIA_TO_SHAPE_SPACING" "5.00,5.00,5.00,5.00,5.00,5.00,5.00,5.00,5.00,5.00,5.00,5.00,5.00,5.00"
					( Origin gBackEnd )
				)
				( attribute "SN_MVIA_TO_TESTPIN_SPACING" "5.00,5.00,5.00,5.00,5.00,5.00,5.00,5.00,5.00,5.00,5.00,5.00,5.00,5.00"
					( Origin gBackEnd )
				)
				( attribute "SN_MVIA_TO_TESTVIA_SPACING" "5.00,5.00,5.00,5.00,5.00,5.00,5.00,5.00,5.00,5.00,5.00,5.00,5.00,5.00"
					( Origin gBackEnd )
				)
				( attribute "SN_BONDPAD_TO_MVIA_SPACING" "5.00,5.00,5.00,5.00,5.00,5.00,5.00,5.00,5.00,5.00,5.00,5.00,5.00,5.00"
					( Origin gBackEnd )
				)
				( objectStatus "3H" )
			)
			( sameNetSpacingCSet "@crescent_city_bb_fab1_lib.crescent_city_bb_fab1(sch_1):\5H_SL\"
				( attribute "SAME_NET" "TRUE,TRUE,TRUE,TRUE,TRUE,TRUE,TRUE,TRUE,TRUE,TRUE,TRUE,TRUE,TRUE,TRUE"
					( Origin gBackEnd )
				)
				( attribute "SN_THRUPIN_TO_THRUPIN_SPACING" "5.00,5.00,5.00,5.00,5.00,5.00,5.00,5.00,5.00,5.00,5.00,5.00,5.00,5.00"
					( Origin gBackEnd )
				)
				( attribute "SN_THRUPIN_TO_SMDPIN_SPACING" "5.00,5.00,5.00,5.00,5.00,5.00,5.00,5.00,5.00,5.00,5.00,5.00,5.00,5.00"
					( Origin gBackEnd )
				)
				( attribute "SN_TESTPIN_TO_THRUPIN_SPACING" "5.00,5.00,5.00,5.00,5.00,5.00,5.00,5.00,5.00,5.00,5.00,5.00,5.00,5.00"
					( Origin gBackEnd )
				)
				( attribute "SN_THRUPIN_TO_THRUVIA_SPACING" "5.00,5.00,5.00,5.00,5.00,5.00,5.00,5.00,5.00,5.00,5.00,5.00,5.00,5.00"
					( Origin gBackEnd )
				)
				( attribute "SN_TESTVIA_TO_THRUPIN_SPACING" "5.00,5.00,5.00,5.00,5.00,5.00,5.00,5.00,5.00,5.00,5.00,5.00,5.00,5.00"
					( Origin gBackEnd )
				)
				( attribute "SN_BBV_TO_THRUPIN_SPACING" "5.00,5.00,5.00,5.00,5.00,5.00,5.00,5.00,5.00,5.00,5.00,5.00,5.00,5.00"
					( Origin gBackEnd )
				)
				( attribute "SN_THRUPIN_TO_BONDPAD_SPACING" "5.00,5.00,5.00,5.00,5.00,5.00,5.00,5.00,5.00,5.00,5.00,5.00,5.00,5.00"
					( Origin gBackEnd )
				)
				( attribute "SN_LINE_TO_THRUPIN_SPACING" "4.50,4.00,4.00,4.00,4.00,4.00,4.00,4.00,4.00,4.00,4.00,4.00,4.00,4.50"
					( Origin gBackEnd )
				)
				( attribute "SN_THRUPIN_TO_SHAPE_SPACING" "5.00,5.00,5.00,5.00,5.00,5.00,5.00,5.00,5.00,5.00,5.00,5.00,5.00,5.00"
					( Origin gBackEnd )
				)
				( attribute "SN_SMDPIN_TO_SMDPIN_SPACING" "5.00,5.00,5.00,5.00,5.00,5.00,5.00,5.00,5.00,5.00,5.00,5.00,5.00,5.00"
					( Origin gBackEnd )
				)
				( attribute "SN_SMDPIN_TO_TESTPIN_SPACING" "5.00,5.00,5.00,5.00,5.00,5.00,5.00,5.00,5.00,5.00,5.00,5.00,5.00,5.00"
					( Origin gBackEnd )
				)
				( attribute "SN_SMDPIN_TO_THRUVIA_SPACING" "5.00,5.00,5.00,5.00,5.00,5.00,5.00,5.00,5.00,5.00,5.00,5.00,5.00,5.00"
					( Origin gBackEnd )
				)
				( attribute "SN_SMDPIN_TO_TESTVIA_SPACING" "5.00,5.00,5.00,5.00,5.00,5.00,5.00,5.00,5.00,5.00,5.00,5.00,5.00,5.00"
					( Origin gBackEnd )
				)
				( attribute "SN_BBV_TO_SMDPIN_SPACING" "5.00,5.00,5.00,5.00,5.00,5.00,5.00,5.00,5.00,5.00,5.00,5.00,5.00,5.00"
					( Origin gBackEnd )
				)
				( attribute "SN_SMDPIN_TO_BONDPAD_SPACING" "5.00,5.00,5.00,5.00,5.00,5.00,5.00,5.00,5.00,5.00,5.00,5.00,5.00,5.00"
					( Origin gBackEnd )
				)
				( attribute "SN_LINE_TO_SMDPIN_SPACING" "4.50,4.50,4.50,4.50,4.50,4.50,4.50,4.50,4.50,4.50,4.50,4.50,4.50,4.50"
					( Origin gBackEnd )
				)
				( attribute "SN_SHAPE_TO_SMDPIN_SPACING" "5.00,5.00,5.00,5.00,5.00,5.00,5.00,5.00,5.00,5.00,5.00,5.00,5.00,5.00"
					( Origin gBackEnd )
				)
				( attribute "SN_TESTPIN_TO_TESTPIN_SPACING" "5.00,5.00,5.00,5.00,5.00,5.00,5.00,5.00,5.00,5.00,5.00,5.00,5.00,5.00"
					( Origin gBackEnd )
				)
				( attribute "SN_TESTPIN_TO_THRUVIA_SPACING" "5.00,5.00,5.00,5.00,5.00,5.00,5.00,5.00,5.00,5.00,5.00,5.00,5.00,5.00"
					( Origin gBackEnd )
				)
				( attribute "SN_TESTPIN_TO_TESTVIA_SPACING" "5.00,5.00,5.00,5.00,5.00,5.00,5.00,5.00,5.00,5.00,5.00,5.00,5.00,5.00"
					( Origin gBackEnd )
				)
				( attribute "SN_BBV_TO_TESTPIN_SPACING" "5.00,5.00,5.00,5.00,5.00,5.00,5.00,5.00,5.00,5.00,5.00,5.00,5.00,5.00"
					( Origin gBackEnd )
				)
				( attribute "SN_BONDPAD_TO_TESTPIN_SPACING" "5.00,5.00,5.00,5.00,5.00,5.00,5.00,5.00,5.00,5.00,5.00,5.00,5.00,5.00"
					( Origin gBackEnd )
				)
				( attribute "SN_LINE_TO_TESTPIN_SPACING" "5.00,4.00,4.00,4.00,4.00,4.00,4.00,4.00,4.00,4.00,4.00,4.00,4.00,5.00"
					( Origin gBackEnd )
				)
				( attribute "SN_SHAPE_TO_TESTPIN_SPACING" "5.00,5.00,5.00,5.00,5.00,5.00,5.00,5.00,5.00,5.00,5.00,5.00,5.00,5.00"
					( Origin gBackEnd )
				)
				( attribute "SN_THRUVIA_TO_THRUVIA_SPACING" "4.50,4.00,4.00,4.00,4.00,4.00,4.00,4.00,4.00,4.00,4.00,4.00,4.00,4.50"
					( Origin gBackEnd )
				)
				( attribute "SN_TESTVIA_TO_THRUVIA_SPACING" "5.00,5.00,5.00,5.00,5.00,5.00,5.00,5.00,5.00,5.00,5.00,5.00,5.00,5.00"
					( Origin gBackEnd )
				)
				( attribute "SN_BBV_TO_THRUVIA_SPACING" "5.00,5.00,5.00,5.00,5.00,5.00,5.00,5.00,5.00,5.00,5.00,5.00,5.00,5.00"
					( Origin gBackEnd )
				)
				( attribute "SN_BONDPAD_TO_THRUVIA_SPACING" "5.00,5.00,5.00,5.00,5.00,5.00,5.00,5.00,5.00,5.00,5.00,5.00,5.00,5.00"
					( Origin gBackEnd )
				)
				( attribute "SN_LINE_TO_THRUVIA_SPACING" "4.50,4.00,4.00,4.00,4.00,4.00,4.00,4.00,4.00,4.00,4.00,4.00,4.00,4.50"
					( Origin gBackEnd )
				)
				( attribute "SN_SHAPE_TO_THRUVIA_SPACING" "5.00,5.00,5.00,5.00,5.00,5.00,5.00,5.00,5.00,5.00,5.00,5.00,5.00,5.00"
					( Origin gBackEnd )
				)
				( attribute "SN_TESTVIA_TO_TESTVIA_SPACING" "5.00,5.00,5.00,5.00,5.00,5.00,5.00,5.00,5.00,5.00,5.00,5.00,5.00,5.00"
					( Origin gBackEnd )
				)
				( attribute "SN_BBV_TO_TESTVIA_SPACING" "5.00,5.00,5.00,5.00,5.00,5.00,5.00,5.00,5.00,5.00,5.00,5.00,5.00,5.00"
					( Origin gBackEnd )
				)
				( attribute "SN_BONDPAD_TO_TESTVIA_SPACING" "5.00,5.00,5.00,5.00,5.00,5.00,5.00,5.00,5.00,5.00,5.00,5.00,5.00,5.00"
					( Origin gBackEnd )
				)
				( attribute "SN_LINE_TO_TESTVIA_SPACING" "5.00,4.00,4.00,4.00,4.00,4.00,4.00,4.00,4.00,4.00,4.00,4.00,4.00,5.00"
					( Origin gBackEnd )
				)
				( attribute "SN_SHAPE_TO_TESTVIA_SPACING" "5.00,5.00,5.00,5.00,5.00,5.00,5.00,5.00,5.00,5.00,5.00,5.00,5.00,5.00"
					( Origin gBackEnd )
				)
				( attribute "SN_BBV_TO_BBV_SPACING" "5.00,5.00,5.00,5.00,5.00,5.00,5.00,5.00,5.00,5.00,5.00,5.00,5.00,5.00"
					( Origin gBackEnd )
				)
				( attribute "SN_BONDPAD_TO_BBV_SPACING" "5.00,5.00,5.00,5.00,5.00,5.00,5.00,5.00,5.00,5.00,5.00,5.00,5.00,5.00"
					( Origin gBackEnd )
				)
				( attribute "SN_BBV_TO_LINE_SPACING" "5.00,5.00,5.00,5.00,5.00,5.00,5.00,5.00,5.00,5.00,5.00,5.00,5.00,5.00"
					( Origin gBackEnd )
				)
				( attribute "SN_BBV_TO_SHAPE_SPACING" "5.00,5.00,5.00,5.00,5.00,5.00,5.00,5.00,5.00,5.00,5.00,5.00,5.00,5.00"
					( Origin gBackEnd )
				)
				( attribute "SN_BONDPAD_TO_BONDPAD_SPACING" "5.00,5.00,5.00,5.00,5.00,5.00,5.00,5.00,5.00,5.00,5.00,5.00,5.00,5.00"
					( Origin gBackEnd )
				)
				( attribute "SN_BONDPAD_TO_LINE_SPACING" "5.00,5.00,5.00,5.00,5.00,5.00,5.00,5.00,5.00,5.00,5.00,5.00,5.00,5.00"
					( Origin gBackEnd )
				)
				( attribute "SN_BONDPAD_TO_SHAPE_SPACING" "5.00,5.00,5.00,5.00,5.00,5.00,5.00,5.00,5.00,5.00,5.00,5.00,5.00,5.00"
					( Origin gBackEnd )
				)
				( attribute "SN_LINE_TO_LINE_SPACING" "13.50,15.00,15.00,15.00,15.00,15.00,15.00,15.00,15.00,15.00,15.00,15.00,15.00,13.50"
					( Origin gBackEnd )
				)
				( attribute "SN_LINE_TO_SHAPE_SPACING" "0.00,0.00,0.00,0.00,0.00,0.00,0.00,0.00,0.00,0.00,0.00,0.00,0.00,0.00"
					( Origin gBackEnd )
				)
				( attribute "SN_SHAPE_TO_SHAPE_SPACING" "5.00,5.00,5.00,5.00,5.00,5.00,5.00,5.00,5.00,5.00,5.00,5.00,5.00,5.00"
					( Origin gBackEnd )
				)
				( attribute "SN_HOLE_TO_PIN_SPACING" "8.00,8.00,8.00,8.00,8.00,8.00,8.00,8.00,8.00,8.00,8.00,8.00,8.00,8.00"
					( Origin gBackEnd )
				)
				( attribute "SN_HOLE_TO_VIA_SPACING" "8.00,8.00,8.00,8.00,8.00,8.00,8.00,8.00,8.00,8.00,8.00,8.00,8.00,8.00"
					( Origin gBackEnd )
				)
				( attribute "SN_HOLE_TO_LINE_SPACING" "8.00,8.00,8.00,8.00,8.00,8.00,8.00,8.00,8.00,8.00,8.00,8.00,8.00,8.00"
					( Origin gBackEnd )
				)
				( attribute "SN_HOLE_TO_SHAPE_SPACING" "8.00,8.00,8.00,8.00,8.00,8.00,8.00,8.00,8.00,8.00,8.00,8.00,8.00,8.00"
					( Origin gBackEnd )
				)
				( attribute "SN_HOLE_TO_HOLE_SPACING" "8.00,8.00,8.00,8.00,8.00,8.00,8.00,8.00,8.00,8.00,8.00,8.00,8.00,8.00"
					( Origin gBackEnd )
				)
				( attribute "SN_MVIA_TO_MVIA_SPACING" "5.00,5.00,5.00,5.00,5.00,5.00,5.00,5.00,5.00,5.00,5.00,5.00,5.00,5.00"
					( Origin gBackEnd )
				)
				( attribute "SN_MVIA_TO_THRUPIN_SPACING" "5.00,5.00,5.00,5.00,5.00,5.00,5.00,5.00,5.00,5.00,5.00,5.00,5.00,5.00"
					( Origin gBackEnd )
				)
				( attribute "SN_MVIA_TO_SMDPIN_SPACING" "5.00,5.00,5.00,5.00,5.00,5.00,5.00,5.00,5.00,5.00,5.00,5.00,5.00,5.00"
					( Origin gBackEnd )
				)
				( attribute "SN_MVIA_TO_THRUVIA_SPACING" "5.00,5.00,5.00,5.00,5.00,5.00,5.00,5.00,5.00,5.00,5.00,5.00,5.00,5.00"
					( Origin gBackEnd )
				)
				( attribute "SN_MVIA_TO_BBV_SPACING" "5.00,5.00,5.00,5.00,5.00,5.00,5.00,5.00,5.00,5.00,5.00,5.00,5.00,5.00"
					( Origin gBackEnd )
				)
				( attribute "SN_MVIA_TO_LINE_SPACING" "5.00,5.00,5.00,5.00,5.00,5.00,5.00,5.00,5.00,5.00,5.00,5.00,5.00,5.00"
					( Origin gBackEnd )
				)
				( attribute "SN_MVIA_TO_SHAPE_SPACING" "5.00,5.00,5.00,5.00,5.00,5.00,5.00,5.00,5.00,5.00,5.00,5.00,5.00,5.00"
					( Origin gBackEnd )
				)
				( attribute "SN_MVIA_TO_TESTPIN_SPACING" "5.00,5.00,5.00,5.00,5.00,5.00,5.00,5.00,5.00,5.00,5.00,5.00,5.00,5.00"
					( Origin gBackEnd )
				)
				( attribute "SN_MVIA_TO_TESTVIA_SPACING" "5.00,5.00,5.00,5.00,5.00,5.00,5.00,5.00,5.00,5.00,5.00,5.00,5.00,5.00"
					( Origin gBackEnd )
				)
				( attribute "SN_BONDPAD_TO_MVIA_SPACING" "5.00,5.00,5.00,5.00,5.00,5.00,5.00,5.00,5.00,5.00,5.00,5.00,5.00,5.00"
					( Origin gBackEnd )
				)
				( objectStatus "5H" )
			)
			( sameNetSpacingCSet "@crescent_city_bb_fab1_lib.crescent_city_bb_fab1(sch_1):\3H_SL_5H_MS\"
				( attribute "SAME_NET" "TRUE,TRUE,TRUE,TRUE,TRUE,TRUE,TRUE,TRUE,TRUE,TRUE,TRUE,TRUE,TRUE,TRUE"
					( Origin gBackEnd )
				)
				( attribute "SN_THRUPIN_TO_THRUPIN_SPACING" "5.00,5.00,5.00,5.00,5.00,5.00,5.00,5.00,5.00,5.00,5.00,5.00,5.00,5.00"
					( Origin gBackEnd )
				)
				( attribute "SN_THRUPIN_TO_SMDPIN_SPACING" "5.00,5.00,5.00,5.00,5.00,5.00,5.00,5.00,5.00,5.00,5.00,5.00,5.00,5.00"
					( Origin gBackEnd )
				)
				( attribute "SN_TESTPIN_TO_THRUPIN_SPACING" "5.00,5.00,5.00,5.00,5.00,5.00,5.00,5.00,5.00,5.00,5.00,5.00,5.00,5.00"
					( Origin gBackEnd )
				)
				( attribute "SN_THRUPIN_TO_THRUVIA_SPACING" "5.00,5.00,5.00,5.00,5.00,5.00,5.00,5.00,5.00,5.00,5.00,5.00,5.00,5.00"
					( Origin gBackEnd )
				)
				( attribute "SN_TESTVIA_TO_THRUPIN_SPACING" "5.00,5.00,5.00,5.00,5.00,5.00,5.00,5.00,5.00,5.00,5.00,5.00,5.00,5.00"
					( Origin gBackEnd )
				)
				( attribute "SN_BBV_TO_THRUPIN_SPACING" "5.00,5.00,5.00,5.00,5.00,5.00,5.00,5.00,5.00,5.00,5.00,5.00,5.00,5.00"
					( Origin gBackEnd )
				)
				( attribute "SN_THRUPIN_TO_BONDPAD_SPACING" "5.00,5.00,5.00,5.00,5.00,5.00,5.00,5.00,5.00,5.00,5.00,5.00,5.00,5.00"
					( Origin gBackEnd )
				)
				( attribute "SN_LINE_TO_THRUPIN_SPACING" "4.50,4.00,4.00,4.00,4.00,4.00,4.00,4.00,4.00,4.00,4.00,4.00,4.00,4.50"
					( Origin gBackEnd )
				)
				( attribute "SN_THRUPIN_TO_SHAPE_SPACING" "5.00,5.00,5.00,5.00,5.00,5.00,5.00,5.00,5.00,5.00,5.00,5.00,5.00,5.00"
					( Origin gBackEnd )
				)
				( attribute "SN_SMDPIN_TO_SMDPIN_SPACING" "5.00,5.00,5.00,5.00,5.00,5.00,5.00,5.00,5.00,5.00,5.00,5.00,5.00,5.00"
					( Origin gBackEnd )
				)
				( attribute "SN_SMDPIN_TO_TESTPIN_SPACING" "5.00,5.00,5.00,5.00,5.00,5.00,5.00,5.00,5.00,5.00,5.00,5.00,5.00,5.00"
					( Origin gBackEnd )
				)
				( attribute "SN_SMDPIN_TO_THRUVIA_SPACING" "5.00,5.00,5.00,5.00,5.00,5.00,5.00,5.00,5.00,5.00,5.00,5.00,5.00,5.00"
					( Origin gBackEnd )
				)
				( attribute "SN_SMDPIN_TO_TESTVIA_SPACING" "5.00,5.00,5.00,5.00,5.00,5.00,5.00,5.00,5.00,5.00,5.00,5.00,5.00,5.00"
					( Origin gBackEnd )
				)
				( attribute "SN_BBV_TO_SMDPIN_SPACING" "5.00,5.00,5.00,5.00,5.00,5.00,5.00,5.00,5.00,5.00,5.00,5.00,5.00,5.00"
					( Origin gBackEnd )
				)
				( attribute "SN_SMDPIN_TO_BONDPAD_SPACING" "5.00,5.00,5.00,5.00,5.00,5.00,5.00,5.00,5.00,5.00,5.00,5.00,5.00,5.00"
					( Origin gBackEnd )
				)
				( attribute "SN_LINE_TO_SMDPIN_SPACING" "4.50,4.50,4.50,4.50,4.50,4.50,4.50,4.50,4.50,4.50,4.50,4.50,4.50,4.50"
					( Origin gBackEnd )
				)
				( attribute "SN_SHAPE_TO_SMDPIN_SPACING" "5.00,5.00,5.00,5.00,5.00,5.00,5.00,5.00,5.00,5.00,5.00,5.00,5.00,5.00"
					( Origin gBackEnd )
				)
				( attribute "SN_TESTPIN_TO_TESTPIN_SPACING" "5.00,5.00,5.00,5.00,5.00,5.00,5.00,5.00,5.00,5.00,5.00,5.00,5.00,5.00"
					( Origin gBackEnd )
				)
				( attribute "SN_TESTPIN_TO_THRUVIA_SPACING" "5.00,5.00,5.00,5.00,5.00,5.00,5.00,5.00,5.00,5.00,5.00,5.00,5.00,5.00"
					( Origin gBackEnd )
				)
				( attribute "SN_TESTPIN_TO_TESTVIA_SPACING" "5.00,5.00,5.00,5.00,5.00,5.00,5.00,5.00,5.00,5.00,5.00,5.00,5.00,5.00"
					( Origin gBackEnd )
				)
				( attribute "SN_BBV_TO_TESTPIN_SPACING" "5.00,5.00,5.00,5.00,5.00,5.00,5.00,5.00,5.00,5.00,5.00,5.00,5.00,5.00"
					( Origin gBackEnd )
				)
				( attribute "SN_BONDPAD_TO_TESTPIN_SPACING" "5.00,5.00,5.00,5.00,5.00,5.00,5.00,5.00,5.00,5.00,5.00,5.00,5.00,5.00"
					( Origin gBackEnd )
				)
				( attribute "SN_LINE_TO_TESTPIN_SPACING" "5.00,4.00,4.00,4.00,4.00,4.00,4.00,4.00,4.00,4.00,4.00,4.00,4.00,5.00"
					( Origin gBackEnd )
				)
				( attribute "SN_SHAPE_TO_TESTPIN_SPACING" "5.00,5.00,5.00,5.00,5.00,5.00,5.00,5.00,5.00,5.00,5.00,5.00,5.00,5.00"
					( Origin gBackEnd )
				)
				( attribute "SN_THRUVIA_TO_THRUVIA_SPACING" "4.50,4.00,4.00,4.00,4.00,4.00,4.00,4.00,4.00,4.00,4.00,4.00,4.00,4.50"
					( Origin gBackEnd )
				)
				( attribute "SN_TESTVIA_TO_THRUVIA_SPACING" "5.00,5.00,5.00,5.00,5.00,5.00,5.00,5.00,5.00,5.00,5.00,5.00,5.00,5.00"
					( Origin gBackEnd )
				)
				( attribute "SN_BBV_TO_THRUVIA_SPACING" "5.00,5.00,5.00,5.00,5.00,5.00,5.00,5.00,5.00,5.00,5.00,5.00,5.00,5.00"
					( Origin gBackEnd )
				)
				( attribute "SN_BONDPAD_TO_THRUVIA_SPACING" "5.00,5.00,5.00,5.00,5.00,5.00,5.00,5.00,5.00,5.00,5.00,5.00,5.00,5.00"
					( Origin gBackEnd )
				)
				( attribute "SN_LINE_TO_THRUVIA_SPACING" "4.50,4.00,4.00,4.00,4.00,4.00,4.00,4.00,4.00,4.00,4.00,4.00,4.00,4.50"
					( Origin gBackEnd )
				)
				( attribute "SN_SHAPE_TO_THRUVIA_SPACING" "5.00,5.00,5.00,5.00,5.00,5.00,5.00,5.00,5.00,5.00,5.00,5.00,5.00,5.00"
					( Origin gBackEnd )
				)
				( attribute "SN_TESTVIA_TO_TESTVIA_SPACING" "6.00,6.00,6.00,6.00,6.00,6.00,6.00,6.00,6.00,6.00,6.00,6.00,6.00,6.00"
					( Origin gBackEnd )
				)
				( attribute "SN_BBV_TO_TESTVIA_SPACING" "5.00,5.00,5.00,5.00,5.00,5.00,5.00,5.00,5.00,5.00,5.00,5.00,5.00,5.00"
					( Origin gBackEnd )
				)
				( attribute "SN_BONDPAD_TO_TESTVIA_SPACING" "5.00,5.00,5.00,5.00,5.00,5.00,5.00,5.00,5.00,5.00,5.00,5.00,5.00,5.00"
					( Origin gBackEnd )
				)
				( attribute "SN_LINE_TO_TESTVIA_SPACING" "5.00,4.00,4.00,4.00,4.00,4.00,4.00,4.00,4.00,4.00,4.00,4.00,4.00,5.00"
					( Origin gBackEnd )
				)
				( attribute "SN_SHAPE_TO_TESTVIA_SPACING" "5.00,5.00,5.00,5.00,5.00,5.00,5.00,5.00,5.00,5.00,5.00,5.00,5.00,5.00"
					( Origin gBackEnd )
				)
				( attribute "SN_BBV_TO_BBV_SPACING" "5.00,5.00,5.00,5.00,5.00,5.00,5.00,5.00,5.00,5.00,5.00,5.00,5.00,5.00"
					( Origin gBackEnd )
				)
				( attribute "SN_BONDPAD_TO_BBV_SPACING" "5.00,5.00,5.00,5.00,5.00,5.00,5.00,5.00,5.00,5.00,5.00,5.00,5.00,5.00"
					( Origin gBackEnd )
				)
				( attribute "SN_BBV_TO_LINE_SPACING" "5.00,5.00,5.00,5.00,5.00,5.00,5.00,5.00,5.00,5.00,5.00,5.00,5.00,5.00"
					( Origin gBackEnd )
				)
				( attribute "SN_BBV_TO_SHAPE_SPACING" "5.00,5.00,5.00,5.00,5.00,5.00,5.00,5.00,5.00,5.00,5.00,5.00,5.00,5.00"
					( Origin gBackEnd )
				)
				( attribute "SN_BONDPAD_TO_BONDPAD_SPACING" "5.00,5.00,5.00,5.00,5.00,5.00,5.00,5.00,5.00,5.00,5.00,5.00,5.00,5.00"
					( Origin gBackEnd )
				)
				( attribute "SN_BONDPAD_TO_LINE_SPACING" "5.00,5.00,5.00,5.00,5.00,5.00,5.00,5.00,5.00,5.00,5.00,5.00,5.00,5.00"
					( Origin gBackEnd )
				)
				( attribute "SN_BONDPAD_TO_SHAPE_SPACING" "5.00,5.00,5.00,5.00,5.00,5.00,5.00,5.00,5.00,5.00,5.00,5.00,5.00,5.00"
					( Origin gBackEnd )
				)
				( attribute "SN_LINE_TO_LINE_SPACING" "13.50,9.00,9.00,9.00,9.00,9.00,9.00,9.00,9.00,9.00,9.00,9.00,9.00,13.50"
					( Origin gBackEnd )
				)
				( attribute "SN_LINE_TO_SHAPE_SPACING" "0.00,0.00,0.00,0.00,0.00,0.00,0.00,0.00,0.00,0.00,0.00,0.00,0.00,0.00"
					( Origin gBackEnd )
				)
				( attribute "SN_SHAPE_TO_SHAPE_SPACING" "5.00,5.00,5.00,5.00,5.00,5.00,5.00,5.00,5.00,5.00,5.00,5.00,5.00,5.00"
					( Origin gBackEnd )
				)
				( attribute "SN_HOLE_TO_PIN_SPACING" "8.00,8.00,8.00,8.00,8.00,8.00,8.00,8.00,8.00,8.00,8.00,8.00,8.00,8.00"
					( Origin gBackEnd )
				)
				( attribute "SN_HOLE_TO_VIA_SPACING" "8.00,8.00,8.00,8.00,8.00,8.00,8.00,8.00,8.00,8.00,8.00,8.00,8.00,8.00"
					( Origin gBackEnd )
				)
				( attribute "SN_HOLE_TO_LINE_SPACING" "8.00,8.00,8.00,8.00,8.00,8.00,8.00,8.00,8.00,8.00,8.00,8.00,8.00,8.00"
					( Origin gBackEnd )
				)
				( attribute "SN_HOLE_TO_SHAPE_SPACING" "8.00,8.00,8.00,8.00,8.00,8.00,8.00,8.00,8.00,8.00,8.00,8.00,8.00,8.00"
					( Origin gBackEnd )
				)
				( attribute "SN_HOLE_TO_HOLE_SPACING" "8.00,8.00,8.00,8.00,8.00,8.00,8.00,8.00,8.00,8.00,8.00,8.00,8.00,8.00"
					( Origin gBackEnd )
				)
				( attribute "SN_MVIA_TO_MVIA_SPACING" "5.00,5.00,5.00,5.00,5.00,5.00,5.00,5.00,5.00,5.00,5.00,5.00,5.00,5.00"
					( Origin gBackEnd )
				)
				( attribute "SN_MVIA_TO_THRUPIN_SPACING" "5.00,5.00,5.00,5.00,5.00,5.00,5.00,5.00,5.00,5.00,5.00,5.00,5.00,5.00"
					( Origin gBackEnd )
				)
				( attribute "SN_MVIA_TO_SMDPIN_SPACING" "5.00,5.00,5.00,5.00,5.00,5.00,5.00,5.00,5.00,5.00,5.00,5.00,5.00,5.00"
					( Origin gBackEnd )
				)
				( attribute "SN_MVIA_TO_THRUVIA_SPACING" "5.00,5.00,5.00,5.00,5.00,5.00,5.00,5.00,5.00,5.00,5.00,5.00,5.00,5.00"
					( Origin gBackEnd )
				)
				( attribute "SN_MVIA_TO_BBV_SPACING" "5.00,5.00,5.00,5.00,5.00,5.00,5.00,5.00,5.00,5.00,5.00,5.00,5.00,5.00"
					( Origin gBackEnd )
				)
				( attribute "SN_MVIA_TO_LINE_SPACING" "5.00,5.00,5.00,5.00,5.00,5.00,5.00,5.00,5.00,5.00,5.00,5.00,5.00,5.00"
					( Origin gBackEnd )
				)
				( attribute "SN_MVIA_TO_SHAPE_SPACING" "5.00,5.00,5.00,5.00,5.00,5.00,5.00,5.00,5.00,5.00,5.00,5.00,5.00,5.00"
					( Origin gBackEnd )
				)
				( attribute "SN_MVIA_TO_TESTPIN_SPACING" "5.00,5.00,5.00,5.00,5.00,5.00,5.00,5.00,5.00,5.00,5.00,5.00,5.00,5.00"
					( Origin gBackEnd )
				)
				( attribute "SN_MVIA_TO_TESTVIA_SPACING" "5.00,5.00,5.00,5.00,5.00,5.00,5.00,5.00,5.00,5.00,5.00,5.00,5.00,5.00"
					( Origin gBackEnd )
				)
				( attribute "SN_BONDPAD_TO_MVIA_SPACING" "5.00,5.00,5.00,5.00,5.00,5.00,5.00,5.00,5.00,5.00,5.00,5.00,5.00,5.00"
					( Origin gBackEnd )
				)
				( objectStatus "5H_US_&_3H_SL" )
			)
			( sameNetSpacingCSet "@crescent_city_bb_fab1_lib.crescent_city_bb_fab1(sch_1):\20_MIL\"
				( attribute "SAME_NET" "TRUE,TRUE,TRUE,TRUE,TRUE,TRUE,TRUE,TRUE,TRUE,TRUE,TRUE,TRUE,TRUE,TRUE"
					( Origin gBackEnd )
				)
				( attribute "SN_THRUPIN_TO_THRUPIN_SPACING" "5.00,5.00,5.00,5.00,5.00,5.00,5.00,5.00,5.00,5.00,5.00,5.00,5.00,5.00"
					( Origin gBackEnd )
				)
				( attribute "SN_THRUPIN_TO_SMDPIN_SPACING" "5.00,5.00,5.00,5.00,5.00,5.00,5.00,5.00,5.00,5.00,5.00,5.00,5.00,5.00"
					( Origin gBackEnd )
				)
				( attribute "SN_TESTPIN_TO_THRUPIN_SPACING" "5.00,5.00,5.00,5.00,5.00,5.00,5.00,5.00,5.00,5.00,5.00,5.00,5.00,5.00"
					( Origin gBackEnd )
				)
				( attribute "SN_THRUPIN_TO_THRUVIA_SPACING" "5.00,5.00,5.00,5.00,5.00,5.00,5.00,5.00,5.00,5.00,5.00,5.00,5.00,5.00"
					( Origin gBackEnd )
				)
				( attribute "SN_TESTVIA_TO_THRUPIN_SPACING" "5.00,5.00,5.00,5.00,5.00,5.00,5.00,5.00,5.00,5.00,5.00,5.00,5.00,5.00"
					( Origin gBackEnd )
				)
				( attribute "SN_BBV_TO_THRUPIN_SPACING" "5.00,5.00,5.00,5.00,5.00,5.00,5.00,5.00,5.00,5.00,5.00,5.00,5.00,5.00"
					( Origin gBackEnd )
				)
				( attribute "SN_THRUPIN_TO_BONDPAD_SPACING" "5.00,5.00,5.00,5.00,5.00,5.00,5.00,5.00,5.00,5.00,5.00,5.00,5.00,5.00"
					( Origin gBackEnd )
				)
				( attribute "SN_LINE_TO_THRUPIN_SPACING" "4.50,4.00,4.00,4.00,4.00,4.00,4.00,4.00,4.00,4.00,4.00,4.00,4.00,4.50"
					( Origin gBackEnd )
				)
				( attribute "SN_THRUPIN_TO_SHAPE_SPACING" "5.00,5.00,5.00,5.00,5.00,5.00,5.00,5.00,5.00,5.00,5.00,5.00,5.00,5.00"
					( Origin gBackEnd )
				)
				( attribute "SN_SMDPIN_TO_SMDPIN_SPACING" "5.00,5.00,5.00,5.00,5.00,5.00,5.00,5.00,5.00,5.00,5.00,5.00,5.00,5.00"
					( Origin gBackEnd )
				)
				( attribute "SN_SMDPIN_TO_TESTPIN_SPACING" "5.00,5.00,5.00,5.00,5.00,5.00,5.00,5.00,5.00,5.00,5.00,5.00,5.00,5.00"
					( Origin gBackEnd )
				)
				( attribute "SN_SMDPIN_TO_THRUVIA_SPACING" "5.00,5.00,5.00,5.00,5.00,5.00,5.00,5.00,5.00,5.00,5.00,5.00,5.00,5.00"
					( Origin gBackEnd )
				)
				( attribute "SN_SMDPIN_TO_TESTVIA_SPACING" "5.00,5.00,5.00,5.00,5.00,5.00,5.00,5.00,5.00,5.00,5.00,5.00,5.00,5.00"
					( Origin gBackEnd )
				)
				( attribute "SN_BBV_TO_SMDPIN_SPACING" "5.00,5.00,5.00,5.00,5.00,5.00,5.00,5.00,5.00,5.00,5.00,5.00,5.00,5.00"
					( Origin gBackEnd )
				)
				( attribute "SN_SMDPIN_TO_BONDPAD_SPACING" "5.00,5.00,5.00,5.00,5.00,5.00,5.00,5.00,5.00,5.00,5.00,5.00,5.00,5.00"
					( Origin gBackEnd )
				)
				( attribute "SN_LINE_TO_SMDPIN_SPACING" "4.50,4.50,4.50,4.50,4.50,4.50,4.50,4.50,4.50,4.50,4.50,4.50,4.50,4.50"
					( Origin gBackEnd )
				)
				( attribute "SN_SHAPE_TO_SMDPIN_SPACING" "5.00,5.00,5.00,5.00,5.00,5.00,5.00,5.00,5.00,5.00,5.00,5.00,5.00,5.00"
					( Origin gBackEnd )
				)
				( attribute "SN_TESTPIN_TO_TESTPIN_SPACING" "5.00,5.00,5.00,5.00,5.00,5.00,5.00,5.00,5.00,5.00,5.00,5.00,5.00,5.00"
					( Origin gBackEnd )
				)
				( attribute "SN_TESTPIN_TO_THRUVIA_SPACING" "5.00,5.00,5.00,5.00,5.00,5.00,5.00,5.00,5.00,5.00,5.00,5.00,5.00,5.00"
					( Origin gBackEnd )
				)
				( attribute "SN_TESTPIN_TO_TESTVIA_SPACING" "5.00,5.00,5.00,5.00,5.00,5.00,5.00,5.00,5.00,5.00,5.00,5.00,5.00,5.00"
					( Origin gBackEnd )
				)
				( attribute "SN_BBV_TO_TESTPIN_SPACING" "5.00,5.00,5.00,5.00,5.00,5.00,5.00,5.00,5.00,5.00,5.00,5.00,5.00,5.00"
					( Origin gBackEnd )
				)
				( attribute "SN_BONDPAD_TO_TESTPIN_SPACING" "5.00,5.00,5.00,5.00,5.00,5.00,5.00,5.00,5.00,5.00,5.00,5.00,5.00,5.00"
					( Origin gBackEnd )
				)
				( attribute "SN_LINE_TO_TESTPIN_SPACING" "5.00,4.00,4.00,4.00,4.00,4.00,4.00,4.00,4.00,4.00,4.00,4.00,4.00,5.00"
					( Origin gBackEnd )
				)
				( attribute "SN_SHAPE_TO_TESTPIN_SPACING" "5.00,5.00,5.00,5.00,5.00,5.00,5.00,5.00,5.00,5.00,5.00,5.00,5.00,5.00"
					( Origin gBackEnd )
				)
				( attribute "SN_THRUVIA_TO_THRUVIA_SPACING" "4.50,4.00,4.00,4.00,4.00,4.00,4.00,4.00,4.00,4.00,4.00,4.00,4.00,4.50"
					( Origin gBackEnd )
				)
				( attribute "SN_TESTVIA_TO_THRUVIA_SPACING" "5.00,5.00,5.00,5.00,5.00,5.00,5.00,5.00,5.00,5.00,5.00,5.00,5.00,5.00"
					( Origin gBackEnd )
				)
				( attribute "SN_BBV_TO_THRUVIA_SPACING" "5.00,5.00,5.00,5.00,5.00,5.00,5.00,5.00,5.00,5.00,5.00,5.00,5.00,5.00"
					( Origin gBackEnd )
				)
				( attribute "SN_BONDPAD_TO_THRUVIA_SPACING" "5.00,5.00,5.00,5.00,5.00,5.00,5.00,5.00,5.00,5.00,5.00,5.00,5.00,5.00"
					( Origin gBackEnd )
				)
				( attribute "SN_LINE_TO_THRUVIA_SPACING" "4.50,4.00,4.00,4.00,4.00,4.00,4.00,4.00,4.00,4.00,4.00,4.00,4.00,4.50"
					( Origin gBackEnd )
				)
				( attribute "SN_SHAPE_TO_THRUVIA_SPACING" "5.00,5.00,5.00,5.00,5.00,5.00,5.00,5.00,5.00,5.00,5.00,5.00,5.00,5.00"
					( Origin gBackEnd )
				)
				( attribute "SN_TESTVIA_TO_TESTVIA_SPACING" "5.00,5.00,5.00,5.00,5.00,5.00,5.00,5.00,5.00,5.00,5.00,5.00,5.00,5.00"
					( Origin gBackEnd )
				)
				( attribute "SN_BBV_TO_TESTVIA_SPACING" "5.00,5.00,5.00,5.00,5.00,5.00,5.00,5.00,5.00,5.00,5.00,5.00,5.00,5.00"
					( Origin gBackEnd )
				)
				( attribute "SN_BONDPAD_TO_TESTVIA_SPACING" "5.00,5.00,5.00,5.00,5.00,5.00,5.00,5.00,5.00,5.00,5.00,5.00,5.00,5.00"
					( Origin gBackEnd )
				)
				( attribute "SN_LINE_TO_TESTVIA_SPACING" "5.00,4.00,4.00,4.00,4.00,4.00,4.00,4.00,4.00,4.00,4.00,4.00,4.00,5.00"
					( Origin gBackEnd )
				)
				( attribute "SN_SHAPE_TO_TESTVIA_SPACING" "5.00,5.00,5.00,5.00,5.00,5.00,5.00,5.00,5.00,5.00,5.00,5.00,5.00,5.00"
					( Origin gBackEnd )
				)
				( attribute "SN_BBV_TO_BBV_SPACING" "5.00,5.00,5.00,5.00,5.00,5.00,5.00,5.00,5.00,5.00,5.00,5.00,5.00,5.00"
					( Origin gBackEnd )
				)
				( attribute "SN_BONDPAD_TO_BBV_SPACING" "5.00,5.00,5.00,5.00,5.00,5.00,5.00,5.00,5.00,5.00,5.00,5.00,5.00,5.00"
					( Origin gBackEnd )
				)
				( attribute "SN_BBV_TO_LINE_SPACING" "5.00,5.00,5.00,5.00,5.00,5.00,5.00,5.00,5.00,5.00,5.00,5.00,5.00,5.00"
					( Origin gBackEnd )
				)
				( attribute "SN_BBV_TO_SHAPE_SPACING" "5.00,5.00,5.00,5.00,5.00,5.00,5.00,5.00,5.00,5.00,5.00,5.00,5.00,5.00"
					( Origin gBackEnd )
				)
				( attribute "SN_BONDPAD_TO_BONDPAD_SPACING" "5.00,5.00,5.00,5.00,5.00,5.00,5.00,5.00,5.00,5.00,5.00,5.00,5.00,5.00"
					( Origin gBackEnd )
				)
				( attribute "SN_BONDPAD_TO_LINE_SPACING" "5.00,5.00,5.00,5.00,5.00,5.00,5.00,5.00,5.00,5.00,5.00,5.00,5.00,5.00"
					( Origin gBackEnd )
				)
				( attribute "SN_BONDPAD_TO_SHAPE_SPACING" "5.00,5.00,5.00,5.00,5.00,5.00,5.00,5.00,5.00,5.00,5.00,5.00,5.00,5.00"
					( Origin gBackEnd )
				)
				( attribute "SN_LINE_TO_LINE_SPACING" "20.00,20.00,20.00,20.00,20.00,20.00,20.00,20.00,20.00,20.00,20.00,20.00,20.00,20.00"
					( Origin gBackEnd )
				)
				( attribute "SN_LINE_TO_SHAPE_SPACING" "0.00,0.00,0.00,0.00,0.00,0.00,0.00,0.00,0.00,0.00,0.00,0.00,0.00,0.00"
					( Origin gBackEnd )
				)
				( attribute "SN_SHAPE_TO_SHAPE_SPACING" "5.00,5.00,5.00,5.00,5.00,5.00,5.00,5.00,5.00,5.00,5.00,5.00,5.00,5.00"
					( Origin gBackEnd )
				)
				( attribute "SN_HOLE_TO_PIN_SPACING" "8.00,8.00,8.00,8.00,8.00,8.00,8.00,8.00,8.00,8.00,8.00,8.00,8.00,8.00"
					( Origin gBackEnd )
				)
				( attribute "SN_HOLE_TO_VIA_SPACING" "8.00,8.00,8.00,8.00,8.00,8.00,8.00,8.00,8.00,8.00,8.00,8.00,8.00,8.00"
					( Origin gBackEnd )
				)
				( attribute "SN_HOLE_TO_LINE_SPACING" "8.00,8.00,8.00,8.00,8.00,8.00,8.00,8.00,8.00,8.00,8.00,8.00,8.00,8.00"
					( Origin gBackEnd )
				)
				( attribute "SN_HOLE_TO_SHAPE_SPACING" "8.00,8.00,8.00,8.00,8.00,8.00,8.00,8.00,8.00,8.00,8.00,8.00,8.00,8.00"
					( Origin gBackEnd )
				)
				( attribute "SN_HOLE_TO_HOLE_SPACING" "8.00,8.00,8.00,8.00,8.00,8.00,8.00,8.00,8.00,8.00,8.00,8.00,8.00,8.00"
					( Origin gBackEnd )
				)
				( attribute "SN_MVIA_TO_MVIA_SPACING" "5.00,5.00,5.00,5.00,5.00,5.00,5.00,5.00,5.00,5.00,5.00,5.00,5.00,5.00"
					( Origin gBackEnd )
				)
				( attribute "SN_MVIA_TO_THRUPIN_SPACING" "5.00,5.00,5.00,5.00,5.00,5.00,5.00,5.00,5.00,5.00,5.00,5.00,5.00,5.00"
					( Origin gBackEnd )
				)
				( attribute "SN_MVIA_TO_SMDPIN_SPACING" "5.00,5.00,5.00,5.00,5.00,5.00,5.00,5.00,5.00,5.00,5.00,5.00,5.00,5.00"
					( Origin gBackEnd )
				)
				( attribute "SN_MVIA_TO_THRUVIA_SPACING" "5.00,5.00,5.00,5.00,5.00,5.00,5.00,5.00,5.00,5.00,5.00,5.00,5.00,5.00"
					( Origin gBackEnd )
				)
				( attribute "SN_MVIA_TO_BBV_SPACING" "5.00,5.00,5.00,5.00,5.00,5.00,5.00,5.00,5.00,5.00,5.00,5.00,5.00,5.00"
					( Origin gBackEnd )
				)
				( attribute "SN_MVIA_TO_LINE_SPACING" "5.00,5.00,5.00,5.00,5.00,5.00,5.00,5.00,5.00,5.00,5.00,5.00,5.00,5.00"
					( Origin gBackEnd )
				)
				( attribute "SN_MVIA_TO_SHAPE_SPACING" "5.00,5.00,5.00,5.00,5.00,5.00,5.00,5.00,5.00,5.00,5.00,5.00,5.00,5.00"
					( Origin gBackEnd )
				)
				( attribute "SN_MVIA_TO_TESTPIN_SPACING" "5.00,5.00,5.00,5.00,5.00,5.00,5.00,5.00,5.00,5.00,5.00,5.00,5.00,5.00"
					( Origin gBackEnd )
				)
				( attribute "SN_MVIA_TO_TESTVIA_SPACING" "5.00,5.00,5.00,5.00,5.00,5.00,5.00,5.00,5.00,5.00,5.00,5.00,5.00,5.00"
					( Origin gBackEnd )
				)
				( attribute "SN_BONDPAD_TO_MVIA_SPACING" "5.00,5.00,5.00,5.00,5.00,5.00,5.00,5.00,5.00,5.00,5.00,5.00,5.00,5.00"
					( Origin gBackEnd )
				)
				( objectStatus "20_MILS" )
			)
			( sameNetSpacingCSet "@crescent_city_bb_fab1_lib.crescent_city_bb_fab1(sch_1):\10MIL\"
				( attribute "SAME_NET" "TRUE,TRUE,TRUE,TRUE,TRUE,TRUE,TRUE,TRUE,TRUE,TRUE,TRUE,TRUE,TRUE,TRUE"
					( Origin gBackEnd )
				)
				( attribute "SN_THRUPIN_TO_THRUPIN_SPACING" "5.00,5.00,5.00,5.00,5.00,5.00,5.00,5.00,5.00,5.00,5.00,5.00,5.00,5.00"
					( Origin gBackEnd )
				)
				( attribute "SN_THRUPIN_TO_SMDPIN_SPACING" "5.00,5.00,5.00,5.00,5.00,5.00,5.00,5.00,5.00,5.00,5.00,5.00,5.00,5.00"
					( Origin gBackEnd )
				)
				( attribute "SN_TESTPIN_TO_THRUPIN_SPACING" "5.00,5.00,5.00,5.00,5.00,5.00,5.00,5.00,5.00,5.00,5.00,5.00,5.00,5.00"
					( Origin gBackEnd )
				)
				( attribute "SN_THRUPIN_TO_THRUVIA_SPACING" "5.00,5.00,5.00,5.00,5.00,5.00,5.00,5.00,5.00,5.00,5.00,5.00,5.00,5.00"
					( Origin gBackEnd )
				)
				( attribute "SN_TESTVIA_TO_THRUPIN_SPACING" "5.00,5.00,5.00,5.00,5.00,5.00,5.00,5.00,5.00,5.00,5.00,5.00,5.00,5.00"
					( Origin gBackEnd )
				)
				( attribute "SN_BBV_TO_THRUPIN_SPACING" "5.00,5.00,5.00,5.00,5.00,5.00,5.00,5.00,5.00,5.00,5.00,5.00,5.00,5.00"
					( Origin gBackEnd )
				)
				( attribute "SN_THRUPIN_TO_BONDPAD_SPACING" "5.00,5.00,5.00,5.00,5.00,5.00,5.00,5.00,5.00,5.00,5.00,5.00,5.00,5.00"
					( Origin gBackEnd )
				)
				( attribute "SN_LINE_TO_THRUPIN_SPACING" "4.50,4.00,4.00,4.00,4.00,4.00,4.00,4.00,4.00,4.00,4.00,4.00,4.00,4.50"
					( Origin gBackEnd )
				)
				( attribute "SN_THRUPIN_TO_SHAPE_SPACING" "5.00,5.00,5.00,5.00,5.00,5.00,5.00,5.00,5.00,5.00,5.00,5.00,5.00,5.00"
					( Origin gBackEnd )
				)
				( attribute "SN_SMDPIN_TO_SMDPIN_SPACING" "5.00,5.00,5.00,5.00,5.00,5.00,5.00,5.00,5.00,5.00,5.00,5.00,5.00,5.00"
					( Origin gBackEnd )
				)
				( attribute "SN_SMDPIN_TO_TESTPIN_SPACING" "5.00,5.00,5.00,5.00,5.00,5.00,5.00,5.00,5.00,5.00,5.00,5.00,5.00,5.00"
					( Origin gBackEnd )
				)
				( attribute "SN_SMDPIN_TO_THRUVIA_SPACING" "5.00,5.00,5.00,5.00,5.00,5.00,5.00,5.00,5.00,5.00,5.00,5.00,5.00,5.00"
					( Origin gBackEnd )
				)
				( attribute "SN_SMDPIN_TO_TESTVIA_SPACING" "5.00,5.00,5.00,5.00,5.00,5.00,5.00,5.00,5.00,5.00,5.00,5.00,5.00,5.00"
					( Origin gBackEnd )
				)
				( attribute "SN_BBV_TO_SMDPIN_SPACING" "5.00,5.00,5.00,5.00,5.00,5.00,5.00,5.00,5.00,5.00,5.00,5.00,5.00,5.00"
					( Origin gBackEnd )
				)
				( attribute "SN_SMDPIN_TO_BONDPAD_SPACING" "5.00,5.00,5.00,5.00,5.00,5.00,5.00,5.00,5.00,5.00,5.00,5.00,5.00,5.00"
					( Origin gBackEnd )
				)
				( attribute "SN_LINE_TO_SMDPIN_SPACING" "4.50,4.50,4.50,4.50,4.50,4.50,4.50,4.50,4.50,4.50,4.50,4.50,4.50,4.50"
					( Origin gBackEnd )
				)
				( attribute "SN_SHAPE_TO_SMDPIN_SPACING" "5.00,5.00,5.00,5.00,5.00,5.00,5.00,5.00,5.00,5.00,5.00,5.00,5.00,5.00"
					( Origin gBackEnd )
				)
				( attribute "SN_TESTPIN_TO_TESTPIN_SPACING" "5.00,5.00,5.00,5.00,5.00,5.00,5.00,5.00,5.00,5.00,5.00,5.00,5.00,5.00"
					( Origin gBackEnd )
				)
				( attribute "SN_TESTPIN_TO_THRUVIA_SPACING" "5.00,5.00,5.00,5.00,5.00,5.00,5.00,5.00,5.00,5.00,5.00,5.00,5.00,5.00"
					( Origin gBackEnd )
				)
				( attribute "SN_TESTPIN_TO_TESTVIA_SPACING" "5.00,5.00,5.00,5.00,5.00,5.00,5.00,5.00,5.00,5.00,5.00,5.00,5.00,5.00"
					( Origin gBackEnd )
				)
				( attribute "SN_BBV_TO_TESTPIN_SPACING" "5.00,5.00,5.00,5.00,5.00,5.00,5.00,5.00,5.00,5.00,5.00,5.00,5.00,5.00"
					( Origin gBackEnd )
				)
				( attribute "SN_BONDPAD_TO_TESTPIN_SPACING" "5.00,5.00,5.00,5.00,5.00,5.00,5.00,5.00,5.00,5.00,5.00,5.00,5.00,5.00"
					( Origin gBackEnd )
				)
				( attribute "SN_LINE_TO_TESTPIN_SPACING" "5.00,4.00,4.00,4.00,4.00,4.00,4.00,4.00,4.00,4.00,4.00,4.00,4.00,5.00"
					( Origin gBackEnd )
				)
				( attribute "SN_SHAPE_TO_TESTPIN_SPACING" "5.00,5.00,5.00,5.00,5.00,5.00,5.00,5.00,5.00,5.00,5.00,5.00,5.00,5.00"
					( Origin gBackEnd )
				)
				( attribute "SN_THRUVIA_TO_THRUVIA_SPACING" "4.00,4.00,4.00,4.00,4.00,4.00,4.00,4.00,4.00,4.00,4.00,4.00,4.00,4.00"
					( Origin gBackEnd )
				)
				( attribute "SN_TESTVIA_TO_THRUVIA_SPACING" "5.00,5.00,5.00,5.00,5.00,5.00,5.00,5.00,5.00,5.00,5.00,5.00,5.00,5.00"
					( Origin gBackEnd )
				)
				( attribute "SN_BBV_TO_THRUVIA_SPACING" "5.00,5.00,5.00,5.00,5.00,5.00,5.00,5.00,5.00,5.00,5.00,5.00,5.00,5.00"
					( Origin gBackEnd )
				)
				( attribute "SN_BONDPAD_TO_THRUVIA_SPACING" "5.00,5.00,5.00,5.00,5.00,5.00,5.00,5.00,5.00,5.00,5.00,5.00,5.00,5.00"
					( Origin gBackEnd )
				)
				( attribute "SN_LINE_TO_THRUVIA_SPACING" "4.50,4.00,4.00,4.00,4.00,4.00,4.00,4.00,4.00,4.00,4.00,4.00,4.00,4.50"
					( Origin gBackEnd )
				)
				( attribute "SN_SHAPE_TO_THRUVIA_SPACING" "5.00,5.00,5.00,5.00,5.00,5.00,5.00,5.00,5.00,5.00,5.00,5.00,5.00,5.00"
					( Origin gBackEnd )
				)
				( attribute "SN_TESTVIA_TO_TESTVIA_SPACING" "6.00,6.00,6.00,6.00,6.00,6.00,6.00,6.00,6.00,6.00,6.00,6.00,6.00,6.00"
					( Origin gBackEnd )
				)
				( attribute "SN_BBV_TO_TESTVIA_SPACING" "5.00,5.00,5.00,5.00,5.00,5.00,5.00,5.00,5.00,5.00,5.00,5.00,5.00,5.00"
					( Origin gBackEnd )
				)
				( attribute "SN_BONDPAD_TO_TESTVIA_SPACING" "5.00,5.00,5.00,5.00,5.00,5.00,5.00,5.00,5.00,5.00,5.00,5.00,5.00,5.00"
					( Origin gBackEnd )
				)
				( attribute "SN_LINE_TO_TESTVIA_SPACING" "5.00,4.00,4.00,4.00,4.00,4.00,4.00,4.00,4.00,4.00,4.00,4.00,4.00,5.00"
					( Origin gBackEnd )
				)
				( attribute "SN_SHAPE_TO_TESTVIA_SPACING" "5.00,5.00,5.00,5.00,5.00,5.00,5.00,5.00,5.00,5.00,5.00,5.00,5.00,5.00"
					( Origin gBackEnd )
				)
				( attribute "SN_BBV_TO_BBV_SPACING" "5.00,5.00,5.00,5.00,5.00,5.00,5.00,5.00,5.00,5.00,5.00,5.00,5.00,5.00"
					( Origin gBackEnd )
				)
				( attribute "SN_BONDPAD_TO_BBV_SPACING" "5.00,5.00,5.00,5.00,5.00,5.00,5.00,5.00,5.00,5.00,5.00,5.00,5.00,5.00"
					( Origin gBackEnd )
				)
				( attribute "SN_BBV_TO_LINE_SPACING" "5.00,5.00,5.00,5.00,5.00,5.00,5.00,5.00,5.00,5.00,5.00,5.00,5.00,5.00"
					( Origin gBackEnd )
				)
				( attribute "SN_BBV_TO_SHAPE_SPACING" "5.00,5.00,5.00,5.00,5.00,5.00,5.00,5.00,5.00,5.00,5.00,5.00,5.00,5.00"
					( Origin gBackEnd )
				)
				( attribute "SN_BONDPAD_TO_BONDPAD_SPACING" "5.00,5.00,5.00,5.00,5.00,5.00,5.00,5.00,5.00,5.00,5.00,5.00,5.00,5.00"
					( Origin gBackEnd )
				)
				( attribute "SN_BONDPAD_TO_LINE_SPACING" "5.00,5.00,5.00,5.00,5.00,5.00,5.00,5.00,5.00,5.00,5.00,5.00,5.00,5.00"
					( Origin gBackEnd )
				)
				( attribute "SN_BONDPAD_TO_SHAPE_SPACING" "5.00,5.00,5.00,5.00,5.00,5.00,5.00,5.00,5.00,5.00,5.00,5.00,5.00,5.00"
					( Origin gBackEnd )
				)
				( attribute "SN_LINE_TO_LINE_SPACING" "10.00,10.00,10.00,10.00,10.00,10.00,10.00,10.00,10.00,10.00,10.00,10.00,10.00,10.00"
					( Origin gBackEnd )
				)
				( attribute "SN_LINE_TO_SHAPE_SPACING" "0.00,0.00,0.00,0.00,0.00,0.00,0.00,0.00,0.00,0.00,0.00,0.00,0.00,0.00"
					( Origin gBackEnd )
				)
				( attribute "SN_SHAPE_TO_SHAPE_SPACING" "5.00,5.00,5.00,5.00,5.00,5.00,5.00,5.00,5.00,5.00,5.00,5.00,5.00,5.00"
					( Origin gBackEnd )
				)
				( attribute "SN_HOLE_TO_PIN_SPACING" "8.00,8.00,8.00,8.00,8.00,8.00,8.00,8.00,8.00,8.00,8.00,8.00,8.00,8.00"
					( Origin gBackEnd )
				)
				( attribute "SN_HOLE_TO_VIA_SPACING" "8.00,8.00,8.00,8.00,8.00,8.00,8.00,8.00,8.00,8.00,8.00,8.00,8.00,8.00"
					( Origin gBackEnd )
				)
				( attribute "SN_HOLE_TO_LINE_SPACING" "8.00,8.00,8.00,8.00,8.00,8.00,8.00,8.00,8.00,8.00,8.00,8.00,8.00,8.00"
					( Origin gBackEnd )
				)
				( attribute "SN_HOLE_TO_SHAPE_SPACING" "8.00,8.00,8.00,8.00,8.00,8.00,8.00,8.00,8.00,8.00,8.00,8.00,8.00,8.00"
					( Origin gBackEnd )
				)
				( attribute "SN_HOLE_TO_HOLE_SPACING" "8.00,8.00,8.00,8.00,8.00,8.00,8.00,8.00,8.00,8.00,8.00,8.00,8.00,8.00"
					( Origin gBackEnd )
				)
				( attribute "SN_MVIA_TO_MVIA_SPACING" "5.00,5.00,5.00,5.00,5.00,5.00,5.00,5.00,5.00,5.00,5.00,5.00,5.00,5.00"
					( Origin gBackEnd )
				)
				( attribute "SN_MVIA_TO_THRUPIN_SPACING" "5.00,5.00,5.00,5.00,5.00,5.00,5.00,5.00,5.00,5.00,5.00,5.00,5.00,5.00"
					( Origin gBackEnd )
				)
				( attribute "SN_MVIA_TO_SMDPIN_SPACING" "5.00,5.00,5.00,5.00,5.00,5.00,5.00,5.00,5.00,5.00,5.00,5.00,5.00,5.00"
					( Origin gBackEnd )
				)
				( attribute "SN_MVIA_TO_THRUVIA_SPACING" "5.00,5.00,5.00,5.00,5.00,5.00,5.00,5.00,5.00,5.00,5.00,5.00,5.00,5.00"
					( Origin gBackEnd )
				)
				( attribute "SN_MVIA_TO_BBV_SPACING" "5.00,5.00,5.00,5.00,5.00,5.00,5.00,5.00,5.00,5.00,5.00,5.00,5.00,5.00"
					( Origin gBackEnd )
				)
				( attribute "SN_MVIA_TO_LINE_SPACING" "5.00,5.00,5.00,5.00,5.00,5.00,5.00,5.00,5.00,5.00,5.00,5.00,5.00,5.00"
					( Origin gBackEnd )
				)
				( attribute "SN_MVIA_TO_SHAPE_SPACING" "5.00,5.00,5.00,5.00,5.00,5.00,5.00,5.00,5.00,5.00,5.00,5.00,5.00,5.00"
					( Origin gBackEnd )
				)
				( attribute "SN_MVIA_TO_TESTPIN_SPACING" "5.00,5.00,5.00,5.00,5.00,5.00,5.00,5.00,5.00,5.00,5.00,5.00,5.00,5.00"
					( Origin gBackEnd )
				)
				( attribute "SN_MVIA_TO_TESTVIA_SPACING" "5.00,5.00,5.00,5.00,5.00,5.00,5.00,5.00,5.00,5.00,5.00,5.00,5.00,5.00"
					( Origin gBackEnd )
				)
				( attribute "SN_BONDPAD_TO_MVIA_SPACING" "5.00,5.00,5.00,5.00,5.00,5.00,5.00,5.00,5.00,5.00,5.00,5.00,5.00,5.00"
					( Origin gBackEnd )
				)
				( objectStatus "10MIL" )
			)
			( sameNetSpacingCSet "@crescent_city_bb_fab1_lib.crescent_city_bb_fab1(sch_1):\18.5_MIL\"
				( attribute "SAME_NET" "TRUE,TRUE,TRUE,TRUE,TRUE,TRUE,TRUE,TRUE,TRUE,TRUE,TRUE,TRUE,TRUE,TRUE"
					( Origin gBackEnd )
				)
				( attribute "SN_THRUPIN_TO_THRUPIN_SPACING" "5.00,5.00,5.00,5.00,5.00,5.00,5.00,5.00,5.00,5.00,5.00,5.00,5.00,5.00"
					( Origin gBackEnd )
				)
				( attribute "SN_THRUPIN_TO_SMDPIN_SPACING" "5.00,5.00,5.00,5.00,5.00,5.00,5.00,5.00,5.00,5.00,5.00,5.00,5.00,5.00"
					( Origin gBackEnd )
				)
				( attribute "SN_TESTPIN_TO_THRUPIN_SPACING" "5.00,5.00,5.00,5.00,5.00,5.00,5.00,5.00,5.00,5.00,5.00,5.00,5.00,5.00"
					( Origin gBackEnd )
				)
				( attribute "SN_THRUPIN_TO_THRUVIA_SPACING" "5.00,5.00,5.00,5.00,5.00,5.00,5.00,5.00,5.00,5.00,5.00,5.00,5.00,5.00"
					( Origin gBackEnd )
				)
				( attribute "SN_TESTVIA_TO_THRUPIN_SPACING" "5.00,5.00,5.00,5.00,5.00,5.00,5.00,5.00,5.00,5.00,5.00,5.00,5.00,5.00"
					( Origin gBackEnd )
				)
				( attribute "SN_BBV_TO_THRUPIN_SPACING" "5.00,5.00,5.00,5.00,5.00,5.00,5.00,5.00,5.00,5.00,5.00,5.00,5.00,5.00"
					( Origin gBackEnd )
				)
				( attribute "SN_THRUPIN_TO_BONDPAD_SPACING" "5.00,5.00,5.00,5.00,5.00,5.00,5.00,5.00,5.00,5.00,5.00,5.00,5.00,5.00"
					( Origin gBackEnd )
				)
				( attribute "SN_LINE_TO_THRUPIN_SPACING" "4.50,4.00,4.00,4.00,4.00,4.00,4.00,4.00,4.00,4.00,4.00,4.00,4.00,4.50"
					( Origin gBackEnd )
				)
				( attribute "SN_THRUPIN_TO_SHAPE_SPACING" "5.00,5.00,5.00,5.00,5.00,5.00,5.00,5.00,5.00,5.00,5.00,5.00,5.00,5.00"
					( Origin gBackEnd )
				)
				( attribute "SN_SMDPIN_TO_SMDPIN_SPACING" "5.00,5.00,5.00,5.00,5.00,5.00,5.00,5.00,5.00,5.00,5.00,5.00,5.00,5.00"
					( Origin gBackEnd )
				)
				( attribute "SN_SMDPIN_TO_TESTPIN_SPACING" "5.00,5.00,5.00,5.00,5.00,5.00,5.00,5.00,5.00,5.00,5.00,5.00,5.00,5.00"
					( Origin gBackEnd )
				)
				( attribute "SN_SMDPIN_TO_THRUVIA_SPACING" "5.00,5.00,5.00,5.00,5.00,5.00,5.00,5.00,5.00,5.00,5.00,5.00,5.00,5.00"
					( Origin gBackEnd )
				)
				( attribute "SN_SMDPIN_TO_TESTVIA_SPACING" "5.00,5.00,5.00,5.00,5.00,5.00,5.00,5.00,5.00,5.00,5.00,5.00,5.00,5.00"
					( Origin gBackEnd )
				)
				( attribute "SN_BBV_TO_SMDPIN_SPACING" "5.00,5.00,5.00,5.00,5.00,5.00,5.00,5.00,5.00,5.00,5.00,5.00,5.00,5.00"
					( Origin gBackEnd )
				)
				( attribute "SN_SMDPIN_TO_BONDPAD_SPACING" "5.00,5.00,5.00,5.00,5.00,5.00,5.00,5.00,5.00,5.00,5.00,5.00,5.00,5.00"
					( Origin gBackEnd )
				)
				( attribute "SN_LINE_TO_SMDPIN_SPACING" "4.50,4.50,4.50,4.50,4.50,4.50,4.50,4.50,4.50,4.50,4.50,4.50,4.50,4.50"
					( Origin gBackEnd )
				)
				( attribute "SN_SHAPE_TO_SMDPIN_SPACING" "5.00,5.00,5.00,5.00,5.00,5.00,5.00,5.00,5.00,5.00,5.00,5.00,5.00,5.00"
					( Origin gBackEnd )
				)
				( attribute "SN_TESTPIN_TO_TESTPIN_SPACING" "5.00,5.00,5.00,5.00,5.00,5.00,5.00,5.00,5.00,5.00,5.00,5.00,5.00,5.00"
					( Origin gBackEnd )
				)
				( attribute "SN_TESTPIN_TO_THRUVIA_SPACING" "5.00,5.00,5.00,5.00,5.00,5.00,5.00,5.00,5.00,5.00,5.00,5.00,5.00,5.00"
					( Origin gBackEnd )
				)
				( attribute "SN_TESTPIN_TO_TESTVIA_SPACING" "5.00,5.00,5.00,5.00,5.00,5.00,5.00,5.00,5.00,5.00,5.00,5.00,5.00,5.00"
					( Origin gBackEnd )
				)
				( attribute "SN_BBV_TO_TESTPIN_SPACING" "5.00,5.00,5.00,5.00,5.00,5.00,5.00,5.00,5.00,5.00,5.00,5.00,5.00,5.00"
					( Origin gBackEnd )
				)
				( attribute "SN_BONDPAD_TO_TESTPIN_SPACING" "5.00,5.00,5.00,5.00,5.00,5.00,5.00,5.00,5.00,5.00,5.00,5.00,5.00,5.00"
					( Origin gBackEnd )
				)
				( attribute "SN_LINE_TO_TESTPIN_SPACING" "5.00,4.00,4.00,4.00,4.00,4.00,4.00,4.00,4.00,4.00,4.00,4.00,4.00,5.00"
					( Origin gBackEnd )
				)
				( attribute "SN_SHAPE_TO_TESTPIN_SPACING" "5.00,5.00,5.00,5.00,5.00,5.00,5.00,5.00,5.00,5.00,5.00,5.00,5.00,5.00"
					( Origin gBackEnd )
				)
				( attribute "SN_THRUVIA_TO_THRUVIA_SPACING" "4.50,4.00,4.00,4.00,4.00,4.00,4.00,4.00,4.00,4.00,4.00,4.00,4.00,4.50"
					( Origin gBackEnd )
				)
				( attribute "SN_TESTVIA_TO_THRUVIA_SPACING" "5.00,5.00,5.00,5.00,5.00,5.00,5.00,5.00,5.00,5.00,5.00,5.00,5.00,5.00"
					( Origin gBackEnd )
				)
				( attribute "SN_BBV_TO_THRUVIA_SPACING" "5.00,5.00,5.00,5.00,5.00,5.00,5.00,5.00,5.00,5.00,5.00,5.00,5.00,5.00"
					( Origin gBackEnd )
				)
				( attribute "SN_BONDPAD_TO_THRUVIA_SPACING" "5.00,5.00,5.00,5.00,5.00,5.00,5.00,5.00,5.00,5.00,5.00,5.00,5.00,5.00"
					( Origin gBackEnd )
				)
				( attribute "SN_LINE_TO_THRUVIA_SPACING" "4.50,4.00,4.00,4.00,4.00,4.00,4.00,4.00,4.00,4.00,4.00,4.00,4.00,4.50"
					( Origin gBackEnd )
				)
				( attribute "SN_SHAPE_TO_THRUVIA_SPACING" "5.00,5.00,5.00,5.00,5.00,5.00,5.00,5.00,5.00,5.00,5.00,5.00,5.00,5.00"
					( Origin gBackEnd )
				)
				( attribute "SN_TESTVIA_TO_TESTVIA_SPACING" "6.00,6.00,6.00,6.00,6.00,6.00,6.00,6.00,6.00,6.00,6.00,6.00,6.00,6.00"
					( Origin gBackEnd )
				)
				( attribute "SN_BBV_TO_TESTVIA_SPACING" "5.00,5.00,5.00,5.00,5.00,5.00,5.00,5.00,5.00,5.00,5.00,5.00,5.00,5.00"
					( Origin gBackEnd )
				)
				( attribute "SN_BONDPAD_TO_TESTVIA_SPACING" "5.00,5.00,5.00,5.00,5.00,5.00,5.00,5.00,5.00,5.00,5.00,5.00,5.00,5.00"
					( Origin gBackEnd )
				)
				( attribute "SN_LINE_TO_TESTVIA_SPACING" "5.00,4.00,4.00,4.00,4.00,4.00,4.00,4.00,4.00,4.00,4.00,4.00,4.00,5.00"
					( Origin gBackEnd )
				)
				( attribute "SN_SHAPE_TO_TESTVIA_SPACING" "5.00,5.00,5.00,5.00,5.00,5.00,5.00,5.00,5.00,5.00,5.00,5.00,5.00,5.00"
					( Origin gBackEnd )
				)
				( attribute "SN_BBV_TO_BBV_SPACING" "5.00,5.00,5.00,5.00,5.00,5.00,5.00,5.00,5.00,5.00,5.00,5.00,5.00,5.00"
					( Origin gBackEnd )
				)
				( attribute "SN_BONDPAD_TO_BBV_SPACING" "5.00,5.00,5.00,5.00,5.00,5.00,5.00,5.00,5.00,5.00,5.00,5.00,5.00,5.00"
					( Origin gBackEnd )
				)
				( attribute "SN_BBV_TO_LINE_SPACING" "5.00,5.00,5.00,5.00,5.00,5.00,5.00,5.00,5.00,5.00,5.00,5.00,5.00,5.00"
					( Origin gBackEnd )
				)
				( attribute "SN_BBV_TO_SHAPE_SPACING" "5.00,5.00,5.00,5.00,5.00,5.00,5.00,5.00,5.00,5.00,5.00,5.00,5.00,5.00"
					( Origin gBackEnd )
				)
				( attribute "SN_BONDPAD_TO_BONDPAD_SPACING" "5.00,5.00,5.00,5.00,5.00,5.00,5.00,5.00,5.00,5.00,5.00,5.00,5.00,5.00"
					( Origin gBackEnd )
				)
				( attribute "SN_BONDPAD_TO_LINE_SPACING" "5.00,5.00,5.00,5.00,5.00,5.00,5.00,5.00,5.00,5.00,5.00,5.00,5.00,5.00"
					( Origin gBackEnd )
				)
				( attribute "SN_BONDPAD_TO_SHAPE_SPACING" "5.00,5.00,5.00,5.00,5.00,5.00,5.00,5.00,5.00,5.00,5.00,5.00,5.00,5.00"
					( Origin gBackEnd )
				)
				( attribute "SN_LINE_TO_LINE_SPACING" "18.50,18.50,18.50,18.50,18.50,18.50,18.50,18.50,18.50,18.50,18.50,18.50,18.50,18.50"
					( Origin gBackEnd )
				)
				( attribute "SN_LINE_TO_SHAPE_SPACING" "0.00,0.00,0.00,0.00,0.00,0.00,0.00,0.00,0.00,0.00,0.00,0.00,0.00,0.00"
					( Origin gBackEnd )
				)
				( attribute "SN_SHAPE_TO_SHAPE_SPACING" "5.00,5.00,5.00,5.00,5.00,5.00,5.00,5.00,5.00,5.00,5.00,5.00,5.00,5.00"
					( Origin gBackEnd )
				)
				( attribute "SN_HOLE_TO_PIN_SPACING" "8.00,8.00,8.00,8.00,8.00,8.00,8.00,8.00,8.00,8.00,8.00,8.00,8.00,8.00"
					( Origin gBackEnd )
				)
				( attribute "SN_HOLE_TO_VIA_SPACING" "8.00,8.00,8.00,8.00,8.00,8.00,8.00,8.00,8.00,8.00,8.00,8.00,8.00,8.00"
					( Origin gBackEnd )
				)
				( attribute "SN_HOLE_TO_LINE_SPACING" "8.00,8.00,8.00,8.00,8.00,8.00,8.00,8.00,8.00,8.00,8.00,8.00,8.00,8.00"
					( Origin gBackEnd )
				)
				( attribute "SN_HOLE_TO_SHAPE_SPACING" "8.00,8.00,8.00,8.00,8.00,8.00,8.00,8.00,8.00,8.00,8.00,8.00,8.00,8.00"
					( Origin gBackEnd )
				)
				( attribute "SN_HOLE_TO_HOLE_SPACING" "8.00,8.00,8.00,8.00,8.00,8.00,8.00,8.00,8.00,8.00,8.00,8.00,8.00,8.00"
					( Origin gBackEnd )
				)
				( attribute "SN_MVIA_TO_MVIA_SPACING" "5.00,5.00,5.00,5.00,5.00,5.00,5.00,5.00,5.00,5.00,5.00,5.00,5.00,5.00"
					( Origin gBackEnd )
				)
				( attribute "SN_MVIA_TO_THRUPIN_SPACING" "5.00,5.00,5.00,5.00,5.00,5.00,5.00,5.00,5.00,5.00,5.00,5.00,5.00,5.00"
					( Origin gBackEnd )
				)
				( attribute "SN_MVIA_TO_SMDPIN_SPACING" "5.00,5.00,5.00,5.00,5.00,5.00,5.00,5.00,5.00,5.00,5.00,5.00,5.00,5.00"
					( Origin gBackEnd )
				)
				( attribute "SN_MVIA_TO_THRUVIA_SPACING" "5.00,5.00,5.00,5.00,5.00,5.00,5.00,5.00,5.00,5.00,5.00,5.00,5.00,5.00"
					( Origin gBackEnd )
				)
				( attribute "SN_MVIA_TO_BBV_SPACING" "5.00,5.00,5.00,5.00,5.00,5.00,5.00,5.00,5.00,5.00,5.00,5.00,5.00,5.00"
					( Origin gBackEnd )
				)
				( attribute "SN_MVIA_TO_LINE_SPACING" "5.00,5.00,5.00,5.00,5.00,5.00,5.00,5.00,5.00,5.00,5.00,5.00,5.00,5.00"
					( Origin gBackEnd )
				)
				( attribute "SN_MVIA_TO_SHAPE_SPACING" "5.00,5.00,5.00,5.00,5.00,5.00,5.00,5.00,5.00,5.00,5.00,5.00,5.00,5.00"
					( Origin gBackEnd )
				)
				( attribute "SN_MVIA_TO_TESTPIN_SPACING" "5.00,5.00,5.00,5.00,5.00,5.00,5.00,5.00,5.00,5.00,5.00,5.00,5.00,5.00"
					( Origin gBackEnd )
				)
				( attribute "SN_MVIA_TO_TESTVIA_SPACING" "5.00,5.00,5.00,5.00,5.00,5.00,5.00,5.00,5.00,5.00,5.00,5.00,5.00,5.00"
					( Origin gBackEnd )
				)
				( attribute "SN_BONDPAD_TO_MVIA_SPACING" "5.00,5.00,5.00,5.00,5.00,5.00,5.00,5.00,5.00,5.00,5.00,5.00,5.00,5.00"
					( Origin gBackEnd )
				)
				( objectStatus "18.5_MIL" )
			)
			( sameNetSpacingCSet "@crescent_city_bb_fab1_lib.crescent_city_bb_fab1(sch_1):\16_MIL\"
				( attribute "SAME_NET" "TRUE,TRUE,TRUE,TRUE,TRUE,TRUE,TRUE,TRUE,TRUE,TRUE,TRUE,TRUE,TRUE,TRUE"
					( Origin gBackEnd )
				)
				( attribute "SN_THRUPIN_TO_THRUPIN_SPACING" "5.00,5.00,5.00,5.00,5.00,5.00,5.00,5.00,5.00,5.00,5.00,5.00,5.00,5.00"
					( Origin gBackEnd )
				)
				( attribute "SN_THRUPIN_TO_SMDPIN_SPACING" "5.00,5.00,5.00,5.00,5.00,5.00,5.00,5.00,5.00,5.00,5.00,5.00,5.00,5.00"
					( Origin gBackEnd )
				)
				( attribute "SN_TESTPIN_TO_THRUPIN_SPACING" "5.00,5.00,5.00,5.00,5.00,5.00,5.00,5.00,5.00,5.00,5.00,5.00,5.00,5.00"
					( Origin gBackEnd )
				)
				( attribute "SN_THRUPIN_TO_THRUVIA_SPACING" "5.00,5.00,5.00,5.00,5.00,5.00,5.00,5.00,5.00,5.00,5.00,5.00,5.00,5.00"
					( Origin gBackEnd )
				)
				( attribute "SN_TESTVIA_TO_THRUPIN_SPACING" "5.00,5.00,5.00,5.00,5.00,5.00,5.00,5.00,5.00,5.00,5.00,5.00,5.00,5.00"
					( Origin gBackEnd )
				)
				( attribute "SN_BBV_TO_THRUPIN_SPACING" "5.00,5.00,5.00,5.00,5.00,5.00,5.00,5.00,5.00,5.00,5.00,5.00,5.00,5.00"
					( Origin gBackEnd )
				)
				( attribute "SN_THRUPIN_TO_BONDPAD_SPACING" "5.00,5.00,5.00,5.00,5.00,5.00,5.00,5.00,5.00,5.00,5.00,5.00,5.00,5.00"
					( Origin gBackEnd )
				)
				( attribute "SN_LINE_TO_THRUPIN_SPACING" "4.50,4.00,4.00,4.00,4.00,4.00,4.00,4.00,4.00,4.00,4.00,4.00,4.00,4.50"
					( Origin gBackEnd )
				)
				( attribute "SN_THRUPIN_TO_SHAPE_SPACING" "5.00,5.00,5.00,5.00,5.00,5.00,5.00,5.00,5.00,5.00,5.00,5.00,5.00,5.00"
					( Origin gBackEnd )
				)
				( attribute "SN_SMDPIN_TO_SMDPIN_SPACING" "5.00,5.00,5.00,5.00,5.00,5.00,5.00,5.00,5.00,5.00,5.00,5.00,5.00,5.00"
					( Origin gBackEnd )
				)
				( attribute "SN_SMDPIN_TO_TESTPIN_SPACING" "5.00,5.00,5.00,5.00,5.00,5.00,5.00,5.00,5.00,5.00,5.00,5.00,5.00,5.00"
					( Origin gBackEnd )
				)
				( attribute "SN_SMDPIN_TO_THRUVIA_SPACING" "5.00,5.00,5.00,5.00,5.00,5.00,5.00,5.00,5.00,5.00,5.00,5.00,5.00,5.00"
					( Origin gBackEnd )
				)
				( attribute "SN_SMDPIN_TO_TESTVIA_SPACING" "5.00,5.00,5.00,5.00,5.00,5.00,5.00,5.00,5.00,5.00,5.00,5.00,5.00,5.00"
					( Origin gBackEnd )
				)
				( attribute "SN_BBV_TO_SMDPIN_SPACING" "5.00,5.00,5.00,5.00,5.00,5.00,5.00,5.00,5.00,5.00,5.00,5.00,5.00,5.00"
					( Origin gBackEnd )
				)
				( attribute "SN_SMDPIN_TO_BONDPAD_SPACING" "5.00,5.00,5.00,5.00,5.00,5.00,5.00,5.00,5.00,5.00,5.00,5.00,5.00,5.00"
					( Origin gBackEnd )
				)
				( attribute "SN_LINE_TO_SMDPIN_SPACING" "4.50,4.50,4.50,4.50,4.50,4.50,4.50,4.50,4.50,4.50,4.50,4.50,4.50,4.50"
					( Origin gBackEnd )
				)
				( attribute "SN_SHAPE_TO_SMDPIN_SPACING" "5.00,5.00,5.00,5.00,5.00,5.00,5.00,5.00,5.00,5.00,5.00,5.00,5.00,5.00"
					( Origin gBackEnd )
				)
				( attribute "SN_TESTPIN_TO_TESTPIN_SPACING" "5.00,5.00,5.00,5.00,5.00,5.00,5.00,5.00,5.00,5.00,5.00,5.00,5.00,5.00"
					( Origin gBackEnd )
				)
				( attribute "SN_TESTPIN_TO_THRUVIA_SPACING" "5.00,5.00,5.00,5.00,5.00,5.00,5.00,5.00,5.00,5.00,5.00,5.00,5.00,5.00"
					( Origin gBackEnd )
				)
				( attribute "SN_TESTPIN_TO_TESTVIA_SPACING" "5.00,5.00,5.00,5.00,5.00,5.00,5.00,5.00,5.00,5.00,5.00,5.00,5.00,5.00"
					( Origin gBackEnd )
				)
				( attribute "SN_BBV_TO_TESTPIN_SPACING" "5.00,5.00,5.00,5.00,5.00,5.00,5.00,5.00,5.00,5.00,5.00,5.00,5.00,5.00"
					( Origin gBackEnd )
				)
				( attribute "SN_BONDPAD_TO_TESTPIN_SPACING" "5.00,5.00,5.00,5.00,5.00,5.00,5.00,5.00,5.00,5.00,5.00,5.00,5.00,5.00"
					( Origin gBackEnd )
				)
				( attribute "SN_LINE_TO_TESTPIN_SPACING" "5.00,4.00,4.00,4.00,4.00,4.00,4.00,4.00,4.00,4.00,4.00,4.00,4.00,5.00"
					( Origin gBackEnd )
				)
				( attribute "SN_SHAPE_TO_TESTPIN_SPACING" "5.00,5.00,5.00,5.00,5.00,5.00,5.00,5.00,5.00,5.00,5.00,5.00,5.00,5.00"
					( Origin gBackEnd )
				)
				( attribute "SN_THRUVIA_TO_THRUVIA_SPACING" "4.50,4.00,4.00,4.00,4.00,4.00,4.00,4.00,4.00,4.00,4.00,4.00,4.00,4.50"
					( Origin gBackEnd )
				)
				( attribute "SN_TESTVIA_TO_THRUVIA_SPACING" "5.00,5.00,5.00,5.00,5.00,5.00,5.00,5.00,5.00,5.00,5.00,5.00,5.00,5.00"
					( Origin gBackEnd )
				)
				( attribute "SN_BBV_TO_THRUVIA_SPACING" "5.00,5.00,5.00,5.00,5.00,5.00,5.00,5.00,5.00,5.00,5.00,5.00,5.00,5.00"
					( Origin gBackEnd )
				)
				( attribute "SN_BONDPAD_TO_THRUVIA_SPACING" "5.00,5.00,5.00,5.00,5.00,5.00,5.00,5.00,5.00,5.00,5.00,5.00,5.00,5.00"
					( Origin gBackEnd )
				)
				( attribute "SN_LINE_TO_THRUVIA_SPACING" "4.50,4.00,4.00,4.00,4.00,4.00,4.00,4.00,4.00,4.00,4.00,4.00,4.00,4.50"
					( Origin gBackEnd )
				)
				( attribute "SN_SHAPE_TO_THRUVIA_SPACING" "5.00,5.00,5.00,5.00,5.00,5.00,5.00,5.00,5.00,5.00,5.00,5.00,5.00,5.00"
					( Origin gBackEnd )
				)
				( attribute "SN_TESTVIA_TO_TESTVIA_SPACING" "5.00,5.00,5.00,5.00,5.00,5.00,5.00,5.00,5.00,5.00,5.00,5.00,5.00,5.00"
					( Origin gBackEnd )
				)
				( attribute "SN_BBV_TO_TESTVIA_SPACING" "5.00,5.00,5.00,5.00,5.00,5.00,5.00,5.00,5.00,5.00,5.00,5.00,5.00,5.00"
					( Origin gBackEnd )
				)
				( attribute "SN_BONDPAD_TO_TESTVIA_SPACING" "5.00,5.00,5.00,5.00,5.00,5.00,5.00,5.00,5.00,5.00,5.00,5.00,5.00,5.00"
					( Origin gBackEnd )
				)
				( attribute "SN_LINE_TO_TESTVIA_SPACING" "5.00,4.00,4.00,4.00,4.00,4.00,4.00,4.00,4.00,4.00,4.00,4.00,4.00,5.00"
					( Origin gBackEnd )
				)
				( attribute "SN_SHAPE_TO_TESTVIA_SPACING" "5.00,5.00,5.00,5.00,5.00,5.00,5.00,5.00,5.00,5.00,5.00,5.00,5.00,5.00"
					( Origin gBackEnd )
				)
				( attribute "SN_BBV_TO_BBV_SPACING" "5.00,5.00,5.00,5.00,5.00,5.00,5.00,5.00,5.00,5.00,5.00,5.00,5.00,5.00"
					( Origin gBackEnd )
				)
				( attribute "SN_BONDPAD_TO_BBV_SPACING" "5.00,5.00,5.00,5.00,5.00,5.00,5.00,5.00,5.00,5.00,5.00,5.00,5.00,5.00"
					( Origin gBackEnd )
				)
				( attribute "SN_BBV_TO_LINE_SPACING" "5.00,5.00,5.00,5.00,5.00,5.00,5.00,5.00,5.00,5.00,5.00,5.00,5.00,5.00"
					( Origin gBackEnd )
				)
				( attribute "SN_BBV_TO_SHAPE_SPACING" "5.00,5.00,5.00,5.00,5.00,5.00,5.00,5.00,5.00,5.00,5.00,5.00,5.00,5.00"
					( Origin gBackEnd )
				)
				( attribute "SN_BONDPAD_TO_BONDPAD_SPACING" "5.00,5.00,5.00,5.00,5.00,5.00,5.00,5.00,5.00,5.00,5.00,5.00,5.00,5.00"
					( Origin gBackEnd )
				)
				( attribute "SN_BONDPAD_TO_LINE_SPACING" "5.00,5.00,5.00,5.00,5.00,5.00,5.00,5.00,5.00,5.00,5.00,5.00,5.00,5.00"
					( Origin gBackEnd )
				)
				( attribute "SN_BONDPAD_TO_SHAPE_SPACING" "5.00,5.00,5.00,5.00,5.00,5.00,5.00,5.00,5.00,5.00,5.00,5.00,5.00,5.00"
					( Origin gBackEnd )
				)
				( attribute "SN_LINE_TO_LINE_SPACING" "16.00,16.00,16.00,16.00,16.00,16.00,16.00,16.00,16.00,16.00,16.00,16.00,16.00,16.00"
					( Origin gBackEnd )
				)
				( attribute "SN_LINE_TO_SHAPE_SPACING" "0.00,0.00,0.00,0.00,0.00,0.00,0.00,0.00,0.00,0.00,0.00,0.00,0.00,0.00"
					( Origin gBackEnd )
				)
				( attribute "SN_SHAPE_TO_SHAPE_SPACING" "5.00,5.00,5.00,5.00,5.00,5.00,5.00,5.00,5.00,5.00,5.00,5.00,5.00,5.00"
					( Origin gBackEnd )
				)
				( attribute "SN_HOLE_TO_PIN_SPACING" "8.00,8.00,8.00,8.00,8.00,8.00,8.00,8.00,8.00,8.00,8.00,8.00,8.00,8.00"
					( Origin gBackEnd )
				)
				( attribute "SN_HOLE_TO_VIA_SPACING" "8.00,8.00,8.00,8.00,8.00,8.00,8.00,8.00,8.00,8.00,8.00,8.00,8.00,8.00"
					( Origin gBackEnd )
				)
				( attribute "SN_HOLE_TO_LINE_SPACING" "8.00,8.00,8.00,8.00,8.00,8.00,8.00,8.00,8.00,8.00,8.00,8.00,8.00,8.00"
					( Origin gBackEnd )
				)
				( attribute "SN_HOLE_TO_SHAPE_SPACING" "8.00,8.00,8.00,8.00,8.00,8.00,8.00,8.00,8.00,8.00,8.00,8.00,8.00,8.00"
					( Origin gBackEnd )
				)
				( attribute "SN_HOLE_TO_HOLE_SPACING" "8.00,8.00,8.00,8.00,8.00,8.00,8.00,8.00,8.00,8.00,8.00,8.00,8.00,8.00"
					( Origin gBackEnd )
				)
				( attribute "SN_MVIA_TO_MVIA_SPACING" "5.00,5.00,5.00,5.00,5.00,5.00,5.00,5.00,5.00,5.00,5.00,5.00,5.00,5.00"
					( Origin gBackEnd )
				)
				( attribute "SN_MVIA_TO_THRUPIN_SPACING" "5.00,5.00,5.00,5.00,5.00,5.00,5.00,5.00,5.00,5.00,5.00,5.00,5.00,5.00"
					( Origin gBackEnd )
				)
				( attribute "SN_MVIA_TO_SMDPIN_SPACING" "5.00,5.00,5.00,5.00,5.00,5.00,5.00,5.00,5.00,5.00,5.00,5.00,5.00,5.00"
					( Origin gBackEnd )
				)
				( attribute "SN_MVIA_TO_THRUVIA_SPACING" "5.00,5.00,5.00,5.00,5.00,5.00,5.00,5.00,5.00,5.00,5.00,5.00,5.00,5.00"
					( Origin gBackEnd )
				)
				( attribute "SN_MVIA_TO_BBV_SPACING" "5.00,5.00,5.00,5.00,5.00,5.00,5.00,5.00,5.00,5.00,5.00,5.00,5.00,5.00"
					( Origin gBackEnd )
				)
				( attribute "SN_MVIA_TO_LINE_SPACING" "5.00,5.00,5.00,5.00,5.00,5.00,5.00,5.00,5.00,5.00,5.00,5.00,5.00,5.00"
					( Origin gBackEnd )
				)
				( attribute "SN_MVIA_TO_SHAPE_SPACING" "5.00,5.00,5.00,5.00,5.00,5.00,5.00,5.00,5.00,5.00,5.00,5.00,5.00,5.00"
					( Origin gBackEnd )
				)
				( attribute "SN_MVIA_TO_TESTPIN_SPACING" "5.00,5.00,5.00,5.00,5.00,5.00,5.00,5.00,5.00,5.00,5.00,5.00,5.00,5.00"
					( Origin gBackEnd )
				)
				( attribute "SN_MVIA_TO_TESTVIA_SPACING" "5.00,5.00,5.00,5.00,5.00,5.00,5.00,5.00,5.00,5.00,5.00,5.00,5.00,5.00"
					( Origin gBackEnd )
				)
				( attribute "SN_BONDPAD_TO_MVIA_SPACING" "5.00,5.00,5.00,5.00,5.00,5.00,5.00,5.00,5.00,5.00,5.00,5.00,5.00,5.00"
					( Origin gBackEnd )
				)
				( objectStatus "16_MIL" )
			)
			( sameNetSpacingCSet "@crescent_city_bb_fab1_lib.crescent_city_bb_fab1(sch_1):\5H_SL_9H_MS\"
				( attribute "SAME_NET" "TRUE,TRUE,TRUE,TRUE,TRUE,TRUE,TRUE,TRUE,TRUE,TRUE,TRUE,TRUE,TRUE,TRUE"
					( Origin gBackEnd )
				)
				( attribute "SN_THRUPIN_TO_THRUPIN_SPACING" "5.00,5.00,5.00,5.00,5.00,5.00,5.00,5.00,5.00,5.00,5.00,5.00,5.00,5.00"
					( Origin gBackEnd )
				)
				( attribute "SN_THRUPIN_TO_SMDPIN_SPACING" "5.00,5.00,5.00,5.00,5.00,5.00,5.00,5.00,5.00,5.00,5.00,5.00,5.00,5.00"
					( Origin gBackEnd )
				)
				( attribute "SN_TESTPIN_TO_THRUPIN_SPACING" "5.00,5.00,5.00,5.00,5.00,5.00,5.00,5.00,5.00,5.00,5.00,5.00,5.00,5.00"
					( Origin gBackEnd )
				)
				( attribute "SN_THRUPIN_TO_THRUVIA_SPACING" "5.00,5.00,5.00,5.00,5.00,5.00,5.00,5.00,5.00,5.00,5.00,5.00,5.00,5.00"
					( Origin gBackEnd )
				)
				( attribute "SN_TESTVIA_TO_THRUPIN_SPACING" "5.00,5.00,5.00,5.00,5.00,5.00,5.00,5.00,5.00,5.00,5.00,5.00,5.00,5.00"
					( Origin gBackEnd )
				)
				( attribute "SN_BBV_TO_THRUPIN_SPACING" "5.00,5.00,5.00,5.00,5.00,5.00,5.00,5.00,5.00,5.00,5.00,5.00,5.00,5.00"
					( Origin gBackEnd )
				)
				( attribute "SN_THRUPIN_TO_BONDPAD_SPACING" "5.00,5.00,5.00,5.00,5.00,5.00,5.00,5.00,5.00,5.00,5.00,5.00,5.00,5.00"
					( Origin gBackEnd )
				)
				( attribute "SN_LINE_TO_THRUPIN_SPACING" "4.50,4.00,4.00,4.00,4.00,4.00,4.00,4.00,4.00,4.00,4.00,4.00,4.00,4.50"
					( Origin gBackEnd )
				)
				( attribute "SN_THRUPIN_TO_SHAPE_SPACING" "5.00,5.00,5.00,5.00,5.00,5.00,5.00,5.00,5.00,5.00,5.00,5.00,5.00,5.00"
					( Origin gBackEnd )
				)
				( attribute "SN_SMDPIN_TO_SMDPIN_SPACING" "5.00,5.00,5.00,5.00,5.00,5.00,5.00,5.00,5.00,5.00,5.00,5.00,5.00,5.00"
					( Origin gBackEnd )
				)
				( attribute "SN_SMDPIN_TO_TESTPIN_SPACING" "5.00,5.00,5.00,5.00,5.00,5.00,5.00,5.00,5.00,5.00,5.00,5.00,5.00,5.00"
					( Origin gBackEnd )
				)
				( attribute "SN_SMDPIN_TO_THRUVIA_SPACING" "5.00,5.00,5.00,5.00,5.00,5.00,5.00,5.00,5.00,5.00,5.00,5.00,5.00,5.00"
					( Origin gBackEnd )
				)
				( attribute "SN_SMDPIN_TO_TESTVIA_SPACING" "5.00,5.00,5.00,5.00,5.00,5.00,5.00,5.00,5.00,5.00,5.00,5.00,5.00,5.00"
					( Origin gBackEnd )
				)
				( attribute "SN_BBV_TO_SMDPIN_SPACING" "5.00,5.00,5.00,5.00,5.00,5.00,5.00,5.00,5.00,5.00,5.00,5.00,5.00,5.00"
					( Origin gBackEnd )
				)
				( attribute "SN_SMDPIN_TO_BONDPAD_SPACING" "5.00,5.00,5.00,5.00,5.00,5.00,5.00,5.00,5.00,5.00,5.00,5.00,5.00,5.00"
					( Origin gBackEnd )
				)
				( attribute "SN_LINE_TO_SMDPIN_SPACING" "4.50,4.50,4.50,4.50,4.50,4.50,4.50,4.50,4.50,4.50,4.50,4.50,4.50,4.50"
					( Origin gBackEnd )
				)
				( attribute "SN_SHAPE_TO_SMDPIN_SPACING" "5.00,5.00,5.00,5.00,5.00,5.00,5.00,5.00,5.00,5.00,5.00,5.00,5.00,5.00"
					( Origin gBackEnd )
				)
				( attribute "SN_TESTPIN_TO_TESTPIN_SPACING" "5.00,5.00,5.00,5.00,5.00,5.00,5.00,5.00,5.00,5.00,5.00,5.00,5.00,5.00"
					( Origin gBackEnd )
				)
				( attribute "SN_TESTPIN_TO_THRUVIA_SPACING" "5.00,5.00,5.00,5.00,5.00,5.00,5.00,5.00,5.00,5.00,5.00,5.00,5.00,5.00"
					( Origin gBackEnd )
				)
				( attribute "SN_TESTPIN_TO_TESTVIA_SPACING" "5.00,5.00,5.00,5.00,5.00,5.00,5.00,5.00,5.00,5.00,5.00,5.00,5.00,5.00"
					( Origin gBackEnd )
				)
				( attribute "SN_BBV_TO_TESTPIN_SPACING" "5.00,5.00,5.00,5.00,5.00,5.00,5.00,5.00,5.00,5.00,5.00,5.00,5.00,5.00"
					( Origin gBackEnd )
				)
				( attribute "SN_BONDPAD_TO_TESTPIN_SPACING" "5.00,5.00,5.00,5.00,5.00,5.00,5.00,5.00,5.00,5.00,5.00,5.00,5.00,5.00"
					( Origin gBackEnd )
				)
				( attribute "SN_LINE_TO_TESTPIN_SPACING" "5.00,4.00,4.00,4.00,4.00,4.00,4.00,4.00,4.00,4.00,4.00,4.00,4.00,5.00"
					( Origin gBackEnd )
				)
				( attribute "SN_SHAPE_TO_TESTPIN_SPACING" "5.00,5.00,5.00,5.00,5.00,5.00,5.00,5.00,5.00,5.00,5.00,5.00,5.00,5.00"
					( Origin gBackEnd )
				)
				( attribute "SN_THRUVIA_TO_THRUVIA_SPACING" "4.50,4.00,4.00,4.00,4.00,4.00,4.00,4.00,4.00,4.00,4.00,4.00,4.00,4.50"
					( Origin gBackEnd )
				)
				( attribute "SN_TESTVIA_TO_THRUVIA_SPACING" "5.00,5.00,5.00,5.00,5.00,5.00,5.00,5.00,5.00,5.00,5.00,5.00,5.00,5.00"
					( Origin gBackEnd )
				)
				( attribute "SN_BBV_TO_THRUVIA_SPACING" "5.00,5.00,5.00,5.00,5.00,5.00,5.00,5.00,5.00,5.00,5.00,5.00,5.00,5.00"
					( Origin gBackEnd )
				)
				( attribute "SN_BONDPAD_TO_THRUVIA_SPACING" "5.00,5.00,5.00,5.00,5.00,5.00,5.00,5.00,5.00,5.00,5.00,5.00,5.00,5.00"
					( Origin gBackEnd )
				)
				( attribute "SN_LINE_TO_THRUVIA_SPACING" "4.50,4.00,4.00,4.00,4.00,4.00,4.00,4.00,4.00,4.00,4.00,4.00,4.00,4.50"
					( Origin gBackEnd )
				)
				( attribute "SN_SHAPE_TO_THRUVIA_SPACING" "5.00,5.00,5.00,5.00,5.00,5.00,5.00,5.00,5.00,5.00,5.00,5.00,5.00,5.00"
					( Origin gBackEnd )
				)
				( attribute "SN_TESTVIA_TO_TESTVIA_SPACING" "6.00,6.00,6.00,6.00,6.00,6.00,6.00,6.00,6.00,6.00,6.00,6.00,6.00,6.00"
					( Origin gBackEnd )
				)
				( attribute "SN_BBV_TO_TESTVIA_SPACING" "5.00,5.00,5.00,5.00,5.00,5.00,5.00,5.00,5.00,5.00,5.00,5.00,5.00,5.00"
					( Origin gBackEnd )
				)
				( attribute "SN_BONDPAD_TO_TESTVIA_SPACING" "5.00,5.00,5.00,5.00,5.00,5.00,5.00,5.00,5.00,5.00,5.00,5.00,5.00,5.00"
					( Origin gBackEnd )
				)
				( attribute "SN_LINE_TO_TESTVIA_SPACING" "5.00,4.00,4.00,4.00,4.00,4.00,4.00,4.00,4.00,4.00,4.00,4.00,4.00,5.00"
					( Origin gBackEnd )
				)
				( attribute "SN_SHAPE_TO_TESTVIA_SPACING" "5.00,5.00,5.00,5.00,5.00,5.00,5.00,5.00,5.00,5.00,5.00,5.00,5.00,5.00"
					( Origin gBackEnd )
				)
				( attribute "SN_BBV_TO_BBV_SPACING" "5.00,5.00,5.00,5.00,5.00,5.00,5.00,5.00,5.00,5.00,5.00,5.00,5.00,5.00"
					( Origin gBackEnd )
				)
				( attribute "SN_BONDPAD_TO_BBV_SPACING" "5.00,5.00,5.00,5.00,5.00,5.00,5.00,5.00,5.00,5.00,5.00,5.00,5.00,5.00"
					( Origin gBackEnd )
				)
				( attribute "SN_BBV_TO_LINE_SPACING" "5.00,5.00,5.00,5.00,5.00,5.00,5.00,5.00,5.00,5.00,5.00,5.00,5.00,5.00"
					( Origin gBackEnd )
				)
				( attribute "SN_BBV_TO_SHAPE_SPACING" "5.00,5.00,5.00,5.00,5.00,5.00,5.00,5.00,5.00,5.00,5.00,5.00,5.00,5.00"
					( Origin gBackEnd )
				)
				( attribute "SN_BONDPAD_TO_BONDPAD_SPACING" "5.00,5.00,5.00,5.00,5.00,5.00,5.00,5.00,5.00,5.00,5.00,5.00,5.00,5.00"
					( Origin gBackEnd )
				)
				( attribute "SN_BONDPAD_TO_LINE_SPACING" "5.00,5.00,5.00,5.00,5.00,5.00,5.00,5.00,5.00,5.00,5.00,5.00,5.00,5.00"
					( Origin gBackEnd )
				)
				( attribute "SN_BONDPAD_TO_SHAPE_SPACING" "5.00,5.00,5.00,5.00,5.00,5.00,5.00,5.00,5.00,5.00,5.00,5.00,5.00,5.00"
					( Origin gBackEnd )
				)
				( attribute "SN_LINE_TO_LINE_SPACING" "24.30,15.00,15.00,15.00,15.00,15.00,15.00,15.00,15.00,15.00,15.00,15.00,15.00,24.30"
					( Origin gBackEnd )
				)
				( attribute "SN_LINE_TO_SHAPE_SPACING" "0.00,0.00,0.00,0.00,0.00,0.00,0.00,0.00,0.00,0.00,0.00,0.00,0.00,0.00"
					( Origin gBackEnd )
				)
				( attribute "SN_SHAPE_TO_SHAPE_SPACING" "5.00,5.00,5.00,5.00,5.00,5.00,5.00,5.00,5.00,5.00,5.00,5.00,5.00,5.00"
					( Origin gBackEnd )
				)
				( attribute "SN_HOLE_TO_PIN_SPACING" "8.00,8.00,8.00,8.00,8.00,8.00,8.00,8.00,8.00,8.00,8.00,8.00,8.00,8.00"
					( Origin gBackEnd )
				)
				( attribute "SN_HOLE_TO_VIA_SPACING" "8.00,8.00,8.00,8.00,8.00,8.00,8.00,8.00,8.00,8.00,8.00,8.00,8.00,8.00"
					( Origin gBackEnd )
				)
				( attribute "SN_HOLE_TO_LINE_SPACING" "8.00,8.00,8.00,8.00,8.00,8.00,8.00,8.00,8.00,8.00,8.00,8.00,8.00,8.00"
					( Origin gBackEnd )
				)
				( attribute "SN_HOLE_TO_SHAPE_SPACING" "8.00,8.00,8.00,8.00,8.00,8.00,8.00,8.00,8.00,8.00,8.00,8.00,8.00,8.00"
					( Origin gBackEnd )
				)
				( attribute "SN_HOLE_TO_HOLE_SPACING" "8.00,8.00,8.00,8.00,8.00,8.00,8.00,8.00,8.00,8.00,8.00,8.00,8.00,8.00"
					( Origin gBackEnd )
				)
				( attribute "SN_MVIA_TO_MVIA_SPACING" "5.00,5.00,5.00,5.00,5.00,5.00,5.00,5.00,5.00,5.00,5.00,5.00,5.00,5.00"
					( Origin gBackEnd )
				)
				( attribute "SN_MVIA_TO_THRUPIN_SPACING" "5.00,5.00,5.00,5.00,5.00,5.00,5.00,5.00,5.00,5.00,5.00,5.00,5.00,5.00"
					( Origin gBackEnd )
				)
				( attribute "SN_MVIA_TO_SMDPIN_SPACING" "5.00,5.00,5.00,5.00,5.00,5.00,5.00,5.00,5.00,5.00,5.00,5.00,5.00,5.00"
					( Origin gBackEnd )
				)
				( attribute "SN_MVIA_TO_THRUVIA_SPACING" "5.00,5.00,5.00,5.00,5.00,5.00,5.00,5.00,5.00,5.00,5.00,5.00,5.00,5.00"
					( Origin gBackEnd )
				)
				( attribute "SN_MVIA_TO_BBV_SPACING" "5.00,5.00,5.00,5.00,5.00,5.00,5.00,5.00,5.00,5.00,5.00,5.00,5.00,5.00"
					( Origin gBackEnd )
				)
				( attribute "SN_MVIA_TO_LINE_SPACING" "5.00,5.00,5.00,5.00,5.00,5.00,5.00,5.00,5.00,5.00,5.00,5.00,5.00,5.00"
					( Origin gBackEnd )
				)
				( attribute "SN_MVIA_TO_SHAPE_SPACING" "5.00,5.00,5.00,5.00,5.00,5.00,5.00,5.00,5.00,5.00,5.00,5.00,5.00,5.00"
					( Origin gBackEnd )
				)
				( attribute "SN_MVIA_TO_TESTPIN_SPACING" "5.00,5.00,5.00,5.00,5.00,5.00,5.00,5.00,5.00,5.00,5.00,5.00,5.00,5.00"
					( Origin gBackEnd )
				)
				( attribute "SN_MVIA_TO_TESTVIA_SPACING" "5.00,5.00,5.00,5.00,5.00,5.00,5.00,5.00,5.00,5.00,5.00,5.00,5.00,5.00"
					( Origin gBackEnd )
				)
				( attribute "SN_BONDPAD_TO_MVIA_SPACING" "5.00,5.00,5.00,5.00,5.00,5.00,5.00,5.00,5.00,5.00,5.00,5.00,5.00,5.00"
					( Origin gBackEnd )
				)
				( objectStatus "9H_US_&_5H_SL" )
			)
			( sameNetSpacingCSet "@crescent_city_bb_fab1_lib.crescent_city_bb_fab1(sch_1):\3H_SL_9H_MS_VIA_3H+A\"
				( attribute "SAME_NET" "TRUE,TRUE,TRUE,TRUE,TRUE,TRUE,TRUE,TRUE,TRUE,TRUE,TRUE,TRUE,TRUE,TRUE"
					( Origin gBackEnd )
				)
				( attribute "SN_THRUPIN_TO_THRUPIN_SPACING" "5.00,5.00,5.00,5.00,5.00,5.00,5.00,5.00,5.00,5.00,5.00,5.00,5.00,5.00"
					( Origin gBackEnd )
				)
				( attribute "SN_THRUPIN_TO_SMDPIN_SPACING" "5.00,5.00,5.00,5.00,5.00,5.00,5.00,5.00,5.00,5.00,5.00,5.00,5.00,5.00"
					( Origin gBackEnd )
				)
				( attribute "SN_TESTPIN_TO_THRUPIN_SPACING" "5.00,5.00,5.00,5.00,5.00,5.00,5.00,5.00,5.00,5.00,5.00,5.00,5.00,5.00"
					( Origin gBackEnd )
				)
				( attribute "SN_THRUPIN_TO_THRUVIA_SPACING" "5.00,5.00,5.00,5.00,5.00,5.00,5.00,5.00,5.00,5.00,5.00,5.00,5.00,5.00"
					( Origin gBackEnd )
				)
				( attribute "SN_TESTVIA_TO_THRUPIN_SPACING" "5.00,5.00,5.00,5.00,5.00,5.00,5.00,5.00,5.00,5.00,5.00,5.00,5.00,5.00"
					( Origin gBackEnd )
				)
				( attribute "SN_BBV_TO_THRUPIN_SPACING" "5.00,5.00,5.00,5.00,5.00,5.00,5.00,5.00,5.00,5.00,5.00,5.00,5.00,5.00"
					( Origin gBackEnd )
				)
				( attribute "SN_THRUPIN_TO_BONDPAD_SPACING" "5.00,5.00,5.00,5.00,5.00,5.00,5.00,5.00,5.00,5.00,5.00,5.00,5.00,5.00"
					( Origin gBackEnd )
				)
				( attribute "SN_LINE_TO_THRUPIN_SPACING" "13.10,17.00,17.00,17.00,17.00,17.00,17.00,17.00,17.00,17.00,17.00,17.00,17.00,13.10"
					( Origin gBackEnd )
				)
				( attribute "SN_THRUPIN_TO_SHAPE_SPACING" "5.00,5.00,5.00,5.00,5.00,5.00,5.00,5.00,5.00,5.00,5.00,5.00,5.00,5.00"
					( Origin gBackEnd )
				)
				( attribute "SN_SMDPIN_TO_SMDPIN_SPACING" "5.00,5.00,5.00,5.00,5.00,5.00,5.00,5.00,5.00,5.00,5.00,5.00,5.00,5.00"
					( Origin gBackEnd )
				)
				( attribute "SN_SMDPIN_TO_TESTPIN_SPACING" "5.00,5.00,5.00,5.00,5.00,5.00,5.00,5.00,5.00,5.00,5.00,5.00,5.00,5.00"
					( Origin gBackEnd )
				)
				( attribute "SN_SMDPIN_TO_THRUVIA_SPACING" "5.00,5.00,5.00,5.00,5.00,5.00,5.00,5.00,5.00,5.00,5.00,5.00,5.00,5.00"
					( Origin gBackEnd )
				)
				( attribute "SN_SMDPIN_TO_TESTVIA_SPACING" "5.00,5.00,5.00,5.00,5.00,5.00,5.00,5.00,5.00,5.00,5.00,5.00,5.00,5.00"
					( Origin gBackEnd )
				)
				( attribute "SN_BBV_TO_SMDPIN_SPACING" "5.00,5.00,5.00,5.00,5.00,5.00,5.00,5.00,5.00,5.00,5.00,5.00,5.00,5.00"
					( Origin gBackEnd )
				)
				( attribute "SN_SMDPIN_TO_BONDPAD_SPACING" "5.00,5.00,5.00,5.00,5.00,5.00,5.00,5.00,5.00,5.00,5.00,5.00,5.00,5.00"
					( Origin gBackEnd )
				)
				( attribute "SN_LINE_TO_SMDPIN_SPACING" "4.50,4.50,4.50,4.50,4.50,4.50,4.50,4.50,4.50,4.50,4.50,4.50,4.50,4.50"
					( Origin gBackEnd )
				)
				( attribute "SN_SHAPE_TO_SMDPIN_SPACING" "5.00,5.00,5.00,5.00,5.00,5.00,5.00,5.00,5.00,5.00,5.00,5.00,5.00,5.00"
					( Origin gBackEnd )
				)
				( attribute "SN_TESTPIN_TO_TESTPIN_SPACING" "5.00,5.00,5.00,5.00,5.00,5.00,5.00,5.00,5.00,5.00,5.00,5.00,5.00,5.00"
					( Origin gBackEnd )
				)
				( attribute "SN_TESTPIN_TO_THRUVIA_SPACING" "5.00,5.00,5.00,5.00,5.00,5.00,5.00,5.00,5.00,5.00,5.00,5.00,5.00,5.00"
					( Origin gBackEnd )
				)
				( attribute "SN_TESTPIN_TO_TESTVIA_SPACING" "5.00,5.00,5.00,5.00,5.00,5.00,5.00,5.00,5.00,5.00,5.00,5.00,5.00,5.00"
					( Origin gBackEnd )
				)
				( attribute "SN_BBV_TO_TESTPIN_SPACING" "5.00,5.00,5.00,5.00,5.00,5.00,5.00,5.00,5.00,5.00,5.00,5.00,5.00,5.00"
					( Origin gBackEnd )
				)
				( attribute "SN_BONDPAD_TO_TESTPIN_SPACING" "5.00,5.00,5.00,5.00,5.00,5.00,5.00,5.00,5.00,5.00,5.00,5.00,5.00,5.00"
					( Origin gBackEnd )
				)
				( attribute "SN_LINE_TO_TESTPIN_SPACING" "13.10,17.00,17.00,17.00,17.00,17.00,17.00,17.00,17.00,17.00,17.00,17.00,17.00,13.10"
					( Origin gBackEnd )
				)
				( attribute "SN_SHAPE_TO_TESTPIN_SPACING" "5.00,5.00,5.00,5.00,5.00,5.00,5.00,5.00,5.00,5.00,5.00,5.00,5.00,5.00"
					( Origin gBackEnd )
				)
				( attribute "SN_THRUVIA_TO_THRUVIA_SPACING" "4.50,4.00,4.00,4.00,4.00,4.00,4.00,4.00,4.00,4.00,4.00,4.00,4.00,4.50"
					( Origin gBackEnd )
				)
				( attribute "SN_TESTVIA_TO_THRUVIA_SPACING" "5.00,5.00,5.00,5.00,5.00,5.00,5.00,5.00,5.00,5.00,5.00,5.00,5.00,5.00"
					( Origin gBackEnd )
				)
				( attribute "SN_BBV_TO_THRUVIA_SPACING" "5.00,5.00,5.00,5.00,5.00,5.00,5.00,5.00,5.00,5.00,5.00,5.00,5.00,5.00"
					( Origin gBackEnd )
				)
				( attribute "SN_BONDPAD_TO_THRUVIA_SPACING" "5.00,5.00,5.00,5.00,5.00,5.00,5.00,5.00,5.00,5.00,5.00,5.00,5.00,5.00"
					( Origin gBackEnd )
				)
				( attribute "SN_LINE_TO_THRUVIA_SPACING" "13.10,17.00,17.00,17.00,17.00,17.00,17.00,17.00,17.00,17.00,17.00,17.00,17.00,13.10"
					( Origin gBackEnd )
				)
				( attribute "SN_SHAPE_TO_THRUVIA_SPACING" "5.00,5.00,5.00,5.00,5.00,5.00,5.00,5.00,5.00,5.00,5.00,5.00,5.00,5.00"
					( Origin gBackEnd )
				)
				( attribute "SN_TESTVIA_TO_TESTVIA_SPACING" "5.00,5.00,5.00,5.00,5.00,5.00,5.00,5.00,5.00,5.00,5.00,5.00,5.00,5.00"
					( Origin gBackEnd )
				)
				( attribute "SN_BBV_TO_TESTVIA_SPACING" "5.00,5.00,5.00,5.00,5.00,5.00,5.00,5.00,5.00,5.00,5.00,5.00,5.00,5.00"
					( Origin gBackEnd )
				)
				( attribute "SN_BONDPAD_TO_TESTVIA_SPACING" "5.00,5.00,5.00,5.00,5.00,5.00,5.00,5.00,5.00,5.00,5.00,5.00,5.00,5.00"
					( Origin gBackEnd )
				)
				( attribute "SN_LINE_TO_TESTVIA_SPACING" "13.10,17.00,17.00,17.00,17.00,17.00,17.00,17.00,17.00,17.00,17.00,17.00,17.00,13.10"
					( Origin gBackEnd )
				)
				( attribute "SN_SHAPE_TO_TESTVIA_SPACING" "5.00,5.00,5.00,5.00,5.00,5.00,5.00,5.00,5.00,5.00,5.00,5.00,5.00,5.00"
					( Origin gBackEnd )
				)
				( attribute "SN_BBV_TO_BBV_SPACING" "5.00,5.00,5.00,5.00,5.00,5.00,5.00,5.00,5.00,5.00,5.00,5.00,5.00,5.00"
					( Origin gBackEnd )
				)
				( attribute "SN_BONDPAD_TO_BBV_SPACING" "5.00,5.00,5.00,5.00,5.00,5.00,5.00,5.00,5.00,5.00,5.00,5.00,5.00,5.00"
					( Origin gBackEnd )
				)
				( attribute "SN_BBV_TO_LINE_SPACING" "5.00,5.00,5.00,5.00,5.00,5.00,5.00,5.00,5.00,5.00,5.00,5.00,5.00,5.00"
					( Origin gBackEnd )
				)
				( attribute "SN_BBV_TO_SHAPE_SPACING" "5.00,5.00,5.00,5.00,5.00,5.00,5.00,5.00,5.00,5.00,5.00,5.00,5.00,5.00"
					( Origin gBackEnd )
				)
				( attribute "SN_BONDPAD_TO_BONDPAD_SPACING" "5.00,5.00,5.00,5.00,5.00,5.00,5.00,5.00,5.00,5.00,5.00,5.00,5.00,5.00"
					( Origin gBackEnd )
				)
				( attribute "SN_BONDPAD_TO_LINE_SPACING" "5.00,5.00,5.00,5.00,5.00,5.00,5.00,5.00,5.00,5.00,5.00,5.00,5.00,5.00"
					( Origin gBackEnd )
				)
				( attribute "SN_BONDPAD_TO_SHAPE_SPACING" "5.00,5.00,5.00,5.00,5.00,5.00,5.00,5.00,5.00,5.00,5.00,5.00,5.00,5.00"
					( Origin gBackEnd )
				)
				( attribute "SN_LINE_TO_LINE_SPACING" "24.30,9.00,9.00,9.00,9.00,9.00,9.00,9.00,9.00,9.00,9.00,9.00,9.00,24.30"
					( Origin gBackEnd )
				)
				( attribute "SN_LINE_TO_SHAPE_SPACING" "24.30,20.00,20.00,20.00,20.00,20.00,20.00,20.00,20.00,20.00,20.00,20.00,20.00,24.30"
					( Origin gBackEnd )
				)
				( attribute "SN_SHAPE_TO_SHAPE_SPACING" "5.00,5.00,5.00,5.00,5.00,5.00,5.00,5.00,5.00,5.00,5.00,5.00,5.00,5.00"
					( Origin gBackEnd )
				)
				( attribute "SN_HOLE_TO_PIN_SPACING" "8.00,8.00,8.00,8.00,8.00,8.00,8.00,8.00,8.00,8.00,8.00,8.00,8.00,8.00"
					( Origin gBackEnd )
				)
				( attribute "SN_HOLE_TO_VIA_SPACING" "8.00,8.00,8.00,8.00,8.00,8.00,8.00,8.00,8.00,8.00,8.00,8.00,8.00,8.00"
					( Origin gBackEnd )
				)
				( attribute "SN_HOLE_TO_LINE_SPACING" "8.00,8.00,8.00,8.00,8.00,8.00,8.00,8.00,8.00,8.00,8.00,8.00,8.00,8.00"
					( Origin gBackEnd )
				)
				( attribute "SN_HOLE_TO_SHAPE_SPACING" "8.00,8.00,8.00,8.00,8.00,8.00,8.00,8.00,8.00,8.00,8.00,8.00,8.00,8.00"
					( Origin gBackEnd )
				)
				( attribute "SN_HOLE_TO_HOLE_SPACING" "8.00,8.00,8.00,8.00,8.00,8.00,8.00,8.00,8.00,8.00,8.00,8.00,8.00,8.00"
					( Origin gBackEnd )
				)
				( attribute "SN_MVIA_TO_MVIA_SPACING" "5.00,5.00,5.00,5.00,5.00,5.00,5.00,5.00,5.00,5.00,5.00,5.00,5.00,5.00"
					( Origin gBackEnd )
				)
				( attribute "SN_MVIA_TO_THRUPIN_SPACING" "5.00,5.00,5.00,5.00,5.00,5.00,5.00,5.00,5.00,5.00,5.00,5.00,5.00,5.00"
					( Origin gBackEnd )
				)
				( attribute "SN_MVIA_TO_SMDPIN_SPACING" "5.00,5.00,5.00,5.00,5.00,5.00,5.00,5.00,5.00,5.00,5.00,5.00,5.00,5.00"
					( Origin gBackEnd )
				)
				( attribute "SN_MVIA_TO_THRUVIA_SPACING" "5.00,5.00,5.00,5.00,5.00,5.00,5.00,5.00,5.00,5.00,5.00,5.00,5.00,5.00"
					( Origin gBackEnd )
				)
				( attribute "SN_MVIA_TO_BBV_SPACING" "5.00,5.00,5.00,5.00,5.00,5.00,5.00,5.00,5.00,5.00,5.00,5.00,5.00,5.00"
					( Origin gBackEnd )
				)
				( attribute "SN_MVIA_TO_LINE_SPACING" "5.00,5.00,5.00,5.00,5.00,5.00,5.00,5.00,5.00,5.00,5.00,5.00,5.00,5.00"
					( Origin gBackEnd )
				)
				( attribute "SN_MVIA_TO_SHAPE_SPACING" "5.00,5.00,5.00,5.00,5.00,5.00,5.00,5.00,5.00,5.00,5.00,5.00,5.00,5.00"
					( Origin gBackEnd )
				)
				( attribute "SN_MVIA_TO_TESTPIN_SPACING" "5.00,5.00,5.00,5.00,5.00,5.00,5.00,5.00,5.00,5.00,5.00,5.00,5.00,5.00"
					( Origin gBackEnd )
				)
				( attribute "SN_MVIA_TO_TESTVIA_SPACING" "5.00,5.00,5.00,5.00,5.00,5.00,5.00,5.00,5.00,5.00,5.00,5.00,5.00,5.00"
					( Origin gBackEnd )
				)
				( attribute "SN_BONDPAD_TO_MVIA_SPACING" "5.00,5.00,5.00,5.00,5.00,5.00,5.00,5.00,5.00,5.00,5.00,5.00,5.00,5.00"
					( Origin gBackEnd )
				)
				( objectStatus "9H_US_&_3H_SL_VIA_3H+A" )
			)
			( sameNetSpacingCSet "@crescent_city_bb_fab1_lib.crescent_city_bb_fab1(sch_1):\BMC_MEM\"
				( attribute "SAME_NET" "TRUE,TRUE,TRUE,TRUE,TRUE,TRUE,TRUE,TRUE,TRUE,TRUE,TRUE,TRUE,TRUE,TRUE"
					( Origin gBackEnd )
				)
				( attribute "SN_THRUPIN_TO_THRUPIN_SPACING" "5.00,5.00,5.00,5.00,5.00,5.00,5.00,5.00,5.00,5.00,5.00,5.00,5.00,5.00"
					( Origin gBackEnd )
				)
				( attribute "SN_THRUPIN_TO_SMDPIN_SPACING" "5.00,5.00,5.00,5.00,5.00,5.00,5.00,5.00,5.00,5.00,5.00,5.00,5.00,5.00"
					( Origin gBackEnd )
				)
				( attribute "SN_TESTPIN_TO_THRUPIN_SPACING" "5.00,5.00,5.00,5.00,5.00,5.00,5.00,5.00,5.00,5.00,5.00,5.00,5.00,5.00"
					( Origin gBackEnd )
				)
				( attribute "SN_THRUPIN_TO_THRUVIA_SPACING" "5.00,5.00,5.00,5.00,5.00,5.00,5.00,5.00,5.00,5.00,5.00,5.00,5.00,5.00"
					( Origin gBackEnd )
				)
				( attribute "SN_TESTVIA_TO_THRUPIN_SPACING" "5.00,5.00,5.00,5.00,5.00,5.00,5.00,5.00,5.00,5.00,5.00,5.00,5.00,5.00"
					( Origin gBackEnd )
				)
				( attribute "SN_BBV_TO_THRUPIN_SPACING" "5.00,5.00,5.00,5.00,5.00,5.00,5.00,5.00,5.00,5.00,5.00,5.00,5.00,5.00"
					( Origin gBackEnd )
				)
				( attribute "SN_THRUPIN_TO_BONDPAD_SPACING" "5.00,5.00,5.00,5.00,5.00,5.00,5.00,5.00,5.00,5.00,5.00,5.00,5.00,5.00"
					( Origin gBackEnd )
				)
				( attribute "SN_LINE_TO_THRUPIN_SPACING" "4.50,4.00,4.00,4.00,4.00,4.00,4.00,4.00,4.00,4.00,4.00,4.00,4.00,4.50"
					( Origin gBackEnd )
				)
				( attribute "SN_THRUPIN_TO_SHAPE_SPACING" "5.00,5.00,5.00,5.00,5.00,5.00,5.00,5.00,5.00,5.00,5.00,5.00,5.00,5.00"
					( Origin gBackEnd )
				)
				( attribute "SN_SMDPIN_TO_SMDPIN_SPACING" "5.00,5.00,5.00,5.00,5.00,5.00,5.00,5.00,5.00,5.00,5.00,5.00,5.00,5.00"
					( Origin gBackEnd )
				)
				( attribute "SN_SMDPIN_TO_TESTPIN_SPACING" "5.00,5.00,5.00,5.00,5.00,5.00,5.00,5.00,5.00,5.00,5.00,5.00,5.00,5.00"
					( Origin gBackEnd )
				)
				( attribute "SN_SMDPIN_TO_THRUVIA_SPACING" "4.00,4.00,4.00,4.00,4.00,4.00,4.00,4.00,4.00,4.00,4.00,4.00,4.00,4.00"
					( Origin gBackEnd )
				)
				( attribute "SN_SMDPIN_TO_TESTVIA_SPACING" "4.00,4.00,4.00,4.00,4.00,4.00,4.00,4.00,4.00,4.00,4.00,4.00,4.00,4.00"
					( Origin gBackEnd )
				)
				( attribute "SN_BBV_TO_SMDPIN_SPACING" "5.00,5.00,5.00,5.00,5.00,5.00,5.00,5.00,5.00,5.00,5.00,5.00,5.00,5.00"
					( Origin gBackEnd )
				)
				( attribute "SN_SMDPIN_TO_BONDPAD_SPACING" "5.00,5.00,5.00,5.00,5.00,5.00,5.00,5.00,5.00,5.00,5.00,5.00,5.00,5.00"
					( Origin gBackEnd )
				)
				( attribute "SN_LINE_TO_SMDPIN_SPACING" "4.50,4.50,4.50,4.50,4.50,4.50,4.50,4.50,4.50,4.50,4.50,4.50,4.50,4.50"
					( Origin gBackEnd )
				)
				( attribute "SN_SHAPE_TO_SMDPIN_SPACING" "5.00,5.00,5.00,5.00,5.00,5.00,5.00,5.00,5.00,5.00,5.00,5.00,5.00,5.00"
					( Origin gBackEnd )
				)
				( attribute "SN_TESTPIN_TO_TESTPIN_SPACING" "5.00,5.00,5.00,5.00,5.00,5.00,5.00,5.00,5.00,5.00,5.00,5.00,5.00,5.00"
					( Origin gBackEnd )
				)
				( attribute "SN_TESTPIN_TO_THRUVIA_SPACING" "5.00,5.00,5.00,5.00,5.00,5.00,5.00,5.00,5.00,5.00,5.00,5.00,5.00,5.00"
					( Origin gBackEnd )
				)
				( attribute "SN_TESTPIN_TO_TESTVIA_SPACING" "5.00,5.00,5.00,5.00,5.00,5.00,5.00,5.00,5.00,5.00,5.00,5.00,5.00,5.00"
					( Origin gBackEnd )
				)
				( attribute "SN_BBV_TO_TESTPIN_SPACING" "5.00,5.00,5.00,5.00,5.00,5.00,5.00,5.00,5.00,5.00,5.00,5.00,5.00,5.00"
					( Origin gBackEnd )
				)
				( attribute "SN_BONDPAD_TO_TESTPIN_SPACING" "5.00,5.00,5.00,5.00,5.00,5.00,5.00,5.00,5.00,5.00,5.00,5.00,5.00,5.00"
					( Origin gBackEnd )
				)
				( attribute "SN_LINE_TO_TESTPIN_SPACING" "5.00,4.00,4.00,4.00,4.00,4.00,4.00,4.00,4.00,4.00,4.00,4.00,4.00,5.00"
					( Origin gBackEnd )
				)
				( attribute "SN_SHAPE_TO_TESTPIN_SPACING" "5.00,5.00,5.00,5.00,5.00,5.00,5.00,5.00,5.00,5.00,5.00,5.00,5.00,5.00"
					( Origin gBackEnd )
				)
				( attribute "SN_THRUVIA_TO_THRUVIA_SPACING" "4.50,4.00,4.00,4.00,4.00,4.00,4.00,4.00,4.00,4.00,4.00,4.00,4.00,4.50"
					( Origin gBackEnd )
				)
				( attribute "SN_TESTVIA_TO_THRUVIA_SPACING" "5.00,5.00,5.00,5.00,5.00,5.00,5.00,5.00,5.00,5.00,5.00,5.00,5.00,5.00"
					( Origin gBackEnd )
				)
				( attribute "SN_BBV_TO_THRUVIA_SPACING" "5.00,5.00,5.00,5.00,5.00,5.00,5.00,5.00,5.00,5.00,5.00,5.00,5.00,5.00"
					( Origin gBackEnd )
				)
				( attribute "SN_BONDPAD_TO_THRUVIA_SPACING" "5.00,5.00,5.00,5.00,5.00,5.00,5.00,5.00,5.00,5.00,5.00,5.00,5.00,5.00"
					( Origin gBackEnd )
				)
				( attribute "SN_LINE_TO_THRUVIA_SPACING" "4.50,4.00,4.00,4.00,4.00,4.00,4.00,4.00,4.00,4.00,4.00,4.00,4.00,4.50"
					( Origin gBackEnd )
				)
				( attribute "SN_SHAPE_TO_THRUVIA_SPACING" "5.00,5.00,5.00,5.00,5.00,5.00,5.00,5.00,5.00,5.00,5.00,5.00,5.00,5.00"
					( Origin gBackEnd )
				)
				( attribute "SN_TESTVIA_TO_TESTVIA_SPACING" "5.00,5.00,5.00,5.00,5.00,5.00,5.00,5.00,5.00,5.00,5.00,5.00,5.00,5.00"
					( Origin gBackEnd )
				)
				( attribute "SN_BBV_TO_TESTVIA_SPACING" "5.00,5.00,5.00,5.00,5.00,5.00,5.00,5.00,5.00,5.00,5.00,5.00,5.00,5.00"
					( Origin gBackEnd )
				)
				( attribute "SN_BONDPAD_TO_TESTVIA_SPACING" "5.00,5.00,5.00,5.00,5.00,5.00,5.00,5.00,5.00,5.00,5.00,5.00,5.00,5.00"
					( Origin gBackEnd )
				)
				( attribute "SN_LINE_TO_TESTVIA_SPACING" "5.00,4.00,4.00,4.00,4.00,4.00,4.00,4.00,4.00,4.00,4.00,4.00,4.00,5.00"
					( Origin gBackEnd )
				)
				( attribute "SN_SHAPE_TO_TESTVIA_SPACING" "5.00,5.00,5.00,5.00,5.00,5.00,5.00,5.00,5.00,5.00,5.00,5.00,5.00,5.00"
					( Origin gBackEnd )
				)
				( attribute "SN_BBV_TO_BBV_SPACING" "5.00,5.00,5.00,5.00,5.00,5.00,5.00,5.00,5.00,5.00,5.00,5.00,5.00,5.00"
					( Origin gBackEnd )
				)
				( attribute "SN_BONDPAD_TO_BBV_SPACING" "5.00,5.00,5.00,5.00,5.00,5.00,5.00,5.00,5.00,5.00,5.00,5.00,5.00,5.00"
					( Origin gBackEnd )
				)
				( attribute "SN_BBV_TO_LINE_SPACING" "5.00,5.00,5.00,5.00,5.00,5.00,5.00,5.00,5.00,5.00,5.00,5.00,5.00,5.00"
					( Origin gBackEnd )
				)
				( attribute "SN_BBV_TO_SHAPE_SPACING" "5.00,5.00,5.00,5.00,5.00,5.00,5.00,5.00,5.00,5.00,5.00,5.00,5.00,5.00"
					( Origin gBackEnd )
				)
				( attribute "SN_BONDPAD_TO_BONDPAD_SPACING" "5.00,5.00,5.00,5.00,5.00,5.00,5.00,5.00,5.00,5.00,5.00,5.00,5.00,5.00"
					( Origin gBackEnd )
				)
				( attribute "SN_BONDPAD_TO_LINE_SPACING" "5.00,5.00,5.00,5.00,5.00,5.00,5.00,5.00,5.00,5.00,5.00,5.00,5.00,5.00"
					( Origin gBackEnd )
				)
				( attribute "SN_BONDPAD_TO_SHAPE_SPACING" "5.00,5.00,5.00,5.00,5.00,5.00,5.00,5.00,5.00,5.00,5.00,5.00,5.00,5.00"
					( Origin gBackEnd )
				)
				( attribute "SN_LINE_TO_LINE_SPACING" "5.00,5.00,5.00,5.00,5.00,5.00,5.00,5.00,5.00,5.00,5.00,5.00,5.00,5.00"
					( Origin gBackEnd )
				)
				( attribute "SN_LINE_TO_SHAPE_SPACING" "0.00,0.00,0.00,0.00,0.00,0.00,0.00,0.00,0.00,0.00,0.00,0.00,0.00,0.00"
					( Origin gBackEnd )
				)
				( attribute "SN_SHAPE_TO_SHAPE_SPACING" "5.00,5.00,5.00,5.00,5.00,5.00,5.00,5.00,5.00,5.00,5.00,5.00,5.00,5.00"
					( Origin gBackEnd )
				)
				( attribute "SN_HOLE_TO_PIN_SPACING" "8.00,8.00,8.00,8.00,8.00,8.00,8.00,8.00,8.00,8.00,8.00,8.00,8.00,8.00"
					( Origin gBackEnd )
				)
				( attribute "SN_HOLE_TO_VIA_SPACING" "8.00,8.00,8.00,8.00,8.00,8.00,8.00,8.00,8.00,8.00,8.00,8.00,8.00,8.00"
					( Origin gBackEnd )
				)
				( attribute "SN_HOLE_TO_LINE_SPACING" "8.00,8.00,8.00,8.00,8.00,8.00,8.00,8.00,8.00,8.00,8.00,8.00,8.00,8.00"
					( Origin gBackEnd )
				)
				( attribute "SN_HOLE_TO_SHAPE_SPACING" "8.00,8.00,8.00,8.00,8.00,8.00,8.00,8.00,8.00,8.00,8.00,8.00,8.00,8.00"
					( Origin gBackEnd )
				)
				( attribute "SN_HOLE_TO_HOLE_SPACING" "8.00,8.00,8.00,8.00,8.00,8.00,8.00,8.00,8.00,8.00,8.00,8.00,8.00,8.00"
					( Origin gBackEnd )
				)
				( attribute "SN_MVIA_TO_MVIA_SPACING" "5.00,5.00,5.00,5.00,5.00,5.00,5.00,5.00,5.00,5.00,5.00,5.00,5.00,5.00"
					( Origin gBackEnd )
				)
				( attribute "SN_MVIA_TO_THRUPIN_SPACING" "5.00,5.00,5.00,5.00,5.00,5.00,5.00,5.00,5.00,5.00,5.00,5.00,5.00,5.00"
					( Origin gBackEnd )
				)
				( attribute "SN_MVIA_TO_SMDPIN_SPACING" "5.00,5.00,5.00,5.00,5.00,5.00,5.00,5.00,5.00,5.00,5.00,5.00,5.00,5.00"
					( Origin gBackEnd )
				)
				( attribute "SN_MVIA_TO_THRUVIA_SPACING" "5.00,5.00,5.00,5.00,5.00,5.00,5.00,5.00,5.00,5.00,5.00,5.00,5.00,5.00"
					( Origin gBackEnd )
				)
				( attribute "SN_MVIA_TO_BBV_SPACING" "5.00,5.00,5.00,5.00,5.00,5.00,5.00,5.00,5.00,5.00,5.00,5.00,5.00,5.00"
					( Origin gBackEnd )
				)
				( attribute "SN_MVIA_TO_LINE_SPACING" "5.00,5.00,5.00,5.00,5.00,5.00,5.00,5.00,5.00,5.00,5.00,5.00,5.00,5.00"
					( Origin gBackEnd )
				)
				( attribute "SN_MVIA_TO_SHAPE_SPACING" "5.00,5.00,5.00,5.00,5.00,5.00,5.00,5.00,5.00,5.00,5.00,5.00,5.00,5.00"
					( Origin gBackEnd )
				)
				( attribute "SN_MVIA_TO_TESTPIN_SPACING" "5.00,5.00,5.00,5.00,5.00,5.00,5.00,5.00,5.00,5.00,5.00,5.00,5.00,5.00"
					( Origin gBackEnd )
				)
				( attribute "SN_MVIA_TO_TESTVIA_SPACING" "5.00,5.00,5.00,5.00,5.00,5.00,5.00,5.00,5.00,5.00,5.00,5.00,5.00,5.00"
					( Origin gBackEnd )
				)
				( attribute "SN_BONDPAD_TO_MVIA_SPACING" "5.00,5.00,5.00,5.00,5.00,5.00,5.00,5.00,5.00,5.00,5.00,5.00,5.00,5.00"
					( Origin gBackEnd )
				)
				( objectStatus "BMC_MEM" )
			)
			( sameNetSpacingCSet "@crescent_city_bb_fab1_lib.crescent_city_bb_fab1(sch_1):\BGA_WBG\"
				( attribute "SAME_NET" "TRUE,TRUE,TRUE,TRUE,TRUE,TRUE,TRUE,TRUE,TRUE,TRUE,TRUE,TRUE,TRUE,TRUE"
					( Origin gBackEnd )
				)
				( attribute "SN_THRUPIN_TO_THRUPIN_SPACING" "5.00,5.00,5.00,5.00,5.00,5.00,5.00,5.00,5.00,5.00,5.00,5.00,5.00,5.00"
					( Origin gBackEnd )
				)
				( attribute "SN_THRUPIN_TO_SMDPIN_SPACING" "5.00,5.00,5.00,5.00,5.00,5.00,5.00,5.00,5.00,5.00,5.00,5.00,5.00,5.00"
					( Origin gBackEnd )
				)
				( attribute "SN_TESTPIN_TO_THRUPIN_SPACING" "5.00,5.00,5.00,5.00,5.00,5.00,5.00,5.00,5.00,5.00,5.00,5.00,5.00,5.00"
					( Origin gBackEnd )
				)
				( attribute "SN_THRUPIN_TO_THRUVIA_SPACING" "5.00,5.00,5.00,5.00,5.00,5.00,5.00,5.00,5.00,5.00,5.00,5.00,5.00,5.00"
					( Origin gBackEnd )
				)
				( attribute "SN_TESTVIA_TO_THRUPIN_SPACING" "5.00,5.00,5.00,5.00,5.00,5.00,5.00,5.00,5.00,5.00,5.00,5.00,5.00,5.00"
					( Origin gBackEnd )
				)
				( attribute "SN_BBV_TO_THRUPIN_SPACING" "5.00,5.00,5.00,5.00,5.00,5.00,5.00,5.00,5.00,5.00,5.00,5.00,5.00,5.00"
					( Origin gBackEnd )
				)
				( attribute "SN_THRUPIN_TO_BONDPAD_SPACING" "5.00,5.00,5.00,5.00,5.00,5.00,5.00,5.00,5.00,5.00,5.00,5.00,5.00,5.00"
					( Origin gBackEnd )
				)
				( attribute "SN_LINE_TO_THRUPIN_SPACING" "4.50,4.00,4.00,4.00,4.00,4.00,4.00,4.00,4.00,4.00,4.00,4.00,4.00,4.50"
					( Origin gBackEnd )
				)
				( attribute "SN_THRUPIN_TO_SHAPE_SPACING" "5.00,5.00,5.00,5.00,5.00,5.00,5.00,5.00,5.00,5.00,5.00,5.00,5.00,5.00"
					( Origin gBackEnd )
				)
				( attribute "SN_SMDPIN_TO_SMDPIN_SPACING" "5.00,5.00,5.00,5.00,5.00,5.00,5.00,5.00,5.00,5.00,5.00,5.00,5.00,5.00"
					( Origin gBackEnd )
				)
				( attribute "SN_SMDPIN_TO_TESTPIN_SPACING" "5.00,5.00,5.00,5.00,5.00,5.00,5.00,5.00,5.00,5.00,5.00,5.00,5.00,5.00"
					( Origin gBackEnd )
				)
				( attribute "SN_SMDPIN_TO_THRUVIA_SPACING" "4.38,4.38,4.38,4.38,4.38,4.38,4.38,4.38,4.38,4.38,4.38,4.38,4.38,4.38"
					( Origin gBackEnd )
				)
				( attribute "SN_SMDPIN_TO_TESTVIA_SPACING" "4.38,4.38,4.38,4.38,4.38,4.38,4.38,4.38,4.38,4.38,4.38,4.38,4.38,4.38"
					( Origin gBackEnd )
				)
				( attribute "SN_BBV_TO_SMDPIN_SPACING" "5.00,5.00,5.00,5.00,5.00,5.00,5.00,5.00,5.00,5.00,5.00,5.00,5.00,5.00"
					( Origin gBackEnd )
				)
				( attribute "SN_SMDPIN_TO_BONDPAD_SPACING" "5.00,5.00,5.00,5.00,5.00,5.00,5.00,5.00,5.00,5.00,5.00,5.00,5.00,5.00"
					( Origin gBackEnd )
				)
				( attribute "SN_LINE_TO_SMDPIN_SPACING" "4.50,4.50,4.50,4.50,4.50,4.50,4.50,4.50,4.50,4.50,4.50,4.50,4.50,4.50"
					( Origin gBackEnd )
				)
				( attribute "SN_SHAPE_TO_SMDPIN_SPACING" "5.00,5.00,5.00,5.00,5.00,5.00,5.00,5.00,5.00,5.00,5.00,5.00,5.00,5.00"
					( Origin gBackEnd )
				)
				( attribute "SN_TESTPIN_TO_TESTPIN_SPACING" "5.00,5.00,5.00,5.00,5.00,5.00,5.00,5.00,5.00,5.00,5.00,5.00,5.00,5.00"
					( Origin gBackEnd )
				)
				( attribute "SN_TESTPIN_TO_THRUVIA_SPACING" "5.00,5.00,5.00,5.00,5.00,5.00,5.00,5.00,5.00,5.00,5.00,5.00,5.00,5.00"
					( Origin gBackEnd )
				)
				( attribute "SN_TESTPIN_TO_TESTVIA_SPACING" "5.00,5.00,5.00,5.00,5.00,5.00,5.00,5.00,5.00,5.00,5.00,5.00,5.00,5.00"
					( Origin gBackEnd )
				)
				( attribute "SN_BBV_TO_TESTPIN_SPACING" "5.00,5.00,5.00,5.00,5.00,5.00,5.00,5.00,5.00,5.00,5.00,5.00,5.00,5.00"
					( Origin gBackEnd )
				)
				( attribute "SN_BONDPAD_TO_TESTPIN_SPACING" "5.00,5.00,5.00,5.00,5.00,5.00,5.00,5.00,5.00,5.00,5.00,5.00,5.00,5.00"
					( Origin gBackEnd )
				)
				( attribute "SN_LINE_TO_TESTPIN_SPACING" "5.00,5.00,5.00,5.00,5.00,5.00,5.00,5.00,5.00,5.00,5.00,5.00,5.00,5.00"
					( Origin gBackEnd )
				)
				( attribute "SN_SHAPE_TO_TESTPIN_SPACING" "5.00,5.00,5.00,5.00,5.00,5.00,5.00,5.00,5.00,5.00,5.00,5.00,5.00,5.00"
					( Origin gBackEnd )
				)
				( attribute "SN_THRUVIA_TO_THRUVIA_SPACING" "4.50,4.00,4.00,4.00,4.00,4.00,4.00,4.00,4.00,4.00,4.00,4.00,4.00,4.50"
					( Origin gBackEnd )
				)
				( attribute "SN_TESTVIA_TO_THRUVIA_SPACING" "5.00,5.00,5.00,5.00,5.00,5.00,5.00,5.00,5.00,5.00,5.00,5.00,5.00,5.00"
					( Origin gBackEnd )
				)
				( attribute "SN_BBV_TO_THRUVIA_SPACING" "5.00,5.00,5.00,5.00,5.00,5.00,5.00,5.00,5.00,5.00,5.00,5.00,5.00,5.00"
					( Origin gBackEnd )
				)
				( attribute "SN_BONDPAD_TO_THRUVIA_SPACING" "5.00,5.00,5.00,5.00,5.00,5.00,5.00,5.00,5.00,5.00,5.00,5.00,5.00,5.00"
					( Origin gBackEnd )
				)
				( attribute "SN_LINE_TO_THRUVIA_SPACING" "4.00,4.00,4.00,4.00,4.00,4.00,4.00,4.00,4.00,4.00,4.00,4.00,4.00,4.00"
					( Origin gBackEnd )
				)
				( attribute "SN_SHAPE_TO_THRUVIA_SPACING" "5.00,5.00,5.00,5.00,5.00,5.00,5.00,5.00,5.00,5.00,5.00,5.00,5.00,5.00"
					( Origin gBackEnd )
				)
				( attribute "SN_TESTVIA_TO_TESTVIA_SPACING" "5.00,5.00,5.00,5.00,5.00,5.00,5.00,5.00,5.00,5.00,5.00,5.00,5.00,5.00"
					( Origin gBackEnd )
				)
				( attribute "SN_BBV_TO_TESTVIA_SPACING" "5.00,5.00,5.00,5.00,5.00,5.00,5.00,5.00,5.00,5.00,5.00,5.00,5.00,5.00"
					( Origin gBackEnd )
				)
				( attribute "SN_BONDPAD_TO_TESTVIA_SPACING" "5.00,5.00,5.00,5.00,5.00,5.00,5.00,5.00,5.00,5.00,5.00,5.00,5.00,5.00"
					( Origin gBackEnd )
				)
				( attribute "SN_LINE_TO_TESTVIA_SPACING" "4.00,4.00,4.00,4.00,4.00,4.00,4.00,4.00,4.00,4.00,4.00,4.00,4.00,4.00"
					( Origin gBackEnd )
				)
				( attribute "SN_SHAPE_TO_TESTVIA_SPACING" "5.00,5.00,5.00,5.00,5.00,5.00,5.00,5.00,5.00,5.00,5.00,5.00,5.00,5.00"
					( Origin gBackEnd )
				)
				( attribute "SN_BBV_TO_BBV_SPACING" "5.00,5.00,5.00,5.00,5.00,5.00,5.00,5.00,5.00,5.00,5.00,5.00,5.00,5.00"
					( Origin gBackEnd )
				)
				( attribute "SN_BONDPAD_TO_BBV_SPACING" "5.00,5.00,5.00,5.00,5.00,5.00,5.00,5.00,5.00,5.00,5.00,5.00,5.00,5.00"
					( Origin gBackEnd )
				)
				( attribute "SN_BBV_TO_LINE_SPACING" "5.00,5.00,5.00,5.00,5.00,5.00,5.00,5.00,5.00,5.00,5.00,5.00,5.00,5.00"
					( Origin gBackEnd )
				)
				( attribute "SN_BBV_TO_SHAPE_SPACING" "5.00,5.00,5.00,5.00,5.00,5.00,5.00,5.00,5.00,5.00,5.00,5.00,5.00,5.00"
					( Origin gBackEnd )
				)
				( attribute "SN_BONDPAD_TO_BONDPAD_SPACING" "5.00,5.00,5.00,5.00,5.00,5.00,5.00,5.00,5.00,5.00,5.00,5.00,5.00,5.00"
					( Origin gBackEnd )
				)
				( attribute "SN_BONDPAD_TO_LINE_SPACING" "5.00,5.00,5.00,5.00,5.00,5.00,5.00,5.00,5.00,5.00,5.00,5.00,5.00,5.00"
					( Origin gBackEnd )
				)
				( attribute "SN_BONDPAD_TO_SHAPE_SPACING" "5.00,5.00,5.00,5.00,5.00,5.00,5.00,5.00,5.00,5.00,5.00,5.00,5.00,5.00"
					( Origin gBackEnd )
				)
				( attribute "SN_LINE_TO_LINE_SPACING" "4.00,4.00,4.00,4.00,4.00,4.00,4.00,4.00,4.00,4.00,4.00,4.00,4.00,4.00"
					( Origin gBackEnd )
				)
				( attribute "SN_LINE_TO_SHAPE_SPACING" "10.00,10.00,10.00,10.00,10.00,10.00,10.00,10.00,10.00,10.00,10.00,10.00,10.00,10.00"
					( Origin gBackEnd )
				)
				( attribute "SN_SHAPE_TO_SHAPE_SPACING" "5.00,5.00,5.00,5.00,5.00,5.00,5.00,5.00,5.00,5.00,5.00,5.00,5.00,5.00"
					( Origin gBackEnd )
				)
				( attribute "SN_HOLE_TO_PIN_SPACING" "8.00,8.00,8.00,8.00,8.00,8.00,8.00,8.00,8.00,8.00,8.00,8.00,8.00,8.00"
					( Origin gBackEnd )
				)
				( attribute "SN_HOLE_TO_VIA_SPACING" "8.00,8.00,8.00,8.00,8.00,8.00,8.00,8.00,8.00,8.00,8.00,8.00,8.00,8.00"
					( Origin gBackEnd )
				)
				( attribute "SN_HOLE_TO_LINE_SPACING" "8.00,8.00,8.00,8.00,8.00,8.00,8.00,8.00,8.00,8.00,8.00,8.00,8.00,8.00"
					( Origin gBackEnd )
				)
				( attribute "SN_HOLE_TO_SHAPE_SPACING" "8.00,8.00,8.00,8.00,8.00,8.00,8.00,8.00,8.00,8.00,8.00,8.00,8.00,8.00"
					( Origin gBackEnd )
				)
				( attribute "SN_HOLE_TO_HOLE_SPACING" "8.00,8.00,8.00,8.00,8.00,8.00,8.00,8.00,8.00,8.00,8.00,8.00,8.00,8.00"
					( Origin gBackEnd )
				)
				( attribute "SN_MVIA_TO_MVIA_SPACING" "5.00,5.00,5.00,5.00,5.00,5.00,5.00,5.00,5.00,5.00,5.00,5.00,5.00,5.00"
					( Origin gBackEnd )
				)
				( attribute "SN_MVIA_TO_THRUPIN_SPACING" "5.00,5.00,5.00,5.00,5.00,5.00,5.00,5.00,5.00,5.00,5.00,5.00,5.00,5.00"
					( Origin gBackEnd )
				)
				( attribute "SN_MVIA_TO_SMDPIN_SPACING" "5.00,5.00,5.00,5.00,5.00,5.00,5.00,5.00,5.00,5.00,5.00,5.00,5.00,5.00"
					( Origin gBackEnd )
				)
				( attribute "SN_MVIA_TO_THRUVIA_SPACING" "5.00,5.00,5.00,5.00,5.00,5.00,5.00,5.00,5.00,5.00,5.00,5.00,5.00,5.00"
					( Origin gBackEnd )
				)
				( attribute "SN_MVIA_TO_BBV_SPACING" "5.00,5.00,5.00,5.00,5.00,5.00,5.00,5.00,5.00,5.00,5.00,5.00,5.00,5.00"
					( Origin gBackEnd )
				)
				( attribute "SN_MVIA_TO_LINE_SPACING" "5.00,5.00,5.00,5.00,5.00,5.00,5.00,5.00,5.00,5.00,5.00,5.00,5.00,5.00"
					( Origin gBackEnd )
				)
				( attribute "SN_MVIA_TO_SHAPE_SPACING" "5.00,5.00,5.00,5.00,5.00,5.00,5.00,5.00,5.00,5.00,5.00,5.00,5.00,5.00"
					( Origin gBackEnd )
				)
				( attribute "SN_MVIA_TO_TESTPIN_SPACING" "5.00,5.00,5.00,5.00,5.00,5.00,5.00,5.00,5.00,5.00,5.00,5.00,5.00,5.00"
					( Origin gBackEnd )
				)
				( attribute "SN_MVIA_TO_TESTVIA_SPACING" "5.00,5.00,5.00,5.00,5.00,5.00,5.00,5.00,5.00,5.00,5.00,5.00,5.00,5.00"
					( Origin gBackEnd )
				)
				( attribute "SN_BONDPAD_TO_MVIA_SPACING" "5.00,5.00,5.00,5.00,5.00,5.00,5.00,5.00,5.00,5.00,5.00,5.00,5.00,5.00"
					( Origin gBackEnd )
				)
				( objectStatus "BGA_WBG" )
			)
			( sameNetSpacingCSet "@crescent_city_bb_fab1_lib.crescent_city_bb_fab1(sch_1):\BGA\"
				( attribute "SAME_NET" "TRUE,TRUE,TRUE,TRUE,TRUE,TRUE,TRUE,TRUE,TRUE,TRUE,TRUE,TRUE,TRUE,TRUE"
					( Origin gBackEnd )
				)
				( attribute "SN_THRUPIN_TO_THRUPIN_SPACING" "5.00,5.00,5.00,5.00,5.00,5.00,5.00,5.00,5.00,5.00,5.00,5.00,5.00,5.00"
					( Origin gBackEnd )
				)
				( attribute "SN_THRUPIN_TO_SMDPIN_SPACING" "5.00,5.00,5.00,5.00,5.00,5.00,5.00,5.00,5.00,5.00,5.00,5.00,5.00,5.00"
					( Origin gBackEnd )
				)
				( attribute "SN_TESTPIN_TO_THRUPIN_SPACING" "5.00,5.00,5.00,5.00,5.00,5.00,5.00,5.00,5.00,5.00,5.00,5.00,5.00,5.00"
					( Origin gBackEnd )
				)
				( attribute "SN_THRUPIN_TO_THRUVIA_SPACING" "5.00,5.00,5.00,5.00,5.00,5.00,5.00,5.00,5.00,5.00,5.00,5.00,5.00,5.00"
					( Origin gBackEnd )
				)
				( attribute "SN_TESTVIA_TO_THRUPIN_SPACING" "5.00,5.00,5.00,5.00,5.00,5.00,5.00,5.00,5.00,5.00,5.00,5.00,5.00,5.00"
					( Origin gBackEnd )
				)
				( attribute "SN_BBV_TO_THRUPIN_SPACING" "5.00,5.00,5.00,5.00,5.00,5.00,5.00,5.00,5.00,5.00,5.00,5.00,5.00,5.00"
					( Origin gBackEnd )
				)
				( attribute "SN_THRUPIN_TO_BONDPAD_SPACING" "5.00,5.00,5.00,5.00,5.00,5.00,5.00,5.00,5.00,5.00,5.00,5.00,5.00,5.00"
					( Origin gBackEnd )
				)
				( attribute "SN_LINE_TO_THRUPIN_SPACING" "4.50,4.00,4.00,4.00,4.00,4.00,4.00,4.00,4.00,4.00,4.00,4.00,4.00,4.50"
					( Origin gBackEnd )
				)
				( attribute "SN_THRUPIN_TO_SHAPE_SPACING" "5.00,5.00,5.00,5.00,5.00,5.00,5.00,5.00,5.00,5.00,5.00,5.00,5.00,5.00"
					( Origin gBackEnd )
				)
				( attribute "SN_SMDPIN_TO_SMDPIN_SPACING" "5.00,5.00,5.00,5.00,5.00,5.00,5.00,5.00,5.00,5.00,5.00,5.00,5.00,5.00"
					( Origin gBackEnd )
				)
				( attribute "SN_SMDPIN_TO_TESTPIN_SPACING" "5.00,5.00,5.00,5.00,5.00,5.00,5.00,5.00,5.00,5.00,5.00,5.00,5.00,5.00"
					( Origin gBackEnd )
				)
				( attribute "SN_SMDPIN_TO_THRUVIA_SPACING" "4.00,4.00,4.00,4.00,4.00,4.00,4.00,4.00,4.00,4.00,4.00,4.00,4.00,4.00"
					( Origin gBackEnd )
				)
				( attribute "SN_SMDPIN_TO_TESTVIA_SPACING" "4.00,4.00,4.00,4.00,4.00,4.00,4.00,4.00,4.00,4.00,4.00,4.00,4.00,4.00"
					( Origin gBackEnd )
				)
				( attribute "SN_BBV_TO_SMDPIN_SPACING" "5.00,5.00,5.00,5.00,5.00,5.00,5.00,5.00,5.00,5.00,5.00,5.00,5.00,5.00"
					( Origin gBackEnd )
				)
				( attribute "SN_SMDPIN_TO_BONDPAD_SPACING" "5.00,5.00,5.00,5.00,5.00,5.00,5.00,5.00,5.00,5.00,5.00,5.00,5.00,5.00"
					( Origin gBackEnd )
				)
				( attribute "SN_LINE_TO_SMDPIN_SPACING" "4.50,4.50,4.50,4.50,4.50,4.50,4.50,4.50,4.50,4.50,4.50,4.50,4.50,4.50"
					( Origin gBackEnd )
				)
				( attribute "SN_SHAPE_TO_SMDPIN_SPACING" "5.00,5.00,5.00,5.00,5.00,5.00,5.00,5.00,5.00,5.00,5.00,5.00,5.00,5.00"
					( Origin gBackEnd )
				)
				( attribute "SN_TESTPIN_TO_TESTPIN_SPACING" "5.00,5.00,5.00,5.00,5.00,5.00,5.00,5.00,5.00,5.00,5.00,5.00,5.00,5.00"
					( Origin gBackEnd )
				)
				( attribute "SN_TESTPIN_TO_THRUVIA_SPACING" "5.00,5.00,5.00,5.00,5.00,5.00,5.00,5.00,5.00,5.00,5.00,5.00,5.00,5.00"
					( Origin gBackEnd )
				)
				( attribute "SN_TESTPIN_TO_TESTVIA_SPACING" "5.00,5.00,5.00,5.00,5.00,5.00,5.00,5.00,5.00,5.00,5.00,5.00,5.00,5.00"
					( Origin gBackEnd )
				)
				( attribute "SN_BBV_TO_TESTPIN_SPACING" "5.00,5.00,5.00,5.00,5.00,5.00,5.00,5.00,5.00,5.00,5.00,5.00,5.00,5.00"
					( Origin gBackEnd )
				)
				( attribute "SN_BONDPAD_TO_TESTPIN_SPACING" "5.00,5.00,5.00,5.00,5.00,5.00,5.00,5.00,5.00,5.00,5.00,5.00,5.00,5.00"
					( Origin gBackEnd )
				)
				( attribute "SN_LINE_TO_TESTPIN_SPACING" "5.00,5.00,5.00,5.00,5.00,5.00,5.00,5.00,5.00,5.00,5.00,5.00,5.00,5.00"
					( Origin gBackEnd )
				)
				( attribute "SN_SHAPE_TO_TESTPIN_SPACING" "5.00,5.00,5.00,5.00,5.00,5.00,5.00,5.00,5.00,5.00,5.00,5.00,5.00,5.00"
					( Origin gBackEnd )
				)
				( attribute "SN_THRUVIA_TO_THRUVIA_SPACING" "4.50,4.00,4.00,4.00,4.00,4.00,4.00,4.00,4.00,4.00,4.00,4.00,4.00,4.50"
					( Origin gBackEnd )
				)
				( attribute "SN_TESTVIA_TO_THRUVIA_SPACING" "5.00,5.00,5.00,5.00,5.00,5.00,5.00,5.00,5.00,5.00,5.00,5.00,5.00,5.00"
					( Origin gBackEnd )
				)
				( attribute "SN_BBV_TO_THRUVIA_SPACING" "5.00,5.00,5.00,5.00,5.00,5.00,5.00,5.00,5.00,5.00,5.00,5.00,5.00,5.00"
					( Origin gBackEnd )
				)
				( attribute "SN_BONDPAD_TO_THRUVIA_SPACING" "5.00,5.00,5.00,5.00,5.00,5.00,5.00,5.00,5.00,5.00,5.00,5.00,5.00,5.00"
					( Origin gBackEnd )
				)
				( attribute "SN_LINE_TO_THRUVIA_SPACING" "4.00,4.00,4.00,4.00,4.00,4.00,4.00,4.00,4.00,4.00,4.00,4.00,4.00,4.00"
					( Origin gBackEnd )
				)
				( attribute "SN_SHAPE_TO_THRUVIA_SPACING" "5.00,5.00,5.00,5.00,5.00,5.00,5.00,5.00,5.00,5.00,5.00,5.00,5.00,5.00"
					( Origin gBackEnd )
				)
				( attribute "SN_TESTVIA_TO_TESTVIA_SPACING" "5.00,5.00,5.00,5.00,5.00,5.00,5.00,5.00,5.00,5.00,5.00,5.00,5.00,5.00"
					( Origin gBackEnd )
				)
				( attribute "SN_BBV_TO_TESTVIA_SPACING" "5.00,5.00,5.00,5.00,5.00,5.00,5.00,5.00,5.00,5.00,5.00,5.00,5.00,5.00"
					( Origin gBackEnd )
				)
				( attribute "SN_BONDPAD_TO_TESTVIA_SPACING" "5.00,5.00,5.00,5.00,5.00,5.00,5.00,5.00,5.00,5.00,5.00,5.00,5.00,5.00"
					( Origin gBackEnd )
				)
				( attribute "SN_LINE_TO_TESTVIA_SPACING" "4.00,4.00,4.00,4.00,4.00,4.00,4.00,4.00,4.00,4.00,4.00,4.00,4.00,4.00"
					( Origin gBackEnd )
				)
				( attribute "SN_SHAPE_TO_TESTVIA_SPACING" "5.00,5.00,5.00,5.00,5.00,5.00,5.00,5.00,5.00,5.00,5.00,5.00,5.00,5.00"
					( Origin gBackEnd )
				)
				( attribute "SN_BBV_TO_BBV_SPACING" "5.00,5.00,5.00,5.00,5.00,5.00,5.00,5.00,5.00,5.00,5.00,5.00,5.00,5.00"
					( Origin gBackEnd )
				)
				( attribute "SN_BONDPAD_TO_BBV_SPACING" "5.00,5.00,5.00,5.00,5.00,5.00,5.00,5.00,5.00,5.00,5.00,5.00,5.00,5.00"
					( Origin gBackEnd )
				)
				( attribute "SN_BBV_TO_LINE_SPACING" "5.00,5.00,5.00,5.00,5.00,5.00,5.00,5.00,5.00,5.00,5.00,5.00,5.00,5.00"
					( Origin gBackEnd )
				)
				( attribute "SN_BBV_TO_SHAPE_SPACING" "5.00,5.00,5.00,5.00,5.00,5.00,5.00,5.00,5.00,5.00,5.00,5.00,5.00,5.00"
					( Origin gBackEnd )
				)
				( attribute "SN_BONDPAD_TO_BONDPAD_SPACING" "5.00,5.00,5.00,5.00,5.00,5.00,5.00,5.00,5.00,5.00,5.00,5.00,5.00,5.00"
					( Origin gBackEnd )
				)
				( attribute "SN_BONDPAD_TO_LINE_SPACING" "5.00,5.00,5.00,5.00,5.00,5.00,5.00,5.00,5.00,5.00,5.00,5.00,5.00,5.00"
					( Origin gBackEnd )
				)
				( attribute "SN_BONDPAD_TO_SHAPE_SPACING" "5.00,5.00,5.00,5.00,5.00,5.00,5.00,5.00,5.00,5.00,5.00,5.00,5.00,5.00"
					( Origin gBackEnd )
				)
				( attribute "SN_LINE_TO_LINE_SPACING" "4.00,4.00,4.00,4.00,4.00,4.00,4.00,4.00,4.00,4.00,4.00,4.00,4.00,4.00"
					( Origin gBackEnd )
				)
				( attribute "SN_LINE_TO_SHAPE_SPACING" "10.00,10.00,10.00,10.00,10.00,10.00,10.00,10.00,10.00,10.00,10.00,10.00,10.00,10.00"
					( Origin gBackEnd )
				)
				( attribute "SN_SHAPE_TO_SHAPE_SPACING" "5.00,5.00,5.00,5.00,5.00,5.00,5.00,5.00,5.00,5.00,5.00,5.00,5.00,5.00"
					( Origin gBackEnd )
				)
				( attribute "SN_HOLE_TO_PIN_SPACING" "8.00,8.00,8.00,8.00,8.00,8.00,8.00,8.00,8.00,8.00,8.00,8.00,8.00,8.00"
					( Origin gBackEnd )
				)
				( attribute "SN_HOLE_TO_VIA_SPACING" "8.00,8.00,8.00,8.00,8.00,8.00,8.00,8.00,8.00,8.00,8.00,8.00,8.00,8.00"
					( Origin gBackEnd )
				)
				( attribute "SN_HOLE_TO_LINE_SPACING" "8.00,8.00,8.00,8.00,8.00,8.00,8.00,8.00,8.00,8.00,8.00,8.00,8.00,8.00"
					( Origin gBackEnd )
				)
				( attribute "SN_HOLE_TO_SHAPE_SPACING" "8.00,8.00,8.00,8.00,8.00,8.00,8.00,8.00,8.00,8.00,8.00,8.00,8.00,8.00"
					( Origin gBackEnd )
				)
				( attribute "SN_HOLE_TO_HOLE_SPACING" "8.00,8.00,8.00,8.00,8.00,8.00,8.00,8.00,8.00,8.00,8.00,8.00,8.00,8.00"
					( Origin gBackEnd )
				)
				( attribute "SN_MVIA_TO_MVIA_SPACING" "5.00,5.00,5.00,5.00,5.00,5.00,5.00,5.00,5.00,5.00,5.00,5.00,5.00,5.00"
					( Origin gBackEnd )
				)
				( attribute "SN_MVIA_TO_THRUPIN_SPACING" "5.00,5.00,5.00,5.00,5.00,5.00,5.00,5.00,5.00,5.00,5.00,5.00,5.00,5.00"
					( Origin gBackEnd )
				)
				( attribute "SN_MVIA_TO_SMDPIN_SPACING" "5.00,5.00,5.00,5.00,5.00,5.00,5.00,5.00,5.00,5.00,5.00,5.00,5.00,5.00"
					( Origin gBackEnd )
				)
				( attribute "SN_MVIA_TO_THRUVIA_SPACING" "5.00,5.00,5.00,5.00,5.00,5.00,5.00,5.00,5.00,5.00,5.00,5.00,5.00,5.00"
					( Origin gBackEnd )
				)
				( attribute "SN_MVIA_TO_BBV_SPACING" "5.00,5.00,5.00,5.00,5.00,5.00,5.00,5.00,5.00,5.00,5.00,5.00,5.00,5.00"
					( Origin gBackEnd )
				)
				( attribute "SN_MVIA_TO_LINE_SPACING" "5.00,5.00,5.00,5.00,5.00,5.00,5.00,5.00,5.00,5.00,5.00,5.00,5.00,5.00"
					( Origin gBackEnd )
				)
				( attribute "SN_MVIA_TO_SHAPE_SPACING" "5.00,5.00,5.00,5.00,5.00,5.00,5.00,5.00,5.00,5.00,5.00,5.00,5.00,5.00"
					( Origin gBackEnd )
				)
				( attribute "SN_MVIA_TO_TESTPIN_SPACING" "5.00,5.00,5.00,5.00,5.00,5.00,5.00,5.00,5.00,5.00,5.00,5.00,5.00,5.00"
					( Origin gBackEnd )
				)
				( attribute "SN_MVIA_TO_TESTVIA_SPACING" "5.00,5.00,5.00,5.00,5.00,5.00,5.00,5.00,5.00,5.00,5.00,5.00,5.00,5.00"
					( Origin gBackEnd )
				)
				( attribute "SN_BONDPAD_TO_MVIA_SPACING" "5.00,5.00,5.00,5.00,5.00,5.00,5.00,5.00,5.00,5.00,5.00,5.00,5.00,5.00"
					( Origin gBackEnd )
				)
				( objectStatus "BGA" )
			)
			( sameNetSpacingCSet "@crescent_city_bb_fab1_lib.crescent_city_bb_fab1(sch_1):\7H_US_AND_5H_SL\"
				( attribute "SAME_NET" "TRUE,TRUE,TRUE,TRUE,TRUE,TRUE,TRUE,TRUE,TRUE,TRUE,TRUE,TRUE,TRUE,TRUE"
					( Origin gBackEnd )
				)
				( attribute "SN_THRUPIN_TO_THRUPIN_SPACING" "5.00,5.00,5.00,5.00,5.00,5.00,5.00,5.00,5.00,5.00,5.00,5.00,5.00,5.00"
					( Origin gBackEnd )
				)
				( attribute "SN_THRUPIN_TO_SMDPIN_SPACING" "5.00,5.00,5.00,5.00,5.00,5.00,5.00,5.00,5.00,5.00,5.00,5.00,5.00,5.00"
					( Origin gBackEnd )
				)
				( attribute "SN_TESTPIN_TO_THRUPIN_SPACING" "5.00,5.00,5.00,5.00,5.00,5.00,5.00,5.00,5.00,5.00,5.00,5.00,5.00,5.00"
					( Origin gBackEnd )
				)
				( attribute "SN_THRUPIN_TO_THRUVIA_SPACING" "5.00,5.00,5.00,5.00,5.00,5.00,5.00,5.00,5.00,5.00,5.00,5.00,5.00,5.00"
					( Origin gBackEnd )
				)
				( attribute "SN_TESTVIA_TO_THRUPIN_SPACING" "5.00,5.00,5.00,5.00,5.00,5.00,5.00,5.00,5.00,5.00,5.00,5.00,5.00,5.00"
					( Origin gBackEnd )
				)
				( attribute "SN_BBV_TO_THRUPIN_SPACING" "5.00,5.00,5.00,5.00,5.00,5.00,5.00,5.00,5.00,5.00,5.00,5.00,5.00,5.00"
					( Origin gBackEnd )
				)
				( attribute "SN_THRUPIN_TO_BONDPAD_SPACING" "5.00,5.00,5.00,5.00,5.00,5.00,5.00,5.00,5.00,5.00,5.00,5.00,5.00,5.00"
					( Origin gBackEnd )
				)
				( attribute "SN_LINE_TO_THRUPIN_SPACING" "5.00,5.00,5.00,5.00,5.00,5.00,5.00,5.00,5.00,5.00,5.00,5.00,5.00,5.00"
					( Origin gBackEnd )
				)
				( attribute "SN_THRUPIN_TO_SHAPE_SPACING" "5.00,5.00,5.00,5.00,5.00,5.00,5.00,5.00,5.00,5.00,5.00,5.00,5.00,5.00"
					( Origin gBackEnd )
				)
				( attribute "SN_SMDPIN_TO_SMDPIN_SPACING" "5.00,5.00,5.00,5.00,5.00,5.00,5.00,5.00,5.00,5.00,5.00,5.00,5.00,5.00"
					( Origin gBackEnd )
				)
				( attribute "SN_SMDPIN_TO_TESTPIN_SPACING" "5.00,5.00,5.00,5.00,5.00,5.00,5.00,5.00,5.00,5.00,5.00,5.00,5.00,5.00"
					( Origin gBackEnd )
				)
				( attribute "SN_SMDPIN_TO_THRUVIA_SPACING" "4.00,4.00,4.00,4.00,4.00,4.00,4.00,4.00,4.00,4.00,4.00,4.00,4.00,4.00"
					( Origin gBackEnd )
				)
				( attribute "SN_SMDPIN_TO_TESTVIA_SPACING" "4.00,4.00,4.00,4.00,4.00,4.00,4.00,4.00,4.00,4.00,4.00,4.00,4.00,4.00"
					( Origin gBackEnd )
				)
				( attribute "SN_BBV_TO_SMDPIN_SPACING" "5.00,5.00,5.00,5.00,5.00,5.00,5.00,5.00,5.00,5.00,5.00,5.00,5.00,5.00"
					( Origin gBackEnd )
				)
				( attribute "SN_SMDPIN_TO_BONDPAD_SPACING" "5.00,5.00,5.00,5.00,5.00,5.00,5.00,5.00,5.00,5.00,5.00,5.00,5.00,5.00"
					( Origin gBackEnd )
				)
				( attribute "SN_LINE_TO_SMDPIN_SPACING" "4.50,4.50,4.50,4.50,4.50,4.50,4.50,4.50,4.50,4.50,4.50,4.50,4.50,4.50"
					( Origin gBackEnd )
				)
				( attribute "SN_SHAPE_TO_SMDPIN_SPACING" "5.00,5.00,5.00,5.00,5.00,5.00,5.00,5.00,5.00,5.00,5.00,5.00,5.00,5.00"
					( Origin gBackEnd )
				)
				( attribute "SN_TESTPIN_TO_TESTPIN_SPACING" "5.00,5.00,5.00,5.00,5.00,5.00,5.00,5.00,5.00,5.00,5.00,5.00,5.00,5.00"
					( Origin gBackEnd )
				)
				( attribute "SN_TESTPIN_TO_THRUVIA_SPACING" "5.00,5.00,5.00,5.00,5.00,5.00,5.00,5.00,5.00,5.00,5.00,5.00,5.00,5.00"
					( Origin gBackEnd )
				)
				( attribute "SN_TESTPIN_TO_TESTVIA_SPACING" "5.00,5.00,5.00,5.00,5.00,5.00,5.00,5.00,5.00,5.00,5.00,5.00,5.00,5.00"
					( Origin gBackEnd )
				)
				( attribute "SN_BBV_TO_TESTPIN_SPACING" "5.00,5.00,5.00,5.00,5.00,5.00,5.00,5.00,5.00,5.00,5.00,5.00,5.00,5.00"
					( Origin gBackEnd )
				)
				( attribute "SN_BONDPAD_TO_TESTPIN_SPACING" "5.00,5.00,5.00,5.00,5.00,5.00,5.00,5.00,5.00,5.00,5.00,5.00,5.00,5.00"
					( Origin gBackEnd )
				)
				( attribute "SN_LINE_TO_TESTPIN_SPACING" "5.00,5.00,5.00,5.00,5.00,5.00,5.00,5.00,5.00,5.00,5.00,5.00,5.00,5.00"
					( Origin gBackEnd )
				)
				( attribute "SN_SHAPE_TO_TESTPIN_SPACING" "5.00,5.00,5.00,5.00,5.00,5.00,5.00,5.00,5.00,5.00,5.00,5.00,5.00,5.00"
					( Origin gBackEnd )
				)
				( attribute "SN_THRUVIA_TO_THRUVIA_SPACING" "4.50,4.00,4.00,4.00,4.00,4.00,4.00,4.00,4.00,4.00,4.00,4.00,4.00,4.50"
					( Origin gBackEnd )
				)
				( attribute "SN_TESTVIA_TO_THRUVIA_SPACING" "5.00,5.00,5.00,5.00,5.00,5.00,5.00,5.00,5.00,5.00,5.00,5.00,5.00,5.00"
					( Origin gBackEnd )
				)
				( attribute "SN_BBV_TO_THRUVIA_SPACING" "5.00,5.00,5.00,5.00,5.00,5.00,5.00,5.00,5.00,5.00,5.00,5.00,5.00,5.00"
					( Origin gBackEnd )
				)
				( attribute "SN_BONDPAD_TO_THRUVIA_SPACING" "5.00,5.00,5.00,5.00,5.00,5.00,5.00,5.00,5.00,5.00,5.00,5.00,5.00,5.00"
					( Origin gBackEnd )
				)
				( attribute "SN_LINE_TO_THRUVIA_SPACING" "4.50,4.00,4.00,4.00,4.00,4.00,4.00,4.00,4.00,4.00,4.00,4.00,4.00,4.50"
					( Origin gBackEnd )
				)
				( attribute "SN_SHAPE_TO_THRUVIA_SPACING" "5.00,5.00,5.00,5.00,5.00,5.00,5.00,5.00,5.00,5.00,5.00,5.00,5.00,5.00"
					( Origin gBackEnd )
				)
				( attribute "SN_TESTVIA_TO_TESTVIA_SPACING" "5.00,5.00,5.00,5.00,5.00,5.00,5.00,5.00,5.00,5.00,5.00,5.00,5.00,5.00"
					( Origin gBackEnd )
				)
				( attribute "SN_BBV_TO_TESTVIA_SPACING" "5.00,5.00,5.00,5.00,5.00,5.00,5.00,5.00,5.00,5.00,5.00,5.00,5.00,5.00"
					( Origin gBackEnd )
				)
				( attribute "SN_BONDPAD_TO_TESTVIA_SPACING" "5.00,5.00,5.00,5.00,5.00,5.00,5.00,5.00,5.00,5.00,5.00,5.00,5.00,5.00"
					( Origin gBackEnd )
				)
				( attribute "SN_LINE_TO_TESTVIA_SPACING" "5.00,5.00,5.00,5.00,5.00,5.00,5.00,5.00,5.00,5.00,5.00,5.00,5.00,5.00"
					( Origin gBackEnd )
				)
				( attribute "SN_SHAPE_TO_TESTVIA_SPACING" "5.00,5.00,5.00,5.00,5.00,5.00,5.00,5.00,5.00,5.00,5.00,5.00,5.00,5.00"
					( Origin gBackEnd )
				)
				( attribute "SN_BBV_TO_BBV_SPACING" "5.00,5.00,5.00,5.00,5.00,5.00,5.00,5.00,5.00,5.00,5.00,5.00,5.00,5.00"
					( Origin gBackEnd )
				)
				( attribute "SN_BONDPAD_TO_BBV_SPACING" "5.00,5.00,5.00,5.00,5.00,5.00,5.00,5.00,5.00,5.00,5.00,5.00,5.00,5.00"
					( Origin gBackEnd )
				)
				( attribute "SN_BBV_TO_LINE_SPACING" "5.00,5.00,5.00,5.00,5.00,5.00,5.00,5.00,5.00,5.00,5.00,5.00,5.00,5.00"
					( Origin gBackEnd )
				)
				( attribute "SN_BBV_TO_SHAPE_SPACING" "5.00,5.00,5.00,5.00,5.00,5.00,5.00,5.00,5.00,5.00,5.00,5.00,5.00,5.00"
					( Origin gBackEnd )
				)
				( attribute "SN_BONDPAD_TO_BONDPAD_SPACING" "5.00,5.00,5.00,5.00,5.00,5.00,5.00,5.00,5.00,5.00,5.00,5.00,5.00,5.00"
					( Origin gBackEnd )
				)
				( attribute "SN_BONDPAD_TO_LINE_SPACING" "5.00,5.00,5.00,5.00,5.00,5.00,5.00,5.00,5.00,5.00,5.00,5.00,5.00,5.00"
					( Origin gBackEnd )
				)
				( attribute "SN_BONDPAD_TO_SHAPE_SPACING" "5.00,5.00,5.00,5.00,5.00,5.00,5.00,5.00,5.00,5.00,5.00,5.00,5.00,5.00"
					( Origin gBackEnd )
				)
				( attribute "SN_LINE_TO_LINE_SPACING" "18.90,15.00,15.00,15.00,15.00,15.00,15.00,15.00,15.00,15.00,15.00,15.00,15.00,18.90"
					( Origin gBackEnd )
				)
				( attribute "SN_LINE_TO_SHAPE_SPACING" "5.00,5.00,5.00,5.00,5.00,5.00,5.00,5.00,5.00,5.00,5.00,5.00,5.00,5.00"
					( Origin gBackEnd )
				)
				( attribute "SN_SHAPE_TO_SHAPE_SPACING" "5.00,5.00,5.00,5.00,5.00,5.00,5.00,5.00,5.00,5.00,5.00,5.00,5.00,5.00"
					( Origin gBackEnd )
				)
				( attribute "SN_HOLE_TO_PIN_SPACING" "8.00,8.00,8.00,8.00,8.00,8.00,8.00,8.00,8.00,8.00,8.00,8.00,8.00,8.00"
					( Origin gBackEnd )
				)
				( attribute "SN_HOLE_TO_VIA_SPACING" "8.00,8.00,8.00,8.00,8.00,8.00,8.00,8.00,8.00,8.00,8.00,8.00,8.00,8.00"
					( Origin gBackEnd )
				)
				( attribute "SN_HOLE_TO_LINE_SPACING" "8.00,8.00,8.00,8.00,8.00,8.00,8.00,8.00,8.00,8.00,8.00,8.00,8.00,8.00"
					( Origin gBackEnd )
				)
				( attribute "SN_HOLE_TO_SHAPE_SPACING" "8.00,8.00,8.00,8.00,8.00,8.00,8.00,8.00,8.00,8.00,8.00,8.00,8.00,8.00"
					( Origin gBackEnd )
				)
				( attribute "SN_HOLE_TO_HOLE_SPACING" "8.00,8.00,8.00,8.00,8.00,8.00,8.00,8.00,8.00,8.00,8.00,8.00,8.00,8.00"
					( Origin gBackEnd )
				)
				( attribute "SN_MVIA_TO_MVIA_SPACING" "5.00,5.00,5.00,5.00,5.00,5.00,5.00,5.00,5.00,5.00,5.00,5.00,5.00,5.00"
					( Origin gBackEnd )
				)
				( attribute "SN_MVIA_TO_THRUPIN_SPACING" "5.00,5.00,5.00,5.00,5.00,5.00,5.00,5.00,5.00,5.00,5.00,5.00,5.00,5.00"
					( Origin gBackEnd )
				)
				( attribute "SN_MVIA_TO_SMDPIN_SPACING" "5.00,5.00,5.00,5.00,5.00,5.00,5.00,5.00,5.00,5.00,5.00,5.00,5.00,5.00"
					( Origin gBackEnd )
				)
				( attribute "SN_MVIA_TO_THRUVIA_SPACING" "5.00,5.00,5.00,5.00,5.00,5.00,5.00,5.00,5.00,5.00,5.00,5.00,5.00,5.00"
					( Origin gBackEnd )
				)
				( attribute "SN_MVIA_TO_BBV_SPACING" "5.00,5.00,5.00,5.00,5.00,5.00,5.00,5.00,5.00,5.00,5.00,5.00,5.00,5.00"
					( Origin gBackEnd )
				)
				( attribute "SN_MVIA_TO_LINE_SPACING" "5.00,5.00,5.00,5.00,5.00,5.00,5.00,5.00,5.00,5.00,5.00,5.00,5.00,5.00"
					( Origin gBackEnd )
				)
				( attribute "SN_MVIA_TO_SHAPE_SPACING" "5.00,5.00,5.00,5.00,5.00,5.00,5.00,5.00,5.00,5.00,5.00,5.00,5.00,5.00"
					( Origin gBackEnd )
				)
				( attribute "SN_MVIA_TO_TESTPIN_SPACING" "5.00,5.00,5.00,5.00,5.00,5.00,5.00,5.00,5.00,5.00,5.00,5.00,5.00,5.00"
					( Origin gBackEnd )
				)
				( attribute "SN_MVIA_TO_TESTVIA_SPACING" "5.00,5.00,5.00,5.00,5.00,5.00,5.00,5.00,5.00,5.00,5.00,5.00,5.00,5.00"
					( Origin gBackEnd )
				)
				( attribute "SN_BONDPAD_TO_MVIA_SPACING" "5.00,5.00,5.00,5.00,5.00,5.00,5.00,5.00,5.00,5.00,5.00,5.00,5.00,5.00"
					( Origin gBackEnd )
				)
				( objectStatus "7H_US_&_5H_SL" )
			)
			( sameNetSpacingCSet "@crescent_city_bb_fab1_lib.crescent_city_bb_fab1(sch_1):\DEFAULT\"
				( attribute "SAME_NET" "TRUE,TRUE,TRUE,TRUE,TRUE,TRUE,TRUE,TRUE,TRUE,TRUE,TRUE,TRUE,TRUE,TRUE"
					( Origin gBackEnd )
				)
				( attribute "SN_THRUPIN_TO_THRUPIN_SPACING" "5.00,5.00,5.00,5.00,5.00,5.00,5.00,5.00,5.00,5.00,5.00,5.00,5.00,5.00"
					( Origin gBackEnd )
				)
				( attribute "SN_THRUPIN_TO_SMDPIN_SPACING" "5.00,5.00,5.00,5.00,5.00,5.00,5.00,5.00,5.00,5.00,5.00,5.00,5.00,5.00"
					( Origin gBackEnd )
				)
				( attribute "SN_TESTPIN_TO_THRUPIN_SPACING" "5.00,5.00,5.00,5.00,5.00,5.00,5.00,5.00,5.00,5.00,5.00,5.00,5.00,5.00"
					( Origin gBackEnd )
				)
				( attribute "SN_THRUPIN_TO_THRUVIA_SPACING" "4.00,4.00,4.00,4.00,4.00,4.00,4.00,4.00,4.00,4.00,4.00,4.00,4.00,5.00"
					( Origin gBackEnd )
				)
				( attribute "SN_TESTVIA_TO_THRUPIN_SPACING" "5.00,5.00,5.00,5.00,5.00,5.00,5.00,5.00,5.00,5.00,5.00,5.00,5.00,5.00"
					( Origin gBackEnd )
				)
				( attribute "SN_BBV_TO_THRUPIN_SPACING" "5.00,5.00,5.00,5.00,5.00,5.00,5.00,5.00,5.00,5.00,5.00,5.00,5.00,5.00"
					( Origin gBackEnd )
				)
				( attribute "SN_THRUPIN_TO_BONDPAD_SPACING" "5.00,5.00,5.00,5.00,5.00,5.00,5.00,5.00,5.00,5.00,5.00,5.00,5.00,5.00"
					( Origin gBackEnd )
				)
				( attribute "SN_LINE_TO_THRUPIN_SPACING" "5.00,5.00,5.00,5.00,5.00,5.00,5.00,5.00,5.00,5.00,5.00,5.00,5.00,5.00"
					( Origin gBackEnd )
				)
				( attribute "SN_THRUPIN_TO_SHAPE_SPACING" "4.50,4.00,4.00,4.00,4.00,4.00,4.00,4.00,4.00,4.00,4.00,4.00,4.00,5.00"
					( Origin gBackEnd )
				)
				( attribute "SN_SMDPIN_TO_SMDPIN_SPACING" "5.00,5.00,5.00,5.00,5.00,5.00,5.00,5.00,5.00,5.00,5.00,5.00,5.00,5.00"
					( Origin gBackEnd )
				)
				( attribute "SN_SMDPIN_TO_TESTPIN_SPACING" "5.00,5.00,5.00,5.00,5.00,5.00,5.00,5.00,5.00,5.00,5.00,5.00,5.00,25.00"
					( Origin gBackEnd )
				)
				( attribute "SN_SMDPIN_TO_THRUVIA_SPACING" "4.00,4.00,4.00,4.00,4.00,4.00,4.00,4.00,4.00,4.00,4.00,4.00,4.00,5.00"
					( Origin gBackEnd )
				)
				( attribute "SN_SMDPIN_TO_TESTVIA_SPACING" "4.50,4.50,4.50,4.50,4.50,4.50,4.50,4.50,4.50,4.50,4.50,4.50,4.50,5.00"
					( Origin gBackEnd )
				)
				( attribute "SN_BBV_TO_SMDPIN_SPACING" "5.00,5.00,5.00,5.00,5.00,5.00,5.00,5.00,5.00,5.00,5.00,5.00,5.00,5.00"
					( Origin gBackEnd )
				)
				( attribute "SN_SMDPIN_TO_BONDPAD_SPACING" "5.00,5.00,5.00,5.00,5.00,5.00,5.00,5.00,5.00,5.00,5.00,5.00,5.00,5.00"
					( Origin gBackEnd )
				)
				( attribute "SN_LINE_TO_SMDPIN_SPACING" "4.50,4.50,4.50,4.50,4.50,4.50,4.50,4.50,4.50,4.50,4.50,4.50,4.50,4.50"
					( Origin gBackEnd )
				)
				( attribute "SN_SHAPE_TO_SMDPIN_SPACING" "5.00,5.00,5.00,5.00,5.00,5.00,5.00,5.00,5.00,5.00,5.00,5.00,5.00,5.00"
					( Origin gBackEnd )
				)
				( attribute "SN_TESTPIN_TO_TESTPIN_SPACING" "5.00,5.00,5.00,5.00,5.00,5.00,5.00,5.00,5.00,5.00,5.00,5.00,5.00,5.00"
					( Origin gBackEnd )
				)
				( attribute "SN_TESTPIN_TO_THRUVIA_SPACING" "5.00,5.00,5.00,5.00,5.00,5.00,5.00,5.00,5.00,5.00,5.00,5.00,5.00,5.00"
					( Origin gBackEnd )
				)
				( attribute "SN_TESTPIN_TO_TESTVIA_SPACING" "5.00,5.00,5.00,5.00,5.00,5.00,5.00,5.00,5.00,5.00,5.00,5.00,5.00,5.00"
					( Origin gBackEnd )
				)
				( attribute "SN_BBV_TO_TESTPIN_SPACING" "5.00,5.00,5.00,5.00,5.00,5.00,5.00,5.00,5.00,5.00,5.00,5.00,5.00,5.00"
					( Origin gBackEnd )
				)
				( attribute "SN_BONDPAD_TO_TESTPIN_SPACING" "5.00,5.00,5.00,5.00,5.00,5.00,5.00,5.00,5.00,5.00,5.00,5.00,5.00,5.00"
					( Origin gBackEnd )
				)
				( attribute "SN_LINE_TO_TESTPIN_SPACING" "4.50,5.00,5.00,5.00,5.00,5.00,5.00,5.00,5.00,5.00,5.00,5.00,5.00,5.00"
					( Origin gBackEnd )
				)
				( attribute "SN_SHAPE_TO_TESTPIN_SPACING" "4.50,4.00,4.00,4.00,4.00,4.00,4.00,4.00,4.00,4.00,4.00,4.00,4.00,5.00"
					( Origin gBackEnd )
				)
				( attribute "SN_THRUVIA_TO_THRUVIA_SPACING" "4.00,4.00,4.00,4.00,4.00,4.00,4.00,4.00,4.00,4.00,4.00,4.00,4.00,4.00"
					( Origin gBackEnd )
				)
				( attribute "SN_TESTVIA_TO_THRUVIA_SPACING" "5.00,5.00,5.00,5.00,5.00,5.00,5.00,5.00,5.00,5.00,5.00,5.00,5.00,6.00"
					( Origin gBackEnd )
				)
				( attribute "SN_BBV_TO_THRUVIA_SPACING" "5.00,5.00,5.00,5.00,5.00,5.00,5.00,5.00,5.00,5.00,5.00,5.00,5.00,5.00"
					( Origin gBackEnd )
				)
				( attribute "SN_BONDPAD_TO_THRUVIA_SPACING" "5.00,5.00,5.00,5.00,5.00,5.00,5.00,5.00,5.00,5.00,5.00,5.00,5.00,5.00"
					( Origin gBackEnd )
				)
				( attribute "SN_LINE_TO_THRUVIA_SPACING" "4.50,4.00,4.00,4.00,4.00,4.00,4.00,4.00,4.00,4.00,4.00,4.00,4.00,4.50"
					( Origin gBackEnd )
				)
				( attribute "SN_SHAPE_TO_THRUVIA_SPACING" "4.50,4.00,4.00,4.00,4.00,4.00,4.00,4.00,4.00,4.00,4.00,4.00,4.00,5.00"
					( Origin gBackEnd )
				)
				( attribute "SN_TESTVIA_TO_TESTVIA_SPACING" "5.00,5.00,5.00,5.00,5.00,5.00,5.00,5.00,5.00,5.00,5.00,5.00,5.00,6.00"
					( Origin gBackEnd )
				)
				( attribute "SN_BBV_TO_TESTVIA_SPACING" "5.00,5.00,5.00,5.00,5.00,5.00,5.00,5.00,5.00,5.00,5.00,5.00,5.00,5.00"
					( Origin gBackEnd )
				)
				( attribute "SN_BONDPAD_TO_TESTVIA_SPACING" "5.00,5.00,5.00,5.00,5.00,5.00,5.00,5.00,5.00,5.00,5.00,5.00,5.00,5.00"
					( Origin gBackEnd )
				)
				( attribute "SN_LINE_TO_TESTVIA_SPACING" "4.50,5.00,4.00,5.00,4.00,5.00,5.00,5.00,5.00,4.00,5.00,4.00,5.00,4.50"
					( Origin gBackEnd )
				)
				( attribute "SN_SHAPE_TO_TESTVIA_SPACING" "4.50,4.00,4.00,4.00,4.00,4.00,4.00,4.00,4.00,4.00,4.00,4.00,4.00,5.00"
					( Origin gBackEnd )
				)
				( attribute "SN_BBV_TO_BBV_SPACING" "5.00,5.00,5.00,5.00,5.00,5.00,5.00,5.00,5.00,5.00,5.00,5.00,5.00,5.00"
					( Origin gBackEnd )
				)
				( attribute "SN_BONDPAD_TO_BBV_SPACING" "5.00,5.00,5.00,5.00,5.00,5.00,5.00,5.00,5.00,5.00,5.00,5.00,5.00,5.00"
					( Origin gBackEnd )
				)
				( attribute "SN_BBV_TO_LINE_SPACING" "5.00,5.00,5.00,5.00,5.00,5.00,5.00,5.00,5.00,5.00,5.00,5.00,5.00,5.00"
					( Origin gBackEnd )
				)
				( attribute "SN_BBV_TO_SHAPE_SPACING" "5.00,5.00,5.00,5.00,5.00,5.00,5.00,5.00,5.00,5.00,5.00,5.00,5.00,5.00"
					( Origin gBackEnd )
				)
				( attribute "SN_BONDPAD_TO_BONDPAD_SPACING" "5.00,5.00,5.00,5.00,5.00,5.00,5.00,5.00,5.00,5.00,5.00,5.00,5.00,5.00"
					( Origin gBackEnd )
				)
				( attribute "SN_BONDPAD_TO_LINE_SPACING" "5.00,5.00,5.00,5.00,5.00,5.00,5.00,5.00,5.00,5.00,5.00,5.00,5.00,5.00"
					( Origin gBackEnd )
				)
				( attribute "SN_BONDPAD_TO_SHAPE_SPACING" "5.00,5.00,5.00,5.00,5.00,5.00,5.00,5.00,5.00,5.00,5.00,5.00,5.00,5.00"
					( Origin gBackEnd )
				)
				( attribute "SN_LINE_TO_LINE_SPACING" "4.00,4.00,4.00,4.00,4.00,4.00,4.00,4.00,4.00,4.00,4.00,4.00,4.00,4.00"
					( Origin gBackEnd )
				)
				( attribute "SN_LINE_TO_SHAPE_SPACING" "5.00,5.00,5.00,5.00,5.00,5.00,5.00,5.00,5.00,5.00,5.00,5.00,5.00,10.00"
					( Origin gBackEnd )
				)
				( attribute "SN_SHAPE_TO_SHAPE_SPACING" "10.00,10.00,10.00,10.00,10.00,10.00,10.00,10.00,10.00,10.00,10.00,10.00,10.00,10.00"
					( Origin gBackEnd )
				)
				( attribute "SN_HOLE_TO_PIN_SPACING" "8.00,8.00,8.00,8.00,8.00,8.00,8.00,8.00,8.00,8.00,8.00,8.00,8.00,8.00"
					( Origin gBackEnd )
				)
				( attribute "SN_HOLE_TO_VIA_SPACING" "8.00,8.00,8.00,8.00,8.00,8.00,8.00,8.00,8.00,8.00,8.00,8.00,8.00,8.00"
					( Origin gBackEnd )
				)
				( attribute "SN_HOLE_TO_LINE_SPACING" "8.00,8.00,8.00,8.00,8.00,8.00,8.00,8.00,8.00,8.00,8.00,8.00,8.00,8.00"
					( Origin gBackEnd )
				)
				( attribute "SN_HOLE_TO_SHAPE_SPACING" "8.00,8.00,8.00,8.00,8.00,8.00,8.00,8.00,8.00,8.00,8.00,8.00,8.00,8.00"
					( Origin gBackEnd )
				)
				( attribute "SN_HOLE_TO_HOLE_SPACING" "8.00,8.00,8.00,8.00,8.00,8.00,8.00,8.00,8.00,8.00,8.00,8.00,8.00,8.00"
					( Origin gBackEnd )
				)
				( attribute "SN_MVIA_TO_MVIA_SPACING" "5.00,5.00,5.00,5.00,5.00,5.00,5.00,5.00,5.00,5.00,5.00,5.00,5.00,5.00"
					( Origin gBackEnd )
				)
				( attribute "SN_MVIA_TO_THRUPIN_SPACING" "5.00,5.00,5.00,5.00,5.00,5.00,5.00,5.00,5.00,5.00,5.00,5.00,5.00,5.00"
					( Origin gBackEnd )
				)
				( attribute "SN_MVIA_TO_SMDPIN_SPACING" "5.00,5.00,5.00,5.00,5.00,5.00,5.00,5.00,5.00,5.00,5.00,5.00,5.00,5.00"
					( Origin gBackEnd )
				)
				( attribute "SN_MVIA_TO_THRUVIA_SPACING" "5.00,5.00,5.00,5.00,5.00,5.00,5.00,5.00,5.00,5.00,5.00,5.00,5.00,5.00"
					( Origin gBackEnd )
				)
				( attribute "SN_MVIA_TO_BBV_SPACING" "5.00,5.00,5.00,5.00,5.00,5.00,5.00,5.00,5.00,5.00,5.00,5.00,5.00,5.00"
					( Origin gBackEnd )
				)
				( attribute "SN_MVIA_TO_LINE_SPACING" "5.00,5.00,5.00,5.00,5.00,5.00,5.00,5.00,5.00,5.00,5.00,5.00,5.00,5.00"
					( Origin gBackEnd )
				)
				( attribute "SN_MVIA_TO_SHAPE_SPACING" "5.00,5.00,5.00,5.00,5.00,5.00,5.00,5.00,5.00,5.00,5.00,5.00,5.00,5.00"
					( Origin gBackEnd )
				)
				( attribute "SN_MVIA_TO_TESTPIN_SPACING" "5.00,5.00,5.00,5.00,5.00,5.00,5.00,5.00,5.00,5.00,5.00,5.00,5.00,5.00"
					( Origin gBackEnd )
				)
				( attribute "SN_MVIA_TO_TESTVIA_SPACING" "5.00,5.00,5.00,5.00,5.00,5.00,5.00,5.00,5.00,5.00,5.00,5.00,5.00,5.00"
					( Origin gBackEnd )
				)
				( attribute "SN_BONDPAD_TO_MVIA_SPACING" "5.00,5.00,5.00,5.00,5.00,5.00,5.00,5.00,5.00,5.00,5.00,5.00,5.00,5.00"
					( Origin gBackEnd )
				)
				( objectStatus "DEFAULT" )
			)
			( matchGroup "@crescent_city_bb_fab1_lib.crescent_city_bb_fab1(sch_1):\MG_CLK_G2-BCLK\"
				( memberType ( signal ) )
				( attribute "RELATIVE_PROPAGATION_DELAY_SCOPE" "G"
					( Parent
						( matchGroupRef "@crescent_city_bb_fab1_lib.crescent_city_bb_fab1(sch_1):\MG_CLK_G2-BCLK\" )
					)
					( Origin gBackEnd )
				)
				( attribute "RELATIVE_PROPAGATION_DELAY_PATH_TYPE" "AD:AR"
					( Parent
						( matchGroupRef "@crescent_city_bb_fab1_lib.crescent_city_bb_fab1(sch_1):\MG_CLK_G2-BCLK\" )
					)
					( Origin gBackEnd )
				)
				( attribute "RELATIVE_PROPAGATION_DELAY" "-4000.00 MIL,5000.00 MIL"
					( Parent
						( matchGroupRef "@crescent_city_bb_fab1_lib.crescent_city_bb_fab1(sch_1):\MG_CLK_G2-BCLK\" )
					)
					( Units "uMatchProp" "ns" 1.000000)
					( Origin gBackEnd )
				)
				( member ( pinPairRef "@baseboard_fab2_lib.baseboard_fab2(sch_1):\PP5379\") )
				( member ( pinPairRef "@baseboard_fab2_lib.baseboard_fab2(sch_1):\PP5380\") )
				( member ( pinPairRef "@baseboard_fab2_lib.baseboard_fab2(sch_1):\PP6070\") )
				( member ( pinPairRef "@baseboard_fab2_lib.baseboard_fab2(sch_1):\PP5399\") )
				( member ( pinPairRef "@baseboard_fab2_lib.baseboard_fab2(sch_1):\PP5400\") )
				( member ( pinPairRef "@baseboard_fab2_lib.baseboard_fab2(sch_1):\PP5397\") )
				( member ( pinPairRef "@baseboard_fab2_lib.baseboard_fab2(sch_1):\PP5398\") )
				( member ( pinPairRef "@baseboard_fab2_lib.baseboard_fab2(sch_1):\PP5385\") )
				( member ( pinPairRef "@baseboard_fab2_lib.baseboard_fab2(sch_1):\PP5386\") )
				( member ( pinPairRef "@baseboard_fab2_lib.baseboard_fab2(sch_1):\PP5383\") )
				( member ( pinPairRef "@baseboard_fab2_lib.baseboard_fab2(sch_1):\PP5384\") )
				( member ( pinPairRef "@baseboard_fab2_lib.baseboard_fab2(sch_1):\PP5377\") )
				( member ( pinPairRef "@baseboard_fab2_lib.baseboard_fab2(sch_1):\PP5378\") )
				( member ( pinPairRef "@baseboard_fab2_lib.baseboard_fab2(sch_1):\PP5395\") )
				( member ( pinPairRef "@baseboard_fab2_lib.baseboard_fab2(sch_1):\PP5396\") )
				( member ( pinPairRef "@baseboard_fab2_lib.baseboard_fab2(sch_1):\PP5393\") )
				( member ( pinPairRef "@baseboard_fab2_lib.baseboard_fab2(sch_1):\PP5394\") )
				( member ( pinPairRef "@baseboard_fab2_lib.baseboard_fab2(sch_1):\PP5391\") )
				( member ( pinPairRef "@baseboard_fab2_lib.baseboard_fab2(sch_1):\PP5392\") )
				( member ( pinPairRef "@baseboard_fab2_lib.baseboard_fab2(sch_1):\PP5375\") )
				( member ( pinPairRef "@baseboard_fab2_lib.baseboard_fab2(sch_1):\PP5376\") )
				( member ( pinPairRef "@baseboard_fab2_lib.baseboard_fab2(sch_1):\PP5373\") )
				( member ( pinPairRef "@baseboard_fab2_lib.baseboard_fab2(sch_1):\PP5374\") )
				( objectStatus "MG_CLK_G2-BCLK" )
			)
			( matchGroup "@baseboard_fab2_lib.baseboard_fab2(sch_1):\MG_CPU_BCLK\"
				( memberType ( signal ) )
				( member ( pinPairRef "@baseboard_fab2_lib.baseboard_fab2(sch_1):\PP6070\") )
				( member ( pinPairRef "@baseboard_fab2_lib.baseboard_fab2(sch_1):\PP6069\") )
				( member ( pinPairRef "@baseboard_fab2_lib.baseboard_fab2(sch_1):\PP6068\") )
				( member ( pinPairRef "@baseboard_fab2_lib.baseboard_fab2(sch_1):\PP6063\") )
				( member ( pinPairRef "@baseboard_fab2_lib.baseboard_fab2(sch_1):\PP6057\") )
				( member ( pinPairRef "@baseboard_fab2_lib.baseboard_fab2(sch_1):\PP6062\") )
				( member ( pinPairRef "@baseboard_fab2_lib.baseboard_fab2(sch_1):\PP6061\") )
				( member ( pinPairRef "@baseboard_fab2_lib.baseboard_fab2(sch_1):\PP6060\") )
				( member ( pinPairRef "@baseboard_fab2_lib.baseboard_fab2(sch_1):\PP6059\") )
				( member ( pinPairRef "@baseboard_fab2_lib.baseboard_fab2(sch_1):\PP6058\") )
				( member ( pinPairRef "@baseboard_fab2_lib.baseboard_fab2(sch_1):\PP6010\") )
				( member ( pinPairRef "@baseboard_fab2_lib.baseboard_fab2(sch_1):\PP6009\") )
				( objectStatus "MG_CPU_BCLK" )
			)
			( matchGroup "@baseboard_fab2_lib.baseboard_fab2(sch_1):\MG_CLK_G1-BCLK\"
				( memberType ( signal ) )
				( member ( pinPairRef "@baseboard_fab2_lib.baseboard_fab2(sch_1):\PP6053\") )
				( member ( pinPairRef "@baseboard_fab2_lib.baseboard_fab2(sch_1):\PP6052\") )
				( member ( pinPairRef "@baseboard_fab2_lib.baseboard_fab2(sch_1):\PP6044\") )
				( member ( pinPairRef "@baseboard_fab2_lib.baseboard_fab2(sch_1):\PP6054\") )
				( member ( pinPairRef "@baseboard_fab2_lib.baseboard_fab2(sch_1):\PP6056\") )
				( member ( pinPairRef "@baseboard_fab2_lib.baseboard_fab2(sch_1):\PP6055\") )
				( member ( pinPairRef "@baseboard_fab2_lib.baseboard_fab2(sch_1):\PP6048\") )
				( member ( pinPairRef "@baseboard_fab2_lib.baseboard_fab2(sch_1):\PP6045\") )
				( member ( pinPairRef "@baseboard_fab2_lib.baseboard_fab2(sch_1):\PP6051\") )
				( member ( pinPairRef "@baseboard_fab2_lib.baseboard_fab2(sch_1):\PP6050\") )
				( objectStatus "MG_CLK_G1-BCLK" )
			)
			( matchGroup "@crescent_city_bb_fab1_lib.crescent_city_bb_fab1(sch_1):\SPI_BMC-MUX\"
				( memberType ( signal ) )
				( attribute "RELATIVE_PROPAGATION_DELAY_SCOPE" "G"
					( Parent
						( matchGroupRef "@crescent_city_bb_fab1_lib.crescent_city_bb_fab1(sch_1):\SPI_BMC-MUX\" )
					)
					( Origin gBackEnd )
				)
				( attribute "RELATIVE_PROPAGATION_DELAY_PATH_TYPE" "AD:AR"
					( Parent
						( matchGroupRef "@crescent_city_bb_fab1_lib.crescent_city_bb_fab1(sch_1):\SPI_BMC-MUX\" )
					)
					( Origin gBackEnd )
				)
				( attribute "RELATIVE_PROPAGATION_DELAY" "0.00 MIL,125.00 MIL"
					( Parent
						( matchGroupRef "@crescent_city_bb_fab1_lib.crescent_city_bb_fab1(sch_1):\SPI_BMC-MUX\" )
					)
					( Units "uMatchProp" "ns" 1.000000)
					( Origin gBackEnd )
				)
				( member ( pinPairRef "@baseboard_fab2_lib.baseboard_fab2(sch_1):\PP6131\") )
				( member ( pinPairRef "@baseboard_fab2_lib.baseboard_fab2(sch_1):\PP6130\") )
				( member ( pinPairRef "@baseboard_fab2_lib.baseboard_fab2(sch_1):\PP6132\") )
				( member ( pinPairRef "@baseboard_fab2_lib.baseboard_fab2(sch_1):\PP6129\") )
				( objectStatus "SPI_BMC-MUX" )
			)
			( matchGroup "@crescent_city_bb_fab1_lib.crescent_city_bb_fab1(sch_1):\SPI_MUX-U3T1\"
				( memberType ( signal ) )
				( member ( pinPairRef "@baseboard_fab2_lib.baseboard_fab2(sch_1):\PP6071\") )
				( member ( pinPairRef "@baseboard_fab2_lib.baseboard_fab2(sch_1):\PP6090\") )
				( member ( pinPairRef "@baseboard_fab2_lib.baseboard_fab2(sch_1):\PP6093\") )
				( member ( pinPairRef "@baseboard_fab2_lib.baseboard_fab2(sch_1):\PP6108\") )
				( objectStatus "SPI_MUX-U3T1" )
			)
			( matchGroup "@crescent_city_bb_fab1_lib.crescent_city_bb_fab1(sch_1):\SPI_MUX-U7F1\"
				( memberType ( signal ) )
				( member ( pinPairRef "@baseboard_fab2_lib.baseboard_fab2(sch_1):\PP6072\") )
				( member ( pinPairRef "@baseboard_fab2_lib.baseboard_fab2(sch_1):\PP6091\") )
				( member ( pinPairRef "@baseboard_fab2_lib.baseboard_fab2(sch_1):\PP6094\") )
				( member ( pinPairRef "@baseboard_fab2_lib.baseboard_fab2(sch_1):\PP6109\") )
				( objectStatus "SPI_MUX-U7F1" )
			)
			( matchGroup "@baseboard_fab2_lib.baseboard_fab2(sch_1):\SPI_PCH-TPM\"
				( memberType ( signal ) )
				( member ( pinPairRef "@baseboard_fab2_lib.baseboard_fab2(sch_1):\PP6097\") )
				( member ( pinPairRef "@baseboard_fab2_lib.baseboard_fab2(sch_1):\PP6099\") )
				( member ( pinPairRef "@baseboard_fab2_lib.baseboard_fab2(sch_1):\PP6105\") )
				( member ( pinPairRef "@baseboard_fab2_lib.baseboard_fab2(sch_1):\PP6103\") )
				( objectStatus "SPI_PCH-TPM" )
			)
			( matchGroup "@crescent_city_bb_fab1_lib.crescent_city_bb_fab1(sch_1):\SPI_PCH-MUX\"
				( memberType ( signal ) )
				( member ( pinPairRef "@baseboard_fab2_lib.baseboard_fab2(sch_1):\PP6098\") )
				( member ( pinPairRef "@baseboard_fab2_lib.baseboard_fab2(sch_1):\PP6111\") )
				( member ( pinPairRef "@baseboard_fab2_lib.baseboard_fab2(sch_1):\PP6104\") )
				( member ( pinPairRef "@baseboard_fab2_lib.baseboard_fab2(sch_1):\PP29\") )
				( member ( pinPairRef "@baseboard_fab2_lib.baseboard_fab2(sch_1):\PP6112\") )
				( member ( pinPairRef "@baseboard_fab2_lib.baseboard_fab2(sch_1):\PP6096\") )
				( objectStatus "SPI_PCH-MUX" )
			)
			( matchGroup "@crescent_city_bb_fab1_lib.crescent_city_bb_fab1(sch_1):\SPI_BMC\"
				( memberType ( signal ) )
				( attribute "RELATIVE_PROPAGATION_DELAY_SCOPE" "G"
					( Parent
						( matchGroupRef "@crescent_city_bb_fab1_lib.crescent_city_bb_fab1(sch_1):\SPI_BMC\" )
					)
					( Origin gBackEnd )
				)
				( attribute "RELATIVE_PROPAGATION_DELAY_PATH_TYPE" "AD:AR"
					( Parent
						( matchGroupRef "@crescent_city_bb_fab1_lib.crescent_city_bb_fab1(sch_1):\SPI_BMC\" )
					)
					( Origin gBackEnd )
				)
				( attribute "RELATIVE_PROPAGATION_DELAY" "0.00 MIL,250.00 MIL"
					( Parent
						( matchGroupRef "@crescent_city_bb_fab1_lib.crescent_city_bb_fab1(sch_1):\SPI_BMC\" )
					)
					( Units "uMatchProp" "ns" 1.000000)
					( Origin gBackEnd )
				)
				( member ( pinPairRef "@baseboard_fab2_lib.baseboard_fab2(sch_1):\PP5802\") )
				( member ( pinPairRef "@baseboard_fab2_lib.baseboard_fab2(sch_1):\PP5807\") )
				( member ( pinPairRef "@baseboard_fab2_lib.baseboard_fab2(sch_1):\PP5809\") )
				( member ( pinPairRef "@baseboard_fab2_lib.baseboard_fab2(sch_1):\PP5801\") )
				( objectStatus "SPI_BMC" )
			)
			( matchGroup "@crescent_city_bb_fab1_lib.crescent_city_bb_fab1(sch_1):\SPI_NIC\"
				( memberType ( signal ) )
				( attribute "RELATIVE_PROPAGATION_DELAY_SCOPE" "G"
					( Parent
						( matchGroupRef "@crescent_city_bb_fab1_lib.crescent_city_bb_fab1(sch_1):\SPI_NIC\" )
					)
					( Origin gBackEnd )
				)
				( attribute "RELATIVE_PROPAGATION_DELAY_PATH_TYPE" "AD:AR"
					( Parent
						( matchGroupRef "@crescent_city_bb_fab1_lib.crescent_city_bb_fab1(sch_1):\SPI_NIC\" )
					)
					( Origin gBackEnd )
				)
				( attribute "RELATIVE_PROPAGATION_DELAY" "0.00 MIL,250.00 MIL"
					( Parent
						( matchGroupRef "@crescent_city_bb_fab1_lib.crescent_city_bb_fab1(sch_1):\SPI_NIC\" )
					)
					( Units "uMatchProp" "ns" 1.000000)
					( Origin gBackEnd )
				)
				( member ( pinPairRef "@baseboard_fab2_lib.baseboard_fab2(sch_1):\PP6110\") )
				( member ( pinPairRef "@baseboard_fab2_lib.baseboard_fab2(sch_1):\PP5805\") )
				( member ( pinPairRef "@baseboard_fab2_lib.baseboard_fab2(sch_1):\PP5803\") )
				( member ( pinPairRef "@baseboard_fab2_lib.baseboard_fab2(sch_1):\PP5808\") )
				( objectStatus "SPI_NIC" )
			)
			( matchGroup "@baseboard_fab2_lib.baseboard_fab2(sch_1):\MG_DMI_L1\"
				( memberType ( signal ) )
				( member ( pinPairRef "@baseboard_fab2_lib.baseboard_fab2(sch_1):\PP68\") )
				( member ( pinPairRef "@baseboard_fab2_lib.baseboard_fab2(sch_1):\PP71\") )
				( member ( pinPairRef "@baseboard_fab2_lib.baseboard_fab2(sch_1):\PP72\") )
				( member ( pinPairRef "@baseboard_fab2_lib.baseboard_fab2(sch_1):\PP75\") )
				( member ( pinPairRef "@baseboard_fab2_lib.baseboard_fab2(sch_1):\PP76\") )
				( member ( pinPairRef "@baseboard_fab2_lib.baseboard_fab2(sch_1):\PP79\") )
				( member ( pinPairRef "@baseboard_fab2_lib.baseboard_fab2(sch_1):\PP80\") )
				( member ( pinPairRef "@baseboard_fab2_lib.baseboard_fab2(sch_1):\PP83\") )
				( member ( pinPairRef "@baseboard_fab2_lib.baseboard_fab2(sch_1):\PP55\") )
				( member ( pinPairRef "@baseboard_fab2_lib.baseboard_fab2(sch_1):\PP53\") )
				( member ( pinPairRef "@baseboard_fab2_lib.baseboard_fab2(sch_1):\PP59\") )
				( member ( pinPairRef "@baseboard_fab2_lib.baseboard_fab2(sch_1):\PP57\") )
				( member ( pinPairRef "@baseboard_fab2_lib.baseboard_fab2(sch_1):\PP63\") )
				( member ( pinPairRef "@baseboard_fab2_lib.baseboard_fab2(sch_1):\PP61\") )
				( member ( pinPairRef "@baseboard_fab2_lib.baseboard_fab2(sch_1):\PP67\") )
				( member ( pinPairRef "@baseboard_fab2_lib.baseboard_fab2(sch_1):\PP65\") )
				( objectStatus "MG_DMI_L1" )
			)
			( matchGroup "@baseboard_fab2_lib.baseboard_fab2(sch_1):\MG_DMI_L0\"
				( memberType ( signal ) )
				( member ( pinPairRef "@baseboard_fab2_lib.baseboard_fab2(sch_1):\PP69\") )
				( member ( pinPairRef "@baseboard_fab2_lib.baseboard_fab2(sch_1):\PP70\") )
				( member ( pinPairRef "@baseboard_fab2_lib.baseboard_fab2(sch_1):\PP73\") )
				( member ( pinPairRef "@baseboard_fab2_lib.baseboard_fab2(sch_1):\PP74\") )
				( member ( pinPairRef "@baseboard_fab2_lib.baseboard_fab2(sch_1):\PP77\") )
				( member ( pinPairRef "@baseboard_fab2_lib.baseboard_fab2(sch_1):\PP78\") )
				( member ( pinPairRef "@baseboard_fab2_lib.baseboard_fab2(sch_1):\PP81\") )
				( member ( pinPairRef "@baseboard_fab2_lib.baseboard_fab2(sch_1):\PP82\") )
				( member ( pinPairRef "@baseboard_fab2_lib.baseboard_fab2(sch_1):\PP54\") )
				( member ( pinPairRef "@baseboard_fab2_lib.baseboard_fab2(sch_1):\PP52\") )
				( member ( pinPairRef "@baseboard_fab2_lib.baseboard_fab2(sch_1):\PP58\") )
				( member ( pinPairRef "@baseboard_fab2_lib.baseboard_fab2(sch_1):\PP56\") )
				( member ( pinPairRef "@baseboard_fab2_lib.baseboard_fab2(sch_1):\PP62\") )
				( member ( pinPairRef "@baseboard_fab2_lib.baseboard_fab2(sch_1):\PP60\") )
				( member ( pinPairRef "@baseboard_fab2_lib.baseboard_fab2(sch_1):\PP66\") )
				( member ( pinPairRef "@baseboard_fab2_lib.baseboard_fab2(sch_1):\PP64\") )
				( objectStatus "MG_DMI_L0" )
			)
			( matchGroup "@baseboard_fab2_lib.baseboard_fab2(sch_1):\MG_PCIE_L0\"
				( memberType ( signal ) )
				( member ( pinPairRef "@baseboard_fab2_lib.baseboard_fab2(sch_1):\PP84\") )
				( member ( pinPairRef "@baseboard_fab2_lib.baseboard_fab2(sch_1):\PP86\") )
				( member ( pinPairRef "@baseboard_fab2_lib.baseboard_fab2(sch_1):\PP88\") )
				( member ( pinPairRef "@baseboard_fab2_lib.baseboard_fab2(sch_1):\PP90\") )
				( member ( pinPairRef "@baseboard_fab2_lib.baseboard_fab2(sch_1):\PP92\") )
				( member ( pinPairRef "@baseboard_fab2_lib.baseboard_fab2(sch_1):\PP94\") )
				( member ( pinPairRef "@baseboard_fab2_lib.baseboard_fab2(sch_1):\PP3038\") )
				( member ( pinPairRef "@baseboard_fab2_lib.baseboard_fab2(sch_1):\PP3035\") )
				( member ( pinPairRef "@baseboard_fab2_lib.baseboard_fab2(sch_1):\PP2994\") )
				( member ( pinPairRef "@baseboard_fab2_lib.baseboard_fab2(sch_1):\PP2992\") )
				( member ( pinPairRef "@baseboard_fab2_lib.baseboard_fab2(sch_1):\PP2990\") )
				( member ( pinPairRef "@baseboard_fab2_lib.baseboard_fab2(sch_1):\PP2988\") )
				( member ( pinPairRef "@baseboard_fab2_lib.baseboard_fab2(sch_1):\PP2986\") )
				( member ( pinPairRef "@baseboard_fab2_lib.baseboard_fab2(sch_1):\PP2984\") )
				( member ( pinPairRef "@baseboard_fab2_lib.baseboard_fab2(sch_1):\PP2982\") )
				( member ( pinPairRef "@baseboard_fab2_lib.baseboard_fab2(sch_1):\PP2980\") )
				( member ( pinPairRef "@baseboard_fab2_lib.baseboard_fab2(sch_1):\PP2978\") )
				( member ( pinPairRef "@baseboard_fab2_lib.baseboard_fab2(sch_1):\PP2976\") )
				( member ( pinPairRef "@baseboard_fab2_lib.baseboard_fab2(sch_1):\PP2974\") )
				( member ( pinPairRef "@baseboard_fab2_lib.baseboard_fab2(sch_1):\PP2972\") )
				( member ( pinPairRef "@baseboard_fab2_lib.baseboard_fab2(sch_1):\PP3042\") )
				( member ( pinPairRef "@baseboard_fab2_lib.baseboard_fab2(sch_1):\PP3039\") )
				( member ( pinPairRef "@baseboard_fab2_lib.baseboard_fab2(sch_1):\PP164\") )
				( member ( pinPairRef "@baseboard_fab2_lib.baseboard_fab2(sch_1):\PP165\") )
				( member ( pinPairRef "@baseboard_fab2_lib.baseboard_fab2(sch_1):\PP388\") )
				( member ( pinPairRef "@baseboard_fab2_lib.baseboard_fab2(sch_1):\PP389\") )
				( member ( pinPairRef "@baseboard_fab2_lib.baseboard_fab2(sch_1):\PP384\") )
				( member ( pinPairRef "@baseboard_fab2_lib.baseboard_fab2(sch_1):\PP385\") )
				( member ( pinPairRef "@baseboard_fab2_lib.baseboard_fab2(sch_1):\PP380\") )
				( member ( pinPairRef "@baseboard_fab2_lib.baseboard_fab2(sch_1):\PP381\") )
				( member ( pinPairRef "@baseboard_fab2_lib.baseboard_fab2(sch_1):\PP376\") )
				( member ( pinPairRef "@baseboard_fab2_lib.baseboard_fab2(sch_1):\PP377\") )
				( member ( pinPairRef "@baseboard_fab2_lib.baseboard_fab2(sch_1):\PP372\") )
				( member ( pinPairRef "@baseboard_fab2_lib.baseboard_fab2(sch_1):\PP373\") )
				( member ( pinPairRef "@baseboard_fab2_lib.baseboard_fab2(sch_1):\PP368\") )
				( member ( pinPairRef "@baseboard_fab2_lib.baseboard_fab2(sch_1):\PP369\") )
				( member ( pinPairRef "@baseboard_fab2_lib.baseboard_fab2(sch_1):\PP364\") )
				( member ( pinPairRef "@baseboard_fab2_lib.baseboard_fab2(sch_1):\PP365\") )
				( member ( pinPairRef "@baseboard_fab2_lib.baseboard_fab2(sch_1):\PP360\") )
				( member ( pinPairRef "@baseboard_fab2_lib.baseboard_fab2(sch_1):\PP361\") )
				( member ( pinPairRef "@baseboard_fab2_lib.baseboard_fab2(sch_1):\PP356\") )
				( member ( pinPairRef "@baseboard_fab2_lib.baseboard_fab2(sch_1):\PP357\") )
				( member ( pinPairRef "@baseboard_fab2_lib.baseboard_fab2(sch_1):\PP352\") )
				( member ( pinPairRef "@baseboard_fab2_lib.baseboard_fab2(sch_1):\PP353\") )
				( member ( pinPairRef "@baseboard_fab2_lib.baseboard_fab2(sch_1):\PP347\") )
				( member ( pinPairRef "@baseboard_fab2_lib.baseboard_fab2(sch_1):\PP349\") )
				( member ( pinPairRef "@baseboard_fab2_lib.baseboard_fab2(sch_1):\PP343\") )
				( member ( pinPairRef "@baseboard_fab2_lib.baseboard_fab2(sch_1):\PP345\") )
				( member ( pinPairRef "@baseboard_fab2_lib.baseboard_fab2(sch_1):\PP340\") )
				( member ( pinPairRef "@baseboard_fab2_lib.baseboard_fab2(sch_1):\PP341\") )
				( member ( pinPairRef "@baseboard_fab2_lib.baseboard_fab2(sch_1):\PP335\") )
				( member ( pinPairRef "@baseboard_fab2_lib.baseboard_fab2(sch_1):\PP337\") )
				( member ( pinPairRef "@baseboard_fab2_lib.baseboard_fab2(sch_1):\PP331\") )
				( member ( pinPairRef "@baseboard_fab2_lib.baseboard_fab2(sch_1):\PP333\") )
				( member ( pinPairRef "@baseboard_fab2_lib.baseboard_fab2(sch_1):\PP327\") )
				( member ( pinPairRef "@baseboard_fab2_lib.baseboard_fab2(sch_1):\PP329\") )
				( member ( pinPairRef "@baseboard_fab2_lib.baseboard_fab2(sch_1):\PP324\") )
				( member ( pinPairRef "@baseboard_fab2_lib.baseboard_fab2(sch_1):\PP325\") )
				( member ( pinPairRef "@baseboard_fab2_lib.baseboard_fab2(sch_1):\PP320\") )
				( member ( pinPairRef "@baseboard_fab2_lib.baseboard_fab2(sch_1):\PP321\") )
				( member ( pinPairRef "@baseboard_fab2_lib.baseboard_fab2(sch_1):\PP316\") )
				( member ( pinPairRef "@baseboard_fab2_lib.baseboard_fab2(sch_1):\PP317\") )
				( member ( pinPairRef "@baseboard_fab2_lib.baseboard_fab2(sch_1):\PP312\") )
				( member ( pinPairRef "@baseboard_fab2_lib.baseboard_fab2(sch_1):\PP313\") )
				( member ( pinPairRef "@baseboard_fab2_lib.baseboard_fab2(sch_1):\PP308\") )
				( member ( pinPairRef "@baseboard_fab2_lib.baseboard_fab2(sch_1):\PP309\") )
				( member ( pinPairRef "@baseboard_fab2_lib.baseboard_fab2(sch_1):\PP304\") )
				( member ( pinPairRef "@baseboard_fab2_lib.baseboard_fab2(sch_1):\PP305\") )
				( member ( pinPairRef "@baseboard_fab2_lib.baseboard_fab2(sch_1):\PP300\") )
				( member ( pinPairRef "@baseboard_fab2_lib.baseboard_fab2(sch_1):\PP301\") )
				( member ( pinPairRef "@baseboard_fab2_lib.baseboard_fab2(sch_1):\PP296\") )
				( member ( pinPairRef "@baseboard_fab2_lib.baseboard_fab2(sch_1):\PP297\") )
				( member ( pinPairRef "@baseboard_fab2_lib.baseboard_fab2(sch_1):\PP292\") )
				( member ( pinPairRef "@baseboard_fab2_lib.baseboard_fab2(sch_1):\PP293\") )
				( member ( pinPairRef "@baseboard_fab2_lib.baseboard_fab2(sch_1):\PP288\") )
				( member ( pinPairRef "@baseboard_fab2_lib.baseboard_fab2(sch_1):\PP289\") )
				( member ( pinPairRef "@baseboard_fab2_lib.baseboard_fab2(sch_1):\PP284\") )
				( member ( pinPairRef "@baseboard_fab2_lib.baseboard_fab2(sch_1):\PP285\") )
				( member ( pinPairRef "@baseboard_fab2_lib.baseboard_fab2(sch_1):\PP280\") )
				( member ( pinPairRef "@baseboard_fab2_lib.baseboard_fab2(sch_1):\PP281\") )
				( member ( pinPairRef "@baseboard_fab2_lib.baseboard_fab2(sch_1):\PP276\") )
				( member ( pinPairRef "@baseboard_fab2_lib.baseboard_fab2(sch_1):\PP277\") )
				( member ( pinPairRef "@baseboard_fab2_lib.baseboard_fab2(sch_1):\PP272\") )
				( member ( pinPairRef "@baseboard_fab2_lib.baseboard_fab2(sch_1):\PP273\") )
				( member ( pinPairRef "@baseboard_fab2_lib.baseboard_fab2(sch_1):\PP268\") )
				( member ( pinPairRef "@baseboard_fab2_lib.baseboard_fab2(sch_1):\PP269\") )
				( member ( pinPairRef "@baseboard_fab2_lib.baseboard_fab2(sch_1):\PP264\") )
				( member ( pinPairRef "@baseboard_fab2_lib.baseboard_fab2(sch_1):\PP265\") )
				( member ( pinPairRef "@baseboard_fab2_lib.baseboard_fab2(sch_1):\PP260\") )
				( member ( pinPairRef "@baseboard_fab2_lib.baseboard_fab2(sch_1):\PP261\") )
				( member ( pinPairRef "@baseboard_fab2_lib.baseboard_fab2(sch_1):\PP256\") )
				( member ( pinPairRef "@baseboard_fab2_lib.baseboard_fab2(sch_1):\PP257\") )
				( member ( pinPairRef "@baseboard_fab2_lib.baseboard_fab2(sch_1):\PP252\") )
				( member ( pinPairRef "@baseboard_fab2_lib.baseboard_fab2(sch_1):\PP253\") )
				( member ( pinPairRef "@baseboard_fab2_lib.baseboard_fab2(sch_1):\PP248\") )
				( member ( pinPairRef "@baseboard_fab2_lib.baseboard_fab2(sch_1):\PP249\") )
				( member ( pinPairRef "@baseboard_fab2_lib.baseboard_fab2(sch_1):\PP244\") )
				( member ( pinPairRef "@baseboard_fab2_lib.baseboard_fab2(sch_1):\PP245\") )
				( member ( pinPairRef "@baseboard_fab2_lib.baseboard_fab2(sch_1):\PP240\") )
				( member ( pinPairRef "@baseboard_fab2_lib.baseboard_fab2(sch_1):\PP241\") )
				( member ( pinPairRef "@baseboard_fab2_lib.baseboard_fab2(sch_1):\PP236\") )
				( member ( pinPairRef "@baseboard_fab2_lib.baseboard_fab2(sch_1):\PP237\") )
				( member ( pinPairRef "@baseboard_fab2_lib.baseboard_fab2(sch_1):\PP232\") )
				( member ( pinPairRef "@baseboard_fab2_lib.baseboard_fab2(sch_1):\PP233\") )
				( member ( pinPairRef "@baseboard_fab2_lib.baseboard_fab2(sch_1):\PP128\") )
				( member ( pinPairRef "@baseboard_fab2_lib.baseboard_fab2(sch_1):\PP129\") )
				( member ( pinPairRef "@baseboard_fab2_lib.baseboard_fab2(sch_1):\PP132\") )
				( member ( pinPairRef "@baseboard_fab2_lib.baseboard_fab2(sch_1):\PP133\") )
				( member ( pinPairRef "@baseboard_fab2_lib.baseboard_fab2(sch_1):\PP104\") )
				( member ( pinPairRef "@baseboard_fab2_lib.baseboard_fab2(sch_1):\PP105\") )
				( member ( pinPairRef "@baseboard_fab2_lib.baseboard_fab2(sch_1):\PP108\") )
				( member ( pinPairRef "@baseboard_fab2_lib.baseboard_fab2(sch_1):\PP109\") )
				( member ( pinPairRef "@baseboard_fab2_lib.baseboard_fab2(sch_1):\PP112\") )
				( member ( pinPairRef "@baseboard_fab2_lib.baseboard_fab2(sch_1):\PP113\") )
				( member ( pinPairRef "@baseboard_fab2_lib.baseboard_fab2(sch_1):\PP116\") )
				( member ( pinPairRef "@baseboard_fab2_lib.baseboard_fab2(sch_1):\PP117\") )
				( member ( pinPairRef "@baseboard_fab2_lib.baseboard_fab2(sch_1):\PP120\") )
				( member ( pinPairRef "@baseboard_fab2_lib.baseboard_fab2(sch_1):\PP121\") )
				( member ( pinPairRef "@baseboard_fab2_lib.baseboard_fab2(sch_1):\PP124\") )
				( member ( pinPairRef "@baseboard_fab2_lib.baseboard_fab2(sch_1):\PP125\") )
				( member ( pinPairRef "@baseboard_fab2_lib.baseboard_fab2(sch_1):\PP228\") )
				( member ( pinPairRef "@baseboard_fab2_lib.baseboard_fab2(sch_1):\PP230\") )
				( member ( pinPairRef "@baseboard_fab2_lib.baseboard_fab2(sch_1):\PP224\") )
				( member ( pinPairRef "@baseboard_fab2_lib.baseboard_fab2(sch_1):\PP226\") )
				( member ( pinPairRef "@baseboard_fab2_lib.baseboard_fab2(sch_1):\PP135\") )
				( member ( pinPairRef "@baseboard_fab2_lib.baseboard_fab2(sch_1):\PP137\") )
				( member ( pinPairRef "@baseboard_fab2_lib.baseboard_fab2(sch_1):\PP139\") )
				( member ( pinPairRef "@baseboard_fab2_lib.baseboard_fab2(sch_1):\PP141\") )
				( member ( pinPairRef "@baseboard_fab2_lib.baseboard_fab2(sch_1):\PP143\") )
				( member ( pinPairRef "@baseboard_fab2_lib.baseboard_fab2(sch_1):\PP145\") )
				( member ( pinPairRef "@baseboard_fab2_lib.baseboard_fab2(sch_1):\PP147\") )
				( member ( pinPairRef "@baseboard_fab2_lib.baseboard_fab2(sch_1):\PP149\") )
				( member ( pinPairRef "@baseboard_fab2_lib.baseboard_fab2(sch_1):\PP151\") )
				( member ( pinPairRef "@baseboard_fab2_lib.baseboard_fab2(sch_1):\PP153\") )
				( member ( pinPairRef "@baseboard_fab2_lib.baseboard_fab2(sch_1):\PP155\") )
				( member ( pinPairRef "@baseboard_fab2_lib.baseboard_fab2(sch_1):\PP157\") )
				( member ( pinPairRef "@baseboard_fab2_lib.baseboard_fab2(sch_1):\PP159\") )
				( member ( pinPairRef "@baseboard_fab2_lib.baseboard_fab2(sch_1):\PP161\") )
				( member ( pinPairRef "@baseboard_fab2_lib.baseboard_fab2(sch_1):\PP3002\") )
				( member ( pinPairRef "@baseboard_fab2_lib.baseboard_fab2(sch_1):\PP3000\") )
				( member ( pinPairRef "@baseboard_fab2_lib.baseboard_fab2(sch_1):\PP2998\") )
				( member ( pinPairRef "@baseboard_fab2_lib.baseboard_fab2(sch_1):\PP2996\") )
				( member ( pinPairRef "@baseboard_fab2_lib.baseboard_fab2(sch_1):\PP220\") )
				( member ( pinPairRef "@baseboard_fab2_lib.baseboard_fab2(sch_1):\PP222\") )
				( member ( pinPairRef "@baseboard_fab2_lib.baseboard_fab2(sch_1):\PP216\") )
				( member ( pinPairRef "@baseboard_fab2_lib.baseboard_fab2(sch_1):\PP218\") )
				( member ( pinPairRef "@baseboard_fab2_lib.baseboard_fab2(sch_1):\PP212\") )
				( member ( pinPairRef "@baseboard_fab2_lib.baseboard_fab2(sch_1):\PP214\") )
				( member ( pinPairRef "@baseboard_fab2_lib.baseboard_fab2(sch_1):\PP208\") )
				( member ( pinPairRef "@baseboard_fab2_lib.baseboard_fab2(sch_1):\PP210\") )
				( member ( pinPairRef "@baseboard_fab2_lib.baseboard_fab2(sch_1):\PP204\") )
				( member ( pinPairRef "@baseboard_fab2_lib.baseboard_fab2(sch_1):\PP206\") )
				( member ( pinPairRef "@baseboard_fab2_lib.baseboard_fab2(sch_1):\PP200\") )
				( member ( pinPairRef "@baseboard_fab2_lib.baseboard_fab2(sch_1):\PP201\") )
				( member ( pinPairRef "@baseboard_fab2_lib.baseboard_fab2(sch_1):\PP196\") )
				( member ( pinPairRef "@baseboard_fab2_lib.baseboard_fab2(sch_1):\PP197\") )
				( member ( pinPairRef "@baseboard_fab2_lib.baseboard_fab2(sch_1):\PP192\") )
				( member ( pinPairRef "@baseboard_fab2_lib.baseboard_fab2(sch_1):\PP193\") )
				( member ( pinPairRef "@baseboard_fab2_lib.baseboard_fab2(sch_1):\PP188\") )
				( member ( pinPairRef "@baseboard_fab2_lib.baseboard_fab2(sch_1):\PP189\") )
				( member ( pinPairRef "@baseboard_fab2_lib.baseboard_fab2(sch_1):\PP176\") )
				( member ( pinPairRef "@baseboard_fab2_lib.baseboard_fab2(sch_1):\PP177\") )
				( member ( pinPairRef "@baseboard_fab2_lib.baseboard_fab2(sch_1):\PP184\") )
				( member ( pinPairRef "@baseboard_fab2_lib.baseboard_fab2(sch_1):\PP186\") )
				( member ( pinPairRef "@baseboard_fab2_lib.baseboard_fab2(sch_1):\PP180\") )
				( member ( pinPairRef "@baseboard_fab2_lib.baseboard_fab2(sch_1):\PP181\") )
				( objectStatus "MG_PCIE_L0" )
			)
			( matchGroup "@baseboard_fab2_lib.baseboard_fab2(sch_1):\MG_PCIE_L1\"
				( memberType ( signal ) )
				( member ( pinPairRef "@baseboard_fab2_lib.baseboard_fab2(sch_1):\PP85\") )
				( member ( pinPairRef "@baseboard_fab2_lib.baseboard_fab2(sch_1):\PP87\") )
				( member ( pinPairRef "@baseboard_fab2_lib.baseboard_fab2(sch_1):\PP89\") )
				( member ( pinPairRef "@baseboard_fab2_lib.baseboard_fab2(sch_1):\PP91\") )
				( member ( pinPairRef "@baseboard_fab2_lib.baseboard_fab2(sch_1):\PP93\") )
				( member ( pinPairRef "@baseboard_fab2_lib.baseboard_fab2(sch_1):\PP95\") )
				( member ( pinPairRef "@baseboard_fab2_lib.baseboard_fab2(sch_1):\PP3037\") )
				( member ( pinPairRef "@baseboard_fab2_lib.baseboard_fab2(sch_1):\PP3036\") )
				( member ( pinPairRef "@baseboard_fab2_lib.baseboard_fab2(sch_1):\PP2993\") )
				( member ( pinPairRef "@baseboard_fab2_lib.baseboard_fab2(sch_1):\PP2991\") )
				( member ( pinPairRef "@baseboard_fab2_lib.baseboard_fab2(sch_1):\PP2989\") )
				( member ( pinPairRef "@baseboard_fab2_lib.baseboard_fab2(sch_1):\PP2987\") )
				( member ( pinPairRef "@baseboard_fab2_lib.baseboard_fab2(sch_1):\PP2985\") )
				( member ( pinPairRef "@baseboard_fab2_lib.baseboard_fab2(sch_1):\PP2983\") )
				( member ( pinPairRef "@baseboard_fab2_lib.baseboard_fab2(sch_1):\PP2981\") )
				( member ( pinPairRef "@baseboard_fab2_lib.baseboard_fab2(sch_1):\PP2979\") )
				( member ( pinPairRef "@baseboard_fab2_lib.baseboard_fab2(sch_1):\PP2977\") )
				( member ( pinPairRef "@baseboard_fab2_lib.baseboard_fab2(sch_1):\PP2975\") )
				( member ( pinPairRef "@baseboard_fab2_lib.baseboard_fab2(sch_1):\PP2973\") )
				( member ( pinPairRef "@baseboard_fab2_lib.baseboard_fab2(sch_1):\PP2971\") )
				( member ( pinPairRef "@baseboard_fab2_lib.baseboard_fab2(sch_1):\PP3041\") )
				( member ( pinPairRef "@baseboard_fab2_lib.baseboard_fab2(sch_1):\PP3040\") )
				( member ( pinPairRef "@baseboard_fab2_lib.baseboard_fab2(sch_1):\PP163\") )
				( member ( pinPairRef "@baseboard_fab2_lib.baseboard_fab2(sch_1):\PP166\") )
				( member ( pinPairRef "@baseboard_fab2_lib.baseboard_fab2(sch_1):\PP387\") )
				( member ( pinPairRef "@baseboard_fab2_lib.baseboard_fab2(sch_1):\PP390\") )
				( member ( pinPairRef "@baseboard_fab2_lib.baseboard_fab2(sch_1):\PP383\") )
				( member ( pinPairRef "@baseboard_fab2_lib.baseboard_fab2(sch_1):\PP386\") )
				( member ( pinPairRef "@baseboard_fab2_lib.baseboard_fab2(sch_1):\PP379\") )
				( member ( pinPairRef "@baseboard_fab2_lib.baseboard_fab2(sch_1):\PP382\") )
				( member ( pinPairRef "@baseboard_fab2_lib.baseboard_fab2(sch_1):\PP375\") )
				( member ( pinPairRef "@baseboard_fab2_lib.baseboard_fab2(sch_1):\PP378\") )
				( member ( pinPairRef "@baseboard_fab2_lib.baseboard_fab2(sch_1):\PP371\") )
				( member ( pinPairRef "@baseboard_fab2_lib.baseboard_fab2(sch_1):\PP374\") )
				( member ( pinPairRef "@baseboard_fab2_lib.baseboard_fab2(sch_1):\PP367\") )
				( member ( pinPairRef "@baseboard_fab2_lib.baseboard_fab2(sch_1):\PP370\") )
				( member ( pinPairRef "@baseboard_fab2_lib.baseboard_fab2(sch_1):\PP363\") )
				( member ( pinPairRef "@baseboard_fab2_lib.baseboard_fab2(sch_1):\PP366\") )
				( member ( pinPairRef "@baseboard_fab2_lib.baseboard_fab2(sch_1):\PP359\") )
				( member ( pinPairRef "@baseboard_fab2_lib.baseboard_fab2(sch_1):\PP362\") )
				( member ( pinPairRef "@baseboard_fab2_lib.baseboard_fab2(sch_1):\PP355\") )
				( member ( pinPairRef "@baseboard_fab2_lib.baseboard_fab2(sch_1):\PP358\") )
				( member ( pinPairRef "@baseboard_fab2_lib.baseboard_fab2(sch_1):\PP351\") )
				( member ( pinPairRef "@baseboard_fab2_lib.baseboard_fab2(sch_1):\PP354\") )
				( member ( pinPairRef "@baseboard_fab2_lib.baseboard_fab2(sch_1):\PP348\") )
				( member ( pinPairRef "@baseboard_fab2_lib.baseboard_fab2(sch_1):\PP350\") )
				( member ( pinPairRef "@baseboard_fab2_lib.baseboard_fab2(sch_1):\PP344\") )
				( member ( pinPairRef "@baseboard_fab2_lib.baseboard_fab2(sch_1):\PP346\") )
				( member ( pinPairRef "@baseboard_fab2_lib.baseboard_fab2(sch_1):\PP339\") )
				( member ( pinPairRef "@baseboard_fab2_lib.baseboard_fab2(sch_1):\PP342\") )
				( member ( pinPairRef "@baseboard_fab2_lib.baseboard_fab2(sch_1):\PP336\") )
				( member ( pinPairRef "@baseboard_fab2_lib.baseboard_fab2(sch_1):\PP338\") )
				( member ( pinPairRef "@baseboard_fab2_lib.baseboard_fab2(sch_1):\PP332\") )
				( member ( pinPairRef "@baseboard_fab2_lib.baseboard_fab2(sch_1):\PP334\") )
				( member ( pinPairRef "@baseboard_fab2_lib.baseboard_fab2(sch_1):\PP328\") )
				( member ( pinPairRef "@baseboard_fab2_lib.baseboard_fab2(sch_1):\PP330\") )
				( member ( pinPairRef "@baseboard_fab2_lib.baseboard_fab2(sch_1):\PP323\") )
				( member ( pinPairRef "@baseboard_fab2_lib.baseboard_fab2(sch_1):\PP326\") )
				( member ( pinPairRef "@baseboard_fab2_lib.baseboard_fab2(sch_1):\PP319\") )
				( member ( pinPairRef "@baseboard_fab2_lib.baseboard_fab2(sch_1):\PP322\") )
				( member ( pinPairRef "@baseboard_fab2_lib.baseboard_fab2(sch_1):\PP315\") )
				( member ( pinPairRef "@baseboard_fab2_lib.baseboard_fab2(sch_1):\PP318\") )
				( member ( pinPairRef "@baseboard_fab2_lib.baseboard_fab2(sch_1):\PP311\") )
				( member ( pinPairRef "@baseboard_fab2_lib.baseboard_fab2(sch_1):\PP314\") )
				( member ( pinPairRef "@baseboard_fab2_lib.baseboard_fab2(sch_1):\PP307\") )
				( member ( pinPairRef "@baseboard_fab2_lib.baseboard_fab2(sch_1):\PP310\") )
				( member ( pinPairRef "@baseboard_fab2_lib.baseboard_fab2(sch_1):\PP303\") )
				( member ( pinPairRef "@baseboard_fab2_lib.baseboard_fab2(sch_1):\PP306\") )
				( member ( pinPairRef "@baseboard_fab2_lib.baseboard_fab2(sch_1):\PP299\") )
				( member ( pinPairRef "@baseboard_fab2_lib.baseboard_fab2(sch_1):\PP302\") )
				( member ( pinPairRef "@baseboard_fab2_lib.baseboard_fab2(sch_1):\PP295\") )
				( member ( pinPairRef "@baseboard_fab2_lib.baseboard_fab2(sch_1):\PP298\") )
				( member ( pinPairRef "@baseboard_fab2_lib.baseboard_fab2(sch_1):\PP291\") )
				( member ( pinPairRef "@baseboard_fab2_lib.baseboard_fab2(sch_1):\PP294\") )
				( member ( pinPairRef "@baseboard_fab2_lib.baseboard_fab2(sch_1):\PP287\") )
				( member ( pinPairRef "@baseboard_fab2_lib.baseboard_fab2(sch_1):\PP290\") )
				( member ( pinPairRef "@baseboard_fab2_lib.baseboard_fab2(sch_1):\PP283\") )
				( member ( pinPairRef "@baseboard_fab2_lib.baseboard_fab2(sch_1):\PP286\") )
				( member ( pinPairRef "@baseboard_fab2_lib.baseboard_fab2(sch_1):\PP279\") )
				( member ( pinPairRef "@baseboard_fab2_lib.baseboard_fab2(sch_1):\PP282\") )
				( member ( pinPairRef "@baseboard_fab2_lib.baseboard_fab2(sch_1):\PP275\") )
				( member ( pinPairRef "@baseboard_fab2_lib.baseboard_fab2(sch_1):\PP278\") )
				( member ( pinPairRef "@baseboard_fab2_lib.baseboard_fab2(sch_1):\PP271\") )
				( member ( pinPairRef "@baseboard_fab2_lib.baseboard_fab2(sch_1):\PP274\") )
				( member ( pinPairRef "@baseboard_fab2_lib.baseboard_fab2(sch_1):\PP267\") )
				( member ( pinPairRef "@baseboard_fab2_lib.baseboard_fab2(sch_1):\PP270\") )
				( member ( pinPairRef "@baseboard_fab2_lib.baseboard_fab2(sch_1):\PP263\") )
				( member ( pinPairRef "@baseboard_fab2_lib.baseboard_fab2(sch_1):\PP266\") )
				( member ( pinPairRef "@baseboard_fab2_lib.baseboard_fab2(sch_1):\PP259\") )
				( member ( pinPairRef "@baseboard_fab2_lib.baseboard_fab2(sch_1):\PP262\") )
				( member ( pinPairRef "@baseboard_fab2_lib.baseboard_fab2(sch_1):\PP255\") )
				( member ( pinPairRef "@baseboard_fab2_lib.baseboard_fab2(sch_1):\PP258\") )
				( member ( pinPairRef "@baseboard_fab2_lib.baseboard_fab2(sch_1):\PP251\") )
				( member ( pinPairRef "@baseboard_fab2_lib.baseboard_fab2(sch_1):\PP254\") )
				( member ( pinPairRef "@baseboard_fab2_lib.baseboard_fab2(sch_1):\PP247\") )
				( member ( pinPairRef "@baseboard_fab2_lib.baseboard_fab2(sch_1):\PP250\") )
				( member ( pinPairRef "@baseboard_fab2_lib.baseboard_fab2(sch_1):\PP243\") )
				( member ( pinPairRef "@baseboard_fab2_lib.baseboard_fab2(sch_1):\PP246\") )
				( member ( pinPairRef "@baseboard_fab2_lib.baseboard_fab2(sch_1):\PP239\") )
				( member ( pinPairRef "@baseboard_fab2_lib.baseboard_fab2(sch_1):\PP242\") )
				( member ( pinPairRef "@baseboard_fab2_lib.baseboard_fab2(sch_1):\PP235\") )
				( member ( pinPairRef "@baseboard_fab2_lib.baseboard_fab2(sch_1):\PP238\") )
				( member ( pinPairRef "@baseboard_fab2_lib.baseboard_fab2(sch_1):\PP231\") )
				( member ( pinPairRef "@baseboard_fab2_lib.baseboard_fab2(sch_1):\PP234\") )
				( member ( pinPairRef "@baseboard_fab2_lib.baseboard_fab2(sch_1):\PP127\") )
				( member ( pinPairRef "@baseboard_fab2_lib.baseboard_fab2(sch_1):\PP130\") )
				( member ( pinPairRef "@baseboard_fab2_lib.baseboard_fab2(sch_1):\PP131\") )
				( member ( pinPairRef "@baseboard_fab2_lib.baseboard_fab2(sch_1):\PP134\") )
				( member ( pinPairRef "@baseboard_fab2_lib.baseboard_fab2(sch_1):\PP103\") )
				( member ( pinPairRef "@baseboard_fab2_lib.baseboard_fab2(sch_1):\PP106\") )
				( member ( pinPairRef "@baseboard_fab2_lib.baseboard_fab2(sch_1):\PP107\") )
				( member ( pinPairRef "@baseboard_fab2_lib.baseboard_fab2(sch_1):\PP110\") )
				( member ( pinPairRef "@baseboard_fab2_lib.baseboard_fab2(sch_1):\PP111\") )
				( member ( pinPairRef "@baseboard_fab2_lib.baseboard_fab2(sch_1):\PP114\") )
				( member ( pinPairRef "@baseboard_fab2_lib.baseboard_fab2(sch_1):\PP115\") )
				( member ( pinPairRef "@baseboard_fab2_lib.baseboard_fab2(sch_1):\PP118\") )
				( member ( pinPairRef "@baseboard_fab2_lib.baseboard_fab2(sch_1):\PP119\") )
				( member ( pinPairRef "@baseboard_fab2_lib.baseboard_fab2(sch_1):\PP122\") )
				( member ( pinPairRef "@baseboard_fab2_lib.baseboard_fab2(sch_1):\PP123\") )
				( member ( pinPairRef "@baseboard_fab2_lib.baseboard_fab2(sch_1):\PP126\") )
				( member ( pinPairRef "@baseboard_fab2_lib.baseboard_fab2(sch_1):\PP227\") )
				( member ( pinPairRef "@baseboard_fab2_lib.baseboard_fab2(sch_1):\PP229\") )
				( member ( pinPairRef "@baseboard_fab2_lib.baseboard_fab2(sch_1):\PP223\") )
				( member ( pinPairRef "@baseboard_fab2_lib.baseboard_fab2(sch_1):\PP225\") )
				( member ( pinPairRef "@baseboard_fab2_lib.baseboard_fab2(sch_1):\PP136\") )
				( member ( pinPairRef "@baseboard_fab2_lib.baseboard_fab2(sch_1):\PP138\") )
				( member ( pinPairRef "@baseboard_fab2_lib.baseboard_fab2(sch_1):\PP140\") )
				( member ( pinPairRef "@baseboard_fab2_lib.baseboard_fab2(sch_1):\PP142\") )
				( member ( pinPairRef "@baseboard_fab2_lib.baseboard_fab2(sch_1):\PP144\") )
				( member ( pinPairRef "@baseboard_fab2_lib.baseboard_fab2(sch_1):\PP146\") )
				( member ( pinPairRef "@baseboard_fab2_lib.baseboard_fab2(sch_1):\PP148\") )
				( member ( pinPairRef "@baseboard_fab2_lib.baseboard_fab2(sch_1):\PP150\") )
				( member ( pinPairRef "@baseboard_fab2_lib.baseboard_fab2(sch_1):\PP152\") )
				( member ( pinPairRef "@baseboard_fab2_lib.baseboard_fab2(sch_1):\PP154\") )
				( member ( pinPairRef "@baseboard_fab2_lib.baseboard_fab2(sch_1):\PP156\") )
				( member ( pinPairRef "@baseboard_fab2_lib.baseboard_fab2(sch_1):\PP158\") )
				( member ( pinPairRef "@baseboard_fab2_lib.baseboard_fab2(sch_1):\PP160\") )
				( member ( pinPairRef "@baseboard_fab2_lib.baseboard_fab2(sch_1):\PP162\") )
				( member ( pinPairRef "@baseboard_fab2_lib.baseboard_fab2(sch_1):\PP3001\") )
				( member ( pinPairRef "@baseboard_fab2_lib.baseboard_fab2(sch_1):\PP2999\") )
				( member ( pinPairRef "@baseboard_fab2_lib.baseboard_fab2(sch_1):\PP2997\") )
				( member ( pinPairRef "@baseboard_fab2_lib.baseboard_fab2(sch_1):\PP2995\") )
				( member ( pinPairRef "@baseboard_fab2_lib.baseboard_fab2(sch_1):\PP219\") )
				( member ( pinPairRef "@baseboard_fab2_lib.baseboard_fab2(sch_1):\PP221\") )
				( member ( pinPairRef "@baseboard_fab2_lib.baseboard_fab2(sch_1):\PP215\") )
				( member ( pinPairRef "@baseboard_fab2_lib.baseboard_fab2(sch_1):\PP217\") )
				( member ( pinPairRef "@baseboard_fab2_lib.baseboard_fab2(sch_1):\PP211\") )
				( member ( pinPairRef "@baseboard_fab2_lib.baseboard_fab2(sch_1):\PP213\") )
				( member ( pinPairRef "@baseboard_fab2_lib.baseboard_fab2(sch_1):\PP207\") )
				( member ( pinPairRef "@baseboard_fab2_lib.baseboard_fab2(sch_1):\PP209\") )
				( member ( pinPairRef "@baseboard_fab2_lib.baseboard_fab2(sch_1):\PP203\") )
				( member ( pinPairRef "@baseboard_fab2_lib.baseboard_fab2(sch_1):\PP205\") )
				( member ( pinPairRef "@baseboard_fab2_lib.baseboard_fab2(sch_1):\PP199\") )
				( member ( pinPairRef "@baseboard_fab2_lib.baseboard_fab2(sch_1):\PP202\") )
				( member ( pinPairRef "@baseboard_fab2_lib.baseboard_fab2(sch_1):\PP195\") )
				( member ( pinPairRef "@baseboard_fab2_lib.baseboard_fab2(sch_1):\PP198\") )
				( member ( pinPairRef "@baseboard_fab2_lib.baseboard_fab2(sch_1):\PP191\") )
				( member ( pinPairRef "@baseboard_fab2_lib.baseboard_fab2(sch_1):\PP194\") )
				( member ( pinPairRef "@baseboard_fab2_lib.baseboard_fab2(sch_1):\PP187\") )
				( member ( pinPairRef "@baseboard_fab2_lib.baseboard_fab2(sch_1):\PP190\") )
				( member ( pinPairRef "@baseboard_fab2_lib.baseboard_fab2(sch_1):\PP175\") )
				( member ( pinPairRef "@baseboard_fab2_lib.baseboard_fab2(sch_1):\PP178\") )
				( member ( pinPairRef "@baseboard_fab2_lib.baseboard_fab2(sch_1):\PP183\") )
				( member ( pinPairRef "@baseboard_fab2_lib.baseboard_fab2(sch_1):\PP185\") )
				( member ( pinPairRef "@baseboard_fab2_lib.baseboard_fab2(sch_1):\PP179\") )
				( member ( pinPairRef "@baseboard_fab2_lib.baseboard_fab2(sch_1):\PP182\") )
				( objectStatus "MG_PCIE_L1" )
			)
			( matchGroup "@crescent_city_bb_fab1_lib.crescent_city_bb_fab1(sch_1):\MG_KTI_CPU1_CPU0_P1P1\"
				( memberType ( signal ) )
				( member ( pinPairRef "@baseboard_fab2_lib.baseboard_fab2(sch_1):\PP3143\") )
				( member ( pinPairRef "@baseboard_fab2_lib.baseboard_fab2(sch_1):\PP3144\") )
				( member ( pinPairRef "@baseboard_fab2_lib.baseboard_fab2(sch_1):\PP3145\") )
				( member ( pinPairRef "@baseboard_fab2_lib.baseboard_fab2(sch_1):\PP3146\") )
				( member ( pinPairRef "@baseboard_fab2_lib.baseboard_fab2(sch_1):\PP3139\") )
				( member ( pinPairRef "@baseboard_fab2_lib.baseboard_fab2(sch_1):\PP3140\") )
				( member ( pinPairRef "@baseboard_fab2_lib.baseboard_fab2(sch_1):\PP3141\") )
				( member ( pinPairRef "@baseboard_fab2_lib.baseboard_fab2(sch_1):\PP3142\") )
				( member ( pinPairRef "@baseboard_fab2_lib.baseboard_fab2(sch_1):\PP3135\") )
				( member ( pinPairRef "@baseboard_fab2_lib.baseboard_fab2(sch_1):\PP3136\") )
				( member ( pinPairRef "@baseboard_fab2_lib.baseboard_fab2(sch_1):\PP3137\") )
				( member ( pinPairRef "@baseboard_fab2_lib.baseboard_fab2(sch_1):\PP3138\") )
				( member ( pinPairRef "@baseboard_fab2_lib.baseboard_fab2(sch_1):\PP3131\") )
				( member ( pinPairRef "@baseboard_fab2_lib.baseboard_fab2(sch_1):\PP3132\") )
				( member ( pinPairRef "@baseboard_fab2_lib.baseboard_fab2(sch_1):\PP3133\") )
				( member ( pinPairRef "@baseboard_fab2_lib.baseboard_fab2(sch_1):\PP3134\") )
				( member ( pinPairRef "@baseboard_fab2_lib.baseboard_fab2(sch_1):\PP3127\") )
				( member ( pinPairRef "@baseboard_fab2_lib.baseboard_fab2(sch_1):\PP3128\") )
				( member ( pinPairRef "@baseboard_fab2_lib.baseboard_fab2(sch_1):\PP3129\") )
				( member ( pinPairRef "@baseboard_fab2_lib.baseboard_fab2(sch_1):\PP3130\") )
				( member ( pinPairRef "@baseboard_fab2_lib.baseboard_fab2(sch_1):\PP3123\") )
				( member ( pinPairRef "@baseboard_fab2_lib.baseboard_fab2(sch_1):\PP3124\") )
				( member ( pinPairRef "@baseboard_fab2_lib.baseboard_fab2(sch_1):\PP3125\") )
				( member ( pinPairRef "@baseboard_fab2_lib.baseboard_fab2(sch_1):\PP3126\") )
				( member ( pinPairRef "@baseboard_fab2_lib.baseboard_fab2(sch_1):\PP3119\") )
				( member ( pinPairRef "@baseboard_fab2_lib.baseboard_fab2(sch_1):\PP3120\") )
				( member ( pinPairRef "@baseboard_fab2_lib.baseboard_fab2(sch_1):\PP3121\") )
				( member ( pinPairRef "@baseboard_fab2_lib.baseboard_fab2(sch_1):\PP3122\") )
				( member ( pinPairRef "@baseboard_fab2_lib.baseboard_fab2(sch_1):\PP3115\") )
				( member ( pinPairRef "@baseboard_fab2_lib.baseboard_fab2(sch_1):\PP3116\") )
				( member ( pinPairRef "@baseboard_fab2_lib.baseboard_fab2(sch_1):\PP3117\") )
				( member ( pinPairRef "@baseboard_fab2_lib.baseboard_fab2(sch_1):\PP3118\") )
				( member ( pinPairRef "@baseboard_fab2_lib.baseboard_fab2(sch_1):\PP3111\") )
				( member ( pinPairRef "@baseboard_fab2_lib.baseboard_fab2(sch_1):\PP3112\") )
				( member ( pinPairRef "@baseboard_fab2_lib.baseboard_fab2(sch_1):\PP3113\") )
				( member ( pinPairRef "@baseboard_fab2_lib.baseboard_fab2(sch_1):\PP3114\") )
				( member ( pinPairRef "@baseboard_fab2_lib.baseboard_fab2(sch_1):\PP3107\") )
				( member ( pinPairRef "@baseboard_fab2_lib.baseboard_fab2(sch_1):\PP3108\") )
				( member ( pinPairRef "@baseboard_fab2_lib.baseboard_fab2(sch_1):\PP3109\") )
				( member ( pinPairRef "@baseboard_fab2_lib.baseboard_fab2(sch_1):\PP3110\") )
				( objectStatus "MG_KTI_CPU1_CPU0_P1P1" )
			)
			( matchGroup "@baseboard_fab2_lib.baseboard_fab2(sch_1):\MG_KTI_BUNDLE_NG_KTI_CPU1_CPU0_P1P1_0-1\"
				( memberType ( signal ) )
				( member ( pinPairRef "@baseboard_fab2_lib.baseboard_fab2(sch_1):\PP3143\") )
				( member ( pinPairRef "@baseboard_fab2_lib.baseboard_fab2(sch_1):\PP3144\") )
				( member ( pinPairRef "@baseboard_fab2_lib.baseboard_fab2(sch_1):\PP3145\") )
				( member ( pinPairRef "@baseboard_fab2_lib.baseboard_fab2(sch_1):\PP3146\") )
				( objectStatus "MG_KTI_BUNDLE_NG_KTI_CPU1_CPU0_P1P1_0-1" )
			)
			( matchGroup "@baseboard_fab2_lib.baseboard_fab2(sch_1):\MG_KTI_BUNDLE_NG_KTI_CPU1_CPU0_P1P1_2-3\"
				( memberType ( signal ) )
				( member ( pinPairRef "@baseboard_fab2_lib.baseboard_fab2(sch_1):\PP3139\") )
				( member ( pinPairRef "@baseboard_fab2_lib.baseboard_fab2(sch_1):\PP3140\") )
				( member ( pinPairRef "@baseboard_fab2_lib.baseboard_fab2(sch_1):\PP3141\") )
				( member ( pinPairRef "@baseboard_fab2_lib.baseboard_fab2(sch_1):\PP3142\") )
				( objectStatus "MG_KTI_BUNDLE_NG_KTI_CPU1_CPU0_P1P1_2-3" )
			)
			( matchGroup "@baseboard_fab2_lib.baseboard_fab2(sch_1):\MG_KTI_BUNDLE_NG_KTI_CPU1_CPU0_P1P1_4-5\"
				( memberType ( signal ) )
				( member ( pinPairRef "@baseboard_fab2_lib.baseboard_fab2(sch_1):\PP3135\") )
				( member ( pinPairRef "@baseboard_fab2_lib.baseboard_fab2(sch_1):\PP3136\") )
				( member ( pinPairRef "@baseboard_fab2_lib.baseboard_fab2(sch_1):\PP3137\") )
				( member ( pinPairRef "@baseboard_fab2_lib.baseboard_fab2(sch_1):\PP3138\") )
				( objectStatus "MG_KTI_BUNDLE_NG_KTI_CPU1_CPU0_P1P1_4-5" )
			)
			( matchGroup "@baseboard_fab2_lib.baseboard_fab2(sch_1):\MG_KTI_BUNDLE_NG_KTI_CPU1_CPU0_P1P1_6-7\"
				( memberType ( signal ) )
				( member ( pinPairRef "@baseboard_fab2_lib.baseboard_fab2(sch_1):\PP3131\") )
				( member ( pinPairRef "@baseboard_fab2_lib.baseboard_fab2(sch_1):\PP3132\") )
				( member ( pinPairRef "@baseboard_fab2_lib.baseboard_fab2(sch_1):\PP3133\") )
				( member ( pinPairRef "@baseboard_fab2_lib.baseboard_fab2(sch_1):\PP3134\") )
				( objectStatus "MG_KTI_BUNDLE_NG_KTI_CPU1_CPU0_P1P1_6-7" )
			)
			( matchGroup "@baseboard_fab2_lib.baseboard_fab2(sch_1):\MG_KTI_BUNDLE_NG_KTI_CPU1_CPU0_P1P1_8-9\"
				( memberType ( signal ) )
				( member ( pinPairRef "@baseboard_fab2_lib.baseboard_fab2(sch_1):\PP3127\") )
				( member ( pinPairRef "@baseboard_fab2_lib.baseboard_fab2(sch_1):\PP3128\") )
				( member ( pinPairRef "@baseboard_fab2_lib.baseboard_fab2(sch_1):\PP3129\") )
				( member ( pinPairRef "@baseboard_fab2_lib.baseboard_fab2(sch_1):\PP3130\") )
				( objectStatus "MG_KTI_BUNDLE_NG_KTI_CPU1_CPU0_P1P1_8-9" )
			)
			( matchGroup "@baseboard_fab2_lib.baseboard_fab2(sch_1):\MG_KTI_BUNDLE_NG_KTI_CPU1_CPU0_P1P1_10-11\"
				( memberType ( signal ) )
				( member ( pinPairRef "@baseboard_fab2_lib.baseboard_fab2(sch_1):\PP3123\") )
				( member ( pinPairRef "@baseboard_fab2_lib.baseboard_fab2(sch_1):\PP3124\") )
				( member ( pinPairRef "@baseboard_fab2_lib.baseboard_fab2(sch_1):\PP3125\") )
				( member ( pinPairRef "@baseboard_fab2_lib.baseboard_fab2(sch_1):\PP3126\") )
				( objectStatus "MG_KTI_BUNDLE_NG_KTI_CPU1_CPU0_P1P1_10-11" )
			)
			( matchGroup "@baseboard_fab2_lib.baseboard_fab2(sch_1):\MG_KTI_BUNDLE_NG_KTI_CPU1_CPU0_P1P1_12-13\"
				( memberType ( signal ) )
				( member ( pinPairRef "@baseboard_fab2_lib.baseboard_fab2(sch_1):\PP3119\") )
				( member ( pinPairRef "@baseboard_fab2_lib.baseboard_fab2(sch_1):\PP3120\") )
				( member ( pinPairRef "@baseboard_fab2_lib.baseboard_fab2(sch_1):\PP3121\") )
				( member ( pinPairRef "@baseboard_fab2_lib.baseboard_fab2(sch_1):\PP3122\") )
				( objectStatus "MG_KTI_BUNDLE_NG_KTI_CPU1_CPU0_P1P1_12-13" )
			)
			( matchGroup "@baseboard_fab2_lib.baseboard_fab2(sch_1):\MG_KTI_BUNDLE_NG_KTI_CPU1_CPU0_P1P1_14-15\"
				( memberType ( signal ) )
				( member ( pinPairRef "@baseboard_fab2_lib.baseboard_fab2(sch_1):\PP3115\") )
				( member ( pinPairRef "@baseboard_fab2_lib.baseboard_fab2(sch_1):\PP3116\") )
				( member ( pinPairRef "@baseboard_fab2_lib.baseboard_fab2(sch_1):\PP3117\") )
				( member ( pinPairRef "@baseboard_fab2_lib.baseboard_fab2(sch_1):\PP3118\") )
				( objectStatus "MG_KTI_BUNDLE_NG_KTI_CPU1_CPU0_P1P1_14-15" )
			)
			( matchGroup "@baseboard_fab2_lib.baseboard_fab2(sch_1):\MG_KTI_BUNDLE_NG_KTI_CPU1_CPU0_P1P1_16-17\"
				( memberType ( signal ) )
				( member ( pinPairRef "@baseboard_fab2_lib.baseboard_fab2(sch_1):\PP3111\") )
				( member ( pinPairRef "@baseboard_fab2_lib.baseboard_fab2(sch_1):\PP3112\") )
				( member ( pinPairRef "@baseboard_fab2_lib.baseboard_fab2(sch_1):\PP3113\") )
				( member ( pinPairRef "@baseboard_fab2_lib.baseboard_fab2(sch_1):\PP3114\") )
				( objectStatus "MG_KTI_BUNDLE_NG_KTI_CPU1_CPU0_P1P1_16-17" )
			)
			( matchGroup "@baseboard_fab2_lib.baseboard_fab2(sch_1):\MG_KTI_BUNDLE_NG_KTI_CPU1_CPU0_P1P1_18-19\"
				( memberType ( signal ) )
				( member ( pinPairRef "@baseboard_fab2_lib.baseboard_fab2(sch_1):\PP3107\") )
				( member ( pinPairRef "@baseboard_fab2_lib.baseboard_fab2(sch_1):\PP3108\") )
				( member ( pinPairRef "@baseboard_fab2_lib.baseboard_fab2(sch_1):\PP3109\") )
				( member ( pinPairRef "@baseboard_fab2_lib.baseboard_fab2(sch_1):\PP3110\") )
				( objectStatus "MG_KTI_BUNDLE_NG_KTI_CPU1_CPU0_P1P1_18-19" )
			)
			( matchGroup "@crescent_city_bb_fab1_lib.crescent_city_bb_fab1(sch_1):\MG_KTI_CPU1_CPU0_P0P0\"
				( memberType ( signal ) )
				( member ( pinPairRef "@baseboard_fab2_lib.baseboard_fab2(sch_1):\PP3183\") )
				( member ( pinPairRef "@baseboard_fab2_lib.baseboard_fab2(sch_1):\PP3184\") )
				( member ( pinPairRef "@baseboard_fab2_lib.baseboard_fab2(sch_1):\PP3185\") )
				( member ( pinPairRef "@baseboard_fab2_lib.baseboard_fab2(sch_1):\PP3186\") )
				( member ( pinPairRef "@baseboard_fab2_lib.baseboard_fab2(sch_1):\PP3179\") )
				( member ( pinPairRef "@baseboard_fab2_lib.baseboard_fab2(sch_1):\PP3180\") )
				( member ( pinPairRef "@baseboard_fab2_lib.baseboard_fab2(sch_1):\PP3181\") )
				( member ( pinPairRef "@baseboard_fab2_lib.baseboard_fab2(sch_1):\PP3182\") )
				( member ( pinPairRef "@baseboard_fab2_lib.baseboard_fab2(sch_1):\PP3175\") )
				( member ( pinPairRef "@baseboard_fab2_lib.baseboard_fab2(sch_1):\PP3176\") )
				( member ( pinPairRef "@baseboard_fab2_lib.baseboard_fab2(sch_1):\PP3177\") )
				( member ( pinPairRef "@baseboard_fab2_lib.baseboard_fab2(sch_1):\PP3178\") )
				( member ( pinPairRef "@baseboard_fab2_lib.baseboard_fab2(sch_1):\PP3171\") )
				( member ( pinPairRef "@baseboard_fab2_lib.baseboard_fab2(sch_1):\PP3172\") )
				( member ( pinPairRef "@baseboard_fab2_lib.baseboard_fab2(sch_1):\PP3173\") )
				( member ( pinPairRef "@baseboard_fab2_lib.baseboard_fab2(sch_1):\PP3174\") )
				( member ( pinPairRef "@baseboard_fab2_lib.baseboard_fab2(sch_1):\PP3167\") )
				( member ( pinPairRef "@baseboard_fab2_lib.baseboard_fab2(sch_1):\PP3168\") )
				( member ( pinPairRef "@baseboard_fab2_lib.baseboard_fab2(sch_1):\PP3169\") )
				( member ( pinPairRef "@baseboard_fab2_lib.baseboard_fab2(sch_1):\PP3170\") )
				( member ( pinPairRef "@baseboard_fab2_lib.baseboard_fab2(sch_1):\PP3163\") )
				( member ( pinPairRef "@baseboard_fab2_lib.baseboard_fab2(sch_1):\PP3164\") )
				( member ( pinPairRef "@baseboard_fab2_lib.baseboard_fab2(sch_1):\PP3165\") )
				( member ( pinPairRef "@baseboard_fab2_lib.baseboard_fab2(sch_1):\PP3166\") )
				( member ( pinPairRef "@baseboard_fab2_lib.baseboard_fab2(sch_1):\PP3159\") )
				( member ( pinPairRef "@baseboard_fab2_lib.baseboard_fab2(sch_1):\PP3160\") )
				( member ( pinPairRef "@baseboard_fab2_lib.baseboard_fab2(sch_1):\PP3161\") )
				( member ( pinPairRef "@baseboard_fab2_lib.baseboard_fab2(sch_1):\PP3162\") )
				( member ( pinPairRef "@baseboard_fab2_lib.baseboard_fab2(sch_1):\PP3155\") )
				( member ( pinPairRef "@baseboard_fab2_lib.baseboard_fab2(sch_1):\PP3156\") )
				( member ( pinPairRef "@baseboard_fab2_lib.baseboard_fab2(sch_1):\PP3157\") )
				( member ( pinPairRef "@baseboard_fab2_lib.baseboard_fab2(sch_1):\PP3158\") )
				( member ( pinPairRef "@baseboard_fab2_lib.baseboard_fab2(sch_1):\PP3151\") )
				( member ( pinPairRef "@baseboard_fab2_lib.baseboard_fab2(sch_1):\PP3152\") )
				( member ( pinPairRef "@baseboard_fab2_lib.baseboard_fab2(sch_1):\PP3153\") )
				( member ( pinPairRef "@baseboard_fab2_lib.baseboard_fab2(sch_1):\PP3154\") )
				( member ( pinPairRef "@baseboard_fab2_lib.baseboard_fab2(sch_1):\PP3147\") )
				( member ( pinPairRef "@baseboard_fab2_lib.baseboard_fab2(sch_1):\PP3148\") )
				( member ( pinPairRef "@baseboard_fab2_lib.baseboard_fab2(sch_1):\PP3149\") )
				( member ( pinPairRef "@baseboard_fab2_lib.baseboard_fab2(sch_1):\PP3150\") )
				( objectStatus "MG_KTI_CPU1_CPU0_P0P0" )
			)
			( matchGroup "@baseboard_fab2_lib.baseboard_fab2(sch_1):\MG_KTI_BUNDLE_NG_KTI_CPU1_CPU0_P0P0_0-1\"
				( memberType ( signal ) )
				( member ( pinPairRef "@baseboard_fab2_lib.baseboard_fab2(sch_1):\PP3183\") )
				( member ( pinPairRef "@baseboard_fab2_lib.baseboard_fab2(sch_1):\PP3184\") )
				( member ( pinPairRef "@baseboard_fab2_lib.baseboard_fab2(sch_1):\PP3185\") )
				( member ( pinPairRef "@baseboard_fab2_lib.baseboard_fab2(sch_1):\PP3186\") )
				( objectStatus "MG_KTI_BUNDLE_NG_KTI_CPU1_CPU0_P0P0_0-1" )
			)
			( matchGroup "@baseboard_fab2_lib.baseboard_fab2(sch_1):\MG_KTI_BUNDLE_NG_KTI_CPU1_CPU0_P0P0_2-3\"
				( memberType ( signal ) )
				( member ( pinPairRef "@baseboard_fab2_lib.baseboard_fab2(sch_1):\PP3179\") )
				( member ( pinPairRef "@baseboard_fab2_lib.baseboard_fab2(sch_1):\PP3180\") )
				( member ( pinPairRef "@baseboard_fab2_lib.baseboard_fab2(sch_1):\PP3181\") )
				( member ( pinPairRef "@baseboard_fab2_lib.baseboard_fab2(sch_1):\PP3182\") )
				( objectStatus "MG_KTI_BUNDLE_NG_KTI_CPU1_CPU0_P0P0_2-3" )
			)
			( matchGroup "@baseboard_fab2_lib.baseboard_fab2(sch_1):\MG_KTI_BUNDLE_NG_KTI_CPU1_CPU0_P0P0_4-5\"
				( memberType ( signal ) )
				( member ( pinPairRef "@baseboard_fab2_lib.baseboard_fab2(sch_1):\PP3175\") )
				( member ( pinPairRef "@baseboard_fab2_lib.baseboard_fab2(sch_1):\PP3176\") )
				( member ( pinPairRef "@baseboard_fab2_lib.baseboard_fab2(sch_1):\PP3177\") )
				( member ( pinPairRef "@baseboard_fab2_lib.baseboard_fab2(sch_1):\PP3178\") )
				( objectStatus "MG_KTI_BUNDLE_NG_KTI_CPU1_CPU0_P0P0_4-5" )
			)
			( matchGroup "@baseboard_fab2_lib.baseboard_fab2(sch_1):\MG_KTI_BUNDLE_NG_KTI_CPU1_CPU0_P0P0_6-7\"
				( memberType ( signal ) )
				( member ( pinPairRef "@baseboard_fab2_lib.baseboard_fab2(sch_1):\PP3171\") )
				( member ( pinPairRef "@baseboard_fab2_lib.baseboard_fab2(sch_1):\PP3172\") )
				( member ( pinPairRef "@baseboard_fab2_lib.baseboard_fab2(sch_1):\PP3173\") )
				( member ( pinPairRef "@baseboard_fab2_lib.baseboard_fab2(sch_1):\PP3174\") )
				( objectStatus "MG_KTI_BUNDLE_NG_KTI_CPU1_CPU0_P0P0_6-7" )
			)
			( matchGroup "@baseboard_fab2_lib.baseboard_fab2(sch_1):\MG_KTI_BUNDLE_NG_KTI_CPU1_CPU0_P0P0_8-9\"
				( memberType ( signal ) )
				( member ( pinPairRef "@baseboard_fab2_lib.baseboard_fab2(sch_1):\PP3167\") )
				( member ( pinPairRef "@baseboard_fab2_lib.baseboard_fab2(sch_1):\PP3168\") )
				( member ( pinPairRef "@baseboard_fab2_lib.baseboard_fab2(sch_1):\PP3169\") )
				( member ( pinPairRef "@baseboard_fab2_lib.baseboard_fab2(sch_1):\PP3170\") )
				( objectStatus "MG_KTI_BUNDLE_NG_KTI_CPU1_CPU0_P0P0_8-9" )
			)
			( matchGroup "@baseboard_fab2_lib.baseboard_fab2(sch_1):\MG_KTI_BUNDLE_NG_KTI_CPU1_CPU0_P0P0_10-11\"
				( memberType ( signal ) )
				( member ( pinPairRef "@baseboard_fab2_lib.baseboard_fab2(sch_1):\PP3163\") )
				( member ( pinPairRef "@baseboard_fab2_lib.baseboard_fab2(sch_1):\PP3164\") )
				( member ( pinPairRef "@baseboard_fab2_lib.baseboard_fab2(sch_1):\PP3165\") )
				( member ( pinPairRef "@baseboard_fab2_lib.baseboard_fab2(sch_1):\PP3166\") )
				( objectStatus "MG_KTI_BUNDLE_NG_KTI_CPU1_CPU0_P0P0_10-11" )
			)
			( matchGroup "@baseboard_fab2_lib.baseboard_fab2(sch_1):\MG_KTI_BUNDLE_NG_KTI_CPU1_CPU0_P0P0_12-13\"
				( memberType ( signal ) )
				( member ( pinPairRef "@baseboard_fab2_lib.baseboard_fab2(sch_1):\PP3159\") )
				( member ( pinPairRef "@baseboard_fab2_lib.baseboard_fab2(sch_1):\PP3160\") )
				( member ( pinPairRef "@baseboard_fab2_lib.baseboard_fab2(sch_1):\PP3161\") )
				( member ( pinPairRef "@baseboard_fab2_lib.baseboard_fab2(sch_1):\PP3162\") )
				( objectStatus "MG_KTI_BUNDLE_NG_KTI_CPU1_CPU0_P0P0_12-13" )
			)
			( matchGroup "@baseboard_fab2_lib.baseboard_fab2(sch_1):\MG_KTI_BUNDLE_NG_KTI_CPU1_CPU0_P0P0_14-15\"
				( memberType ( signal ) )
				( member ( pinPairRef "@baseboard_fab2_lib.baseboard_fab2(sch_1):\PP3155\") )
				( member ( pinPairRef "@baseboard_fab2_lib.baseboard_fab2(sch_1):\PP3156\") )
				( member ( pinPairRef "@baseboard_fab2_lib.baseboard_fab2(sch_1):\PP3157\") )
				( member ( pinPairRef "@baseboard_fab2_lib.baseboard_fab2(sch_1):\PP3158\") )
				( objectStatus "MG_KTI_BUNDLE_NG_KTI_CPU1_CPU0_P0P0_14-15" )
			)
			( matchGroup "@baseboard_fab2_lib.baseboard_fab2(sch_1):\MG_KTI_BUNDLE_NG_KTI_CPU1_CPU0_P0P0_16-17\"
				( memberType ( signal ) )
				( member ( pinPairRef "@baseboard_fab2_lib.baseboard_fab2(sch_1):\PP3151\") )
				( member ( pinPairRef "@baseboard_fab2_lib.baseboard_fab2(sch_1):\PP3152\") )
				( member ( pinPairRef "@baseboard_fab2_lib.baseboard_fab2(sch_1):\PP3153\") )
				( member ( pinPairRef "@baseboard_fab2_lib.baseboard_fab2(sch_1):\PP3154\") )
				( objectStatus "MG_KTI_BUNDLE_NG_KTI_CPU1_CPU0_P0P0_16-17" )
			)
			( matchGroup "@baseboard_fab2_lib.baseboard_fab2(sch_1):\MG_KTI_BUNDLE_NG_KTI_CPU1_CPU0_P0P0_18-19\"
				( memberType ( signal ) )
				( member ( pinPairRef "@baseboard_fab2_lib.baseboard_fab2(sch_1):\PP3147\") )
				( member ( pinPairRef "@baseboard_fab2_lib.baseboard_fab2(sch_1):\PP3148\") )
				( member ( pinPairRef "@baseboard_fab2_lib.baseboard_fab2(sch_1):\PP3149\") )
				( member ( pinPairRef "@baseboard_fab2_lib.baseboard_fab2(sch_1):\PP3150\") )
				( objectStatus "MG_KTI_BUNDLE_NG_KTI_CPU1_CPU0_P0P0_18-19" )
			)
			( matchGroup "@crescent_city_bb_fab1_lib.crescent_city_bb_fab1(sch_1):\MG_KTI_CPU0_CPU1_P1P1\"
				( memberType ( signal ) )
				( member ( pinPairRef "@baseboard_fab2_lib.baseboard_fab2(sch_1):\PP3223\") )
				( member ( pinPairRef "@baseboard_fab2_lib.baseboard_fab2(sch_1):\PP3224\") )
				( member ( pinPairRef "@baseboard_fab2_lib.baseboard_fab2(sch_1):\PP3225\") )
				( member ( pinPairRef "@baseboard_fab2_lib.baseboard_fab2(sch_1):\PP3226\") )
				( member ( pinPairRef "@baseboard_fab2_lib.baseboard_fab2(sch_1):\PP3219\") )
				( member ( pinPairRef "@baseboard_fab2_lib.baseboard_fab2(sch_1):\PP3220\") )
				( member ( pinPairRef "@baseboard_fab2_lib.baseboard_fab2(sch_1):\PP3221\") )
				( member ( pinPairRef "@baseboard_fab2_lib.baseboard_fab2(sch_1):\PP3222\") )
				( member ( pinPairRef "@baseboard_fab2_lib.baseboard_fab2(sch_1):\PP3215\") )
				( member ( pinPairRef "@baseboard_fab2_lib.baseboard_fab2(sch_1):\PP3216\") )
				( member ( pinPairRef "@baseboard_fab2_lib.baseboard_fab2(sch_1):\PP3217\") )
				( member ( pinPairRef "@baseboard_fab2_lib.baseboard_fab2(sch_1):\PP3218\") )
				( member ( pinPairRef "@baseboard_fab2_lib.baseboard_fab2(sch_1):\PP3211\") )
				( member ( pinPairRef "@baseboard_fab2_lib.baseboard_fab2(sch_1):\PP3212\") )
				( member ( pinPairRef "@baseboard_fab2_lib.baseboard_fab2(sch_1):\PP3213\") )
				( member ( pinPairRef "@baseboard_fab2_lib.baseboard_fab2(sch_1):\PP3214\") )
				( member ( pinPairRef "@baseboard_fab2_lib.baseboard_fab2(sch_1):\PP3207\") )
				( member ( pinPairRef "@baseboard_fab2_lib.baseboard_fab2(sch_1):\PP3208\") )
				( member ( pinPairRef "@baseboard_fab2_lib.baseboard_fab2(sch_1):\PP3209\") )
				( member ( pinPairRef "@baseboard_fab2_lib.baseboard_fab2(sch_1):\PP3210\") )
				( member ( pinPairRef "@baseboard_fab2_lib.baseboard_fab2(sch_1):\PP3203\") )
				( member ( pinPairRef "@baseboard_fab2_lib.baseboard_fab2(sch_1):\PP3204\") )
				( member ( pinPairRef "@baseboard_fab2_lib.baseboard_fab2(sch_1):\PP3205\") )
				( member ( pinPairRef "@baseboard_fab2_lib.baseboard_fab2(sch_1):\PP3206\") )
				( member ( pinPairRef "@baseboard_fab2_lib.baseboard_fab2(sch_1):\PP3199\") )
				( member ( pinPairRef "@baseboard_fab2_lib.baseboard_fab2(sch_1):\PP3200\") )
				( member ( pinPairRef "@baseboard_fab2_lib.baseboard_fab2(sch_1):\PP3201\") )
				( member ( pinPairRef "@baseboard_fab2_lib.baseboard_fab2(sch_1):\PP3202\") )
				( member ( pinPairRef "@baseboard_fab2_lib.baseboard_fab2(sch_1):\PP3195\") )
				( member ( pinPairRef "@baseboard_fab2_lib.baseboard_fab2(sch_1):\PP3196\") )
				( member ( pinPairRef "@baseboard_fab2_lib.baseboard_fab2(sch_1):\PP3197\") )
				( member ( pinPairRef "@baseboard_fab2_lib.baseboard_fab2(sch_1):\PP3198\") )
				( member ( pinPairRef "@baseboard_fab2_lib.baseboard_fab2(sch_1):\PP3191\") )
				( member ( pinPairRef "@baseboard_fab2_lib.baseboard_fab2(sch_1):\PP3192\") )
				( member ( pinPairRef "@baseboard_fab2_lib.baseboard_fab2(sch_1):\PP3193\") )
				( member ( pinPairRef "@baseboard_fab2_lib.baseboard_fab2(sch_1):\PP3194\") )
				( member ( pinPairRef "@baseboard_fab2_lib.baseboard_fab2(sch_1):\PP3187\") )
				( member ( pinPairRef "@baseboard_fab2_lib.baseboard_fab2(sch_1):\PP3188\") )
				( member ( pinPairRef "@baseboard_fab2_lib.baseboard_fab2(sch_1):\PP3189\") )
				( member ( pinPairRef "@baseboard_fab2_lib.baseboard_fab2(sch_1):\PP3190\") )
				( objectStatus "MG_KTI_CPU0_CPU1_P1P1" )
			)
			( matchGroup "@baseboard_fab2_lib.baseboard_fab2(sch_1):\MG_KTI_BUNDLE_NG_KTI_CPU0_CPU1_P1P1_0-1\"
				( memberType ( signal ) )
				( member ( pinPairRef "@baseboard_fab2_lib.baseboard_fab2(sch_1):\PP3223\") )
				( member ( pinPairRef "@baseboard_fab2_lib.baseboard_fab2(sch_1):\PP3224\") )
				( member ( pinPairRef "@baseboard_fab2_lib.baseboard_fab2(sch_1):\PP3225\") )
				( member ( pinPairRef "@baseboard_fab2_lib.baseboard_fab2(sch_1):\PP3226\") )
				( objectStatus "MG_KTI_BUNDLE_NG_KTI_CPU0_CPU1_P1P1_0-1" )
			)
			( matchGroup "@baseboard_fab2_lib.baseboard_fab2(sch_1):\MG_KTI_BUNDLE_NG_KTI_CPU0_CPU1_P1P1_2-3\"
				( memberType ( signal ) )
				( member ( pinPairRef "@baseboard_fab2_lib.baseboard_fab2(sch_1):\PP3219\") )
				( member ( pinPairRef "@baseboard_fab2_lib.baseboard_fab2(sch_1):\PP3220\") )
				( member ( pinPairRef "@baseboard_fab2_lib.baseboard_fab2(sch_1):\PP3221\") )
				( member ( pinPairRef "@baseboard_fab2_lib.baseboard_fab2(sch_1):\PP3222\") )
				( objectStatus "MG_KTI_BUNDLE_NG_KTI_CPU0_CPU1_P1P1_2-3" )
			)
			( matchGroup "@baseboard_fab2_lib.baseboard_fab2(sch_1):\MG_KTI_BUNDLE_NG_KTI_CPU0_CPU1_P1P1_4-5\"
				( memberType ( signal ) )
				( member ( pinPairRef "@baseboard_fab2_lib.baseboard_fab2(sch_1):\PP3215\") )
				( member ( pinPairRef "@baseboard_fab2_lib.baseboard_fab2(sch_1):\PP3216\") )
				( member ( pinPairRef "@baseboard_fab2_lib.baseboard_fab2(sch_1):\PP3217\") )
				( member ( pinPairRef "@baseboard_fab2_lib.baseboard_fab2(sch_1):\PP3218\") )
				( objectStatus "MG_KTI_BUNDLE_NG_KTI_CPU0_CPU1_P1P1_4-5" )
			)
			( matchGroup "@baseboard_fab2_lib.baseboard_fab2(sch_1):\MG_KTI_BUNDLE_NG_KTI_CPU0_CPU1_P1P1_6-7\"
				( memberType ( signal ) )
				( member ( pinPairRef "@baseboard_fab2_lib.baseboard_fab2(sch_1):\PP3211\") )
				( member ( pinPairRef "@baseboard_fab2_lib.baseboard_fab2(sch_1):\PP3212\") )
				( member ( pinPairRef "@baseboard_fab2_lib.baseboard_fab2(sch_1):\PP3213\") )
				( member ( pinPairRef "@baseboard_fab2_lib.baseboard_fab2(sch_1):\PP3214\") )
				( objectStatus "MG_KTI_BUNDLE_NG_KTI_CPU0_CPU1_P1P1_6-7" )
			)
			( matchGroup "@baseboard_fab2_lib.baseboard_fab2(sch_1):\MG_KTI_BUNDLE_NG_KTI_CPU0_CPU1_P1P1_8-9\"
				( memberType ( signal ) )
				( member ( pinPairRef "@baseboard_fab2_lib.baseboard_fab2(sch_1):\PP3207\") )
				( member ( pinPairRef "@baseboard_fab2_lib.baseboard_fab2(sch_1):\PP3208\") )
				( member ( pinPairRef "@baseboard_fab2_lib.baseboard_fab2(sch_1):\PP3209\") )
				( member ( pinPairRef "@baseboard_fab2_lib.baseboard_fab2(sch_1):\PP3210\") )
				( objectStatus "MG_KTI_BUNDLE_NG_KTI_CPU0_CPU1_P1P1_8-9" )
			)
			( matchGroup "@baseboard_fab2_lib.baseboard_fab2(sch_1):\MG_KTI_BUNDLE_NG_KTI_CPU0_CPU1_P1P1_10-11\"
				( memberType ( signal ) )
				( member ( pinPairRef "@baseboard_fab2_lib.baseboard_fab2(sch_1):\PP3203\") )
				( member ( pinPairRef "@baseboard_fab2_lib.baseboard_fab2(sch_1):\PP3204\") )
				( member ( pinPairRef "@baseboard_fab2_lib.baseboard_fab2(sch_1):\PP3205\") )
				( member ( pinPairRef "@baseboard_fab2_lib.baseboard_fab2(sch_1):\PP3206\") )
				( objectStatus "MG_KTI_BUNDLE_NG_KTI_CPU0_CPU1_P1P1_10-11" )
			)
			( matchGroup "@baseboard_fab2_lib.baseboard_fab2(sch_1):\MG_KTI_BUNDLE_NG_KTI_CPU0_CPU1_P1P1_12-13\"
				( memberType ( signal ) )
				( member ( pinPairRef "@baseboard_fab2_lib.baseboard_fab2(sch_1):\PP3199\") )
				( member ( pinPairRef "@baseboard_fab2_lib.baseboard_fab2(sch_1):\PP3200\") )
				( member ( pinPairRef "@baseboard_fab2_lib.baseboard_fab2(sch_1):\PP3201\") )
				( member ( pinPairRef "@baseboard_fab2_lib.baseboard_fab2(sch_1):\PP3202\") )
				( objectStatus "MG_KTI_BUNDLE_NG_KTI_CPU0_CPU1_P1P1_12-13" )
			)
			( matchGroup "@baseboard_fab2_lib.baseboard_fab2(sch_1):\MG_KTI_BUNDLE_NG_KTI_CPU0_CPU1_P1P1_14-15\"
				( memberType ( signal ) )
				( member ( pinPairRef "@baseboard_fab2_lib.baseboard_fab2(sch_1):\PP3195\") )
				( member ( pinPairRef "@baseboard_fab2_lib.baseboard_fab2(sch_1):\PP3196\") )
				( member ( pinPairRef "@baseboard_fab2_lib.baseboard_fab2(sch_1):\PP3197\") )
				( member ( pinPairRef "@baseboard_fab2_lib.baseboard_fab2(sch_1):\PP3198\") )
				( objectStatus "MG_KTI_BUNDLE_NG_KTI_CPU0_CPU1_P1P1_14-15" )
			)
			( matchGroup "@baseboard_fab2_lib.baseboard_fab2(sch_1):\MG_KTI_BUNDLE_NG_KTI_CPU0_CPU1_P1P1_16-17\"
				( memberType ( signal ) )
				( member ( pinPairRef "@baseboard_fab2_lib.baseboard_fab2(sch_1):\PP3191\") )
				( member ( pinPairRef "@baseboard_fab2_lib.baseboard_fab2(sch_1):\PP3192\") )
				( member ( pinPairRef "@baseboard_fab2_lib.baseboard_fab2(sch_1):\PP3193\") )
				( member ( pinPairRef "@baseboard_fab2_lib.baseboard_fab2(sch_1):\PP3194\") )
				( objectStatus "MG_KTI_BUNDLE_NG_KTI_CPU0_CPU1_P1P1_16-17" )
			)
			( matchGroup "@baseboard_fab2_lib.baseboard_fab2(sch_1):\MG_KTI_BUNDLE_NG_KTI_CPU0_CPU1_P1P1_18-19\"
				( memberType ( signal ) )
				( member ( pinPairRef "@baseboard_fab2_lib.baseboard_fab2(sch_1):\PP3187\") )
				( member ( pinPairRef "@baseboard_fab2_lib.baseboard_fab2(sch_1):\PP3188\") )
				( member ( pinPairRef "@baseboard_fab2_lib.baseboard_fab2(sch_1):\PP3189\") )
				( member ( pinPairRef "@baseboard_fab2_lib.baseboard_fab2(sch_1):\PP3190\") )
				( objectStatus "MG_KTI_BUNDLE_NG_KTI_CPU0_CPU1_P1P1_18-19" )
			)
			( matchGroup "@baseboard_fab2_lib.baseboard_fab2(sch_1):\MG_KTI_CPU0_CPU1_P0P0\"
				( memberType ( signal ) )
				( member ( pinPairRef "@baseboard_fab2_lib.baseboard_fab2(sch_1):\PP3263\") )
				( member ( pinPairRef "@baseboard_fab2_lib.baseboard_fab2(sch_1):\PP3264\") )
				( member ( pinPairRef "@baseboard_fab2_lib.baseboard_fab2(sch_1):\PP3265\") )
				( member ( pinPairRef "@baseboard_fab2_lib.baseboard_fab2(sch_1):\PP3266\") )
				( member ( pinPairRef "@baseboard_fab2_lib.baseboard_fab2(sch_1):\PP3259\") )
				( member ( pinPairRef "@baseboard_fab2_lib.baseboard_fab2(sch_1):\PP3260\") )
				( member ( pinPairRef "@baseboard_fab2_lib.baseboard_fab2(sch_1):\PP3261\") )
				( member ( pinPairRef "@baseboard_fab2_lib.baseboard_fab2(sch_1):\PP3262\") )
				( member ( pinPairRef "@baseboard_fab2_lib.baseboard_fab2(sch_1):\PP3255\") )
				( member ( pinPairRef "@baseboard_fab2_lib.baseboard_fab2(sch_1):\PP3256\") )
				( member ( pinPairRef "@baseboard_fab2_lib.baseboard_fab2(sch_1):\PP3257\") )
				( member ( pinPairRef "@baseboard_fab2_lib.baseboard_fab2(sch_1):\PP3258\") )
				( member ( pinPairRef "@baseboard_fab2_lib.baseboard_fab2(sch_1):\PP3251\") )
				( member ( pinPairRef "@baseboard_fab2_lib.baseboard_fab2(sch_1):\PP3252\") )
				( member ( pinPairRef "@baseboard_fab2_lib.baseboard_fab2(sch_1):\PP3253\") )
				( member ( pinPairRef "@baseboard_fab2_lib.baseboard_fab2(sch_1):\PP3254\") )
				( member ( pinPairRef "@baseboard_fab2_lib.baseboard_fab2(sch_1):\PP3247\") )
				( member ( pinPairRef "@baseboard_fab2_lib.baseboard_fab2(sch_1):\PP3248\") )
				( member ( pinPairRef "@baseboard_fab2_lib.baseboard_fab2(sch_1):\PP3249\") )
				( member ( pinPairRef "@baseboard_fab2_lib.baseboard_fab2(sch_1):\PP3250\") )
				( member ( pinPairRef "@baseboard_fab2_lib.baseboard_fab2(sch_1):\PP3243\") )
				( member ( pinPairRef "@baseboard_fab2_lib.baseboard_fab2(sch_1):\PP3244\") )
				( member ( pinPairRef "@baseboard_fab2_lib.baseboard_fab2(sch_1):\PP3245\") )
				( member ( pinPairRef "@baseboard_fab2_lib.baseboard_fab2(sch_1):\PP3246\") )
				( member ( pinPairRef "@baseboard_fab2_lib.baseboard_fab2(sch_1):\PP3239\") )
				( member ( pinPairRef "@baseboard_fab2_lib.baseboard_fab2(sch_1):\PP3240\") )
				( member ( pinPairRef "@baseboard_fab2_lib.baseboard_fab2(sch_1):\PP3241\") )
				( member ( pinPairRef "@baseboard_fab2_lib.baseboard_fab2(sch_1):\PP3242\") )
				( member ( pinPairRef "@baseboard_fab2_lib.baseboard_fab2(sch_1):\PP3235\") )
				( member ( pinPairRef "@baseboard_fab2_lib.baseboard_fab2(sch_1):\PP3236\") )
				( member ( pinPairRef "@baseboard_fab2_lib.baseboard_fab2(sch_1):\PP3237\") )
				( member ( pinPairRef "@baseboard_fab2_lib.baseboard_fab2(sch_1):\PP3238\") )
				( member ( pinPairRef "@baseboard_fab2_lib.baseboard_fab2(sch_1):\PP3231\") )
				( member ( pinPairRef "@baseboard_fab2_lib.baseboard_fab2(sch_1):\PP3232\") )
				( member ( pinPairRef "@baseboard_fab2_lib.baseboard_fab2(sch_1):\PP3233\") )
				( member ( pinPairRef "@baseboard_fab2_lib.baseboard_fab2(sch_1):\PP3234\") )
				( member ( pinPairRef "@baseboard_fab2_lib.baseboard_fab2(sch_1):\PP3227\") )
				( member ( pinPairRef "@baseboard_fab2_lib.baseboard_fab2(sch_1):\PP3228\") )
				( member ( pinPairRef "@baseboard_fab2_lib.baseboard_fab2(sch_1):\PP3229\") )
				( member ( pinPairRef "@baseboard_fab2_lib.baseboard_fab2(sch_1):\PP3230\") )
				( objectStatus "MG_KTI_CPU0_CPU1_P0P0" )
			)
			( matchGroup "@baseboard_fab2_lib.baseboard_fab2(sch_1):\MG_KTI_BUNDLE_NG_KTI_CPU0_CPU1_P0P0_0-1\"
				( memberType ( signal ) )
				( member ( pinPairRef "@baseboard_fab2_lib.baseboard_fab2(sch_1):\PP3263\") )
				( member ( pinPairRef "@baseboard_fab2_lib.baseboard_fab2(sch_1):\PP3264\") )
				( member ( pinPairRef "@baseboard_fab2_lib.baseboard_fab2(sch_1):\PP3265\") )
				( member ( pinPairRef "@baseboard_fab2_lib.baseboard_fab2(sch_1):\PP3266\") )
				( objectStatus "MG_KTI_BUNDLE_NG_KTI_CPU0_CPU1_P0P0_0-1" )
			)
			( matchGroup "@baseboard_fab2_lib.baseboard_fab2(sch_1):\MG_KTI_BUNDLE_NG_KTI_CPU0_CPU1_P0P0_2-3\"
				( memberType ( signal ) )
				( member ( pinPairRef "@baseboard_fab2_lib.baseboard_fab2(sch_1):\PP3259\") )
				( member ( pinPairRef "@baseboard_fab2_lib.baseboard_fab2(sch_1):\PP3260\") )
				( member ( pinPairRef "@baseboard_fab2_lib.baseboard_fab2(sch_1):\PP3261\") )
				( member ( pinPairRef "@baseboard_fab2_lib.baseboard_fab2(sch_1):\PP3262\") )
				( objectStatus "MG_KTI_BUNDLE_NG_KTI_CPU0_CPU1_P0P0_2-3" )
			)
			( matchGroup "@baseboard_fab2_lib.baseboard_fab2(sch_1):\MG_KTI_BUNDLE_NG_KTI_CPU0_CPU1_P0P0_4-5\"
				( memberType ( signal ) )
				( member ( pinPairRef "@baseboard_fab2_lib.baseboard_fab2(sch_1):\PP3255\") )
				( member ( pinPairRef "@baseboard_fab2_lib.baseboard_fab2(sch_1):\PP3256\") )
				( member ( pinPairRef "@baseboard_fab2_lib.baseboard_fab2(sch_1):\PP3257\") )
				( member ( pinPairRef "@baseboard_fab2_lib.baseboard_fab2(sch_1):\PP3258\") )
				( objectStatus "MG_KTI_BUNDLE_NG_KTI_CPU0_CPU1_P0P0_4-5" )
			)
			( matchGroup "@baseboard_fab2_lib.baseboard_fab2(sch_1):\MG_KTI_BUNDLE_NG_KTI_CPU0_CPU1_P0P0_6-7\"
				( memberType ( signal ) )
				( member ( pinPairRef "@baseboard_fab2_lib.baseboard_fab2(sch_1):\PP3251\") )
				( member ( pinPairRef "@baseboard_fab2_lib.baseboard_fab2(sch_1):\PP3252\") )
				( member ( pinPairRef "@baseboard_fab2_lib.baseboard_fab2(sch_1):\PP3253\") )
				( member ( pinPairRef "@baseboard_fab2_lib.baseboard_fab2(sch_1):\PP3254\") )
				( objectStatus "MG_KTI_BUNDLE_NG_KTI_CPU0_CPU1_P0P0_6-7" )
			)
			( matchGroup "@baseboard_fab2_lib.baseboard_fab2(sch_1):\MG_KTI_BUNDLE_NG_KTI_CPU0_CPU1_P0P0_8-9\"
				( memberType ( signal ) )
				( member ( pinPairRef "@baseboard_fab2_lib.baseboard_fab2(sch_1):\PP3247\") )
				( member ( pinPairRef "@baseboard_fab2_lib.baseboard_fab2(sch_1):\PP3248\") )
				( member ( pinPairRef "@baseboard_fab2_lib.baseboard_fab2(sch_1):\PP3249\") )
				( member ( pinPairRef "@baseboard_fab2_lib.baseboard_fab2(sch_1):\PP3250\") )
				( objectStatus "MG_KTI_BUNDLE_NG_KTI_CPU0_CPU1_P0P0_8-9" )
			)
			( matchGroup "@baseboard_fab2_lib.baseboard_fab2(sch_1):\MG_KTI_BUNDLE_NG_KTI_CPU0_CPU1_P0P0_10-11\"
				( memberType ( signal ) )
				( member ( pinPairRef "@baseboard_fab2_lib.baseboard_fab2(sch_1):\PP3243\") )
				( member ( pinPairRef "@baseboard_fab2_lib.baseboard_fab2(sch_1):\PP3244\") )
				( member ( pinPairRef "@baseboard_fab2_lib.baseboard_fab2(sch_1):\PP3245\") )
				( member ( pinPairRef "@baseboard_fab2_lib.baseboard_fab2(sch_1):\PP3246\") )
				( objectStatus "MG_KTI_BUNDLE_NG_KTI_CPU0_CPU1_P0P0_10-11" )
			)
			( matchGroup "@baseboard_fab2_lib.baseboard_fab2(sch_1):\MG_KTI_BUNDLE_NG_KTI_CPU0_CPU1_P0P0_12-13\"
				( memberType ( signal ) )
				( member ( pinPairRef "@baseboard_fab2_lib.baseboard_fab2(sch_1):\PP3239\") )
				( member ( pinPairRef "@baseboard_fab2_lib.baseboard_fab2(sch_1):\PP3240\") )
				( member ( pinPairRef "@baseboard_fab2_lib.baseboard_fab2(sch_1):\PP3241\") )
				( member ( pinPairRef "@baseboard_fab2_lib.baseboard_fab2(sch_1):\PP3242\") )
				( objectStatus "MG_KTI_BUNDLE_NG_KTI_CPU0_CPU1_P0P0_12-13" )
			)
			( matchGroup "@baseboard_fab2_lib.baseboard_fab2(sch_1):\MG_KTI_BUNDLE_NG_KTI_CPU0_CPU1_P0P0_14-15\"
				( memberType ( signal ) )
				( member ( pinPairRef "@baseboard_fab2_lib.baseboard_fab2(sch_1):\PP3235\") )
				( member ( pinPairRef "@baseboard_fab2_lib.baseboard_fab2(sch_1):\PP3236\") )
				( member ( pinPairRef "@baseboard_fab2_lib.baseboard_fab2(sch_1):\PP3237\") )
				( member ( pinPairRef "@baseboard_fab2_lib.baseboard_fab2(sch_1):\PP3238\") )
				( objectStatus "MG_KTI_BUNDLE_NG_KTI_CPU0_CPU1_P0P0_14-15" )
			)
			( matchGroup "@baseboard_fab2_lib.baseboard_fab2(sch_1):\MG_KTI_BUNDLE_NG_KTI_CPU0_CPU1_P0P0_16-17\"
				( memberType ( signal ) )
				( member ( pinPairRef "@baseboard_fab2_lib.baseboard_fab2(sch_1):\PP3231\") )
				( member ( pinPairRef "@baseboard_fab2_lib.baseboard_fab2(sch_1):\PP3232\") )
				( member ( pinPairRef "@baseboard_fab2_lib.baseboard_fab2(sch_1):\PP3233\") )
				( member ( pinPairRef "@baseboard_fab2_lib.baseboard_fab2(sch_1):\PP3234\") )
				( objectStatus "MG_KTI_BUNDLE_NG_KTI_CPU0_CPU1_P0P0_16-17" )
			)
			( matchGroup "@baseboard_fab2_lib.baseboard_fab2(sch_1):\MG_KTI_BUNDLE_NG_KTI_CPU0_CPU1_P0P0_18-19\"
				( memberType ( signal ) )
				( member ( pinPairRef "@baseboard_fab2_lib.baseboard_fab2(sch_1):\PP3227\") )
				( member ( pinPairRef "@baseboard_fab2_lib.baseboard_fab2(sch_1):\PP3228\") )
				( member ( pinPairRef "@baseboard_fab2_lib.baseboard_fab2(sch_1):\PP3229\") )
				( member ( pinPairRef "@baseboard_fab2_lib.baseboard_fab2(sch_1):\PP3230\") )
				( objectStatus "MG_KTI_BUNDLE_NG_KTI_CPU0_CPU1_P0P0_18-19" )
			)
			( matchGroup "@baseboard_fab2_lib.baseboard_fab2(sch_1):\MG_DDR_FAR_DIMM_CMD_NG_DDR_M_DLL_1\"
				( memberType ( signal ) )
				( member ( pinPairRef "@baseboard_fab2_lib.baseboard_fab2(sch_1):\PP3329\") )
				( member ( pinPairRef "@baseboard_fab2_lib.baseboard_fab2(sch_1):\PP3331\") )
				( objectStatus "MG_DDR_FAR_DIMM_CMD_NG_DDR_M_DLL_1" )
			)
			( matchGroup "@crescent_city_bb_fab1_lib.crescent_city_bb_fab1(sch_1):\MG_DDR_FAR_DIMM-CLK0_CLS_DDR_M_CAC-CLKS\"
				( memberType ( signal ) )
				( member ( pinPairRef "@baseboard_fab2_lib.baseboard_fab2(sch_1):\PP3329\") )
				( member ( pinPairRef "@baseboard_fab2_lib.baseboard_fab2(sch_1):\PP3331\") )
				( member ( pinPairRef "@baseboard_fab2_lib.baseboard_fab2(sch_1):\PP3325\") )
				( member ( pinPairRef "@baseboard_fab2_lib.baseboard_fab2(sch_1):\PP3327\") )
				( member ( pinPairRef "@baseboard_fab2_lib.baseboard_fab2(sch_1):\PP3321\") )
				( member ( pinPairRef "@baseboard_fab2_lib.baseboard_fab2(sch_1):\PP3323\") )
				( member ( pinPairRef "@baseboard_fab2_lib.baseboard_fab2(sch_1):\PP3317\") )
				( member ( pinPairRef "@baseboard_fab2_lib.baseboard_fab2(sch_1):\PP3319\") )
				( member ( pinPairRef "@baseboard_fab2_lib.baseboard_fab2(sch_1):\PP3313\") )
				( member ( pinPairRef "@baseboard_fab2_lib.baseboard_fab2(sch_1):\PP3315\") )
				( member ( pinPairRef "@baseboard_fab2_lib.baseboard_fab2(sch_1):\PP3311\") )
				( member ( pinPairRef "@baseboard_fab2_lib.baseboard_fab2(sch_1):\PP3307\") )
				( member ( pinPairRef "@baseboard_fab2_lib.baseboard_fab2(sch_1):\PP3309\") )
				( member ( pinPairRef "@baseboard_fab2_lib.baseboard_fab2(sch_1):\PP3303\") )
				( member ( pinPairRef "@baseboard_fab2_lib.baseboard_fab2(sch_1):\PP3305\") )
				( member ( pinPairRef "@baseboard_fab2_lib.baseboard_fab2(sch_1):\PP3299\") )
				( member ( pinPairRef "@baseboard_fab2_lib.baseboard_fab2(sch_1):\PP3301\") )
				( member ( pinPairRef "@baseboard_fab2_lib.baseboard_fab2(sch_1):\PP3295\") )
				( member ( pinPairRef "@baseboard_fab2_lib.baseboard_fab2(sch_1):\PP3297\") )
				( member ( pinPairRef "@baseboard_fab2_lib.baseboard_fab2(sch_1):\PP3291\") )
				( member ( pinPairRef "@baseboard_fab2_lib.baseboard_fab2(sch_1):\PP3293\") )
				( member ( pinPairRef "@baseboard_fab2_lib.baseboard_fab2(sch_1):\PP3287\") )
				( member ( pinPairRef "@baseboard_fab2_lib.baseboard_fab2(sch_1):\PP3289\") )
				( member ( pinPairRef "@baseboard_fab2_lib.baseboard_fab2(sch_1):\PP3283\") )
				( member ( pinPairRef "@baseboard_fab2_lib.baseboard_fab2(sch_1):\PP3285\") )
				( member ( pinPairRef "@baseboard_fab2_lib.baseboard_fab2(sch_1):\PP3281\") )
				( member ( pinPairRef "@baseboard_fab2_lib.baseboard_fab2(sch_1):\PP3282\") )
				( member ( pinPairRef "@baseboard_fab2_lib.baseboard_fab2(sch_1):\PP3280\") )
				( member ( pinPairRef "@baseboard_fab2_lib.baseboard_fab2(sch_1):\PP3279\") )
				( member ( pinPairRef "@baseboard_fab2_lib.baseboard_fab2(sch_1):\PP3278\") )
				( member ( pinPairRef "@baseboard_fab2_lib.baseboard_fab2(sch_1):\PP3276\") )
				( member ( pinPairRef "@baseboard_fab2_lib.baseboard_fab2(sch_1):\PP3277\") )
				( member ( pinPairRef "@baseboard_fab2_lib.baseboard_fab2(sch_1):\PP3275\") )
				( member ( signalRef "@baseboard_fab2_lib.baseboard_fab2(sch_1):m_m_clk_dp(0)") )
				( objectStatus "MG_DDR_FAR_DIMM-CLK0_CLS_DDR_M_CAC-CLKS" )
			)
			( matchGroup "@crescent_city_bb_fab1_lib.crescent_city_bb_fab1(sch_1):\MG_DDR_NEAR_DIMM-CLK1_CLS_DDR_M_CAC-CLKS\"
				( memberType ( signal ) )
				( member ( pinPairRef "@baseboard_fab2_lib.baseboard_fab2(sch_1):\PP3330\") )
				( member ( pinPairRef "@baseboard_fab2_lib.baseboard_fab2(sch_1):\PP3332\") )
				( member ( pinPairRef "@baseboard_fab2_lib.baseboard_fab2(sch_1):\PP3326\") )
				( member ( pinPairRef "@baseboard_fab2_lib.baseboard_fab2(sch_1):\PP3328\") )
				( member ( pinPairRef "@baseboard_fab2_lib.baseboard_fab2(sch_1):\PP3322\") )
				( member ( pinPairRef "@baseboard_fab2_lib.baseboard_fab2(sch_1):\PP3324\") )
				( member ( pinPairRef "@baseboard_fab2_lib.baseboard_fab2(sch_1):\PP3318\") )
				( member ( pinPairRef "@baseboard_fab2_lib.baseboard_fab2(sch_1):\PP3320\") )
				( member ( pinPairRef "@baseboard_fab2_lib.baseboard_fab2(sch_1):\PP3314\") )
				( member ( pinPairRef "@baseboard_fab2_lib.baseboard_fab2(sch_1):\PP3316\") )
				( member ( pinPairRef "@baseboard_fab2_lib.baseboard_fab2(sch_1):\PP3312\") )
				( member ( pinPairRef "@baseboard_fab2_lib.baseboard_fab2(sch_1):\PP3308\") )
				( member ( pinPairRef "@baseboard_fab2_lib.baseboard_fab2(sch_1):\PP3310\") )
				( member ( pinPairRef "@baseboard_fab2_lib.baseboard_fab2(sch_1):\PP3304\") )
				( member ( pinPairRef "@baseboard_fab2_lib.baseboard_fab2(sch_1):\PP3306\") )
				( member ( pinPairRef "@baseboard_fab2_lib.baseboard_fab2(sch_1):\PP3300\") )
				( member ( pinPairRef "@baseboard_fab2_lib.baseboard_fab2(sch_1):\PP3302\") )
				( member ( pinPairRef "@baseboard_fab2_lib.baseboard_fab2(sch_1):\PP3296\") )
				( member ( pinPairRef "@baseboard_fab2_lib.baseboard_fab2(sch_1):\PP3298\") )
				( member ( pinPairRef "@baseboard_fab2_lib.baseboard_fab2(sch_1):\PP3292\") )
				( member ( pinPairRef "@baseboard_fab2_lib.baseboard_fab2(sch_1):\PP3294\") )
				( member ( pinPairRef "@baseboard_fab2_lib.baseboard_fab2(sch_1):\PP3288\") )
				( member ( pinPairRef "@baseboard_fab2_lib.baseboard_fab2(sch_1):\PP3290\") )
				( member ( pinPairRef "@baseboard_fab2_lib.baseboard_fab2(sch_1):\PP3284\") )
				( member ( pinPairRef "@baseboard_fab2_lib.baseboard_fab2(sch_1):\PP3286\") )
				( member ( pinPairRef "@baseboard_fab2_lib.baseboard_fab2(sch_1):\PP3273\") )
				( member ( pinPairRef "@baseboard_fab2_lib.baseboard_fab2(sch_1):\PP3274\") )
				( member ( pinPairRef "@baseboard_fab2_lib.baseboard_fab2(sch_1):\PP3272\") )
				( member ( pinPairRef "@baseboard_fab2_lib.baseboard_fab2(sch_1):\PP3270\") )
				( member ( pinPairRef "@baseboard_fab2_lib.baseboard_fab2(sch_1):\PP3271\") )
				( member ( pinPairRef "@baseboard_fab2_lib.baseboard_fab2(sch_1):\PP3268\") )
				( member ( pinPairRef "@baseboard_fab2_lib.baseboard_fab2(sch_1):\PP3269\") )
				( member ( pinPairRef "@baseboard_fab2_lib.baseboard_fab2(sch_1):\PP3267\") )
				( member ( signalRef "@baseboard_fab2_lib.baseboard_fab2(sch_1):m_m_clk_dp(2)") )
				( objectStatus "MG_DDR_NEAR_DIMM-CLK1_CLS_DDR_M_CAC-CLKS" )
			)
			( matchGroup "@baseboard_fab2_lib.baseboard_fab2(sch_1):\MG_DDR_CMD_NEAR_DIMM_NG_DDR_M_DLL_1\"
				( memberType ( signal ) )
				( member ( pinPairRef "@baseboard_fab2_lib.baseboard_fab2(sch_1):\PP3330\") )
				( member ( pinPairRef "@baseboard_fab2_lib.baseboard_fab2(sch_1):\PP3332\") )
				( objectStatus "MG_DDR_CMD_NEAR_DIMM_NG_DDR_M_DLL_1" )
			)
			( matchGroup "@baseboard_fab2_lib.baseboard_fab2(sch_1):\MG_DDR_FAR_DIMM_CMD_NG_DDR_M_DLL_2\"
				( memberType ( signal ) )
				( member ( pinPairRef "@baseboard_fab2_lib.baseboard_fab2(sch_1):\PP3325\") )
				( member ( pinPairRef "@baseboard_fab2_lib.baseboard_fab2(sch_1):\PP3327\") )
				( objectStatus "MG_DDR_FAR_DIMM_CMD_NG_DDR_M_DLL_2" )
			)
			( matchGroup "@baseboard_fab2_lib.baseboard_fab2(sch_1):\MG_DDR_CMD_NEAR_DIMM_NG_DDR_M_DLL_2\"
				( memberType ( signal ) )
				( member ( pinPairRef "@baseboard_fab2_lib.baseboard_fab2(sch_1):\PP3326\") )
				( member ( pinPairRef "@baseboard_fab2_lib.baseboard_fab2(sch_1):\PP3328\") )
				( objectStatus "MG_DDR_CMD_NEAR_DIMM_NG_DDR_M_DLL_2" )
			)
			( matchGroup "@baseboard_fab2_lib.baseboard_fab2(sch_1):\MG_DDR_FAR_DIMM_CMD_NG_DDR_M_DLL_3\"
				( memberType ( signal ) )
				( member ( pinPairRef "@baseboard_fab2_lib.baseboard_fab2(sch_1):\PP3321\") )
				( member ( pinPairRef "@baseboard_fab2_lib.baseboard_fab2(sch_1):\PP3323\") )
				( objectStatus "MG_DDR_FAR_DIMM_CMD_NG_DDR_M_DLL_3" )
			)
			( matchGroup "@baseboard_fab2_lib.baseboard_fab2(sch_1):\MG_DDR_CMD_NEAR_DIMM_NG_DDR_M_DLL_3\"
				( memberType ( signal ) )
				( member ( pinPairRef "@baseboard_fab2_lib.baseboard_fab2(sch_1):\PP3322\") )
				( member ( pinPairRef "@baseboard_fab2_lib.baseboard_fab2(sch_1):\PP3324\") )
				( objectStatus "MG_DDR_CMD_NEAR_DIMM_NG_DDR_M_DLL_3" )
			)
			( matchGroup "@baseboard_fab2_lib.baseboard_fab2(sch_1):\MG_DDR_FAR_DIMM_CMD_NG_DDR_M_DLL_4\"
				( memberType ( signal ) )
				( member ( pinPairRef "@baseboard_fab2_lib.baseboard_fab2(sch_1):\PP3317\") )
				( member ( pinPairRef "@baseboard_fab2_lib.baseboard_fab2(sch_1):\PP3319\") )
				( objectStatus "MG_DDR_FAR_DIMM_CMD_NG_DDR_M_DLL_4" )
			)
			( matchGroup "@baseboard_fab2_lib.baseboard_fab2(sch_1):\MG_DDR_CMD_NEAR_DIMM_NG_DDR_M_DLL_4\"
				( memberType ( signal ) )
				( member ( pinPairRef "@baseboard_fab2_lib.baseboard_fab2(sch_1):\PP3318\") )
				( member ( pinPairRef "@baseboard_fab2_lib.baseboard_fab2(sch_1):\PP3320\") )
				( objectStatus "MG_DDR_CMD_NEAR_DIMM_NG_DDR_M_DLL_4" )
			)
			( matchGroup "@baseboard_fab2_lib.baseboard_fab2(sch_1):\MG_DDR_FAR_DIMM_CMD_NG_DDR_M_DLL_5\"
				( memberType ( signal ) )
				( member ( pinPairRef "@baseboard_fab2_lib.baseboard_fab2(sch_1):\PP3313\") )
				( member ( pinPairRef "@baseboard_fab2_lib.baseboard_fab2(sch_1):\PP3315\") )
				( objectStatus "MG_DDR_FAR_DIMM_CMD_NG_DDR_M_DLL_5" )
			)
			( matchGroup "@baseboard_fab2_lib.baseboard_fab2(sch_1):\MG_DDR_CMD_NEAR_DIMM_NG_DDR_M_DLL_5\"
				( memberType ( signal ) )
				( member ( pinPairRef "@baseboard_fab2_lib.baseboard_fab2(sch_1):\PP3314\") )
				( member ( pinPairRef "@baseboard_fab2_lib.baseboard_fab2(sch_1):\PP3316\") )
				( objectStatus "MG_DDR_CMD_NEAR_DIMM_NG_DDR_M_DLL_5" )
			)
			( matchGroup "@baseboard_fab2_lib.baseboard_fab2(sch_1):\MG_DDR_FAR_DIMM_CMD_NG_DDR_M_DLL_6\"
				( memberType ( signal ) )
				( member ( pinPairRef "@baseboard_fab2_lib.baseboard_fab2(sch_1):\PP3311\") )
				( objectStatus "MG_DDR_FAR_DIMM_CMD_NG_DDR_M_DLL_6" )
			)
			( matchGroup "@baseboard_fab2_lib.baseboard_fab2(sch_1):\MG_DDR_CMD_NEAR_DIMM_NG_DDR_M_DLL_6\"
				( memberType ( signal ) )
				( member ( pinPairRef "@baseboard_fab2_lib.baseboard_fab2(sch_1):\PP3312\") )
				( objectStatus "MG_DDR_CMD_NEAR_DIMM_NG_DDR_M_DLL_6" )
			)
			( matchGroup "@baseboard_fab2_lib.baseboard_fab2(sch_1):\MG_DDR_FAR_DIMM_CMD_NG_DDR_M_DLL_7\"
				( memberType ( signal ) )
				( member ( pinPairRef "@baseboard_fab2_lib.baseboard_fab2(sch_1):\PP3307\") )
				( member ( pinPairRef "@baseboard_fab2_lib.baseboard_fab2(sch_1):\PP3309\") )
				( objectStatus "MG_DDR_FAR_DIMM_CMD_NG_DDR_M_DLL_7" )
			)
			( matchGroup "@baseboard_fab2_lib.baseboard_fab2(sch_1):\MG_DDR_CMD_NEAR_DIMM_NG_DDR_M_DLL_7\"
				( memberType ( signal ) )
				( member ( pinPairRef "@baseboard_fab2_lib.baseboard_fab2(sch_1):\PP3308\") )
				( member ( pinPairRef "@baseboard_fab2_lib.baseboard_fab2(sch_1):\PP3310\") )
				( objectStatus "MG_DDR_CMD_NEAR_DIMM_NG_DDR_M_DLL_7" )
			)
			( matchGroup "@baseboard_fab2_lib.baseboard_fab2(sch_1):\MG_DDR_FAR_DIMM_CMD_NG_DDR_M_DLL_8\"
				( memberType ( signal ) )
				( member ( pinPairRef "@baseboard_fab2_lib.baseboard_fab2(sch_1):\PP3303\") )
				( member ( pinPairRef "@baseboard_fab2_lib.baseboard_fab2(sch_1):\PP3305\") )
				( objectStatus "MG_DDR_FAR_DIMM_CMD_NG_DDR_M_DLL_8" )
			)
			( matchGroup "@baseboard_fab2_lib.baseboard_fab2(sch_1):\MG_DDR_CMD_NEAR_DIMM_NG_DDR_M_DLL_8\"
				( memberType ( signal ) )
				( member ( pinPairRef "@baseboard_fab2_lib.baseboard_fab2(sch_1):\PP3304\") )
				( member ( pinPairRef "@baseboard_fab2_lib.baseboard_fab2(sch_1):\PP3306\") )
				( objectStatus "MG_DDR_CMD_NEAR_DIMM_NG_DDR_M_DLL_8" )
			)
			( matchGroup "@baseboard_fab2_lib.baseboard_fab2(sch_1):\MG_DDR_FAR_DIMM_CMD_NG_DDR_M_DLL_9\"
				( memberType ( signal ) )
				( member ( pinPairRef "@baseboard_fab2_lib.baseboard_fab2(sch_1):\PP3299\") )
				( member ( pinPairRef "@baseboard_fab2_lib.baseboard_fab2(sch_1):\PP3301\") )
				( objectStatus "MG_DDR_FAR_DIMM_CMD_NG_DDR_M_DLL_9" )
			)
			( matchGroup "@baseboard_fab2_lib.baseboard_fab2(sch_1):\MG_DDR_CMD_NEAR_DIMM_NG_DDR_M_DLL_9\"
				( memberType ( signal ) )
				( member ( pinPairRef "@baseboard_fab2_lib.baseboard_fab2(sch_1):\PP3300\") )
				( member ( pinPairRef "@baseboard_fab2_lib.baseboard_fab2(sch_1):\PP3302\") )
				( objectStatus "MG_DDR_CMD_NEAR_DIMM_NG_DDR_M_DLL_9" )
			)
			( matchGroup "@baseboard_fab2_lib.baseboard_fab2(sch_1):\MG_DDR_FAR_DIMM_CMD_NG_DDR_M_DLL_10\"
				( memberType ( signal ) )
				( member ( pinPairRef "@baseboard_fab2_lib.baseboard_fab2(sch_1):\PP3295\") )
				( member ( pinPairRef "@baseboard_fab2_lib.baseboard_fab2(sch_1):\PP3297\") )
				( objectStatus "MG_DDR_FAR_DIMM_CMD_NG_DDR_M_DLL_10" )
			)
			( matchGroup "@baseboard_fab2_lib.baseboard_fab2(sch_1):\MG_DDR_CMD_NEAR_DIMM_NG_DDR_M_DLL_10\"
				( memberType ( signal ) )
				( member ( pinPairRef "@baseboard_fab2_lib.baseboard_fab2(sch_1):\PP3296\") )
				( member ( pinPairRef "@baseboard_fab2_lib.baseboard_fab2(sch_1):\PP3298\") )
				( objectStatus "MG_DDR_CMD_NEAR_DIMM_NG_DDR_M_DLL_10" )
			)
			( matchGroup "@baseboard_fab2_lib.baseboard_fab2(sch_1):\MG_DDR_FAR_DIMM_CMD_NG_DDR_M_DLL_11\"
				( memberType ( signal ) )
				( member ( pinPairRef "@baseboard_fab2_lib.baseboard_fab2(sch_1):\PP3291\") )
				( member ( pinPairRef "@baseboard_fab2_lib.baseboard_fab2(sch_1):\PP3293\") )
				( objectStatus "MG_DDR_FAR_DIMM_CMD_NG_DDR_M_DLL_11" )
			)
			( matchGroup "@baseboard_fab2_lib.baseboard_fab2(sch_1):\MG_DDR_CMD_NEAR_DIMM_NG_DDR_M_DLL_11\"
				( memberType ( signal ) )
				( member ( pinPairRef "@baseboard_fab2_lib.baseboard_fab2(sch_1):\PP3292\") )
				( member ( pinPairRef "@baseboard_fab2_lib.baseboard_fab2(sch_1):\PP3294\") )
				( objectStatus "MG_DDR_CMD_NEAR_DIMM_NG_DDR_M_DLL_11" )
			)
			( matchGroup "@baseboard_fab2_lib.baseboard_fab2(sch_1):\MG_DDR_FAR_DIMM_CMD_NG_DDR_M_DLL_12\"
				( memberType ( signal ) )
				( member ( pinPairRef "@baseboard_fab2_lib.baseboard_fab2(sch_1):\PP3287\") )
				( member ( pinPairRef "@baseboard_fab2_lib.baseboard_fab2(sch_1):\PP3289\") )
				( objectStatus "MG_DDR_FAR_DIMM_CMD_NG_DDR_M_DLL_12" )
			)
			( matchGroup "@baseboard_fab2_lib.baseboard_fab2(sch_1):\MG_DDR_CMD_NEAR_DIMM_NG_DDR_M_DLL_12\"
				( memberType ( signal ) )
				( member ( pinPairRef "@baseboard_fab2_lib.baseboard_fab2(sch_1):\PP3288\") )
				( member ( pinPairRef "@baseboard_fab2_lib.baseboard_fab2(sch_1):\PP3290\") )
				( objectStatus "MG_DDR_CMD_NEAR_DIMM_NG_DDR_M_DLL_12" )
			)
			( matchGroup "@baseboard_fab2_lib.baseboard_fab2(sch_1):\MG_DDR_FAR_DIMM_CMD_NG_DDR_M_DLL_13\"
				( memberType ( signal ) )
				( member ( pinPairRef "@baseboard_fab2_lib.baseboard_fab2(sch_1):\PP3283\") )
				( member ( pinPairRef "@baseboard_fab2_lib.baseboard_fab2(sch_1):\PP3285\") )
				( objectStatus "MG_DDR_FAR_DIMM_CMD_NG_DDR_M_DLL_13" )
			)
			( matchGroup "@baseboard_fab2_lib.baseboard_fab2(sch_1):\MG_DDR_CMD_NEAR_DIMM_NG_DDR_M_DLL_13\"
				( memberType ( signal ) )
				( member ( pinPairRef "@baseboard_fab2_lib.baseboard_fab2(sch_1):\PP3284\") )
				( member ( pinPairRef "@baseboard_fab2_lib.baseboard_fab2(sch_1):\PP3286\") )
				( objectStatus "MG_DDR_CMD_NEAR_DIMM_NG_DDR_M_DLL_13" )
			)
			( matchGroup "@baseboard_fab2_lib.baseboard_fab2(sch_1):\MG_DDR_CTRL_NG_DDR_M_DLL_14\"
				( memberType ( signal ) )
				( member ( pinPairRef "@baseboard_fab2_lib.baseboard_fab2(sch_1):\PP3281\") )
				( member ( pinPairRef "@baseboard_fab2_lib.baseboard_fab2(sch_1):\PP3282\") )
				( objectStatus "MG_DDR_CTRL_NG_DDR_M_DLL_14" )
			)
			( matchGroup "@baseboard_fab2_lib.baseboard_fab2(sch_1):\MG_DDR_CTRL_NG_DDR_M_DLL_15\"
				( memberType ( signal ) )
				( member ( pinPairRef "@baseboard_fab2_lib.baseboard_fab2(sch_1):\PP3280\") )
				( objectStatus "MG_DDR_CTRL_NG_DDR_M_DLL_15" )
			)
			( matchGroup "@baseboard_fab2_lib.baseboard_fab2(sch_1):\MG_DDR_CTRL_NG_DDR_M_DLL_16\"
				( memberType ( signal ) )
				( member ( pinPairRef "@baseboard_fab2_lib.baseboard_fab2(sch_1):\PP3279\") )
				( objectStatus "MG_DDR_CTRL_NG_DDR_M_DLL_16" )
			)
			( matchGroup "@baseboard_fab2_lib.baseboard_fab2(sch_1):\MG_DDR_CTRL_NG_DDR_M_DLL_17\"
				( memberType ( signal ) )
				( member ( pinPairRef "@baseboard_fab2_lib.baseboard_fab2(sch_1):\PP3278\") )
				( objectStatus "MG_DDR_CTRL_NG_DDR_M_DLL_17" )
			)
			( matchGroup "@baseboard_fab2_lib.baseboard_fab2(sch_1):\MG_DDR_CTRL_NG_DDR_M_DLL_18\"
				( memberType ( signal ) )
				( member ( pinPairRef "@baseboard_fab2_lib.baseboard_fab2(sch_1):\PP3276\") )
				( member ( pinPairRef "@baseboard_fab2_lib.baseboard_fab2(sch_1):\PP3277\") )
				( objectStatus "MG_DDR_CTRL_NG_DDR_M_DLL_18" )
			)
			( matchGroup "@baseboard_fab2_lib.baseboard_fab2(sch_1):\MG_DDR_CTRL_NG_DDR_M_DLL_19\"
				( memberType ( signal ) )
				( member ( pinPairRef "@baseboard_fab2_lib.baseboard_fab2(sch_1):\PP3275\") )
				( objectStatus "MG_DDR_CTRL_NG_DDR_M_DLL_19" )
			)
			( matchGroup "@baseboard_fab2_lib.baseboard_fab2(sch_1):\MG_DDR_CTRL_NG_DDR_M_DLL_20\"
				( memberType ( signal ) )
				( member ( pinPairRef "@baseboard_fab2_lib.baseboard_fab2(sch_1):\PP3273\") )
				( member ( pinPairRef "@baseboard_fab2_lib.baseboard_fab2(sch_1):\PP3274\") )
				( objectStatus "MG_DDR_CTRL_NG_DDR_M_DLL_20" )
			)
			( matchGroup "@baseboard_fab2_lib.baseboard_fab2(sch_1):\MG_DDR_CTRL_NG_DDR_M_DLL_21\"
				( memberType ( signal ) )
				( member ( pinPairRef "@baseboard_fab2_lib.baseboard_fab2(sch_1):\PP3272\") )
				( objectStatus "MG_DDR_CTRL_NG_DDR_M_DLL_21" )
			)
			( matchGroup "@baseboard_fab2_lib.baseboard_fab2(sch_1):\MG_DDR_CTRL_NG_DDR_M_DLL_22\"
				( memberType ( signal ) )
				( member ( pinPairRef "@baseboard_fab2_lib.baseboard_fab2(sch_1):\PP3270\") )
				( member ( pinPairRef "@baseboard_fab2_lib.baseboard_fab2(sch_1):\PP3271\") )
				( objectStatus "MG_DDR_CTRL_NG_DDR_M_DLL_22" )
			)
			( matchGroup "@baseboard_fab2_lib.baseboard_fab2(sch_1):\MG_DDR_CTRL_NG_DDR_M_DLL_23\"
				( memberType ( signal ) )
				( member ( pinPairRef "@baseboard_fab2_lib.baseboard_fab2(sch_1):\PP3268\") )
				( member ( pinPairRef "@baseboard_fab2_lib.baseboard_fab2(sch_1):\PP3269\") )
				( objectStatus "MG_DDR_CTRL_NG_DDR_M_DLL_23" )
			)
			( matchGroup "@baseboard_fab2_lib.baseboard_fab2(sch_1):\MG_DDR_CTRL_NG_DDR_M_DLL_24\"
				( memberType ( signal ) )
				( member ( pinPairRef "@baseboard_fab2_lib.baseboard_fab2(sch_1):\PP3267\") )
				( objectStatus "MG_DDR_CTRL_NG_DDR_M_DLL_24" )
			)
			( matchGroup "@baseboard_fab2_lib.baseboard_fab2(sch_1):\MG_DDR_FAR_DIMM_CMD_NG_DDR_L_DLL_1\"
				( memberType ( signal ) )
				( member ( pinPairRef "@baseboard_fab2_lib.baseboard_fab2(sch_1):\PP3395\") )
				( member ( pinPairRef "@baseboard_fab2_lib.baseboard_fab2(sch_1):\PP3397\") )
				( objectStatus "MG_DDR_FAR_DIMM_CMD_NG_DDR_L_DLL_1" )
			)
			( matchGroup "@crescent_city_bb_fab1_lib.crescent_city_bb_fab1(sch_1):\MG_DDR_FAR_DIMM-CLK0_CLS_DDR_L_CAC-CLKS\"
				( memberType ( signal ) )
				( member ( pinPairRef "@baseboard_fab2_lib.baseboard_fab2(sch_1):\PP3395\") )
				( member ( pinPairRef "@baseboard_fab2_lib.baseboard_fab2(sch_1):\PP3397\") )
				( member ( pinPairRef "@baseboard_fab2_lib.baseboard_fab2(sch_1):\PP3391\") )
				( member ( pinPairRef "@baseboard_fab2_lib.baseboard_fab2(sch_1):\PP3393\") )
				( member ( pinPairRef "@baseboard_fab2_lib.baseboard_fab2(sch_1):\PP3387\") )
				( member ( pinPairRef "@baseboard_fab2_lib.baseboard_fab2(sch_1):\PP3389\") )
				( member ( pinPairRef "@baseboard_fab2_lib.baseboard_fab2(sch_1):\PP3383\") )
				( member ( pinPairRef "@baseboard_fab2_lib.baseboard_fab2(sch_1):\PP3385\") )
				( member ( pinPairRef "@baseboard_fab2_lib.baseboard_fab2(sch_1):\PP3379\") )
				( member ( pinPairRef "@baseboard_fab2_lib.baseboard_fab2(sch_1):\PP3381\") )
				( member ( pinPairRef "@baseboard_fab2_lib.baseboard_fab2(sch_1):\PP3377\") )
				( member ( pinPairRef "@baseboard_fab2_lib.baseboard_fab2(sch_1):\PP3373\") )
				( member ( pinPairRef "@baseboard_fab2_lib.baseboard_fab2(sch_1):\PP3375\") )
				( member ( pinPairRef "@baseboard_fab2_lib.baseboard_fab2(sch_1):\PP3369\") )
				( member ( pinPairRef "@baseboard_fab2_lib.baseboard_fab2(sch_1):\PP3371\") )
				( member ( pinPairRef "@baseboard_fab2_lib.baseboard_fab2(sch_1):\PP3365\") )
				( member ( pinPairRef "@baseboard_fab2_lib.baseboard_fab2(sch_1):\PP3367\") )
				( member ( pinPairRef "@baseboard_fab2_lib.baseboard_fab2(sch_1):\PP3361\") )
				( member ( pinPairRef "@baseboard_fab2_lib.baseboard_fab2(sch_1):\PP3363\") )
				( member ( pinPairRef "@baseboard_fab2_lib.baseboard_fab2(sch_1):\PP3357\") )
				( member ( pinPairRef "@baseboard_fab2_lib.baseboard_fab2(sch_1):\PP3359\") )
				( member ( pinPairRef "@baseboard_fab2_lib.baseboard_fab2(sch_1):\PP3353\") )
				( member ( pinPairRef "@baseboard_fab2_lib.baseboard_fab2(sch_1):\PP3355\") )
				( member ( pinPairRef "@baseboard_fab2_lib.baseboard_fab2(sch_1):\PP3349\") )
				( member ( pinPairRef "@baseboard_fab2_lib.baseboard_fab2(sch_1):\PP3351\") )
				( member ( pinPairRef "@baseboard_fab2_lib.baseboard_fab2(sch_1):\PP3347\") )
				( member ( pinPairRef "@baseboard_fab2_lib.baseboard_fab2(sch_1):\PP3348\") )
				( member ( pinPairRef "@baseboard_fab2_lib.baseboard_fab2(sch_1):\PP3346\") )
				( member ( pinPairRef "@baseboard_fab2_lib.baseboard_fab2(sch_1):\PP3345\") )
				( member ( pinPairRef "@baseboard_fab2_lib.baseboard_fab2(sch_1):\PP3344\") )
				( member ( pinPairRef "@baseboard_fab2_lib.baseboard_fab2(sch_1):\PP3342\") )
				( member ( pinPairRef "@baseboard_fab2_lib.baseboard_fab2(sch_1):\PP3343\") )
				( member ( pinPairRef "@baseboard_fab2_lib.baseboard_fab2(sch_1):\PP3341\") )
				( member ( signalRef "@baseboard_fab2_lib.baseboard_fab2(sch_1):m_l_clk_dp(0)") )
				( objectStatus "MG_DDR_FAR_DIMM-CLK0_CLS_DDR_L_CAC-CLKS" )
			)
			( matchGroup "@crescent_city_bb_fab1_lib.crescent_city_bb_fab1(sch_1):\MG_DDR_NEAR_DIMM-CLK1_CLS_DDR_L_CAC-CLKS\"
				( memberType ( signal ) )
				( member ( pinPairRef "@baseboard_fab2_lib.baseboard_fab2(sch_1):\PP3396\") )
				( member ( pinPairRef "@baseboard_fab2_lib.baseboard_fab2(sch_1):\PP3398\") )
				( member ( pinPairRef "@baseboard_fab2_lib.baseboard_fab2(sch_1):\PP3392\") )
				( member ( pinPairRef "@baseboard_fab2_lib.baseboard_fab2(sch_1):\PP3394\") )
				( member ( pinPairRef "@baseboard_fab2_lib.baseboard_fab2(sch_1):\PP3388\") )
				( member ( pinPairRef "@baseboard_fab2_lib.baseboard_fab2(sch_1):\PP3390\") )
				( member ( pinPairRef "@baseboard_fab2_lib.baseboard_fab2(sch_1):\PP3384\") )
				( member ( pinPairRef "@baseboard_fab2_lib.baseboard_fab2(sch_1):\PP3386\") )
				( member ( pinPairRef "@baseboard_fab2_lib.baseboard_fab2(sch_1):\PP3380\") )
				( member ( pinPairRef "@baseboard_fab2_lib.baseboard_fab2(sch_1):\PP3382\") )
				( member ( pinPairRef "@baseboard_fab2_lib.baseboard_fab2(sch_1):\PP3378\") )
				( member ( pinPairRef "@baseboard_fab2_lib.baseboard_fab2(sch_1):\PP3374\") )
				( member ( pinPairRef "@baseboard_fab2_lib.baseboard_fab2(sch_1):\PP3376\") )
				( member ( pinPairRef "@baseboard_fab2_lib.baseboard_fab2(sch_1):\PP3370\") )
				( member ( pinPairRef "@baseboard_fab2_lib.baseboard_fab2(sch_1):\PP3372\") )
				( member ( pinPairRef "@baseboard_fab2_lib.baseboard_fab2(sch_1):\PP3366\") )
				( member ( pinPairRef "@baseboard_fab2_lib.baseboard_fab2(sch_1):\PP3368\") )
				( member ( pinPairRef "@baseboard_fab2_lib.baseboard_fab2(sch_1):\PP3362\") )
				( member ( pinPairRef "@baseboard_fab2_lib.baseboard_fab2(sch_1):\PP3364\") )
				( member ( pinPairRef "@baseboard_fab2_lib.baseboard_fab2(sch_1):\PP3358\") )
				( member ( pinPairRef "@baseboard_fab2_lib.baseboard_fab2(sch_1):\PP3360\") )
				( member ( pinPairRef "@baseboard_fab2_lib.baseboard_fab2(sch_1):\PP3354\") )
				( member ( pinPairRef "@baseboard_fab2_lib.baseboard_fab2(sch_1):\PP3356\") )
				( member ( pinPairRef "@baseboard_fab2_lib.baseboard_fab2(sch_1):\PP3350\") )
				( member ( pinPairRef "@baseboard_fab2_lib.baseboard_fab2(sch_1):\PP3352\") )
				( member ( pinPairRef "@baseboard_fab2_lib.baseboard_fab2(sch_1):\PP3339\") )
				( member ( pinPairRef "@baseboard_fab2_lib.baseboard_fab2(sch_1):\PP3340\") )
				( member ( pinPairRef "@baseboard_fab2_lib.baseboard_fab2(sch_1):\PP3338\") )
				( member ( pinPairRef "@baseboard_fab2_lib.baseboard_fab2(sch_1):\PP3336\") )
				( member ( pinPairRef "@baseboard_fab2_lib.baseboard_fab2(sch_1):\PP3337\") )
				( member ( pinPairRef "@baseboard_fab2_lib.baseboard_fab2(sch_1):\PP3334\") )
				( member ( pinPairRef "@baseboard_fab2_lib.baseboard_fab2(sch_1):\PP3335\") )
				( member ( pinPairRef "@baseboard_fab2_lib.baseboard_fab2(sch_1):\PP3333\") )
				( member ( signalRef "@baseboard_fab2_lib.baseboard_fab2(sch_1):m_l_clk_dp(2)") )
				( objectStatus "MG_DDR_NEAR_DIMM-CLK1_CLS_DDR_L_CAC-CLKS" )
			)
			( matchGroup "@baseboard_fab2_lib.baseboard_fab2(sch_1):\MG_DDR_CMD_NEAR_DIMM_NG_DDR_L_DLL_1\"
				( memberType ( signal ) )
				( member ( pinPairRef "@baseboard_fab2_lib.baseboard_fab2(sch_1):\PP3396\") )
				( member ( pinPairRef "@baseboard_fab2_lib.baseboard_fab2(sch_1):\PP3398\") )
				( objectStatus "MG_DDR_CMD_NEAR_DIMM_NG_DDR_L_DLL_1" )
			)
			( matchGroup "@baseboard_fab2_lib.baseboard_fab2(sch_1):\MG_DDR_FAR_DIMM_CMD_NG_DDR_L_DLL_2\"
				( memberType ( signal ) )
				( member ( pinPairRef "@baseboard_fab2_lib.baseboard_fab2(sch_1):\PP3391\") )
				( member ( pinPairRef "@baseboard_fab2_lib.baseboard_fab2(sch_1):\PP3393\") )
				( objectStatus "MG_DDR_FAR_DIMM_CMD_NG_DDR_L_DLL_2" )
			)
			( matchGroup "@baseboard_fab2_lib.baseboard_fab2(sch_1):\MG_DDR_CMD_NEAR_DIMM_NG_DDR_L_DLL_2\"
				( memberType ( signal ) )
				( member ( pinPairRef "@baseboard_fab2_lib.baseboard_fab2(sch_1):\PP3392\") )
				( member ( pinPairRef "@baseboard_fab2_lib.baseboard_fab2(sch_1):\PP3394\") )
				( objectStatus "MG_DDR_CMD_NEAR_DIMM_NG_DDR_L_DLL_2" )
			)
			( matchGroup "@baseboard_fab2_lib.baseboard_fab2(sch_1):\MG_DDR_FAR_DIMM_CMD_NG_DDR_L_DLL_3\"
				( memberType ( signal ) )
				( member ( pinPairRef "@baseboard_fab2_lib.baseboard_fab2(sch_1):\PP3387\") )
				( member ( pinPairRef "@baseboard_fab2_lib.baseboard_fab2(sch_1):\PP3389\") )
				( objectStatus "MG_DDR_FAR_DIMM_CMD_NG_DDR_L_DLL_3" )
			)
			( matchGroup "@baseboard_fab2_lib.baseboard_fab2(sch_1):\MG_DDR_CMD_NEAR_DIMM_NG_DDR_L_DLL_3\"
				( memberType ( signal ) )
				( member ( pinPairRef "@baseboard_fab2_lib.baseboard_fab2(sch_1):\PP3388\") )
				( member ( pinPairRef "@baseboard_fab2_lib.baseboard_fab2(sch_1):\PP3390\") )
				( objectStatus "MG_DDR_CMD_NEAR_DIMM_NG_DDR_L_DLL_3" )
			)
			( matchGroup "@baseboard_fab2_lib.baseboard_fab2(sch_1):\MG_DDR_FAR_DIMM_CMD_NG_DDR_L_DLL_4\"
				( memberType ( signal ) )
				( member ( pinPairRef "@baseboard_fab2_lib.baseboard_fab2(sch_1):\PP3383\") )
				( member ( pinPairRef "@baseboard_fab2_lib.baseboard_fab2(sch_1):\PP3385\") )
				( objectStatus "MG_DDR_FAR_DIMM_CMD_NG_DDR_L_DLL_4" )
			)
			( matchGroup "@baseboard_fab2_lib.baseboard_fab2(sch_1):\MG_DDR_CMD_NEAR_DIMM_NG_DDR_L_DLL_4\"
				( memberType ( signal ) )
				( member ( pinPairRef "@baseboard_fab2_lib.baseboard_fab2(sch_1):\PP3384\") )
				( member ( pinPairRef "@baseboard_fab2_lib.baseboard_fab2(sch_1):\PP3386\") )
				( objectStatus "MG_DDR_CMD_NEAR_DIMM_NG_DDR_L_DLL_4" )
			)
			( matchGroup "@baseboard_fab2_lib.baseboard_fab2(sch_1):\MG_DDR_FAR_DIMM_CMD_NG_DDR_L_DLL_5\"
				( memberType ( signal ) )
				( member ( pinPairRef "@baseboard_fab2_lib.baseboard_fab2(sch_1):\PP3379\") )
				( member ( pinPairRef "@baseboard_fab2_lib.baseboard_fab2(sch_1):\PP3381\") )
				( objectStatus "MG_DDR_FAR_DIMM_CMD_NG_DDR_L_DLL_5" )
			)
			( matchGroup "@baseboard_fab2_lib.baseboard_fab2(sch_1):\MG_DDR_CMD_NEAR_DIMM_NG_DDR_L_DLL_5\"
				( memberType ( signal ) )
				( member ( pinPairRef "@baseboard_fab2_lib.baseboard_fab2(sch_1):\PP3380\") )
				( member ( pinPairRef "@baseboard_fab2_lib.baseboard_fab2(sch_1):\PP3382\") )
				( objectStatus "MG_DDR_CMD_NEAR_DIMM_NG_DDR_L_DLL_5" )
			)
			( matchGroup "@baseboard_fab2_lib.baseboard_fab2(sch_1):\MG_DDR_FAR_DIMM_CMD_NG_DDR_L_DLL_6\"
				( memberType ( signal ) )
				( member ( pinPairRef "@baseboard_fab2_lib.baseboard_fab2(sch_1):\PP3377\") )
				( objectStatus "MG_DDR_FAR_DIMM_CMD_NG_DDR_L_DLL_6" )
			)
			( matchGroup "@baseboard_fab2_lib.baseboard_fab2(sch_1):\MG_DDR_CMD_NEAR_DIMM_NG_DDR_L_DLL_6\"
				( memberType ( signal ) )
				( member ( pinPairRef "@baseboard_fab2_lib.baseboard_fab2(sch_1):\PP3378\") )
				( objectStatus "MG_DDR_CMD_NEAR_DIMM_NG_DDR_L_DLL_6" )
			)
			( matchGroup "@baseboard_fab2_lib.baseboard_fab2(sch_1):\MG_DDR_FAR_DIMM_CMD_NG_DDR_L_DLL_7\"
				( memberType ( signal ) )
				( member ( pinPairRef "@baseboard_fab2_lib.baseboard_fab2(sch_1):\PP3373\") )
				( member ( pinPairRef "@baseboard_fab2_lib.baseboard_fab2(sch_1):\PP3375\") )
				( objectStatus "MG_DDR_FAR_DIMM_CMD_NG_DDR_L_DLL_7" )
			)
			( matchGroup "@baseboard_fab2_lib.baseboard_fab2(sch_1):\MG_DDR_CMD_NEAR_DIMM_NG_DDR_L_DLL_7\"
				( memberType ( signal ) )
				( member ( pinPairRef "@baseboard_fab2_lib.baseboard_fab2(sch_1):\PP3374\") )
				( member ( pinPairRef "@baseboard_fab2_lib.baseboard_fab2(sch_1):\PP3376\") )
				( objectStatus "MG_DDR_CMD_NEAR_DIMM_NG_DDR_L_DLL_7" )
			)
			( matchGroup "@baseboard_fab2_lib.baseboard_fab2(sch_1):\MG_DDR_FAR_DIMM_CMD_NG_DDR_L_DLL_8\"
				( memberType ( signal ) )
				( member ( pinPairRef "@baseboard_fab2_lib.baseboard_fab2(sch_1):\PP3369\") )
				( member ( pinPairRef "@baseboard_fab2_lib.baseboard_fab2(sch_1):\PP3371\") )
				( objectStatus "MG_DDR_FAR_DIMM_CMD_NG_DDR_L_DLL_8" )
			)
			( matchGroup "@baseboard_fab2_lib.baseboard_fab2(sch_1):\MG_DDR_CMD_NEAR_DIMM_NG_DDR_L_DLL_8\"
				( memberType ( signal ) )
				( member ( pinPairRef "@baseboard_fab2_lib.baseboard_fab2(sch_1):\PP3370\") )
				( member ( pinPairRef "@baseboard_fab2_lib.baseboard_fab2(sch_1):\PP3372\") )
				( objectStatus "MG_DDR_CMD_NEAR_DIMM_NG_DDR_L_DLL_8" )
			)
			( matchGroup "@baseboard_fab2_lib.baseboard_fab2(sch_1):\MG_DDR_FAR_DIMM_CMD_NG_DDR_L_DLL_9\"
				( memberType ( signal ) )
				( member ( pinPairRef "@baseboard_fab2_lib.baseboard_fab2(sch_1):\PP3365\") )
				( member ( pinPairRef "@baseboard_fab2_lib.baseboard_fab2(sch_1):\PP3367\") )
				( objectStatus "MG_DDR_FAR_DIMM_CMD_NG_DDR_L_DLL_9" )
			)
			( matchGroup "@baseboard_fab2_lib.baseboard_fab2(sch_1):\MG_DDR_CMD_NEAR_DIMM_NG_DDR_L_DLL_9\"
				( memberType ( signal ) )
				( member ( pinPairRef "@baseboard_fab2_lib.baseboard_fab2(sch_1):\PP3366\") )
				( member ( pinPairRef "@baseboard_fab2_lib.baseboard_fab2(sch_1):\PP3368\") )
				( objectStatus "MG_DDR_CMD_NEAR_DIMM_NG_DDR_L_DLL_9" )
			)
			( matchGroup "@baseboard_fab2_lib.baseboard_fab2(sch_1):\MG_DDR_FAR_DIMM_CMD_NG_DDR_L_DLL_10\"
				( memberType ( signal ) )
				( member ( pinPairRef "@baseboard_fab2_lib.baseboard_fab2(sch_1):\PP3361\") )
				( member ( pinPairRef "@baseboard_fab2_lib.baseboard_fab2(sch_1):\PP3363\") )
				( objectStatus "MG_DDR_FAR_DIMM_CMD_NG_DDR_L_DLL_10" )
			)
			( matchGroup "@baseboard_fab2_lib.baseboard_fab2(sch_1):\MG_DDR_CMD_NEAR_DIMM_NG_DDR_L_DLL_10\"
				( memberType ( signal ) )
				( member ( pinPairRef "@baseboard_fab2_lib.baseboard_fab2(sch_1):\PP3362\") )
				( member ( pinPairRef "@baseboard_fab2_lib.baseboard_fab2(sch_1):\PP3364\") )
				( objectStatus "MG_DDR_CMD_NEAR_DIMM_NG_DDR_L_DLL_10" )
			)
			( matchGroup "@baseboard_fab2_lib.baseboard_fab2(sch_1):\MG_DDR_FAR_DIMM_CMD_NG_DDR_L_DLL_11\"
				( memberType ( signal ) )
				( member ( pinPairRef "@baseboard_fab2_lib.baseboard_fab2(sch_1):\PP3357\") )
				( member ( pinPairRef "@baseboard_fab2_lib.baseboard_fab2(sch_1):\PP3359\") )
				( objectStatus "MG_DDR_FAR_DIMM_CMD_NG_DDR_L_DLL_11" )
			)
			( matchGroup "@baseboard_fab2_lib.baseboard_fab2(sch_1):\MG_DDR_CMD_NEAR_DIMM_NG_DDR_L_DLL_11\"
				( memberType ( signal ) )
				( member ( pinPairRef "@baseboard_fab2_lib.baseboard_fab2(sch_1):\PP3358\") )
				( member ( pinPairRef "@baseboard_fab2_lib.baseboard_fab2(sch_1):\PP3360\") )
				( objectStatus "MG_DDR_CMD_NEAR_DIMM_NG_DDR_L_DLL_11" )
			)
			( matchGroup "@baseboard_fab2_lib.baseboard_fab2(sch_1):\MG_DDR_FAR_DIMM_CMD_NG_DDR_L_DLL_12\"
				( memberType ( signal ) )
				( member ( pinPairRef "@baseboard_fab2_lib.baseboard_fab2(sch_1):\PP3353\") )
				( member ( pinPairRef "@baseboard_fab2_lib.baseboard_fab2(sch_1):\PP3355\") )
				( objectStatus "MG_DDR_FAR_DIMM_CMD_NG_DDR_L_DLL_12" )
			)
			( matchGroup "@baseboard_fab2_lib.baseboard_fab2(sch_1):\MG_DDR_CMD_NEAR_DIMM_NG_DDR_L_DLL_12\"
				( memberType ( signal ) )
				( member ( pinPairRef "@baseboard_fab2_lib.baseboard_fab2(sch_1):\PP3354\") )
				( member ( pinPairRef "@baseboard_fab2_lib.baseboard_fab2(sch_1):\PP3356\") )
				( objectStatus "MG_DDR_CMD_NEAR_DIMM_NG_DDR_L_DLL_12" )
			)
			( matchGroup "@baseboard_fab2_lib.baseboard_fab2(sch_1):\MG_DDR_FAR_DIMM_CMD_NG_DDR_L_DLL_13\"
				( memberType ( signal ) )
				( member ( pinPairRef "@baseboard_fab2_lib.baseboard_fab2(sch_1):\PP3349\") )
				( member ( pinPairRef "@baseboard_fab2_lib.baseboard_fab2(sch_1):\PP3351\") )
				( objectStatus "MG_DDR_FAR_DIMM_CMD_NG_DDR_L_DLL_13" )
			)
			( matchGroup "@baseboard_fab2_lib.baseboard_fab2(sch_1):\MG_DDR_CMD_NEAR_DIMM_NG_DDR_L_DLL_13\"
				( memberType ( signal ) )
				( member ( pinPairRef "@baseboard_fab2_lib.baseboard_fab2(sch_1):\PP3350\") )
				( member ( pinPairRef "@baseboard_fab2_lib.baseboard_fab2(sch_1):\PP3352\") )
				( objectStatus "MG_DDR_CMD_NEAR_DIMM_NG_DDR_L_DLL_13" )
			)
			( matchGroup "@baseboard_fab2_lib.baseboard_fab2(sch_1):\MG_DDR_CTRL_NG_DDR_L_DLL_14\"
				( memberType ( signal ) )
				( member ( pinPairRef "@baseboard_fab2_lib.baseboard_fab2(sch_1):\PP3347\") )
				( member ( pinPairRef "@baseboard_fab2_lib.baseboard_fab2(sch_1):\PP3348\") )
				( objectStatus "MG_DDR_CTRL_NG_DDR_L_DLL_14" )
			)
			( matchGroup "@baseboard_fab2_lib.baseboard_fab2(sch_1):\MG_DDR_CTRL_NG_DDR_L_DLL_15\"
				( memberType ( signal ) )
				( member ( pinPairRef "@baseboard_fab2_lib.baseboard_fab2(sch_1):\PP3346\") )
				( objectStatus "MG_DDR_CTRL_NG_DDR_L_DLL_15" )
			)
			( matchGroup "@baseboard_fab2_lib.baseboard_fab2(sch_1):\MG_DDR_CTRL_NG_DDR_L_DLL_16\"
				( memberType ( signal ) )
				( member ( pinPairRef "@baseboard_fab2_lib.baseboard_fab2(sch_1):\PP3345\") )
				( objectStatus "MG_DDR_CTRL_NG_DDR_L_DLL_16" )
			)
			( matchGroup "@baseboard_fab2_lib.baseboard_fab2(sch_1):\MG_DDR_CTRL_NG_DDR_L_DLL_17\"
				( memberType ( signal ) )
				( member ( pinPairRef "@baseboard_fab2_lib.baseboard_fab2(sch_1):\PP3344\") )
				( objectStatus "MG_DDR_CTRL_NG_DDR_L_DLL_17" )
			)
			( matchGroup "@baseboard_fab2_lib.baseboard_fab2(sch_1):\MG_DDR_CTRL_NG_DDR_L_DLL_18\"
				( memberType ( signal ) )
				( member ( pinPairRef "@baseboard_fab2_lib.baseboard_fab2(sch_1):\PP3342\") )
				( member ( pinPairRef "@baseboard_fab2_lib.baseboard_fab2(sch_1):\PP3343\") )
				( objectStatus "MG_DDR_CTRL_NG_DDR_L_DLL_18" )
			)
			( matchGroup "@baseboard_fab2_lib.baseboard_fab2(sch_1):\MG_DDR_CTRL_NG_DDR_L_DLL_19\"
				( memberType ( signal ) )
				( member ( pinPairRef "@baseboard_fab2_lib.baseboard_fab2(sch_1):\PP3341\") )
				( objectStatus "MG_DDR_CTRL_NG_DDR_L_DLL_19" )
			)
			( matchGroup "@baseboard_fab2_lib.baseboard_fab2(sch_1):\MG_DDR_CTRL_NG_DDR_L_DLL_20\"
				( memberType ( signal ) )
				( member ( pinPairRef "@baseboard_fab2_lib.baseboard_fab2(sch_1):\PP3339\") )
				( member ( pinPairRef "@baseboard_fab2_lib.baseboard_fab2(sch_1):\PP3340\") )
				( objectStatus "MG_DDR_CTRL_NG_DDR_L_DLL_20" )
			)
			( matchGroup "@baseboard_fab2_lib.baseboard_fab2(sch_1):\MG_DDR_CTRL_NG_DDR_L_DLL_21\"
				( memberType ( signal ) )
				( member ( pinPairRef "@baseboard_fab2_lib.baseboard_fab2(sch_1):\PP3338\") )
				( objectStatus "MG_DDR_CTRL_NG_DDR_L_DLL_21" )
			)
			( matchGroup "@baseboard_fab2_lib.baseboard_fab2(sch_1):\MG_DDR_CTRL_NG_DDR_L_DLL_22\"
				( memberType ( signal ) )
				( member ( pinPairRef "@baseboard_fab2_lib.baseboard_fab2(sch_1):\PP3336\") )
				( member ( pinPairRef "@baseboard_fab2_lib.baseboard_fab2(sch_1):\PP3337\") )
				( objectStatus "MG_DDR_CTRL_NG_DDR_L_DLL_22" )
			)
			( matchGroup "@baseboard_fab2_lib.baseboard_fab2(sch_1):\MG_DDR_CTRL_NG_DDR_L_DLL_23\"
				( memberType ( signal ) )
				( member ( pinPairRef "@baseboard_fab2_lib.baseboard_fab2(sch_1):\PP3334\") )
				( member ( pinPairRef "@baseboard_fab2_lib.baseboard_fab2(sch_1):\PP3335\") )
				( objectStatus "MG_DDR_CTRL_NG_DDR_L_DLL_23" )
			)
			( matchGroup "@baseboard_fab2_lib.baseboard_fab2(sch_1):\MG_DDR_CTRL_NG_DDR_L_DLL_24\"
				( memberType ( signal ) )
				( member ( pinPairRef "@baseboard_fab2_lib.baseboard_fab2(sch_1):\PP3333\") )
				( objectStatus "MG_DDR_CTRL_NG_DDR_L_DLL_24" )
			)
			( matchGroup "@baseboard_fab2_lib.baseboard_fab2(sch_1):\MG_DDR_FAR_DIMM_CMD_NG_DDR_K_DLL_1\"
				( memberType ( signal ) )
				( member ( pinPairRef "@baseboard_fab2_lib.baseboard_fab2(sch_1):\PP3461\") )
				( member ( pinPairRef "@baseboard_fab2_lib.baseboard_fab2(sch_1):\PP3463\") )
				( objectStatus "MG_DDR_FAR_DIMM_CMD_NG_DDR_K_DLL_1" )
			)
			( matchGroup "@crescent_city_bb_fab1_lib.crescent_city_bb_fab1(sch_1):\MG_DDR_FAR_DIMM-CLK0_CLS_DDR_K_CAC-CLKS\"
				( memberType ( signal ) )
				( member ( pinPairRef "@baseboard_fab2_lib.baseboard_fab2(sch_1):\PP3461\") )
				( member ( pinPairRef "@baseboard_fab2_lib.baseboard_fab2(sch_1):\PP3463\") )
				( member ( pinPairRef "@baseboard_fab2_lib.baseboard_fab2(sch_1):\PP3457\") )
				( member ( pinPairRef "@baseboard_fab2_lib.baseboard_fab2(sch_1):\PP3459\") )
				( member ( pinPairRef "@baseboard_fab2_lib.baseboard_fab2(sch_1):\PP3453\") )
				( member ( pinPairRef "@baseboard_fab2_lib.baseboard_fab2(sch_1):\PP3455\") )
				( member ( pinPairRef "@baseboard_fab2_lib.baseboard_fab2(sch_1):\PP3449\") )
				( member ( pinPairRef "@baseboard_fab2_lib.baseboard_fab2(sch_1):\PP3451\") )
				( member ( pinPairRef "@baseboard_fab2_lib.baseboard_fab2(sch_1):\PP3445\") )
				( member ( pinPairRef "@baseboard_fab2_lib.baseboard_fab2(sch_1):\PP3447\") )
				( member ( pinPairRef "@baseboard_fab2_lib.baseboard_fab2(sch_1):\PP3443\") )
				( member ( pinPairRef "@baseboard_fab2_lib.baseboard_fab2(sch_1):\PP3439\") )
				( member ( pinPairRef "@baseboard_fab2_lib.baseboard_fab2(sch_1):\PP3441\") )
				( member ( pinPairRef "@baseboard_fab2_lib.baseboard_fab2(sch_1):\PP3435\") )
				( member ( pinPairRef "@baseboard_fab2_lib.baseboard_fab2(sch_1):\PP3437\") )
				( member ( pinPairRef "@baseboard_fab2_lib.baseboard_fab2(sch_1):\PP3431\") )
				( member ( pinPairRef "@baseboard_fab2_lib.baseboard_fab2(sch_1):\PP3433\") )
				( member ( pinPairRef "@baseboard_fab2_lib.baseboard_fab2(sch_1):\PP3427\") )
				( member ( pinPairRef "@baseboard_fab2_lib.baseboard_fab2(sch_1):\PP3429\") )
				( member ( pinPairRef "@baseboard_fab2_lib.baseboard_fab2(sch_1):\PP3423\") )
				( member ( pinPairRef "@baseboard_fab2_lib.baseboard_fab2(sch_1):\PP3425\") )
				( member ( pinPairRef "@baseboard_fab2_lib.baseboard_fab2(sch_1):\PP3419\") )
				( member ( pinPairRef "@baseboard_fab2_lib.baseboard_fab2(sch_1):\PP3421\") )
				( member ( pinPairRef "@baseboard_fab2_lib.baseboard_fab2(sch_1):\PP3415\") )
				( member ( pinPairRef "@baseboard_fab2_lib.baseboard_fab2(sch_1):\PP3417\") )
				( member ( pinPairRef "@baseboard_fab2_lib.baseboard_fab2(sch_1):\PP3413\") )
				( member ( pinPairRef "@baseboard_fab2_lib.baseboard_fab2(sch_1):\PP3414\") )
				( member ( pinPairRef "@baseboard_fab2_lib.baseboard_fab2(sch_1):\PP3412\") )
				( member ( pinPairRef "@baseboard_fab2_lib.baseboard_fab2(sch_1):\PP3411\") )
				( member ( pinPairRef "@baseboard_fab2_lib.baseboard_fab2(sch_1):\PP3410\") )
				( member ( pinPairRef "@baseboard_fab2_lib.baseboard_fab2(sch_1):\PP3408\") )
				( member ( pinPairRef "@baseboard_fab2_lib.baseboard_fab2(sch_1):\PP3409\") )
				( member ( pinPairRef "@baseboard_fab2_lib.baseboard_fab2(sch_1):\PP3407\") )
				( member ( signalRef "@baseboard_fab2_lib.baseboard_fab2(sch_1):m_k_clk_dp(0)") )
				( objectStatus "MG_DDR_FAR_DIMM-CLK0_CLS_DDR_K_CAC-CLKS" )
			)
			( matchGroup "@crescent_city_bb_fab1_lib.crescent_city_bb_fab1(sch_1):\MG_DDR_NEAR_DIMM-CLK1_CLS_DDR_K_CAC-CLKS\"
				( memberType ( signal ) )
				( member ( pinPairRef "@baseboard_fab2_lib.baseboard_fab2(sch_1):\PP3462\") )
				( member ( pinPairRef "@baseboard_fab2_lib.baseboard_fab2(sch_1):\PP3464\") )
				( member ( pinPairRef "@baseboard_fab2_lib.baseboard_fab2(sch_1):\PP3458\") )
				( member ( pinPairRef "@baseboard_fab2_lib.baseboard_fab2(sch_1):\PP3460\") )
				( member ( pinPairRef "@baseboard_fab2_lib.baseboard_fab2(sch_1):\PP3454\") )
				( member ( pinPairRef "@baseboard_fab2_lib.baseboard_fab2(sch_1):\PP3456\") )
				( member ( pinPairRef "@baseboard_fab2_lib.baseboard_fab2(sch_1):\PP3450\") )
				( member ( pinPairRef "@baseboard_fab2_lib.baseboard_fab2(sch_1):\PP3452\") )
				( member ( pinPairRef "@baseboard_fab2_lib.baseboard_fab2(sch_1):\PP3446\") )
				( member ( pinPairRef "@baseboard_fab2_lib.baseboard_fab2(sch_1):\PP3448\") )
				( member ( pinPairRef "@baseboard_fab2_lib.baseboard_fab2(sch_1):\PP3444\") )
				( member ( pinPairRef "@baseboard_fab2_lib.baseboard_fab2(sch_1):\PP3440\") )
				( member ( pinPairRef "@baseboard_fab2_lib.baseboard_fab2(sch_1):\PP3442\") )
				( member ( pinPairRef "@baseboard_fab2_lib.baseboard_fab2(sch_1):\PP3436\") )
				( member ( pinPairRef "@baseboard_fab2_lib.baseboard_fab2(sch_1):\PP3438\") )
				( member ( pinPairRef "@baseboard_fab2_lib.baseboard_fab2(sch_1):\PP3432\") )
				( member ( pinPairRef "@baseboard_fab2_lib.baseboard_fab2(sch_1):\PP3434\") )
				( member ( pinPairRef "@baseboard_fab2_lib.baseboard_fab2(sch_1):\PP3428\") )
				( member ( pinPairRef "@baseboard_fab2_lib.baseboard_fab2(sch_1):\PP3430\") )
				( member ( pinPairRef "@baseboard_fab2_lib.baseboard_fab2(sch_1):\PP3424\") )
				( member ( pinPairRef "@baseboard_fab2_lib.baseboard_fab2(sch_1):\PP3426\") )
				( member ( pinPairRef "@baseboard_fab2_lib.baseboard_fab2(sch_1):\PP3420\") )
				( member ( pinPairRef "@baseboard_fab2_lib.baseboard_fab2(sch_1):\PP3422\") )
				( member ( pinPairRef "@baseboard_fab2_lib.baseboard_fab2(sch_1):\PP3416\") )
				( member ( pinPairRef "@baseboard_fab2_lib.baseboard_fab2(sch_1):\PP3418\") )
				( member ( pinPairRef "@baseboard_fab2_lib.baseboard_fab2(sch_1):\PP3405\") )
				( member ( pinPairRef "@baseboard_fab2_lib.baseboard_fab2(sch_1):\PP3406\") )
				( member ( pinPairRef "@baseboard_fab2_lib.baseboard_fab2(sch_1):\PP3404\") )
				( member ( pinPairRef "@baseboard_fab2_lib.baseboard_fab2(sch_1):\PP3402\") )
				( member ( pinPairRef "@baseboard_fab2_lib.baseboard_fab2(sch_1):\PP3403\") )
				( member ( pinPairRef "@baseboard_fab2_lib.baseboard_fab2(sch_1):\PP3400\") )
				( member ( pinPairRef "@baseboard_fab2_lib.baseboard_fab2(sch_1):\PP3401\") )
				( member ( pinPairRef "@baseboard_fab2_lib.baseboard_fab2(sch_1):\PP3399\") )
				( member ( signalRef "@baseboard_fab2_lib.baseboard_fab2(sch_1):m_k_clk_dp(2)") )
				( objectStatus "MG_DDR_NEAR_DIMM-CLK1_CLS_DDR_K_CAC-CLKS" )
			)
			( matchGroup "@baseboard_fab2_lib.baseboard_fab2(sch_1):\MG_DDR_CMD_NEAR_DIMM_NG_DDR_K_DLL_1\"
				( memberType ( signal ) )
				( member ( pinPairRef "@baseboard_fab2_lib.baseboard_fab2(sch_1):\PP3462\") )
				( member ( pinPairRef "@baseboard_fab2_lib.baseboard_fab2(sch_1):\PP3464\") )
				( objectStatus "MG_DDR_CMD_NEAR_DIMM_NG_DDR_K_DLL_1" )
			)
			( matchGroup "@baseboard_fab2_lib.baseboard_fab2(sch_1):\MG_DDR_FAR_DIMM_CMD_NG_DDR_K_DLL_2\"
				( memberType ( signal ) )
				( member ( pinPairRef "@baseboard_fab2_lib.baseboard_fab2(sch_1):\PP3457\") )
				( member ( pinPairRef "@baseboard_fab2_lib.baseboard_fab2(sch_1):\PP3459\") )
				( objectStatus "MG_DDR_FAR_DIMM_CMD_NG_DDR_K_DLL_2" )
			)
			( matchGroup "@baseboard_fab2_lib.baseboard_fab2(sch_1):\MG_DDR_CMD_NEAR_DIMM_NG_DDR_K_DLL_2\"
				( memberType ( signal ) )
				( member ( pinPairRef "@baseboard_fab2_lib.baseboard_fab2(sch_1):\PP3458\") )
				( member ( pinPairRef "@baseboard_fab2_lib.baseboard_fab2(sch_1):\PP3460\") )
				( objectStatus "MG_DDR_CMD_NEAR_DIMM_NG_DDR_K_DLL_2" )
			)
			( matchGroup "@baseboard_fab2_lib.baseboard_fab2(sch_1):\MG_DDR_FAR_DIMM_CMD_NG_DDR_K_DLL_3\"
				( memberType ( signal ) )
				( member ( pinPairRef "@baseboard_fab2_lib.baseboard_fab2(sch_1):\PP3453\") )
				( member ( pinPairRef "@baseboard_fab2_lib.baseboard_fab2(sch_1):\PP3455\") )
				( objectStatus "MG_DDR_FAR_DIMM_CMD_NG_DDR_K_DLL_3" )
			)
			( matchGroup "@baseboard_fab2_lib.baseboard_fab2(sch_1):\MG_DDR_CMD_NEAR_DIMM_NG_DDR_K_DLL_3\"
				( memberType ( signal ) )
				( member ( pinPairRef "@baseboard_fab2_lib.baseboard_fab2(sch_1):\PP3454\") )
				( member ( pinPairRef "@baseboard_fab2_lib.baseboard_fab2(sch_1):\PP3456\") )
				( objectStatus "MG_DDR_CMD_NEAR_DIMM_NG_DDR_K_DLL_3" )
			)
			( matchGroup "@baseboard_fab2_lib.baseboard_fab2(sch_1):\MG_DDR_FAR_DIMM_CMD_NG_DDR_K_DLL_4\"
				( memberType ( signal ) )
				( member ( pinPairRef "@baseboard_fab2_lib.baseboard_fab2(sch_1):\PP3449\") )
				( member ( pinPairRef "@baseboard_fab2_lib.baseboard_fab2(sch_1):\PP3451\") )
				( objectStatus "MG_DDR_FAR_DIMM_CMD_NG_DDR_K_DLL_4" )
			)
			( matchGroup "@baseboard_fab2_lib.baseboard_fab2(sch_1):\MG_DDR_CMD_NEAR_DIMM_NG_DDR_K_DLL_4\"
				( memberType ( signal ) )
				( member ( pinPairRef "@baseboard_fab2_lib.baseboard_fab2(sch_1):\PP3450\") )
				( member ( pinPairRef "@baseboard_fab2_lib.baseboard_fab2(sch_1):\PP3452\") )
				( objectStatus "MG_DDR_CMD_NEAR_DIMM_NG_DDR_K_DLL_4" )
			)
			( matchGroup "@baseboard_fab2_lib.baseboard_fab2(sch_1):\MG_DDR_FAR_DIMM_CMD_NG_DDR_K_DLL_5\"
				( memberType ( signal ) )
				( member ( pinPairRef "@baseboard_fab2_lib.baseboard_fab2(sch_1):\PP3445\") )
				( member ( pinPairRef "@baseboard_fab2_lib.baseboard_fab2(sch_1):\PP3447\") )
				( objectStatus "MG_DDR_FAR_DIMM_CMD_NG_DDR_K_DLL_5" )
			)
			( matchGroup "@baseboard_fab2_lib.baseboard_fab2(sch_1):\MG_DDR_CMD_NEAR_DIMM_NG_DDR_K_DLL_5\"
				( memberType ( signal ) )
				( member ( pinPairRef "@baseboard_fab2_lib.baseboard_fab2(sch_1):\PP3446\") )
				( member ( pinPairRef "@baseboard_fab2_lib.baseboard_fab2(sch_1):\PP3448\") )
				( objectStatus "MG_DDR_CMD_NEAR_DIMM_NG_DDR_K_DLL_5" )
			)
			( matchGroup "@baseboard_fab2_lib.baseboard_fab2(sch_1):\MG_DDR_FAR_DIMM_CMD_NG_DDR_K_DLL_6\"
				( memberType ( signal ) )
				( member ( pinPairRef "@baseboard_fab2_lib.baseboard_fab2(sch_1):\PP3443\") )
				( objectStatus "MG_DDR_FAR_DIMM_CMD_NG_DDR_K_DLL_6" )
			)
			( matchGroup "@baseboard_fab2_lib.baseboard_fab2(sch_1):\MG_DDR_CMD_NEAR_DIMM_NG_DDR_K_DLL_6\"
				( memberType ( signal ) )
				( member ( pinPairRef "@baseboard_fab2_lib.baseboard_fab2(sch_1):\PP3444\") )
				( objectStatus "MG_DDR_CMD_NEAR_DIMM_NG_DDR_K_DLL_6" )
			)
			( matchGroup "@baseboard_fab2_lib.baseboard_fab2(sch_1):\MG_DDR_FAR_DIMM_CMD_NG_DDR_K_DLL_7\"
				( memberType ( signal ) )
				( member ( pinPairRef "@baseboard_fab2_lib.baseboard_fab2(sch_1):\PP3439\") )
				( member ( pinPairRef "@baseboard_fab2_lib.baseboard_fab2(sch_1):\PP3441\") )
				( objectStatus "MG_DDR_FAR_DIMM_CMD_NG_DDR_K_DLL_7" )
			)
			( matchGroup "@baseboard_fab2_lib.baseboard_fab2(sch_1):\MG_DDR_CMD_NEAR_DIMM_NG_DDR_K_DLL_7\"
				( memberType ( signal ) )
				( member ( pinPairRef "@baseboard_fab2_lib.baseboard_fab2(sch_1):\PP3440\") )
				( member ( pinPairRef "@baseboard_fab2_lib.baseboard_fab2(sch_1):\PP3442\") )
				( objectStatus "MG_DDR_CMD_NEAR_DIMM_NG_DDR_K_DLL_7" )
			)
			( matchGroup "@baseboard_fab2_lib.baseboard_fab2(sch_1):\MG_DDR_FAR_DIMM_CMD_NG_DDR_K_DLL_8\"
				( memberType ( signal ) )
				( member ( pinPairRef "@baseboard_fab2_lib.baseboard_fab2(sch_1):\PP3435\") )
				( member ( pinPairRef "@baseboard_fab2_lib.baseboard_fab2(sch_1):\PP3437\") )
				( objectStatus "MG_DDR_FAR_DIMM_CMD_NG_DDR_K_DLL_8" )
			)
			( matchGroup "@baseboard_fab2_lib.baseboard_fab2(sch_1):\MG_DDR_CMD_NEAR_DIMM_NG_DDR_K_DLL_8\"
				( memberType ( signal ) )
				( member ( pinPairRef "@baseboard_fab2_lib.baseboard_fab2(sch_1):\PP3436\") )
				( member ( pinPairRef "@baseboard_fab2_lib.baseboard_fab2(sch_1):\PP3438\") )
				( objectStatus "MG_DDR_CMD_NEAR_DIMM_NG_DDR_K_DLL_8" )
			)
			( matchGroup "@baseboard_fab2_lib.baseboard_fab2(sch_1):\MG_DDR_FAR_DIMM_CMD_NG_DDR_K_DLL_9\"
				( memberType ( signal ) )
				( member ( pinPairRef "@baseboard_fab2_lib.baseboard_fab2(sch_1):\PP3431\") )
				( member ( pinPairRef "@baseboard_fab2_lib.baseboard_fab2(sch_1):\PP3433\") )
				( objectStatus "MG_DDR_FAR_DIMM_CMD_NG_DDR_K_DLL_9" )
			)
			( matchGroup "@baseboard_fab2_lib.baseboard_fab2(sch_1):\MG_DDR_CMD_NEAR_DIMM_NG_DDR_K_DLL_9\"
				( memberType ( signal ) )
				( member ( pinPairRef "@baseboard_fab2_lib.baseboard_fab2(sch_1):\PP3432\") )
				( member ( pinPairRef "@baseboard_fab2_lib.baseboard_fab2(sch_1):\PP3434\") )
				( objectStatus "MG_DDR_CMD_NEAR_DIMM_NG_DDR_K_DLL_9" )
			)
			( matchGroup "@baseboard_fab2_lib.baseboard_fab2(sch_1):\MG_DDR_FAR_DIMM_CMD_NG_DDR_K_DLL_10\"
				( memberType ( signal ) )
				( member ( pinPairRef "@baseboard_fab2_lib.baseboard_fab2(sch_1):\PP3427\") )
				( member ( pinPairRef "@baseboard_fab2_lib.baseboard_fab2(sch_1):\PP3429\") )
				( objectStatus "MG_DDR_FAR_DIMM_CMD_NG_DDR_K_DLL_10" )
			)
			( matchGroup "@baseboard_fab2_lib.baseboard_fab2(sch_1):\MG_DDR_CMD_NEAR_DIMM_NG_DDR_K_DLL_10\"
				( memberType ( signal ) )
				( member ( pinPairRef "@baseboard_fab2_lib.baseboard_fab2(sch_1):\PP3428\") )
				( member ( pinPairRef "@baseboard_fab2_lib.baseboard_fab2(sch_1):\PP3430\") )
				( objectStatus "MG_DDR_CMD_NEAR_DIMM_NG_DDR_K_DLL_10" )
			)
			( matchGroup "@baseboard_fab2_lib.baseboard_fab2(sch_1):\MG_DDR_FAR_DIMM_CMD_NG_DDR_K_DLL_11\"
				( memberType ( signal ) )
				( member ( pinPairRef "@baseboard_fab2_lib.baseboard_fab2(sch_1):\PP3423\") )
				( member ( pinPairRef "@baseboard_fab2_lib.baseboard_fab2(sch_1):\PP3425\") )
				( objectStatus "MG_DDR_FAR_DIMM_CMD_NG_DDR_K_DLL_11" )
			)
			( matchGroup "@baseboard_fab2_lib.baseboard_fab2(sch_1):\MG_DDR_CMD_NEAR_DIMM_NG_DDR_K_DLL_11\"
				( memberType ( signal ) )
				( member ( pinPairRef "@baseboard_fab2_lib.baseboard_fab2(sch_1):\PP3424\") )
				( member ( pinPairRef "@baseboard_fab2_lib.baseboard_fab2(sch_1):\PP3426\") )
				( objectStatus "MG_DDR_CMD_NEAR_DIMM_NG_DDR_K_DLL_11" )
			)
			( matchGroup "@baseboard_fab2_lib.baseboard_fab2(sch_1):\MG_DDR_FAR_DIMM_CMD_NG_DDR_K_DLL_12\"
				( memberType ( signal ) )
				( member ( pinPairRef "@baseboard_fab2_lib.baseboard_fab2(sch_1):\PP3419\") )
				( member ( pinPairRef "@baseboard_fab2_lib.baseboard_fab2(sch_1):\PP3421\") )
				( objectStatus "MG_DDR_FAR_DIMM_CMD_NG_DDR_K_DLL_12" )
			)
			( matchGroup "@baseboard_fab2_lib.baseboard_fab2(sch_1):\MG_DDR_CMD_NEAR_DIMM_NG_DDR_K_DLL_12\"
				( memberType ( signal ) )
				( member ( pinPairRef "@baseboard_fab2_lib.baseboard_fab2(sch_1):\PP3420\") )
				( member ( pinPairRef "@baseboard_fab2_lib.baseboard_fab2(sch_1):\PP3422\") )
				( objectStatus "MG_DDR_CMD_NEAR_DIMM_NG_DDR_K_DLL_12" )
			)
			( matchGroup "@baseboard_fab2_lib.baseboard_fab2(sch_1):\MG_DDR_FAR_DIMM_CMD_NG_DDR_K_DLL_13\"
				( memberType ( signal ) )
				( member ( pinPairRef "@baseboard_fab2_lib.baseboard_fab2(sch_1):\PP3415\") )
				( member ( pinPairRef "@baseboard_fab2_lib.baseboard_fab2(sch_1):\PP3417\") )
				( objectStatus "MG_DDR_FAR_DIMM_CMD_NG_DDR_K_DLL_13" )
			)
			( matchGroup "@baseboard_fab2_lib.baseboard_fab2(sch_1):\MG_DDR_CMD_NEAR_DIMM_NG_DDR_K_DLL_13\"
				( memberType ( signal ) )
				( member ( pinPairRef "@baseboard_fab2_lib.baseboard_fab2(sch_1):\PP3416\") )
				( member ( pinPairRef "@baseboard_fab2_lib.baseboard_fab2(sch_1):\PP3418\") )
				( objectStatus "MG_DDR_CMD_NEAR_DIMM_NG_DDR_K_DLL_13" )
			)
			( matchGroup "@baseboard_fab2_lib.baseboard_fab2(sch_1):\MG_DDR_CTRL_NG_DDR_K_DLL_14\"
				( memberType ( signal ) )
				( member ( pinPairRef "@baseboard_fab2_lib.baseboard_fab2(sch_1):\PP3413\") )
				( member ( pinPairRef "@baseboard_fab2_lib.baseboard_fab2(sch_1):\PP3414\") )
				( objectStatus "MG_DDR_CTRL_NG_DDR_K_DLL_14" )
			)
			( matchGroup "@baseboard_fab2_lib.baseboard_fab2(sch_1):\MG_DDR_CTRL_NG_DDR_K_DLL_15\"
				( memberType ( signal ) )
				( member ( pinPairRef "@baseboard_fab2_lib.baseboard_fab2(sch_1):\PP3412\") )
				( objectStatus "MG_DDR_CTRL_NG_DDR_K_DLL_15" )
			)
			( matchGroup "@baseboard_fab2_lib.baseboard_fab2(sch_1):\MG_DDR_CTRL_NG_DDR_K_DLL_16\"
				( memberType ( signal ) )
				( member ( pinPairRef "@baseboard_fab2_lib.baseboard_fab2(sch_1):\PP3411\") )
				( objectStatus "MG_DDR_CTRL_NG_DDR_K_DLL_16" )
			)
			( matchGroup "@baseboard_fab2_lib.baseboard_fab2(sch_1):\MG_DDR_CTRL_NG_DDR_K_DLL_17\"
				( memberType ( signal ) )
				( member ( pinPairRef "@baseboard_fab2_lib.baseboard_fab2(sch_1):\PP3410\") )
				( objectStatus "MG_DDR_CTRL_NG_DDR_K_DLL_17" )
			)
			( matchGroup "@baseboard_fab2_lib.baseboard_fab2(sch_1):\MG_DDR_CTRL_NG_DDR_K_DLL_18\"
				( memberType ( signal ) )
				( member ( pinPairRef "@baseboard_fab2_lib.baseboard_fab2(sch_1):\PP3408\") )
				( member ( pinPairRef "@baseboard_fab2_lib.baseboard_fab2(sch_1):\PP3409\") )
				( objectStatus "MG_DDR_CTRL_NG_DDR_K_DLL_18" )
			)
			( matchGroup "@baseboard_fab2_lib.baseboard_fab2(sch_1):\MG_DDR_CTRL_NG_DDR_K_DLL_19\"
				( memberType ( signal ) )
				( member ( pinPairRef "@baseboard_fab2_lib.baseboard_fab2(sch_1):\PP3407\") )
				( objectStatus "MG_DDR_CTRL_NG_DDR_K_DLL_19" )
			)
			( matchGroup "@baseboard_fab2_lib.baseboard_fab2(sch_1):\MG_DDR_CTRL_NG_DDR_K_DLL_20\"
				( memberType ( signal ) )
				( member ( pinPairRef "@baseboard_fab2_lib.baseboard_fab2(sch_1):\PP3405\") )
				( member ( pinPairRef "@baseboard_fab2_lib.baseboard_fab2(sch_1):\PP3406\") )
				( objectStatus "MG_DDR_CTRL_NG_DDR_K_DLL_20" )
			)
			( matchGroup "@baseboard_fab2_lib.baseboard_fab2(sch_1):\MG_DDR_CTRL_NG_DDR_K_DLL_21\"
				( memberType ( signal ) )
				( member ( pinPairRef "@baseboard_fab2_lib.baseboard_fab2(sch_1):\PP3404\") )
				( objectStatus "MG_DDR_CTRL_NG_DDR_K_DLL_21" )
			)
			( matchGroup "@baseboard_fab2_lib.baseboard_fab2(sch_1):\MG_DDR_CTRL_NG_DDR_K_DLL_22\"
				( memberType ( signal ) )
				( member ( pinPairRef "@baseboard_fab2_lib.baseboard_fab2(sch_1):\PP3402\") )
				( member ( pinPairRef "@baseboard_fab2_lib.baseboard_fab2(sch_1):\PP3403\") )
				( objectStatus "MG_DDR_CTRL_NG_DDR_K_DLL_22" )
			)
			( matchGroup "@baseboard_fab2_lib.baseboard_fab2(sch_1):\MG_DDR_CTRL_NG_DDR_K_DLL_23\"
				( memberType ( signal ) )
				( member ( pinPairRef "@baseboard_fab2_lib.baseboard_fab2(sch_1):\PP3400\") )
				( member ( pinPairRef "@baseboard_fab2_lib.baseboard_fab2(sch_1):\PP3401\") )
				( objectStatus "MG_DDR_CTRL_NG_DDR_K_DLL_23" )
			)
			( matchGroup "@baseboard_fab2_lib.baseboard_fab2(sch_1):\MG_DDR_CTRL_NG_DDR_K_DLL_24\"
				( memberType ( signal ) )
				( member ( pinPairRef "@baseboard_fab2_lib.baseboard_fab2(sch_1):\PP3399\") )
				( objectStatus "MG_DDR_CTRL_NG_DDR_K_DLL_24" )
			)
			( matchGroup "@baseboard_fab2_lib.baseboard_fab2(sch_1):\MG_DDR_FAR_DIMM_CMD_NG_DDR_J_DLL_1\"
				( memberType ( signal ) )
				( member ( pinPairRef "@baseboard_fab2_lib.baseboard_fab2(sch_1):\PP3527\") )
				( member ( pinPairRef "@baseboard_fab2_lib.baseboard_fab2(sch_1):\PP3529\") )
				( objectStatus "MG_DDR_FAR_DIMM_CMD_NG_DDR_J_DLL_1" )
			)
			( matchGroup "@crescent_city_bb_fab1_lib.crescent_city_bb_fab1(sch_1):\MG_DDR_FAR_DIMM-CLK0_CLS_DDR_J_CAC-CLKS\"
				( memberType ( signal ) )
				( member ( pinPairRef "@baseboard_fab2_lib.baseboard_fab2(sch_1):\PP3527\") )
				( member ( pinPairRef "@baseboard_fab2_lib.baseboard_fab2(sch_1):\PP3529\") )
				( member ( pinPairRef "@baseboard_fab2_lib.baseboard_fab2(sch_1):\PP3523\") )
				( member ( pinPairRef "@baseboard_fab2_lib.baseboard_fab2(sch_1):\PP3525\") )
				( member ( pinPairRef "@baseboard_fab2_lib.baseboard_fab2(sch_1):\PP3519\") )
				( member ( pinPairRef "@baseboard_fab2_lib.baseboard_fab2(sch_1):\PP3521\") )
				( member ( pinPairRef "@baseboard_fab2_lib.baseboard_fab2(sch_1):\PP3515\") )
				( member ( pinPairRef "@baseboard_fab2_lib.baseboard_fab2(sch_1):\PP3517\") )
				( member ( pinPairRef "@baseboard_fab2_lib.baseboard_fab2(sch_1):\PP3511\") )
				( member ( pinPairRef "@baseboard_fab2_lib.baseboard_fab2(sch_1):\PP3513\") )
				( member ( pinPairRef "@baseboard_fab2_lib.baseboard_fab2(sch_1):\PP3509\") )
				( member ( pinPairRef "@baseboard_fab2_lib.baseboard_fab2(sch_1):\PP3505\") )
				( member ( pinPairRef "@baseboard_fab2_lib.baseboard_fab2(sch_1):\PP3507\") )
				( member ( pinPairRef "@baseboard_fab2_lib.baseboard_fab2(sch_1):\PP3501\") )
				( member ( pinPairRef "@baseboard_fab2_lib.baseboard_fab2(sch_1):\PP3503\") )
				( member ( pinPairRef "@baseboard_fab2_lib.baseboard_fab2(sch_1):\PP3497\") )
				( member ( pinPairRef "@baseboard_fab2_lib.baseboard_fab2(sch_1):\PP3499\") )
				( member ( pinPairRef "@baseboard_fab2_lib.baseboard_fab2(sch_1):\PP3493\") )
				( member ( pinPairRef "@baseboard_fab2_lib.baseboard_fab2(sch_1):\PP3495\") )
				( member ( pinPairRef "@baseboard_fab2_lib.baseboard_fab2(sch_1):\PP3489\") )
				( member ( pinPairRef "@baseboard_fab2_lib.baseboard_fab2(sch_1):\PP3491\") )
				( member ( pinPairRef "@baseboard_fab2_lib.baseboard_fab2(sch_1):\PP3485\") )
				( member ( pinPairRef "@baseboard_fab2_lib.baseboard_fab2(sch_1):\PP3487\") )
				( member ( pinPairRef "@baseboard_fab2_lib.baseboard_fab2(sch_1):\PP3481\") )
				( member ( pinPairRef "@baseboard_fab2_lib.baseboard_fab2(sch_1):\PP3483\") )
				( member ( pinPairRef "@baseboard_fab2_lib.baseboard_fab2(sch_1):\PP3479\") )
				( member ( pinPairRef "@baseboard_fab2_lib.baseboard_fab2(sch_1):\PP3480\") )
				( member ( pinPairRef "@baseboard_fab2_lib.baseboard_fab2(sch_1):\PP3478\") )
				( member ( pinPairRef "@baseboard_fab2_lib.baseboard_fab2(sch_1):\PP3477\") )
				( member ( pinPairRef "@baseboard_fab2_lib.baseboard_fab2(sch_1):\PP3476\") )
				( member ( pinPairRef "@baseboard_fab2_lib.baseboard_fab2(sch_1):\PP3474\") )
				( member ( pinPairRef "@baseboard_fab2_lib.baseboard_fab2(sch_1):\PP3475\") )
				( member ( pinPairRef "@baseboard_fab2_lib.baseboard_fab2(sch_1):\PP3473\") )
				( member ( signalRef "@baseboard_fab2_lib.baseboard_fab2(sch_1):m_j_clk_dp(0)") )
				( objectStatus "MG_DDR_FAR_DIMM-CLK0_CLS_DDR_J_CAC-CLKS" )
			)
			( matchGroup "@crescent_city_bb_fab1_lib.crescent_city_bb_fab1(sch_1):\MG_DDR_NEAR_DIMM-CLK1_CLS_DDR_J_CAC-CLKS\"
				( memberType ( signal ) )
				( member ( pinPairRef "@baseboard_fab2_lib.baseboard_fab2(sch_1):\PP3528\") )
				( member ( pinPairRef "@baseboard_fab2_lib.baseboard_fab2(sch_1):\PP3530\") )
				( member ( pinPairRef "@baseboard_fab2_lib.baseboard_fab2(sch_1):\PP3524\") )
				( member ( pinPairRef "@baseboard_fab2_lib.baseboard_fab2(sch_1):\PP3526\") )
				( member ( pinPairRef "@baseboard_fab2_lib.baseboard_fab2(sch_1):\PP3520\") )
				( member ( pinPairRef "@baseboard_fab2_lib.baseboard_fab2(sch_1):\PP3522\") )
				( member ( pinPairRef "@baseboard_fab2_lib.baseboard_fab2(sch_1):\PP3516\") )
				( member ( pinPairRef "@baseboard_fab2_lib.baseboard_fab2(sch_1):\PP3518\") )
				( member ( pinPairRef "@baseboard_fab2_lib.baseboard_fab2(sch_1):\PP3512\") )
				( member ( pinPairRef "@baseboard_fab2_lib.baseboard_fab2(sch_1):\PP3514\") )
				( member ( pinPairRef "@baseboard_fab2_lib.baseboard_fab2(sch_1):\PP3510\") )
				( member ( pinPairRef "@baseboard_fab2_lib.baseboard_fab2(sch_1):\PP3506\") )
				( member ( pinPairRef "@baseboard_fab2_lib.baseboard_fab2(sch_1):\PP3508\") )
				( member ( pinPairRef "@baseboard_fab2_lib.baseboard_fab2(sch_1):\PP3502\") )
				( member ( pinPairRef "@baseboard_fab2_lib.baseboard_fab2(sch_1):\PP3504\") )
				( member ( pinPairRef "@baseboard_fab2_lib.baseboard_fab2(sch_1):\PP3498\") )
				( member ( pinPairRef "@baseboard_fab2_lib.baseboard_fab2(sch_1):\PP3500\") )
				( member ( pinPairRef "@baseboard_fab2_lib.baseboard_fab2(sch_1):\PP3494\") )
				( member ( pinPairRef "@baseboard_fab2_lib.baseboard_fab2(sch_1):\PP3496\") )
				( member ( pinPairRef "@baseboard_fab2_lib.baseboard_fab2(sch_1):\PP3490\") )
				( member ( pinPairRef "@baseboard_fab2_lib.baseboard_fab2(sch_1):\PP3492\") )
				( member ( pinPairRef "@baseboard_fab2_lib.baseboard_fab2(sch_1):\PP3486\") )
				( member ( pinPairRef "@baseboard_fab2_lib.baseboard_fab2(sch_1):\PP3488\") )
				( member ( pinPairRef "@baseboard_fab2_lib.baseboard_fab2(sch_1):\PP3482\") )
				( member ( pinPairRef "@baseboard_fab2_lib.baseboard_fab2(sch_1):\PP3484\") )
				( member ( pinPairRef "@baseboard_fab2_lib.baseboard_fab2(sch_1):\PP3471\") )
				( member ( pinPairRef "@baseboard_fab2_lib.baseboard_fab2(sch_1):\PP3472\") )
				( member ( pinPairRef "@baseboard_fab2_lib.baseboard_fab2(sch_1):\PP3470\") )
				( member ( pinPairRef "@baseboard_fab2_lib.baseboard_fab2(sch_1):\PP3468\") )
				( member ( pinPairRef "@baseboard_fab2_lib.baseboard_fab2(sch_1):\PP3469\") )
				( member ( pinPairRef "@baseboard_fab2_lib.baseboard_fab2(sch_1):\PP3466\") )
				( member ( pinPairRef "@baseboard_fab2_lib.baseboard_fab2(sch_1):\PP3467\") )
				( member ( pinPairRef "@baseboard_fab2_lib.baseboard_fab2(sch_1):\PP3465\") )
				( member ( signalRef "@baseboard_fab2_lib.baseboard_fab2(sch_1):m_j_clk_dp(2)") )
				( objectStatus "MG_DDR_NEAR_DIMM-CLK1_CLS_DDR_J_CAC-CLKS" )
			)
			( matchGroup "@baseboard_fab2_lib.baseboard_fab2(sch_1):\MG_DDR_CMD_NEAR_DIMM_NG_DDR_J_DLL_1\"
				( memberType ( signal ) )
				( member ( pinPairRef "@baseboard_fab2_lib.baseboard_fab2(sch_1):\PP3528\") )
				( member ( pinPairRef "@baseboard_fab2_lib.baseboard_fab2(sch_1):\PP3530\") )
				( objectStatus "MG_DDR_CMD_NEAR_DIMM_NG_DDR_J_DLL_1" )
			)
			( matchGroup "@baseboard_fab2_lib.baseboard_fab2(sch_1):\MG_DDR_FAR_DIMM_CMD_NG_DDR_J_DLL_2\"
				( memberType ( signal ) )
				( member ( pinPairRef "@baseboard_fab2_lib.baseboard_fab2(sch_1):\PP3523\") )
				( member ( pinPairRef "@baseboard_fab2_lib.baseboard_fab2(sch_1):\PP3525\") )
				( objectStatus "MG_DDR_FAR_DIMM_CMD_NG_DDR_J_DLL_2" )
			)
			( matchGroup "@baseboard_fab2_lib.baseboard_fab2(sch_1):\MG_DDR_CMD_NEAR_DIMM_NG_DDR_J_DLL_2\"
				( memberType ( signal ) )
				( member ( pinPairRef "@baseboard_fab2_lib.baseboard_fab2(sch_1):\PP3524\") )
				( member ( pinPairRef "@baseboard_fab2_lib.baseboard_fab2(sch_1):\PP3526\") )
				( objectStatus "MG_DDR_CMD_NEAR_DIMM_NG_DDR_J_DLL_2" )
			)
			( matchGroup "@baseboard_fab2_lib.baseboard_fab2(sch_1):\MG_DDR_FAR_DIMM_CMD_NG_DDR_J_DLL_3\"
				( memberType ( signal ) )
				( member ( pinPairRef "@baseboard_fab2_lib.baseboard_fab2(sch_1):\PP3519\") )
				( member ( pinPairRef "@baseboard_fab2_lib.baseboard_fab2(sch_1):\PP3521\") )
				( objectStatus "MG_DDR_FAR_DIMM_CMD_NG_DDR_J_DLL_3" )
			)
			( matchGroup "@baseboard_fab2_lib.baseboard_fab2(sch_1):\MG_DDR_CMD_NEAR_DIMM_NG_DDR_J_DLL_3\"
				( memberType ( signal ) )
				( member ( pinPairRef "@baseboard_fab2_lib.baseboard_fab2(sch_1):\PP3520\") )
				( member ( pinPairRef "@baseboard_fab2_lib.baseboard_fab2(sch_1):\PP3522\") )
				( objectStatus "MG_DDR_CMD_NEAR_DIMM_NG_DDR_J_DLL_3" )
			)
			( matchGroup "@baseboard_fab2_lib.baseboard_fab2(sch_1):\MG_DDR_FAR_DIMM_CMD_NG_DDR_J_DLL_4\"
				( memberType ( signal ) )
				( member ( pinPairRef "@baseboard_fab2_lib.baseboard_fab2(sch_1):\PP3515\") )
				( member ( pinPairRef "@baseboard_fab2_lib.baseboard_fab2(sch_1):\PP3517\") )
				( objectStatus "MG_DDR_FAR_DIMM_CMD_NG_DDR_J_DLL_4" )
			)
			( matchGroup "@baseboard_fab2_lib.baseboard_fab2(sch_1):\MG_DDR_CMD_NEAR_DIMM_NG_DDR_J_DLL_4\"
				( memberType ( signal ) )
				( member ( pinPairRef "@baseboard_fab2_lib.baseboard_fab2(sch_1):\PP3516\") )
				( member ( pinPairRef "@baseboard_fab2_lib.baseboard_fab2(sch_1):\PP3518\") )
				( objectStatus "MG_DDR_CMD_NEAR_DIMM_NG_DDR_J_DLL_4" )
			)
			( matchGroup "@baseboard_fab2_lib.baseboard_fab2(sch_1):\MG_DDR_FAR_DIMM_CMD_NG_DDR_J_DLL_5\"
				( memberType ( signal ) )
				( member ( pinPairRef "@baseboard_fab2_lib.baseboard_fab2(sch_1):\PP3511\") )
				( member ( pinPairRef "@baseboard_fab2_lib.baseboard_fab2(sch_1):\PP3513\") )
				( objectStatus "MG_DDR_FAR_DIMM_CMD_NG_DDR_J_DLL_5" )
			)
			( matchGroup "@baseboard_fab2_lib.baseboard_fab2(sch_1):\MG_DDR_CMD_NEAR_DIMM_NG_DDR_J_DLL_5\"
				( memberType ( signal ) )
				( member ( pinPairRef "@baseboard_fab2_lib.baseboard_fab2(sch_1):\PP3512\") )
				( member ( pinPairRef "@baseboard_fab2_lib.baseboard_fab2(sch_1):\PP3514\") )
				( objectStatus "MG_DDR_CMD_NEAR_DIMM_NG_DDR_J_DLL_5" )
			)
			( matchGroup "@baseboard_fab2_lib.baseboard_fab2(sch_1):\MG_DDR_FAR_DIMM_CMD_NG_DDR_J_DLL_6\"
				( memberType ( signal ) )
				( member ( pinPairRef "@baseboard_fab2_lib.baseboard_fab2(sch_1):\PP3509\") )
				( objectStatus "MG_DDR_FAR_DIMM_CMD_NG_DDR_J_DLL_6" )
			)
			( matchGroup "@baseboard_fab2_lib.baseboard_fab2(sch_1):\MG_DDR_CMD_NEAR_DIMM_NG_DDR_J_DLL_6\"
				( memberType ( signal ) )
				( member ( pinPairRef "@baseboard_fab2_lib.baseboard_fab2(sch_1):\PP3510\") )
				( objectStatus "MG_DDR_CMD_NEAR_DIMM_NG_DDR_J_DLL_6" )
			)
			( matchGroup "@baseboard_fab2_lib.baseboard_fab2(sch_1):\MG_DDR_FAR_DIMM_CMD_NG_DDR_J_DLL_7\"
				( memberType ( signal ) )
				( member ( pinPairRef "@baseboard_fab2_lib.baseboard_fab2(sch_1):\PP3505\") )
				( member ( pinPairRef "@baseboard_fab2_lib.baseboard_fab2(sch_1):\PP3507\") )
				( objectStatus "MG_DDR_FAR_DIMM_CMD_NG_DDR_J_DLL_7" )
			)
			( matchGroup "@baseboard_fab2_lib.baseboard_fab2(sch_1):\MG_DDR_CMD_NEAR_DIMM_NG_DDR_J_DLL_7\"
				( memberType ( signal ) )
				( member ( pinPairRef "@baseboard_fab2_lib.baseboard_fab2(sch_1):\PP3506\") )
				( member ( pinPairRef "@baseboard_fab2_lib.baseboard_fab2(sch_1):\PP3508\") )
				( objectStatus "MG_DDR_CMD_NEAR_DIMM_NG_DDR_J_DLL_7" )
			)
			( matchGroup "@baseboard_fab2_lib.baseboard_fab2(sch_1):\MG_DDR_FAR_DIMM_CMD_NG_DDR_J_DLL_8\"
				( memberType ( signal ) )
				( member ( pinPairRef "@baseboard_fab2_lib.baseboard_fab2(sch_1):\PP3501\") )
				( member ( pinPairRef "@baseboard_fab2_lib.baseboard_fab2(sch_1):\PP3503\") )
				( objectStatus "MG_DDR_FAR_DIMM_CMD_NG_DDR_J_DLL_8" )
			)
			( matchGroup "@baseboard_fab2_lib.baseboard_fab2(sch_1):\MG_DDR_CMD_NEAR_DIMM_NG_DDR_J_DLL_8\"
				( memberType ( signal ) )
				( member ( pinPairRef "@baseboard_fab2_lib.baseboard_fab2(sch_1):\PP3502\") )
				( member ( pinPairRef "@baseboard_fab2_lib.baseboard_fab2(sch_1):\PP3504\") )
				( objectStatus "MG_DDR_CMD_NEAR_DIMM_NG_DDR_J_DLL_8" )
			)
			( matchGroup "@baseboard_fab2_lib.baseboard_fab2(sch_1):\MG_DDR_FAR_DIMM_CMD_NG_DDR_J_DLL_9\"
				( memberType ( signal ) )
				( member ( pinPairRef "@baseboard_fab2_lib.baseboard_fab2(sch_1):\PP3497\") )
				( member ( pinPairRef "@baseboard_fab2_lib.baseboard_fab2(sch_1):\PP3499\") )
				( objectStatus "MG_DDR_FAR_DIMM_CMD_NG_DDR_J_DLL_9" )
			)
			( matchGroup "@baseboard_fab2_lib.baseboard_fab2(sch_1):\MG_DDR_CMD_NEAR_DIMM_NG_DDR_J_DLL_9\"
				( memberType ( signal ) )
				( member ( pinPairRef "@baseboard_fab2_lib.baseboard_fab2(sch_1):\PP3498\") )
				( member ( pinPairRef "@baseboard_fab2_lib.baseboard_fab2(sch_1):\PP3500\") )
				( objectStatus "MG_DDR_CMD_NEAR_DIMM_NG_DDR_J_DLL_9" )
			)
			( matchGroup "@baseboard_fab2_lib.baseboard_fab2(sch_1):\MG_DDR_FAR_DIMM_CMD_NG_DDR_J_DLL_10\"
				( memberType ( signal ) )
				( member ( pinPairRef "@baseboard_fab2_lib.baseboard_fab2(sch_1):\PP3493\") )
				( member ( pinPairRef "@baseboard_fab2_lib.baseboard_fab2(sch_1):\PP3495\") )
				( objectStatus "MG_DDR_FAR_DIMM_CMD_NG_DDR_J_DLL_10" )
			)
			( matchGroup "@baseboard_fab2_lib.baseboard_fab2(sch_1):\MG_DDR_CMD_NEAR_DIMM_NG_DDR_J_DLL_10\"
				( memberType ( signal ) )
				( member ( pinPairRef "@baseboard_fab2_lib.baseboard_fab2(sch_1):\PP3494\") )
				( member ( pinPairRef "@baseboard_fab2_lib.baseboard_fab2(sch_1):\PP3496\") )
				( objectStatus "MG_DDR_CMD_NEAR_DIMM_NG_DDR_J_DLL_10" )
			)
			( matchGroup "@baseboard_fab2_lib.baseboard_fab2(sch_1):\MG_DDR_FAR_DIMM_CMD_NG_DDR_J_DLL_11\"
				( memberType ( signal ) )
				( member ( pinPairRef "@baseboard_fab2_lib.baseboard_fab2(sch_1):\PP3489\") )
				( member ( pinPairRef "@baseboard_fab2_lib.baseboard_fab2(sch_1):\PP3491\") )
				( objectStatus "MG_DDR_FAR_DIMM_CMD_NG_DDR_J_DLL_11" )
			)
			( matchGroup "@baseboard_fab2_lib.baseboard_fab2(sch_1):\MG_DDR_CMD_NEAR_DIMM_NG_DDR_J_DLL_11\"
				( memberType ( signal ) )
				( member ( pinPairRef "@baseboard_fab2_lib.baseboard_fab2(sch_1):\PP3490\") )
				( member ( pinPairRef "@baseboard_fab2_lib.baseboard_fab2(sch_1):\PP3492\") )
				( objectStatus "MG_DDR_CMD_NEAR_DIMM_NG_DDR_J_DLL_11" )
			)
			( matchGroup "@baseboard_fab2_lib.baseboard_fab2(sch_1):\MG_DDR_FAR_DIMM_CMD_NG_DDR_J_DLL_12\"
				( memberType ( signal ) )
				( member ( pinPairRef "@baseboard_fab2_lib.baseboard_fab2(sch_1):\PP3485\") )
				( member ( pinPairRef "@baseboard_fab2_lib.baseboard_fab2(sch_1):\PP3487\") )
				( objectStatus "MG_DDR_FAR_DIMM_CMD_NG_DDR_J_DLL_12" )
			)
			( matchGroup "@baseboard_fab2_lib.baseboard_fab2(sch_1):\MG_DDR_CMD_NEAR_DIMM_NG_DDR_J_DLL_12\"
				( memberType ( signal ) )
				( member ( pinPairRef "@baseboard_fab2_lib.baseboard_fab2(sch_1):\PP3486\") )
				( member ( pinPairRef "@baseboard_fab2_lib.baseboard_fab2(sch_1):\PP3488\") )
				( objectStatus "MG_DDR_CMD_NEAR_DIMM_NG_DDR_J_DLL_12" )
			)
			( matchGroup "@baseboard_fab2_lib.baseboard_fab2(sch_1):\MG_DDR_FAR_DIMM_CMD_NG_DDR_J_DLL_13\"
				( memberType ( signal ) )
				( member ( pinPairRef "@baseboard_fab2_lib.baseboard_fab2(sch_1):\PP3481\") )
				( member ( pinPairRef "@baseboard_fab2_lib.baseboard_fab2(sch_1):\PP3483\") )
				( objectStatus "MG_DDR_FAR_DIMM_CMD_NG_DDR_J_DLL_13" )
			)
			( matchGroup "@baseboard_fab2_lib.baseboard_fab2(sch_1):\MG_DDR_CMD_NEAR_DIMM_NG_DDR_J_DLL_13\"
				( memberType ( signal ) )
				( member ( pinPairRef "@baseboard_fab2_lib.baseboard_fab2(sch_1):\PP3482\") )
				( member ( pinPairRef "@baseboard_fab2_lib.baseboard_fab2(sch_1):\PP3484\") )
				( objectStatus "MG_DDR_CMD_NEAR_DIMM_NG_DDR_J_DLL_13" )
			)
			( matchGroup "@baseboard_fab2_lib.baseboard_fab2(sch_1):\MG_DDR_CTRL_NG_DDR_J_DLL_14\"
				( memberType ( signal ) )
				( member ( pinPairRef "@baseboard_fab2_lib.baseboard_fab2(sch_1):\PP3479\") )
				( member ( pinPairRef "@baseboard_fab2_lib.baseboard_fab2(sch_1):\PP3480\") )
				( objectStatus "MG_DDR_CTRL_NG_DDR_J_DLL_14" )
			)
			( matchGroup "@baseboard_fab2_lib.baseboard_fab2(sch_1):\MG_DDR_CTRL_NG_DDR_J_DLL_15\"
				( memberType ( signal ) )
				( member ( pinPairRef "@baseboard_fab2_lib.baseboard_fab2(sch_1):\PP3478\") )
				( objectStatus "MG_DDR_CTRL_NG_DDR_J_DLL_15" )
			)
			( matchGroup "@baseboard_fab2_lib.baseboard_fab2(sch_1):\MG_DDR_CTRL_NG_DDR_J_DLL_16\"
				( memberType ( signal ) )
				( member ( pinPairRef "@baseboard_fab2_lib.baseboard_fab2(sch_1):\PP3477\") )
				( objectStatus "MG_DDR_CTRL_NG_DDR_J_DLL_16" )
			)
			( matchGroup "@baseboard_fab2_lib.baseboard_fab2(sch_1):\MG_DDR_CTRL_NG_DDR_J_DLL_17\"
				( memberType ( signal ) )
				( member ( pinPairRef "@baseboard_fab2_lib.baseboard_fab2(sch_1):\PP3476\") )
				( objectStatus "MG_DDR_CTRL_NG_DDR_J_DLL_17" )
			)
			( matchGroup "@baseboard_fab2_lib.baseboard_fab2(sch_1):\MG_DDR_CTRL_NG_DDR_J_DLL_18\"
				( memberType ( signal ) )
				( member ( pinPairRef "@baseboard_fab2_lib.baseboard_fab2(sch_1):\PP3474\") )
				( member ( pinPairRef "@baseboard_fab2_lib.baseboard_fab2(sch_1):\PP3475\") )
				( objectStatus "MG_DDR_CTRL_NG_DDR_J_DLL_18" )
			)
			( matchGroup "@baseboard_fab2_lib.baseboard_fab2(sch_1):\MG_DDR_CTRL_NG_DDR_J_DLL_19\"
				( memberType ( signal ) )
				( member ( pinPairRef "@baseboard_fab2_lib.baseboard_fab2(sch_1):\PP3473\") )
				( objectStatus "MG_DDR_CTRL_NG_DDR_J_DLL_19" )
			)
			( matchGroup "@baseboard_fab2_lib.baseboard_fab2(sch_1):\MG_DDR_CTRL_NG_DDR_J_DLL_20\"
				( memberType ( signal ) )
				( member ( pinPairRef "@baseboard_fab2_lib.baseboard_fab2(sch_1):\PP3471\") )
				( member ( pinPairRef "@baseboard_fab2_lib.baseboard_fab2(sch_1):\PP3472\") )
				( objectStatus "MG_DDR_CTRL_NG_DDR_J_DLL_20" )
			)
			( matchGroup "@baseboard_fab2_lib.baseboard_fab2(sch_1):\MG_DDR_CTRL_NG_DDR_J_DLL_21\"
				( memberType ( signal ) )
				( member ( pinPairRef "@baseboard_fab2_lib.baseboard_fab2(sch_1):\PP3470\") )
				( objectStatus "MG_DDR_CTRL_NG_DDR_J_DLL_21" )
			)
			( matchGroup "@baseboard_fab2_lib.baseboard_fab2(sch_1):\MG_DDR_CTRL_NG_DDR_J_DLL_22\"
				( memberType ( signal ) )
				( member ( pinPairRef "@baseboard_fab2_lib.baseboard_fab2(sch_1):\PP3468\") )
				( member ( pinPairRef "@baseboard_fab2_lib.baseboard_fab2(sch_1):\PP3469\") )
				( objectStatus "MG_DDR_CTRL_NG_DDR_J_DLL_22" )
			)
			( matchGroup "@baseboard_fab2_lib.baseboard_fab2(sch_1):\MG_DDR_CTRL_NG_DDR_J_DLL_23\"
				( memberType ( signal ) )
				( member ( pinPairRef "@baseboard_fab2_lib.baseboard_fab2(sch_1):\PP3466\") )
				( member ( pinPairRef "@baseboard_fab2_lib.baseboard_fab2(sch_1):\PP3467\") )
				( objectStatus "MG_DDR_CTRL_NG_DDR_J_DLL_23" )
			)
			( matchGroup "@baseboard_fab2_lib.baseboard_fab2(sch_1):\MG_DDR_CTRL_NG_DDR_J_DLL_24\"
				( memberType ( signal ) )
				( member ( pinPairRef "@baseboard_fab2_lib.baseboard_fab2(sch_1):\PP3465\") )
				( objectStatus "MG_DDR_CTRL_NG_DDR_J_DLL_24" )
			)
			( matchGroup "@baseboard_fab2_lib.baseboard_fab2(sch_1):\MG_DDR_FAR_DIMM_CMD_NG_DDR_H_DLL_1\"
				( memberType ( signal ) )
				( member ( pinPairRef "@baseboard_fab2_lib.baseboard_fab2(sch_1):\PP3593\") )
				( member ( pinPairRef "@baseboard_fab2_lib.baseboard_fab2(sch_1):\PP3595\") )
				( objectStatus "MG_DDR_FAR_DIMM_CMD_NG_DDR_H_DLL_1" )
			)
			( matchGroup "@crescent_city_bb_fab1_lib.crescent_city_bb_fab1(sch_1):\MG_DDR_FAR_DIMM-CLK0_CLS_DDR_H_CAC-CLKS\"
				( memberType ( signal ) )
				( member ( pinPairRef "@baseboard_fab2_lib.baseboard_fab2(sch_1):\PP3593\") )
				( member ( pinPairRef "@baseboard_fab2_lib.baseboard_fab2(sch_1):\PP3595\") )
				( member ( pinPairRef "@baseboard_fab2_lib.baseboard_fab2(sch_1):\PP3589\") )
				( member ( pinPairRef "@baseboard_fab2_lib.baseboard_fab2(sch_1):\PP3591\") )
				( member ( pinPairRef "@baseboard_fab2_lib.baseboard_fab2(sch_1):\PP3585\") )
				( member ( pinPairRef "@baseboard_fab2_lib.baseboard_fab2(sch_1):\PP3587\") )
				( member ( pinPairRef "@baseboard_fab2_lib.baseboard_fab2(sch_1):\PP3581\") )
				( member ( pinPairRef "@baseboard_fab2_lib.baseboard_fab2(sch_1):\PP3583\") )
				( member ( pinPairRef "@baseboard_fab2_lib.baseboard_fab2(sch_1):\PP3577\") )
				( member ( pinPairRef "@baseboard_fab2_lib.baseboard_fab2(sch_1):\PP3579\") )
				( member ( pinPairRef "@baseboard_fab2_lib.baseboard_fab2(sch_1):\PP3575\") )
				( member ( pinPairRef "@baseboard_fab2_lib.baseboard_fab2(sch_1):\PP3571\") )
				( member ( pinPairRef "@baseboard_fab2_lib.baseboard_fab2(sch_1):\PP3573\") )
				( member ( pinPairRef "@baseboard_fab2_lib.baseboard_fab2(sch_1):\PP3567\") )
				( member ( pinPairRef "@baseboard_fab2_lib.baseboard_fab2(sch_1):\PP3569\") )
				( member ( pinPairRef "@baseboard_fab2_lib.baseboard_fab2(sch_1):\PP3563\") )
				( member ( pinPairRef "@baseboard_fab2_lib.baseboard_fab2(sch_1):\PP3565\") )
				( member ( pinPairRef "@baseboard_fab2_lib.baseboard_fab2(sch_1):\PP3559\") )
				( member ( pinPairRef "@baseboard_fab2_lib.baseboard_fab2(sch_1):\PP3561\") )
				( member ( pinPairRef "@baseboard_fab2_lib.baseboard_fab2(sch_1):\PP3555\") )
				( member ( pinPairRef "@baseboard_fab2_lib.baseboard_fab2(sch_1):\PP3557\") )
				( member ( pinPairRef "@baseboard_fab2_lib.baseboard_fab2(sch_1):\PP3551\") )
				( member ( pinPairRef "@baseboard_fab2_lib.baseboard_fab2(sch_1):\PP3553\") )
				( member ( pinPairRef "@baseboard_fab2_lib.baseboard_fab2(sch_1):\PP3547\") )
				( member ( pinPairRef "@baseboard_fab2_lib.baseboard_fab2(sch_1):\PP3549\") )
				( member ( pinPairRef "@baseboard_fab2_lib.baseboard_fab2(sch_1):\PP3545\") )
				( member ( pinPairRef "@baseboard_fab2_lib.baseboard_fab2(sch_1):\PP3546\") )
				( member ( pinPairRef "@baseboard_fab2_lib.baseboard_fab2(sch_1):\PP3544\") )
				( member ( pinPairRef "@baseboard_fab2_lib.baseboard_fab2(sch_1):\PP3543\") )
				( member ( pinPairRef "@baseboard_fab2_lib.baseboard_fab2(sch_1):\PP3542\") )
				( member ( pinPairRef "@baseboard_fab2_lib.baseboard_fab2(sch_1):\PP3540\") )
				( member ( pinPairRef "@baseboard_fab2_lib.baseboard_fab2(sch_1):\PP3541\") )
				( member ( pinPairRef "@baseboard_fab2_lib.baseboard_fab2(sch_1):\PP3539\") )
				( member ( signalRef "@baseboard_fab2_lib.baseboard_fab2(sch_1):m_h_clk_dp(0)") )
				( objectStatus "MG_DDR_FAR_DIMM-CLK0_CLS_DDR_H_CAC-CLKS" )
			)
			( matchGroup "@crescent_city_bb_fab1_lib.crescent_city_bb_fab1(sch_1):\MG_DDR_NEAR_DIMM-CLK1_CLS_DDR_H_CAC-CLKS\"
				( memberType ( signal ) )
				( member ( pinPairRef "@baseboard_fab2_lib.baseboard_fab2(sch_1):\PP3594\") )
				( member ( pinPairRef "@baseboard_fab2_lib.baseboard_fab2(sch_1):\PP3596\") )
				( member ( pinPairRef "@baseboard_fab2_lib.baseboard_fab2(sch_1):\PP3590\") )
				( member ( pinPairRef "@baseboard_fab2_lib.baseboard_fab2(sch_1):\PP3592\") )
				( member ( pinPairRef "@baseboard_fab2_lib.baseboard_fab2(sch_1):\PP3586\") )
				( member ( pinPairRef "@baseboard_fab2_lib.baseboard_fab2(sch_1):\PP3588\") )
				( member ( pinPairRef "@baseboard_fab2_lib.baseboard_fab2(sch_1):\PP3582\") )
				( member ( pinPairRef "@baseboard_fab2_lib.baseboard_fab2(sch_1):\PP3584\") )
				( member ( pinPairRef "@baseboard_fab2_lib.baseboard_fab2(sch_1):\PP3578\") )
				( member ( pinPairRef "@baseboard_fab2_lib.baseboard_fab2(sch_1):\PP3580\") )
				( member ( pinPairRef "@baseboard_fab2_lib.baseboard_fab2(sch_1):\PP3576\") )
				( member ( pinPairRef "@baseboard_fab2_lib.baseboard_fab2(sch_1):\PP3572\") )
				( member ( pinPairRef "@baseboard_fab2_lib.baseboard_fab2(sch_1):\PP3574\") )
				( member ( pinPairRef "@baseboard_fab2_lib.baseboard_fab2(sch_1):\PP3568\") )
				( member ( pinPairRef "@baseboard_fab2_lib.baseboard_fab2(sch_1):\PP3570\") )
				( member ( pinPairRef "@baseboard_fab2_lib.baseboard_fab2(sch_1):\PP3564\") )
				( member ( pinPairRef "@baseboard_fab2_lib.baseboard_fab2(sch_1):\PP3566\") )
				( member ( pinPairRef "@baseboard_fab2_lib.baseboard_fab2(sch_1):\PP3560\") )
				( member ( pinPairRef "@baseboard_fab2_lib.baseboard_fab2(sch_1):\PP3562\") )
				( member ( pinPairRef "@baseboard_fab2_lib.baseboard_fab2(sch_1):\PP3556\") )
				( member ( pinPairRef "@baseboard_fab2_lib.baseboard_fab2(sch_1):\PP3558\") )
				( member ( pinPairRef "@baseboard_fab2_lib.baseboard_fab2(sch_1):\PP3552\") )
				( member ( pinPairRef "@baseboard_fab2_lib.baseboard_fab2(sch_1):\PP3554\") )
				( member ( pinPairRef "@baseboard_fab2_lib.baseboard_fab2(sch_1):\PP3548\") )
				( member ( pinPairRef "@baseboard_fab2_lib.baseboard_fab2(sch_1):\PP3550\") )
				( member ( pinPairRef "@baseboard_fab2_lib.baseboard_fab2(sch_1):\PP3537\") )
				( member ( pinPairRef "@baseboard_fab2_lib.baseboard_fab2(sch_1):\PP3538\") )
				( member ( pinPairRef "@baseboard_fab2_lib.baseboard_fab2(sch_1):\PP3536\") )
				( member ( pinPairRef "@baseboard_fab2_lib.baseboard_fab2(sch_1):\PP3534\") )
				( member ( pinPairRef "@baseboard_fab2_lib.baseboard_fab2(sch_1):\PP3535\") )
				( member ( pinPairRef "@baseboard_fab2_lib.baseboard_fab2(sch_1):\PP3532\") )
				( member ( pinPairRef "@baseboard_fab2_lib.baseboard_fab2(sch_1):\PP3533\") )
				( member ( pinPairRef "@baseboard_fab2_lib.baseboard_fab2(sch_1):\PP3531\") )
				( member ( signalRef "@baseboard_fab2_lib.baseboard_fab2(sch_1):m_h_clk_dp(2)") )
				( objectStatus "MG_DDR_NEAR_DIMM-CLK1_CLS_DDR_H_CAC-CLKS" )
			)
			( matchGroup "@baseboard_fab2_lib.baseboard_fab2(sch_1):\MG_DDR_CMD_NEAR_DIMM_NG_DDR_H_DLL_1\"
				( memberType ( signal ) )
				( member ( pinPairRef "@baseboard_fab2_lib.baseboard_fab2(sch_1):\PP3594\") )
				( member ( pinPairRef "@baseboard_fab2_lib.baseboard_fab2(sch_1):\PP3596\") )
				( objectStatus "MG_DDR_CMD_NEAR_DIMM_NG_DDR_H_DLL_1" )
			)
			( matchGroup "@baseboard_fab2_lib.baseboard_fab2(sch_1):\MG_DDR_FAR_DIMM_CMD_NG_DDR_H_DLL_2\"
				( memberType ( signal ) )
				( member ( pinPairRef "@baseboard_fab2_lib.baseboard_fab2(sch_1):\PP3589\") )
				( member ( pinPairRef "@baseboard_fab2_lib.baseboard_fab2(sch_1):\PP3591\") )
				( objectStatus "MG_DDR_FAR_DIMM_CMD_NG_DDR_H_DLL_2" )
			)
			( matchGroup "@baseboard_fab2_lib.baseboard_fab2(sch_1):\MG_DDR_CMD_NEAR_DIMM_NG_DDR_H_DLL_2\"
				( memberType ( signal ) )
				( member ( pinPairRef "@baseboard_fab2_lib.baseboard_fab2(sch_1):\PP3590\") )
				( member ( pinPairRef "@baseboard_fab2_lib.baseboard_fab2(sch_1):\PP3592\") )
				( objectStatus "MG_DDR_CMD_NEAR_DIMM_NG_DDR_H_DLL_2" )
			)
			( matchGroup "@baseboard_fab2_lib.baseboard_fab2(sch_1):\MG_DDR_FAR_DIMM_CMD_NG_DDR_H_DLL_3\"
				( memberType ( signal ) )
				( member ( pinPairRef "@baseboard_fab2_lib.baseboard_fab2(sch_1):\PP3585\") )
				( member ( pinPairRef "@baseboard_fab2_lib.baseboard_fab2(sch_1):\PP3587\") )
				( objectStatus "MG_DDR_FAR_DIMM_CMD_NG_DDR_H_DLL_3" )
			)
			( matchGroup "@baseboard_fab2_lib.baseboard_fab2(sch_1):\MG_DDR_CMD_NEAR_DIMM_NG_DDR_H_DLL_3\"
				( memberType ( signal ) )
				( member ( pinPairRef "@baseboard_fab2_lib.baseboard_fab2(sch_1):\PP3586\") )
				( member ( pinPairRef "@baseboard_fab2_lib.baseboard_fab2(sch_1):\PP3588\") )
				( objectStatus "MG_DDR_CMD_NEAR_DIMM_NG_DDR_H_DLL_3" )
			)
			( matchGroup "@baseboard_fab2_lib.baseboard_fab2(sch_1):\MG_DDR_FAR_DIMM_CMD_NG_DDR_H_DLL_4\"
				( memberType ( signal ) )
				( member ( pinPairRef "@baseboard_fab2_lib.baseboard_fab2(sch_1):\PP3581\") )
				( member ( pinPairRef "@baseboard_fab2_lib.baseboard_fab2(sch_1):\PP3583\") )
				( objectStatus "MG_DDR_FAR_DIMM_CMD_NG_DDR_H_DLL_4" )
			)
			( matchGroup "@baseboard_fab2_lib.baseboard_fab2(sch_1):\MG_DDR_CMD_NEAR_DIMM_NG_DDR_H_DLL_4\"
				( memberType ( signal ) )
				( member ( pinPairRef "@baseboard_fab2_lib.baseboard_fab2(sch_1):\PP3582\") )
				( member ( pinPairRef "@baseboard_fab2_lib.baseboard_fab2(sch_1):\PP3584\") )
				( objectStatus "MG_DDR_CMD_NEAR_DIMM_NG_DDR_H_DLL_4" )
			)
			( matchGroup "@baseboard_fab2_lib.baseboard_fab2(sch_1):\MG_DDR_FAR_DIMM_CMD_NG_DDR_H_DLL_5\"
				( memberType ( signal ) )
				( member ( pinPairRef "@baseboard_fab2_lib.baseboard_fab2(sch_1):\PP3577\") )
				( member ( pinPairRef "@baseboard_fab2_lib.baseboard_fab2(sch_1):\PP3579\") )
				( objectStatus "MG_DDR_FAR_DIMM_CMD_NG_DDR_H_DLL_5" )
			)
			( matchGroup "@baseboard_fab2_lib.baseboard_fab2(sch_1):\MG_DDR_CMD_NEAR_DIMM_NG_DDR_H_DLL_5\"
				( memberType ( signal ) )
				( member ( pinPairRef "@baseboard_fab2_lib.baseboard_fab2(sch_1):\PP3578\") )
				( member ( pinPairRef "@baseboard_fab2_lib.baseboard_fab2(sch_1):\PP3580\") )
				( objectStatus "MG_DDR_CMD_NEAR_DIMM_NG_DDR_H_DLL_5" )
			)
			( matchGroup "@baseboard_fab2_lib.baseboard_fab2(sch_1):\MG_DDR_FAR_DIMM_CMD_NG_DDR_H_DLL_6\"
				( memberType ( signal ) )
				( member ( pinPairRef "@baseboard_fab2_lib.baseboard_fab2(sch_1):\PP3575\") )
				( objectStatus "MG_DDR_FAR_DIMM_CMD_NG_DDR_H_DLL_6" )
			)
			( matchGroup "@baseboard_fab2_lib.baseboard_fab2(sch_1):\MG_DDR_CMD_NEAR_DIMM_NG_DDR_H_DLL_6\"
				( memberType ( signal ) )
				( member ( pinPairRef "@baseboard_fab2_lib.baseboard_fab2(sch_1):\PP3576\") )
				( objectStatus "MG_DDR_CMD_NEAR_DIMM_NG_DDR_H_DLL_6" )
			)
			( matchGroup "@baseboard_fab2_lib.baseboard_fab2(sch_1):\MG_DDR_FAR_DIMM_CMD_NG_DDR_H_DLL_7\"
				( memberType ( signal ) )
				( member ( pinPairRef "@baseboard_fab2_lib.baseboard_fab2(sch_1):\PP3571\") )
				( member ( pinPairRef "@baseboard_fab2_lib.baseboard_fab2(sch_1):\PP3573\") )
				( objectStatus "MG_DDR_FAR_DIMM_CMD_NG_DDR_H_DLL_7" )
			)
			( matchGroup "@baseboard_fab2_lib.baseboard_fab2(sch_1):\MG_DDR_CMD_NEAR_DIMM_NG_DDR_H_DLL_7\"
				( memberType ( signal ) )
				( member ( pinPairRef "@baseboard_fab2_lib.baseboard_fab2(sch_1):\PP3572\") )
				( member ( pinPairRef "@baseboard_fab2_lib.baseboard_fab2(sch_1):\PP3574\") )
				( objectStatus "MG_DDR_CMD_NEAR_DIMM_NG_DDR_H_DLL_7" )
			)
			( matchGroup "@baseboard_fab2_lib.baseboard_fab2(sch_1):\MG_DDR_FAR_DIMM_CMD_NG_DDR_H_DLL_8\"
				( memberType ( signal ) )
				( member ( pinPairRef "@baseboard_fab2_lib.baseboard_fab2(sch_1):\PP3567\") )
				( member ( pinPairRef "@baseboard_fab2_lib.baseboard_fab2(sch_1):\PP3569\") )
				( objectStatus "MG_DDR_FAR_DIMM_CMD_NG_DDR_H_DLL_8" )
			)
			( matchGroup "@baseboard_fab2_lib.baseboard_fab2(sch_1):\MG_DDR_CMD_NEAR_DIMM_NG_DDR_H_DLL_8\"
				( memberType ( signal ) )
				( member ( pinPairRef "@baseboard_fab2_lib.baseboard_fab2(sch_1):\PP3568\") )
				( member ( pinPairRef "@baseboard_fab2_lib.baseboard_fab2(sch_1):\PP3570\") )
				( objectStatus "MG_DDR_CMD_NEAR_DIMM_NG_DDR_H_DLL_8" )
			)
			( matchGroup "@baseboard_fab2_lib.baseboard_fab2(sch_1):\MG_DDR_FAR_DIMM_CMD_NG_DDR_H_DLL_9\"
				( memberType ( signal ) )
				( member ( pinPairRef "@baseboard_fab2_lib.baseboard_fab2(sch_1):\PP3563\") )
				( member ( pinPairRef "@baseboard_fab2_lib.baseboard_fab2(sch_1):\PP3565\") )
				( objectStatus "MG_DDR_FAR_DIMM_CMD_NG_DDR_H_DLL_9" )
			)
			( matchGroup "@baseboard_fab2_lib.baseboard_fab2(sch_1):\MG_DDR_CMD_NEAR_DIMM_NG_DDR_H_DLL_9\"
				( memberType ( signal ) )
				( member ( pinPairRef "@baseboard_fab2_lib.baseboard_fab2(sch_1):\PP3564\") )
				( member ( pinPairRef "@baseboard_fab2_lib.baseboard_fab2(sch_1):\PP3566\") )
				( objectStatus "MG_DDR_CMD_NEAR_DIMM_NG_DDR_H_DLL_9" )
			)
			( matchGroup "@baseboard_fab2_lib.baseboard_fab2(sch_1):\MG_DDR_FAR_DIMM_CMD_NG_DDR_H_DLL_10\"
				( memberType ( signal ) )
				( member ( pinPairRef "@baseboard_fab2_lib.baseboard_fab2(sch_1):\PP3559\") )
				( member ( pinPairRef "@baseboard_fab2_lib.baseboard_fab2(sch_1):\PP3561\") )
				( objectStatus "MG_DDR_FAR_DIMM_CMD_NG_DDR_H_DLL_10" )
			)
			( matchGroup "@baseboard_fab2_lib.baseboard_fab2(sch_1):\MG_DDR_CMD_NEAR_DIMM_NG_DDR_H_DLL_10\"
				( memberType ( signal ) )
				( member ( pinPairRef "@baseboard_fab2_lib.baseboard_fab2(sch_1):\PP3560\") )
				( member ( pinPairRef "@baseboard_fab2_lib.baseboard_fab2(sch_1):\PP3562\") )
				( objectStatus "MG_DDR_CMD_NEAR_DIMM_NG_DDR_H_DLL_10" )
			)
			( matchGroup "@baseboard_fab2_lib.baseboard_fab2(sch_1):\MG_DDR_FAR_DIMM_CMD_NG_DDR_H_DLL_11\"
				( memberType ( signal ) )
				( member ( pinPairRef "@baseboard_fab2_lib.baseboard_fab2(sch_1):\PP3555\") )
				( member ( pinPairRef "@baseboard_fab2_lib.baseboard_fab2(sch_1):\PP3557\") )
				( objectStatus "MG_DDR_FAR_DIMM_CMD_NG_DDR_H_DLL_11" )
			)
			( matchGroup "@baseboard_fab2_lib.baseboard_fab2(sch_1):\MG_DDR_CMD_NEAR_DIMM_NG_DDR_H_DLL_11\"
				( memberType ( signal ) )
				( member ( pinPairRef "@baseboard_fab2_lib.baseboard_fab2(sch_1):\PP3556\") )
				( member ( pinPairRef "@baseboard_fab2_lib.baseboard_fab2(sch_1):\PP3558\") )
				( objectStatus "MG_DDR_CMD_NEAR_DIMM_NG_DDR_H_DLL_11" )
			)
			( matchGroup "@baseboard_fab2_lib.baseboard_fab2(sch_1):\MG_DDR_FAR_DIMM_CMD_NG_DDR_H_DLL_12\"
				( memberType ( signal ) )
				( member ( pinPairRef "@baseboard_fab2_lib.baseboard_fab2(sch_1):\PP3551\") )
				( member ( pinPairRef "@baseboard_fab2_lib.baseboard_fab2(sch_1):\PP3553\") )
				( objectStatus "MG_DDR_FAR_DIMM_CMD_NG_DDR_H_DLL_12" )
			)
			( matchGroup "@baseboard_fab2_lib.baseboard_fab2(sch_1):\MG_DDR_CMD_NEAR_DIMM_NG_DDR_H_DLL_12\"
				( memberType ( signal ) )
				( member ( pinPairRef "@baseboard_fab2_lib.baseboard_fab2(sch_1):\PP3552\") )
				( member ( pinPairRef "@baseboard_fab2_lib.baseboard_fab2(sch_1):\PP3554\") )
				( objectStatus "MG_DDR_CMD_NEAR_DIMM_NG_DDR_H_DLL_12" )
			)
			( matchGroup "@baseboard_fab2_lib.baseboard_fab2(sch_1):\MG_DDR_FAR_DIMM_CMD_NG_DDR_H_DLL_13\"
				( memberType ( signal ) )
				( member ( pinPairRef "@baseboard_fab2_lib.baseboard_fab2(sch_1):\PP3547\") )
				( member ( pinPairRef "@baseboard_fab2_lib.baseboard_fab2(sch_1):\PP3549\") )
				( objectStatus "MG_DDR_FAR_DIMM_CMD_NG_DDR_H_DLL_13" )
			)
			( matchGroup "@baseboard_fab2_lib.baseboard_fab2(sch_1):\MG_DDR_CMD_NEAR_DIMM_NG_DDR_H_DLL_13\"
				( memberType ( signal ) )
				( member ( pinPairRef "@baseboard_fab2_lib.baseboard_fab2(sch_1):\PP3548\") )
				( member ( pinPairRef "@baseboard_fab2_lib.baseboard_fab2(sch_1):\PP3550\") )
				( objectStatus "MG_DDR_CMD_NEAR_DIMM_NG_DDR_H_DLL_13" )
			)
			( matchGroup "@baseboard_fab2_lib.baseboard_fab2(sch_1):\MG_DDR_CTRL_NG_DDR_H_DLL_14\"
				( memberType ( signal ) )
				( member ( pinPairRef "@baseboard_fab2_lib.baseboard_fab2(sch_1):\PP3545\") )
				( member ( pinPairRef "@baseboard_fab2_lib.baseboard_fab2(sch_1):\PP3546\") )
				( objectStatus "MG_DDR_CTRL_NG_DDR_H_DLL_14" )
			)
			( matchGroup "@baseboard_fab2_lib.baseboard_fab2(sch_1):\MG_DDR_CTRL_NG_DDR_H_DLL_15\"
				( memberType ( signal ) )
				( member ( pinPairRef "@baseboard_fab2_lib.baseboard_fab2(sch_1):\PP3544\") )
				( objectStatus "MG_DDR_CTRL_NG_DDR_H_DLL_15" )
			)
			( matchGroup "@baseboard_fab2_lib.baseboard_fab2(sch_1):\MG_DDR_CTRL_NG_DDR_H_DLL_16\"
				( memberType ( signal ) )
				( member ( pinPairRef "@baseboard_fab2_lib.baseboard_fab2(sch_1):\PP3543\") )
				( objectStatus "MG_DDR_CTRL_NG_DDR_H_DLL_16" )
			)
			( matchGroup "@baseboard_fab2_lib.baseboard_fab2(sch_1):\MG_DDR_CTRL_NG_DDR_H_DLL_17\"
				( memberType ( signal ) )
				( member ( pinPairRef "@baseboard_fab2_lib.baseboard_fab2(sch_1):\PP3542\") )
				( objectStatus "MG_DDR_CTRL_NG_DDR_H_DLL_17" )
			)
			( matchGroup "@baseboard_fab2_lib.baseboard_fab2(sch_1):\MG_DDR_CTRL_NG_DDR_H_DLL_18\"
				( memberType ( signal ) )
				( member ( pinPairRef "@baseboard_fab2_lib.baseboard_fab2(sch_1):\PP3540\") )
				( member ( pinPairRef "@baseboard_fab2_lib.baseboard_fab2(sch_1):\PP3541\") )
				( objectStatus "MG_DDR_CTRL_NG_DDR_H_DLL_18" )
			)
			( matchGroup "@baseboard_fab2_lib.baseboard_fab2(sch_1):\MG_DDR_CTRL_NG_DDR_H_DLL_19\"
				( memberType ( signal ) )
				( member ( pinPairRef "@baseboard_fab2_lib.baseboard_fab2(sch_1):\PP3539\") )
				( objectStatus "MG_DDR_CTRL_NG_DDR_H_DLL_19" )
			)
			( matchGroup "@baseboard_fab2_lib.baseboard_fab2(sch_1):\MG_DDR_CTRL_NG_DDR_H_DLL_20\"
				( memberType ( signal ) )
				( member ( pinPairRef "@baseboard_fab2_lib.baseboard_fab2(sch_1):\PP3537\") )
				( member ( pinPairRef "@baseboard_fab2_lib.baseboard_fab2(sch_1):\PP3538\") )
				( objectStatus "MG_DDR_CTRL_NG_DDR_H_DLL_20" )
			)
			( matchGroup "@baseboard_fab2_lib.baseboard_fab2(sch_1):\MG_DDR_CTRL_NG_DDR_H_DLL_21\"
				( memberType ( signal ) )
				( member ( pinPairRef "@baseboard_fab2_lib.baseboard_fab2(sch_1):\PP3536\") )
				( objectStatus "MG_DDR_CTRL_NG_DDR_H_DLL_21" )
			)
			( matchGroup "@baseboard_fab2_lib.baseboard_fab2(sch_1):\MG_DDR_CTRL_NG_DDR_H_DLL_22\"
				( memberType ( signal ) )
				( member ( pinPairRef "@baseboard_fab2_lib.baseboard_fab2(sch_1):\PP3534\") )
				( member ( pinPairRef "@baseboard_fab2_lib.baseboard_fab2(sch_1):\PP3535\") )
				( objectStatus "MG_DDR_CTRL_NG_DDR_H_DLL_22" )
			)
			( matchGroup "@baseboard_fab2_lib.baseboard_fab2(sch_1):\MG_DDR_CTRL_NG_DDR_H_DLL_23\"
				( memberType ( signal ) )
				( member ( pinPairRef "@baseboard_fab2_lib.baseboard_fab2(sch_1):\PP3532\") )
				( member ( pinPairRef "@baseboard_fab2_lib.baseboard_fab2(sch_1):\PP3533\") )
				( objectStatus "MG_DDR_CTRL_NG_DDR_H_DLL_23" )
			)
			( matchGroup "@baseboard_fab2_lib.baseboard_fab2(sch_1):\MG_DDR_CTRL_NG_DDR_H_DLL_24\"
				( memberType ( signal ) )
				( member ( pinPairRef "@baseboard_fab2_lib.baseboard_fab2(sch_1):\PP3531\") )
				( objectStatus "MG_DDR_CTRL_NG_DDR_H_DLL_24" )
			)
			( matchGroup "@crescent_city_bb_fab1_lib.crescent_city_bb_fab1(sch_1):\MG_DDR_FAR_DIMM-CLK0_CLS_DDR_G_CAC-CLKS\"
				( memberType ( signal ) )
				( member ( pinPairRef "@baseboard_fab2_lib.baseboard_fab2(sch_1):\PP3659\") )
				( member ( pinPairRef "@baseboard_fab2_lib.baseboard_fab2(sch_1):\PP3661\") )
				( member ( pinPairRef "@baseboard_fab2_lib.baseboard_fab2(sch_1):\PP3655\") )
				( member ( pinPairRef "@baseboard_fab2_lib.baseboard_fab2(sch_1):\PP3657\") )
				( member ( pinPairRef "@baseboard_fab2_lib.baseboard_fab2(sch_1):\PP3651\") )
				( member ( pinPairRef "@baseboard_fab2_lib.baseboard_fab2(sch_1):\PP3653\") )
				( member ( pinPairRef "@baseboard_fab2_lib.baseboard_fab2(sch_1):\PP3647\") )
				( member ( pinPairRef "@baseboard_fab2_lib.baseboard_fab2(sch_1):\PP3649\") )
				( member ( pinPairRef "@baseboard_fab2_lib.baseboard_fab2(sch_1):\PP3643\") )
				( member ( pinPairRef "@baseboard_fab2_lib.baseboard_fab2(sch_1):\PP3645\") )
				( member ( pinPairRef "@baseboard_fab2_lib.baseboard_fab2(sch_1):\PP3641\") )
				( member ( pinPairRef "@baseboard_fab2_lib.baseboard_fab2(sch_1):\PP3637\") )
				( member ( pinPairRef "@baseboard_fab2_lib.baseboard_fab2(sch_1):\PP3639\") )
				( member ( pinPairRef "@baseboard_fab2_lib.baseboard_fab2(sch_1):\PP3633\") )
				( member ( pinPairRef "@baseboard_fab2_lib.baseboard_fab2(sch_1):\PP3635\") )
				( member ( pinPairRef "@baseboard_fab2_lib.baseboard_fab2(sch_1):\PP3629\") )
				( member ( pinPairRef "@baseboard_fab2_lib.baseboard_fab2(sch_1):\PP3631\") )
				( member ( pinPairRef "@baseboard_fab2_lib.baseboard_fab2(sch_1):\PP3625\") )
				( member ( pinPairRef "@baseboard_fab2_lib.baseboard_fab2(sch_1):\PP3627\") )
				( member ( pinPairRef "@baseboard_fab2_lib.baseboard_fab2(sch_1):\PP3621\") )
				( member ( pinPairRef "@baseboard_fab2_lib.baseboard_fab2(sch_1):\PP3623\") )
				( member ( pinPairRef "@baseboard_fab2_lib.baseboard_fab2(sch_1):\PP3617\") )
				( member ( pinPairRef "@baseboard_fab2_lib.baseboard_fab2(sch_1):\PP3619\") )
				( member ( pinPairRef "@baseboard_fab2_lib.baseboard_fab2(sch_1):\PP3613\") )
				( member ( pinPairRef "@baseboard_fab2_lib.baseboard_fab2(sch_1):\PP3615\") )
				( member ( pinPairRef "@baseboard_fab2_lib.baseboard_fab2(sch_1):\PP3611\") )
				( member ( pinPairRef "@baseboard_fab2_lib.baseboard_fab2(sch_1):\PP3612\") )
				( member ( pinPairRef "@baseboard_fab2_lib.baseboard_fab2(sch_1):\PP3610\") )
				( member ( pinPairRef "@baseboard_fab2_lib.baseboard_fab2(sch_1):\PP3609\") )
				( member ( pinPairRef "@baseboard_fab2_lib.baseboard_fab2(sch_1):\PP3608\") )
				( member ( pinPairRef "@baseboard_fab2_lib.baseboard_fab2(sch_1):\PP3606\") )
				( member ( pinPairRef "@baseboard_fab2_lib.baseboard_fab2(sch_1):\PP3607\") )
				( member ( pinPairRef "@baseboard_fab2_lib.baseboard_fab2(sch_1):\PP3605\") )
				( member ( signalRef "@baseboard_fab2_lib.baseboard_fab2(sch_1):m_g_clk_dp(0)") )
				( objectStatus "MG_DDR_FAR_DIMM-CLK0_CLS_DDR_G_CAC-CLKS" )
			)
			( matchGroup "@baseboard_fab2_lib.baseboard_fab2(sch_1):\MG_DDR_FAR_DIMM_CMD_NG_DDR_G_DLL_1\"
				( memberType ( signal ) )
				( member ( pinPairRef "@baseboard_fab2_lib.baseboard_fab2(sch_1):\PP3659\") )
				( member ( pinPairRef "@baseboard_fab2_lib.baseboard_fab2(sch_1):\PP3661\") )
				( objectStatus "MG_DDR_FAR_DIMM_CMD_NG_DDR_G_DLL_1" )
			)
			( matchGroup "@baseboard_fab2_lib.baseboard_fab2(sch_1):\MG_DDR_CMD_NEAR_DIMM_NG_DDR_G_DLL_1\"
				( memberType ( signal ) )
				( member ( pinPairRef "@baseboard_fab2_lib.baseboard_fab2(sch_1):\PP3660\") )
				( member ( pinPairRef "@baseboard_fab2_lib.baseboard_fab2(sch_1):\PP3662\") )
				( objectStatus "MG_DDR_CMD_NEAR_DIMM_NG_DDR_G_DLL_1" )
			)
			( matchGroup "@crescent_city_bb_fab1_lib.crescent_city_bb_fab1(sch_1):\MG_DDR_NEAR_DIMM-CLK1_CLS_DDR_G_CAC-CLKS\"
				( memberType ( signal ) )
				( member ( pinPairRef "@baseboard_fab2_lib.baseboard_fab2(sch_1):\PP3660\") )
				( member ( pinPairRef "@baseboard_fab2_lib.baseboard_fab2(sch_1):\PP3662\") )
				( member ( pinPairRef "@baseboard_fab2_lib.baseboard_fab2(sch_1):\PP3656\") )
				( member ( pinPairRef "@baseboard_fab2_lib.baseboard_fab2(sch_1):\PP3658\") )
				( member ( pinPairRef "@baseboard_fab2_lib.baseboard_fab2(sch_1):\PP3652\") )
				( member ( pinPairRef "@baseboard_fab2_lib.baseboard_fab2(sch_1):\PP3654\") )
				( member ( pinPairRef "@baseboard_fab2_lib.baseboard_fab2(sch_1):\PP3648\") )
				( member ( pinPairRef "@baseboard_fab2_lib.baseboard_fab2(sch_1):\PP3650\") )
				( member ( pinPairRef "@baseboard_fab2_lib.baseboard_fab2(sch_1):\PP3644\") )
				( member ( pinPairRef "@baseboard_fab2_lib.baseboard_fab2(sch_1):\PP3646\") )
				( member ( pinPairRef "@baseboard_fab2_lib.baseboard_fab2(sch_1):\PP3642\") )
				( member ( pinPairRef "@baseboard_fab2_lib.baseboard_fab2(sch_1):\PP3638\") )
				( member ( pinPairRef "@baseboard_fab2_lib.baseboard_fab2(sch_1):\PP3640\") )
				( member ( pinPairRef "@baseboard_fab2_lib.baseboard_fab2(sch_1):\PP3634\") )
				( member ( pinPairRef "@baseboard_fab2_lib.baseboard_fab2(sch_1):\PP3636\") )
				( member ( pinPairRef "@baseboard_fab2_lib.baseboard_fab2(sch_1):\PP3630\") )
				( member ( pinPairRef "@baseboard_fab2_lib.baseboard_fab2(sch_1):\PP3632\") )
				( member ( pinPairRef "@baseboard_fab2_lib.baseboard_fab2(sch_1):\PP3626\") )
				( member ( pinPairRef "@baseboard_fab2_lib.baseboard_fab2(sch_1):\PP3628\") )
				( member ( pinPairRef "@baseboard_fab2_lib.baseboard_fab2(sch_1):\PP3622\") )
				( member ( pinPairRef "@baseboard_fab2_lib.baseboard_fab2(sch_1):\PP3624\") )
				( member ( pinPairRef "@baseboard_fab2_lib.baseboard_fab2(sch_1):\PP3618\") )
				( member ( pinPairRef "@baseboard_fab2_lib.baseboard_fab2(sch_1):\PP3620\") )
				( member ( pinPairRef "@baseboard_fab2_lib.baseboard_fab2(sch_1):\PP3614\") )
				( member ( pinPairRef "@baseboard_fab2_lib.baseboard_fab2(sch_1):\PP3616\") )
				( member ( pinPairRef "@baseboard_fab2_lib.baseboard_fab2(sch_1):\PP3603\") )
				( member ( pinPairRef "@baseboard_fab2_lib.baseboard_fab2(sch_1):\PP3604\") )
				( member ( pinPairRef "@baseboard_fab2_lib.baseboard_fab2(sch_1):\PP3602\") )
				( member ( pinPairRef "@baseboard_fab2_lib.baseboard_fab2(sch_1):\PP3600\") )
				( member ( pinPairRef "@baseboard_fab2_lib.baseboard_fab2(sch_1):\PP3601\") )
				( member ( pinPairRef "@baseboard_fab2_lib.baseboard_fab2(sch_1):\PP3598\") )
				( member ( pinPairRef "@baseboard_fab2_lib.baseboard_fab2(sch_1):\PP3599\") )
				( member ( pinPairRef "@baseboard_fab2_lib.baseboard_fab2(sch_1):\PP3597\") )
				( member ( signalRef "@baseboard_fab2_lib.baseboard_fab2(sch_1):m_g_clk_dn(2)") )
				( objectStatus "MG_DDR_NEAR_DIMM-CLK1_CLS_DDR_G_CAC-CLKS" )
			)
			( matchGroup "@baseboard_fab2_lib.baseboard_fab2(sch_1):\MG_DDR_FAR_DIMM_CMD_NG_DDR_G_DLL_2\"
				( memberType ( signal ) )
				( member ( pinPairRef "@baseboard_fab2_lib.baseboard_fab2(sch_1):\PP3655\") )
				( member ( pinPairRef "@baseboard_fab2_lib.baseboard_fab2(sch_1):\PP3657\") )
				( objectStatus "MG_DDR_FAR_DIMM_CMD_NG_DDR_G_DLL_2" )
			)
			( matchGroup "@baseboard_fab2_lib.baseboard_fab2(sch_1):\MG_DDR_CMD_NEAR_DIMM_NG_DDR_G_DLL_2\"
				( memberType ( signal ) )
				( member ( pinPairRef "@baseboard_fab2_lib.baseboard_fab2(sch_1):\PP3656\") )
				( member ( pinPairRef "@baseboard_fab2_lib.baseboard_fab2(sch_1):\PP3658\") )
				( objectStatus "MG_DDR_CMD_NEAR_DIMM_NG_DDR_G_DLL_2" )
			)
			( matchGroup "@baseboard_fab2_lib.baseboard_fab2(sch_1):\MG_DDR_FAR_DIMM_CMD_NG_DDR_G_DLL_3\"
				( memberType ( signal ) )
				( member ( pinPairRef "@baseboard_fab2_lib.baseboard_fab2(sch_1):\PP3651\") )
				( member ( pinPairRef "@baseboard_fab2_lib.baseboard_fab2(sch_1):\PP3653\") )
				( objectStatus "MG_DDR_FAR_DIMM_CMD_NG_DDR_G_DLL_3" )
			)
			( matchGroup "@baseboard_fab2_lib.baseboard_fab2(sch_1):\MG_DDR_CMD_NEAR_DIMM_NG_DDR_G_DLL_3\"
				( memberType ( signal ) )
				( member ( pinPairRef "@baseboard_fab2_lib.baseboard_fab2(sch_1):\PP3652\") )
				( member ( pinPairRef "@baseboard_fab2_lib.baseboard_fab2(sch_1):\PP3654\") )
				( objectStatus "MG_DDR_CMD_NEAR_DIMM_NG_DDR_G_DLL_3" )
			)
			( matchGroup "@baseboard_fab2_lib.baseboard_fab2(sch_1):\MG_DDR_FAR_DIMM_CMD_NG_DDR_G_DLL_4\"
				( memberType ( signal ) )
				( member ( pinPairRef "@baseboard_fab2_lib.baseboard_fab2(sch_1):\PP3647\") )
				( member ( pinPairRef "@baseboard_fab2_lib.baseboard_fab2(sch_1):\PP3649\") )
				( objectStatus "MG_DDR_FAR_DIMM_CMD_NG_DDR_G_DLL_4" )
			)
			( matchGroup "@baseboard_fab2_lib.baseboard_fab2(sch_1):\MG_DDR_CMD_NEAR_DIMM_NG_DDR_G_DLL_4\"
				( memberType ( signal ) )
				( member ( pinPairRef "@baseboard_fab2_lib.baseboard_fab2(sch_1):\PP3648\") )
				( member ( pinPairRef "@baseboard_fab2_lib.baseboard_fab2(sch_1):\PP3650\") )
				( objectStatus "MG_DDR_CMD_NEAR_DIMM_NG_DDR_G_DLL_4" )
			)
			( matchGroup "@baseboard_fab2_lib.baseboard_fab2(sch_1):\MG_DDR_FAR_DIMM_CMD_NG_DDR_G_DLL_5\"
				( memberType ( signal ) )
				( member ( pinPairRef "@baseboard_fab2_lib.baseboard_fab2(sch_1):\PP3643\") )
				( member ( pinPairRef "@baseboard_fab2_lib.baseboard_fab2(sch_1):\PP3645\") )
				( objectStatus "MG_DDR_FAR_DIMM_CMD_NG_DDR_G_DLL_5" )
			)
			( matchGroup "@baseboard_fab2_lib.baseboard_fab2(sch_1):\MG_DDR_CMD_NEAR_DIMM_NG_DDR_G_DLL_5\"
				( memberType ( signal ) )
				( member ( pinPairRef "@baseboard_fab2_lib.baseboard_fab2(sch_1):\PP3644\") )
				( member ( pinPairRef "@baseboard_fab2_lib.baseboard_fab2(sch_1):\PP3646\") )
				( objectStatus "MG_DDR_CMD_NEAR_DIMM_NG_DDR_G_DLL_5" )
			)
			( matchGroup "@baseboard_fab2_lib.baseboard_fab2(sch_1):\MG_DDR_FAR_DIMM_CMD_NG_DDR_G_DLL_6\"
				( memberType ( signal ) )
				( member ( pinPairRef "@baseboard_fab2_lib.baseboard_fab2(sch_1):\PP3641\") )
				( objectStatus "MG_DDR_FAR_DIMM_CMD_NG_DDR_G_DLL_6" )
			)
			( matchGroup "@baseboard_fab2_lib.baseboard_fab2(sch_1):\MG_DDR_CMD_NEAR_DIMM_NG_DDR_G_DLL_6\"
				( memberType ( signal ) )
				( member ( pinPairRef "@baseboard_fab2_lib.baseboard_fab2(sch_1):\PP3642\") )
				( objectStatus "MG_DDR_CMD_NEAR_DIMM_NG_DDR_G_DLL_6" )
			)
			( matchGroup "@baseboard_fab2_lib.baseboard_fab2(sch_1):\MG_DDR_FAR_DIMM_CMD_NG_DDR_G_DLL_7\"
				( memberType ( signal ) )
				( member ( pinPairRef "@baseboard_fab2_lib.baseboard_fab2(sch_1):\PP3637\") )
				( member ( pinPairRef "@baseboard_fab2_lib.baseboard_fab2(sch_1):\PP3639\") )
				( objectStatus "MG_DDR_FAR_DIMM_CMD_NG_DDR_G_DLL_7" )
			)
			( matchGroup "@baseboard_fab2_lib.baseboard_fab2(sch_1):\MG_DDR_CMD_NEAR_DIMM_NG_DDR_G_DLL_7\"
				( memberType ( signal ) )
				( member ( pinPairRef "@baseboard_fab2_lib.baseboard_fab2(sch_1):\PP3638\") )
				( member ( pinPairRef "@baseboard_fab2_lib.baseboard_fab2(sch_1):\PP3640\") )
				( objectStatus "MG_DDR_CMD_NEAR_DIMM_NG_DDR_G_DLL_7" )
			)
			( matchGroup "@baseboard_fab2_lib.baseboard_fab2(sch_1):\MG_DDR_FAR_DIMM_CMD_NG_DDR_G_DLL_8\"
				( memberType ( signal ) )
				( member ( pinPairRef "@baseboard_fab2_lib.baseboard_fab2(sch_1):\PP3633\") )
				( member ( pinPairRef "@baseboard_fab2_lib.baseboard_fab2(sch_1):\PP3635\") )
				( objectStatus "MG_DDR_FAR_DIMM_CMD_NG_DDR_G_DLL_8" )
			)
			( matchGroup "@baseboard_fab2_lib.baseboard_fab2(sch_1):\MG_DDR_CMD_NEAR_DIMM_NG_DDR_G_DLL_8\"
				( memberType ( signal ) )
				( member ( pinPairRef "@baseboard_fab2_lib.baseboard_fab2(sch_1):\PP3634\") )
				( member ( pinPairRef "@baseboard_fab2_lib.baseboard_fab2(sch_1):\PP3636\") )
				( objectStatus "MG_DDR_CMD_NEAR_DIMM_NG_DDR_G_DLL_8" )
			)
			( matchGroup "@baseboard_fab2_lib.baseboard_fab2(sch_1):\MG_DDR_FAR_DIMM_CMD_NG_DDR_G_DLL_9\"
				( memberType ( signal ) )
				( member ( pinPairRef "@baseboard_fab2_lib.baseboard_fab2(sch_1):\PP3629\") )
				( member ( pinPairRef "@baseboard_fab2_lib.baseboard_fab2(sch_1):\PP3631\") )
				( objectStatus "MG_DDR_FAR_DIMM_CMD_NG_DDR_G_DLL_9" )
			)
			( matchGroup "@baseboard_fab2_lib.baseboard_fab2(sch_1):\MG_DDR_CMD_NEAR_DIMM_NG_DDR_G_DLL_9\"
				( memberType ( signal ) )
				( member ( pinPairRef "@baseboard_fab2_lib.baseboard_fab2(sch_1):\PP3630\") )
				( member ( pinPairRef "@baseboard_fab2_lib.baseboard_fab2(sch_1):\PP3632\") )
				( objectStatus "MG_DDR_CMD_NEAR_DIMM_NG_DDR_G_DLL_9" )
			)
			( matchGroup "@baseboard_fab2_lib.baseboard_fab2(sch_1):\MG_DDR_FAR_DIMM_CMD_NG_DDR_G_DLL_10\"
				( memberType ( signal ) )
				( member ( pinPairRef "@baseboard_fab2_lib.baseboard_fab2(sch_1):\PP3625\") )
				( member ( pinPairRef "@baseboard_fab2_lib.baseboard_fab2(sch_1):\PP3627\") )
				( objectStatus "MG_DDR_FAR_DIMM_CMD_NG_DDR_G_DLL_10" )
			)
			( matchGroup "@baseboard_fab2_lib.baseboard_fab2(sch_1):\MG_DDR_CMD_NEAR_DIMM_NG_DDR_G_DLL_10\"
				( memberType ( signal ) )
				( member ( pinPairRef "@baseboard_fab2_lib.baseboard_fab2(sch_1):\PP3626\") )
				( member ( pinPairRef "@baseboard_fab2_lib.baseboard_fab2(sch_1):\PP3628\") )
				( objectStatus "MG_DDR_CMD_NEAR_DIMM_NG_DDR_G_DLL_10" )
			)
			( matchGroup "@baseboard_fab2_lib.baseboard_fab2(sch_1):\MG_DDR_FAR_DIMM_CMD_NG_DDR_G_DLL_11\"
				( memberType ( signal ) )
				( member ( pinPairRef "@baseboard_fab2_lib.baseboard_fab2(sch_1):\PP3621\") )
				( member ( pinPairRef "@baseboard_fab2_lib.baseboard_fab2(sch_1):\PP3623\") )
				( objectStatus "MG_DDR_FAR_DIMM_CMD_NG_DDR_G_DLL_11" )
			)
			( matchGroup "@baseboard_fab2_lib.baseboard_fab2(sch_1):\MG_DDR_CMD_NEAR_DIMM_NG_DDR_G_DLL_11\"
				( memberType ( signal ) )
				( member ( pinPairRef "@baseboard_fab2_lib.baseboard_fab2(sch_1):\PP3622\") )
				( member ( pinPairRef "@baseboard_fab2_lib.baseboard_fab2(sch_1):\PP3624\") )
				( objectStatus "MG_DDR_CMD_NEAR_DIMM_NG_DDR_G_DLL_11" )
			)
			( matchGroup "@baseboard_fab2_lib.baseboard_fab2(sch_1):\MG_DDR_FAR_DIMM_CMD_NG_DDR_G_DLL_12\"
				( memberType ( signal ) )
				( member ( pinPairRef "@baseboard_fab2_lib.baseboard_fab2(sch_1):\PP3617\") )
				( member ( pinPairRef "@baseboard_fab2_lib.baseboard_fab2(sch_1):\PP3619\") )
				( objectStatus "MG_DDR_FAR_DIMM_CMD_NG_DDR_G_DLL_12" )
			)
			( matchGroup "@baseboard_fab2_lib.baseboard_fab2(sch_1):\MG_DDR_CMD_NEAR_DIMM_NG_DDR_G_DLL_12\"
				( memberType ( signal ) )
				( member ( pinPairRef "@baseboard_fab2_lib.baseboard_fab2(sch_1):\PP3618\") )
				( member ( pinPairRef "@baseboard_fab2_lib.baseboard_fab2(sch_1):\PP3620\") )
				( objectStatus "MG_DDR_CMD_NEAR_DIMM_NG_DDR_G_DLL_12" )
			)
			( matchGroup "@baseboard_fab2_lib.baseboard_fab2(sch_1):\MG_DDR_FAR_DIMM_CMD_NG_DDR_G_DLL_13\"
				( memberType ( signal ) )
				( member ( pinPairRef "@baseboard_fab2_lib.baseboard_fab2(sch_1):\PP3613\") )
				( member ( pinPairRef "@baseboard_fab2_lib.baseboard_fab2(sch_1):\PP3615\") )
				( objectStatus "MG_DDR_FAR_DIMM_CMD_NG_DDR_G_DLL_13" )
			)
			( matchGroup "@baseboard_fab2_lib.baseboard_fab2(sch_1):\MG_DDR_CMD_NEAR_DIMM_NG_DDR_G_DLL_13\"
				( memberType ( signal ) )
				( member ( pinPairRef "@baseboard_fab2_lib.baseboard_fab2(sch_1):\PP3614\") )
				( member ( pinPairRef "@baseboard_fab2_lib.baseboard_fab2(sch_1):\PP3616\") )
				( objectStatus "MG_DDR_CMD_NEAR_DIMM_NG_DDR_G_DLL_13" )
			)
			( matchGroup "@baseboard_fab2_lib.baseboard_fab2(sch_1):\MG_DDR_CTRL_NG_DDR_G_DLL_14\"
				( memberType ( signal ) )
				( member ( pinPairRef "@baseboard_fab2_lib.baseboard_fab2(sch_1):\PP3611\") )
				( member ( pinPairRef "@baseboard_fab2_lib.baseboard_fab2(sch_1):\PP3612\") )
				( objectStatus "MG_DDR_CTRL_NG_DDR_G_DLL_14" )
			)
			( matchGroup "@baseboard_fab2_lib.baseboard_fab2(sch_1):\MG_DDR_CTRL_NG_DDR_G_DLL_15\"
				( memberType ( signal ) )
				( member ( pinPairRef "@baseboard_fab2_lib.baseboard_fab2(sch_1):\PP3610\") )
				( objectStatus "MG_DDR_CTRL_NG_DDR_G_DLL_15" )
			)
			( matchGroup "@baseboard_fab2_lib.baseboard_fab2(sch_1):\MG_DDR_CTRL_NG_DDR_G_DLL_16\"
				( memberType ( signal ) )
				( member ( pinPairRef "@baseboard_fab2_lib.baseboard_fab2(sch_1):\PP3609\") )
				( objectStatus "MG_DDR_CTRL_NG_DDR_G_DLL_16" )
			)
			( matchGroup "@baseboard_fab2_lib.baseboard_fab2(sch_1):\MG_DDR_CTRL_NG_DDR_G_DLL_17\"
				( memberType ( signal ) )
				( member ( pinPairRef "@baseboard_fab2_lib.baseboard_fab2(sch_1):\PP3608\") )
				( objectStatus "MG_DDR_CTRL_NG_DDR_G_DLL_17" )
			)
			( matchGroup "@baseboard_fab2_lib.baseboard_fab2(sch_1):\MG_DDR_CTRL_NG_DDR_G_DLL_18\"
				( memberType ( signal ) )
				( member ( pinPairRef "@baseboard_fab2_lib.baseboard_fab2(sch_1):\PP3606\") )
				( member ( pinPairRef "@baseboard_fab2_lib.baseboard_fab2(sch_1):\PP3607\") )
				( objectStatus "MG_DDR_CTRL_NG_DDR_G_DLL_18" )
			)
			( matchGroup "@baseboard_fab2_lib.baseboard_fab2(sch_1):\MG_DDR_CTRL_NG_DDR_G_DLL_19\"
				( memberType ( signal ) )
				( member ( pinPairRef "@baseboard_fab2_lib.baseboard_fab2(sch_1):\PP3605\") )
				( objectStatus "MG_DDR_CTRL_NG_DDR_G_DLL_19" )
			)
			( matchGroup "@baseboard_fab2_lib.baseboard_fab2(sch_1):\MG_DDR_CTRL_NG_DDR_G_DLL_20\"
				( memberType ( signal ) )
				( member ( pinPairRef "@baseboard_fab2_lib.baseboard_fab2(sch_1):\PP3603\") )
				( member ( pinPairRef "@baseboard_fab2_lib.baseboard_fab2(sch_1):\PP3604\") )
				( objectStatus "MG_DDR_CTRL_NG_DDR_G_DLL_20" )
			)
			( matchGroup "@baseboard_fab2_lib.baseboard_fab2(sch_1):\MG_DDR_CTRL_NG_DDR_G_DLL_21\"
				( memberType ( signal ) )
				( member ( pinPairRef "@baseboard_fab2_lib.baseboard_fab2(sch_1):\PP3602\") )
				( objectStatus "MG_DDR_CTRL_NG_DDR_G_DLL_21" )
			)
			( matchGroup "@baseboard_fab2_lib.baseboard_fab2(sch_1):\MG_DDR_CTRL_NG_DDR_G_DLL_22\"
				( memberType ( signal ) )
				( member ( pinPairRef "@baseboard_fab2_lib.baseboard_fab2(sch_1):\PP3600\") )
				( member ( pinPairRef "@baseboard_fab2_lib.baseboard_fab2(sch_1):\PP3601\") )
				( objectStatus "MG_DDR_CTRL_NG_DDR_G_DLL_22" )
			)
			( matchGroup "@baseboard_fab2_lib.baseboard_fab2(sch_1):\MG_DDR_CTRL_NG_DDR_G_DLL_23\"
				( memberType ( signal ) )
				( member ( pinPairRef "@baseboard_fab2_lib.baseboard_fab2(sch_1):\PP3598\") )
				( member ( pinPairRef "@baseboard_fab2_lib.baseboard_fab2(sch_1):\PP3599\") )
				( objectStatus "MG_DDR_CTRL_NG_DDR_G_DLL_23" )
			)
			( matchGroup "@baseboard_fab2_lib.baseboard_fab2(sch_1):\MG_DDR_CTRL_NG_DDR_G_DLL_24\"
				( memberType ( signal ) )
				( member ( pinPairRef "@baseboard_fab2_lib.baseboard_fab2(sch_1):\PP3597\") )
				( objectStatus "MG_DDR_CTRL_NG_DDR_G_DLL_24" )
			)
			( matchGroup "@crescent_city_bb_fab1_lib.crescent_city_bb_fab1(sch_1):\MG_DDR_FAR_DIMM-CLK0_CLS_DDR_F_CAC-CLKS\"
				( memberType ( signal ) )
				( member ( pinPairRef "@baseboard_fab2_lib.baseboard_fab2(sch_1):\PP3725\") )
				( member ( pinPairRef "@baseboard_fab2_lib.baseboard_fab2(sch_1):\PP3727\") )
				( member ( pinPairRef "@baseboard_fab2_lib.baseboard_fab2(sch_1):\PP3721\") )
				( member ( pinPairRef "@baseboard_fab2_lib.baseboard_fab2(sch_1):\PP3723\") )
				( member ( pinPairRef "@baseboard_fab2_lib.baseboard_fab2(sch_1):\PP3717\") )
				( member ( pinPairRef "@baseboard_fab2_lib.baseboard_fab2(sch_1):\PP3719\") )
				( member ( pinPairRef "@baseboard_fab2_lib.baseboard_fab2(sch_1):\PP3713\") )
				( member ( pinPairRef "@baseboard_fab2_lib.baseboard_fab2(sch_1):\PP3715\") )
				( member ( pinPairRef "@baseboard_fab2_lib.baseboard_fab2(sch_1):\PP3709\") )
				( member ( pinPairRef "@baseboard_fab2_lib.baseboard_fab2(sch_1):\PP3711\") )
				( member ( pinPairRef "@baseboard_fab2_lib.baseboard_fab2(sch_1):\PP3707\") )
				( member ( pinPairRef "@baseboard_fab2_lib.baseboard_fab2(sch_1):\PP3703\") )
				( member ( pinPairRef "@baseboard_fab2_lib.baseboard_fab2(sch_1):\PP3705\") )
				( member ( pinPairRef "@baseboard_fab2_lib.baseboard_fab2(sch_1):\PP3699\") )
				( member ( pinPairRef "@baseboard_fab2_lib.baseboard_fab2(sch_1):\PP3701\") )
				( member ( pinPairRef "@baseboard_fab2_lib.baseboard_fab2(sch_1):\PP3695\") )
				( member ( pinPairRef "@baseboard_fab2_lib.baseboard_fab2(sch_1):\PP3697\") )
				( member ( pinPairRef "@baseboard_fab2_lib.baseboard_fab2(sch_1):\PP3691\") )
				( member ( pinPairRef "@baseboard_fab2_lib.baseboard_fab2(sch_1):\PP3693\") )
				( member ( pinPairRef "@baseboard_fab2_lib.baseboard_fab2(sch_1):\PP3687\") )
				( member ( pinPairRef "@baseboard_fab2_lib.baseboard_fab2(sch_1):\PP3689\") )
				( member ( pinPairRef "@baseboard_fab2_lib.baseboard_fab2(sch_1):\PP3683\") )
				( member ( pinPairRef "@baseboard_fab2_lib.baseboard_fab2(sch_1):\PP3685\") )
				( member ( pinPairRef "@baseboard_fab2_lib.baseboard_fab2(sch_1):\PP3679\") )
				( member ( pinPairRef "@baseboard_fab2_lib.baseboard_fab2(sch_1):\PP3681\") )
				( member ( pinPairRef "@baseboard_fab2_lib.baseboard_fab2(sch_1):\PP3677\") )
				( member ( pinPairRef "@baseboard_fab2_lib.baseboard_fab2(sch_1):\PP3678\") )
				( member ( pinPairRef "@baseboard_fab2_lib.baseboard_fab2(sch_1):\PP3676\") )
				( member ( pinPairRef "@baseboard_fab2_lib.baseboard_fab2(sch_1):\PP3675\") )
				( member ( pinPairRef "@baseboard_fab2_lib.baseboard_fab2(sch_1):\PP3674\") )
				( member ( pinPairRef "@baseboard_fab2_lib.baseboard_fab2(sch_1):\PP3672\") )
				( member ( pinPairRef "@baseboard_fab2_lib.baseboard_fab2(sch_1):\PP3673\") )
				( member ( pinPairRef "@baseboard_fab2_lib.baseboard_fab2(sch_1):\PP3671\") )
				( member ( signalRef "@baseboard_fab2_lib.baseboard_fab2(sch_1):m_f_clk_dp(0)") )
				( objectStatus "MG_DDR_FAR_DIMM-CLK0_CLS_DDR_F_CAC-CLKS" )
			)
			( matchGroup "@baseboard_fab2_lib.baseboard_fab2(sch_1):\MG_DDR_FAR_DIMM_CMD_NG_DDR_F_DLL_1\"
				( memberType ( signal ) )
				( member ( pinPairRef "@baseboard_fab2_lib.baseboard_fab2(sch_1):\PP3725\") )
				( member ( pinPairRef "@baseboard_fab2_lib.baseboard_fab2(sch_1):\PP3727\") )
				( objectStatus "MG_DDR_FAR_DIMM_CMD_NG_DDR_F_DLL_1" )
			)
			( matchGroup "@baseboard_fab2_lib.baseboard_fab2(sch_1):\MG_DDR_CMD_NEAR_DIMM_NG_DDR_F_DLL_1\"
				( memberType ( signal ) )
				( member ( pinPairRef "@baseboard_fab2_lib.baseboard_fab2(sch_1):\PP3726\") )
				( member ( pinPairRef "@baseboard_fab2_lib.baseboard_fab2(sch_1):\PP3728\") )
				( objectStatus "MG_DDR_CMD_NEAR_DIMM_NG_DDR_F_DLL_1" )
			)
			( matchGroup "@crescent_city_bb_fab1_lib.crescent_city_bb_fab1(sch_1):\MG_DDR_NEAR_DIMM-CLK1_CLS_DDR_F_CAC-CLKS\"
				( memberType ( signal ) )
				( member ( pinPairRef "@baseboard_fab2_lib.baseboard_fab2(sch_1):\PP3726\") )
				( member ( pinPairRef "@baseboard_fab2_lib.baseboard_fab2(sch_1):\PP3728\") )
				( member ( pinPairRef "@baseboard_fab2_lib.baseboard_fab2(sch_1):\PP3722\") )
				( member ( pinPairRef "@baseboard_fab2_lib.baseboard_fab2(sch_1):\PP3724\") )
				( member ( pinPairRef "@baseboard_fab2_lib.baseboard_fab2(sch_1):\PP3718\") )
				( member ( pinPairRef "@baseboard_fab2_lib.baseboard_fab2(sch_1):\PP3720\") )
				( member ( pinPairRef "@baseboard_fab2_lib.baseboard_fab2(sch_1):\PP3714\") )
				( member ( pinPairRef "@baseboard_fab2_lib.baseboard_fab2(sch_1):\PP3716\") )
				( member ( pinPairRef "@baseboard_fab2_lib.baseboard_fab2(sch_1):\PP3710\") )
				( member ( pinPairRef "@baseboard_fab2_lib.baseboard_fab2(sch_1):\PP3712\") )
				( member ( pinPairRef "@baseboard_fab2_lib.baseboard_fab2(sch_1):\PP3708\") )
				( member ( pinPairRef "@baseboard_fab2_lib.baseboard_fab2(sch_1):\PP3704\") )
				( member ( pinPairRef "@baseboard_fab2_lib.baseboard_fab2(sch_1):\PP3706\") )
				( member ( pinPairRef "@baseboard_fab2_lib.baseboard_fab2(sch_1):\PP3700\") )
				( member ( pinPairRef "@baseboard_fab2_lib.baseboard_fab2(sch_1):\PP3702\") )
				( member ( pinPairRef "@baseboard_fab2_lib.baseboard_fab2(sch_1):\PP3696\") )
				( member ( pinPairRef "@baseboard_fab2_lib.baseboard_fab2(sch_1):\PP3698\") )
				( member ( pinPairRef "@baseboard_fab2_lib.baseboard_fab2(sch_1):\PP3692\") )
				( member ( pinPairRef "@baseboard_fab2_lib.baseboard_fab2(sch_1):\PP3694\") )
				( member ( pinPairRef "@baseboard_fab2_lib.baseboard_fab2(sch_1):\PP3688\") )
				( member ( pinPairRef "@baseboard_fab2_lib.baseboard_fab2(sch_1):\PP3690\") )
				( member ( pinPairRef "@baseboard_fab2_lib.baseboard_fab2(sch_1):\PP3684\") )
				( member ( pinPairRef "@baseboard_fab2_lib.baseboard_fab2(sch_1):\PP3686\") )
				( member ( pinPairRef "@baseboard_fab2_lib.baseboard_fab2(sch_1):\PP3680\") )
				( member ( pinPairRef "@baseboard_fab2_lib.baseboard_fab2(sch_1):\PP3682\") )
				( member ( pinPairRef "@baseboard_fab2_lib.baseboard_fab2(sch_1):\PP3669\") )
				( member ( pinPairRef "@baseboard_fab2_lib.baseboard_fab2(sch_1):\PP3670\") )
				( member ( pinPairRef "@baseboard_fab2_lib.baseboard_fab2(sch_1):\PP3668\") )
				( member ( pinPairRef "@baseboard_fab2_lib.baseboard_fab2(sch_1):\PP3666\") )
				( member ( pinPairRef "@baseboard_fab2_lib.baseboard_fab2(sch_1):\PP3667\") )
				( member ( pinPairRef "@baseboard_fab2_lib.baseboard_fab2(sch_1):\PP3664\") )
				( member ( pinPairRef "@baseboard_fab2_lib.baseboard_fab2(sch_1):\PP3665\") )
				( member ( pinPairRef "@baseboard_fab2_lib.baseboard_fab2(sch_1):\PP3663\") )
				( member ( signalRef "@baseboard_fab2_lib.baseboard_fab2(sch_1):m_f_clk_dp(2)") )
				( objectStatus "MG_DDR_NEAR_DIMM-CLK1_CLS_DDR_F_CAC-CLKS" )
			)
			( matchGroup "@baseboard_fab2_lib.baseboard_fab2(sch_1):\MG_DDR_FAR_DIMM_CMD_NG_DDR_F_DLL_2\"
				( memberType ( signal ) )
				( member ( pinPairRef "@baseboard_fab2_lib.baseboard_fab2(sch_1):\PP3721\") )
				( member ( pinPairRef "@baseboard_fab2_lib.baseboard_fab2(sch_1):\PP3723\") )
				( objectStatus "MG_DDR_FAR_DIMM_CMD_NG_DDR_F_DLL_2" )
			)
			( matchGroup "@baseboard_fab2_lib.baseboard_fab2(sch_1):\MG_DDR_CMD_NEAR_DIMM_NG_DDR_F_DLL_2\"
				( memberType ( signal ) )
				( member ( pinPairRef "@baseboard_fab2_lib.baseboard_fab2(sch_1):\PP3722\") )
				( member ( pinPairRef "@baseboard_fab2_lib.baseboard_fab2(sch_1):\PP3724\") )
				( objectStatus "MG_DDR_CMD_NEAR_DIMM_NG_DDR_F_DLL_2" )
			)
			( matchGroup "@baseboard_fab2_lib.baseboard_fab2(sch_1):\MG_DDR_FAR_DIMM_CMD_NG_DDR_F_DLL_3\"
				( memberType ( signal ) )
				( member ( pinPairRef "@baseboard_fab2_lib.baseboard_fab2(sch_1):\PP3717\") )
				( member ( pinPairRef "@baseboard_fab2_lib.baseboard_fab2(sch_1):\PP3719\") )
				( objectStatus "MG_DDR_FAR_DIMM_CMD_NG_DDR_F_DLL_3" )
			)
			( matchGroup "@baseboard_fab2_lib.baseboard_fab2(sch_1):\MG_DDR_CMD_NEAR_DIMM_NG_DDR_F_DLL_3\"
				( memberType ( signal ) )
				( member ( pinPairRef "@baseboard_fab2_lib.baseboard_fab2(sch_1):\PP3718\") )
				( member ( pinPairRef "@baseboard_fab2_lib.baseboard_fab2(sch_1):\PP3720\") )
				( objectStatus "MG_DDR_CMD_NEAR_DIMM_NG_DDR_F_DLL_3" )
			)
			( matchGroup "@baseboard_fab2_lib.baseboard_fab2(sch_1):\MG_DDR_FAR_DIMM_CMD_NG_DDR_F_DLL_4\"
				( memberType ( signal ) )
				( member ( pinPairRef "@baseboard_fab2_lib.baseboard_fab2(sch_1):\PP3713\") )
				( member ( pinPairRef "@baseboard_fab2_lib.baseboard_fab2(sch_1):\PP3715\") )
				( objectStatus "MG_DDR_FAR_DIMM_CMD_NG_DDR_F_DLL_4" )
			)
			( matchGroup "@baseboard_fab2_lib.baseboard_fab2(sch_1):\MG_DDR_CMD_NEAR_DIMM_NG_DDR_F_DLL_4\"
				( memberType ( signal ) )
				( member ( pinPairRef "@baseboard_fab2_lib.baseboard_fab2(sch_1):\PP3714\") )
				( member ( pinPairRef "@baseboard_fab2_lib.baseboard_fab2(sch_1):\PP3716\") )
				( objectStatus "MG_DDR_CMD_NEAR_DIMM_NG_DDR_F_DLL_4" )
			)
			( matchGroup "@baseboard_fab2_lib.baseboard_fab2(sch_1):\MG_DDR_FAR_DIMM_CMD_NG_DDR_F_DLL_5\"
				( memberType ( signal ) )
				( member ( pinPairRef "@baseboard_fab2_lib.baseboard_fab2(sch_1):\PP3709\") )
				( member ( pinPairRef "@baseboard_fab2_lib.baseboard_fab2(sch_1):\PP3711\") )
				( objectStatus "MG_DDR_FAR_DIMM_CMD_NG_DDR_F_DLL_5" )
			)
			( matchGroup "@baseboard_fab2_lib.baseboard_fab2(sch_1):\MG_DDR_CMD_NEAR_DIMM_NG_DDR_F_DLL_5\"
				( memberType ( signal ) )
				( member ( pinPairRef "@baseboard_fab2_lib.baseboard_fab2(sch_1):\PP3710\") )
				( member ( pinPairRef "@baseboard_fab2_lib.baseboard_fab2(sch_1):\PP3712\") )
				( objectStatus "MG_DDR_CMD_NEAR_DIMM_NG_DDR_F_DLL_5" )
			)
			( matchGroup "@baseboard_fab2_lib.baseboard_fab2(sch_1):\MG_DDR_FAR_DIMM_CMD_NG_DDR_F_DLL_6\"
				( memberType ( signal ) )
				( member ( pinPairRef "@baseboard_fab2_lib.baseboard_fab2(sch_1):\PP3707\") )
				( objectStatus "MG_DDR_FAR_DIMM_CMD_NG_DDR_F_DLL_6" )
			)
			( matchGroup "@baseboard_fab2_lib.baseboard_fab2(sch_1):\MG_DDR_CMD_NEAR_DIMM_NG_DDR_F_DLL_6\"
				( memberType ( signal ) )
				( member ( pinPairRef "@baseboard_fab2_lib.baseboard_fab2(sch_1):\PP3708\") )
				( objectStatus "MG_DDR_CMD_NEAR_DIMM_NG_DDR_F_DLL_6" )
			)
			( matchGroup "@baseboard_fab2_lib.baseboard_fab2(sch_1):\MG_DDR_FAR_DIMM_CMD_NG_DDR_F_DLL_7\"
				( memberType ( signal ) )
				( member ( pinPairRef "@baseboard_fab2_lib.baseboard_fab2(sch_1):\PP3703\") )
				( member ( pinPairRef "@baseboard_fab2_lib.baseboard_fab2(sch_1):\PP3705\") )
				( objectStatus "MG_DDR_FAR_DIMM_CMD_NG_DDR_F_DLL_7" )
			)
			( matchGroup "@baseboard_fab2_lib.baseboard_fab2(sch_1):\MG_DDR_CMD_NEAR_DIMM_NG_DDR_F_DLL_7\"
				( memberType ( signal ) )
				( member ( pinPairRef "@baseboard_fab2_lib.baseboard_fab2(sch_1):\PP3704\") )
				( member ( pinPairRef "@baseboard_fab2_lib.baseboard_fab2(sch_1):\PP3706\") )
				( objectStatus "MG_DDR_CMD_NEAR_DIMM_NG_DDR_F_DLL_7" )
			)
			( matchGroup "@baseboard_fab2_lib.baseboard_fab2(sch_1):\MG_DDR_FAR_DIMM_CMD_NG_DDR_F_DLL_8\"
				( memberType ( signal ) )
				( member ( pinPairRef "@baseboard_fab2_lib.baseboard_fab2(sch_1):\PP3699\") )
				( member ( pinPairRef "@baseboard_fab2_lib.baseboard_fab2(sch_1):\PP3701\") )
				( objectStatus "MG_DDR_FAR_DIMM_CMD_NG_DDR_F_DLL_8" )
			)
			( matchGroup "@baseboard_fab2_lib.baseboard_fab2(sch_1):\MG_DDR_CMD_NEAR_DIMM_NG_DDR_F_DLL_8\"
				( memberType ( signal ) )
				( member ( pinPairRef "@baseboard_fab2_lib.baseboard_fab2(sch_1):\PP3700\") )
				( member ( pinPairRef "@baseboard_fab2_lib.baseboard_fab2(sch_1):\PP3702\") )
				( objectStatus "MG_DDR_CMD_NEAR_DIMM_NG_DDR_F_DLL_8" )
			)
			( matchGroup "@baseboard_fab2_lib.baseboard_fab2(sch_1):\MG_DDR_FAR_DIMM_CMD_NG_DDR_F_DLL_9\"
				( memberType ( signal ) )
				( member ( pinPairRef "@baseboard_fab2_lib.baseboard_fab2(sch_1):\PP3695\") )
				( member ( pinPairRef "@baseboard_fab2_lib.baseboard_fab2(sch_1):\PP3697\") )
				( objectStatus "MG_DDR_FAR_DIMM_CMD_NG_DDR_F_DLL_9" )
			)
			( matchGroup "@baseboard_fab2_lib.baseboard_fab2(sch_1):\MG_DDR_CMD_NEAR_DIMM_NG_DDR_F_DLL_9\"
				( memberType ( signal ) )
				( member ( pinPairRef "@baseboard_fab2_lib.baseboard_fab2(sch_1):\PP3696\") )
				( member ( pinPairRef "@baseboard_fab2_lib.baseboard_fab2(sch_1):\PP3698\") )
				( objectStatus "MG_DDR_CMD_NEAR_DIMM_NG_DDR_F_DLL_9" )
			)
			( matchGroup "@baseboard_fab2_lib.baseboard_fab2(sch_1):\MG_DDR_FAR_DIMM_CMD_NG_DDR_F_DLL_10\"
				( memberType ( signal ) )
				( member ( pinPairRef "@baseboard_fab2_lib.baseboard_fab2(sch_1):\PP3691\") )
				( member ( pinPairRef "@baseboard_fab2_lib.baseboard_fab2(sch_1):\PP3693\") )
				( objectStatus "MG_DDR_FAR_DIMM_CMD_NG_DDR_F_DLL_10" )
			)
			( matchGroup "@baseboard_fab2_lib.baseboard_fab2(sch_1):\MG_DDR_CMD_NEAR_DIMM_NG_DDR_F_DLL_10\"
				( memberType ( signal ) )
				( member ( pinPairRef "@baseboard_fab2_lib.baseboard_fab2(sch_1):\PP3692\") )
				( member ( pinPairRef "@baseboard_fab2_lib.baseboard_fab2(sch_1):\PP3694\") )
				( objectStatus "MG_DDR_CMD_NEAR_DIMM_NG_DDR_F_DLL_10" )
			)
			( matchGroup "@baseboard_fab2_lib.baseboard_fab2(sch_1):\MG_DDR_FAR_DIMM_CMD_NG_DDR_F_DLL_11\"
				( memberType ( signal ) )
				( member ( pinPairRef "@baseboard_fab2_lib.baseboard_fab2(sch_1):\PP3687\") )
				( member ( pinPairRef "@baseboard_fab2_lib.baseboard_fab2(sch_1):\PP3689\") )
				( objectStatus "MG_DDR_FAR_DIMM_CMD_NG_DDR_F_DLL_11" )
			)
			( matchGroup "@baseboard_fab2_lib.baseboard_fab2(sch_1):\MG_DDR_CMD_NEAR_DIMM_NG_DDR_F_DLL_11\"
				( memberType ( signal ) )
				( member ( pinPairRef "@baseboard_fab2_lib.baseboard_fab2(sch_1):\PP3688\") )
				( member ( pinPairRef "@baseboard_fab2_lib.baseboard_fab2(sch_1):\PP3690\") )
				( objectStatus "MG_DDR_CMD_NEAR_DIMM_NG_DDR_F_DLL_11" )
			)
			( matchGroup "@baseboard_fab2_lib.baseboard_fab2(sch_1):\MG_DDR_FAR_DIMM_CMD_NG_DDR_F_DLL_12\"
				( memberType ( signal ) )
				( member ( pinPairRef "@baseboard_fab2_lib.baseboard_fab2(sch_1):\PP3683\") )
				( member ( pinPairRef "@baseboard_fab2_lib.baseboard_fab2(sch_1):\PP3685\") )
				( objectStatus "MG_DDR_FAR_DIMM_CMD_NG_DDR_F_DLL_12" )
			)
			( matchGroup "@baseboard_fab2_lib.baseboard_fab2(sch_1):\MG_DDR_CMD_NEAR_DIMM_NG_DDR_F_DLL_12\"
				( memberType ( signal ) )
				( member ( pinPairRef "@baseboard_fab2_lib.baseboard_fab2(sch_1):\PP3684\") )
				( member ( pinPairRef "@baseboard_fab2_lib.baseboard_fab2(sch_1):\PP3686\") )
				( objectStatus "MG_DDR_CMD_NEAR_DIMM_NG_DDR_F_DLL_12" )
			)
			( matchGroup "@baseboard_fab2_lib.baseboard_fab2(sch_1):\MG_DDR_FAR_DIMM_CMD_NG_DDR_F_DLL_13\"
				( memberType ( signal ) )
				( member ( pinPairRef "@baseboard_fab2_lib.baseboard_fab2(sch_1):\PP3679\") )
				( member ( pinPairRef "@baseboard_fab2_lib.baseboard_fab2(sch_1):\PP3681\") )
				( objectStatus "MG_DDR_FAR_DIMM_CMD_NG_DDR_F_DLL_13" )
			)
			( matchGroup "@baseboard_fab2_lib.baseboard_fab2(sch_1):\MG_DDR_CMD_NEAR_DIMM_NG_DDR_F_DLL_13\"
				( memberType ( signal ) )
				( member ( pinPairRef "@baseboard_fab2_lib.baseboard_fab2(sch_1):\PP3680\") )
				( member ( pinPairRef "@baseboard_fab2_lib.baseboard_fab2(sch_1):\PP3682\") )
				( objectStatus "MG_DDR_CMD_NEAR_DIMM_NG_DDR_F_DLL_13" )
			)
			( matchGroup "@baseboard_fab2_lib.baseboard_fab2(sch_1):\MG_DDR_CTRL_NG_DDR_F_DLL_14\"
				( memberType ( signal ) )
				( member ( pinPairRef "@baseboard_fab2_lib.baseboard_fab2(sch_1):\PP3677\") )
				( member ( pinPairRef "@baseboard_fab2_lib.baseboard_fab2(sch_1):\PP3678\") )
				( objectStatus "MG_DDR_CTRL_NG_DDR_F_DLL_14" )
			)
			( matchGroup "@baseboard_fab2_lib.baseboard_fab2(sch_1):\MG_DDR_CTRL_NG_DDR_F_DLL_15\"
				( memberType ( signal ) )
				( member ( pinPairRef "@baseboard_fab2_lib.baseboard_fab2(sch_1):\PP3676\") )
				( objectStatus "MG_DDR_CTRL_NG_DDR_F_DLL_15" )
			)
			( matchGroup "@baseboard_fab2_lib.baseboard_fab2(sch_1):\MG_DDR_CTRL_NG_DDR_F_DLL_16\"
				( memberType ( signal ) )
				( member ( pinPairRef "@baseboard_fab2_lib.baseboard_fab2(sch_1):\PP3675\") )
				( objectStatus "MG_DDR_CTRL_NG_DDR_F_DLL_16" )
			)
			( matchGroup "@baseboard_fab2_lib.baseboard_fab2(sch_1):\MG_DDR_CTRL_NG_DDR_F_DLL_17\"
				( memberType ( signal ) )
				( member ( pinPairRef "@baseboard_fab2_lib.baseboard_fab2(sch_1):\PP3674\") )
				( objectStatus "MG_DDR_CTRL_NG_DDR_F_DLL_17" )
			)
			( matchGroup "@baseboard_fab2_lib.baseboard_fab2(sch_1):\MG_DDR_CTRL_NG_DDR_F_DLL_18\"
				( memberType ( signal ) )
				( member ( pinPairRef "@baseboard_fab2_lib.baseboard_fab2(sch_1):\PP3672\") )
				( member ( pinPairRef "@baseboard_fab2_lib.baseboard_fab2(sch_1):\PP3673\") )
				( objectStatus "MG_DDR_CTRL_NG_DDR_F_DLL_18" )
			)
			( matchGroup "@baseboard_fab2_lib.baseboard_fab2(sch_1):\MG_DDR_CTRL_NG_DDR_F_DLL_19\"
				( memberType ( signal ) )
				( member ( pinPairRef "@baseboard_fab2_lib.baseboard_fab2(sch_1):\PP3671\") )
				( objectStatus "MG_DDR_CTRL_NG_DDR_F_DLL_19" )
			)
			( matchGroup "@baseboard_fab2_lib.baseboard_fab2(sch_1):\MG_DDR_CTRL_NG_DDR_F_DLL_20\"
				( memberType ( signal ) )
				( member ( pinPairRef "@baseboard_fab2_lib.baseboard_fab2(sch_1):\PP3669\") )
				( member ( pinPairRef "@baseboard_fab2_lib.baseboard_fab2(sch_1):\PP3670\") )
				( objectStatus "MG_DDR_CTRL_NG_DDR_F_DLL_20" )
			)
			( matchGroup "@baseboard_fab2_lib.baseboard_fab2(sch_1):\MG_DDR_CTRL_NG_DDR_F_DLL_21\"
				( memberType ( signal ) )
				( member ( pinPairRef "@baseboard_fab2_lib.baseboard_fab2(sch_1):\PP3668\") )
				( objectStatus "MG_DDR_CTRL_NG_DDR_F_DLL_21" )
			)
			( matchGroup "@baseboard_fab2_lib.baseboard_fab2(sch_1):\MG_DDR_CTRL_NG_DDR_F_DLL_22\"
				( memberType ( signal ) )
				( member ( pinPairRef "@baseboard_fab2_lib.baseboard_fab2(sch_1):\PP3666\") )
				( member ( pinPairRef "@baseboard_fab2_lib.baseboard_fab2(sch_1):\PP3667\") )
				( objectStatus "MG_DDR_CTRL_NG_DDR_F_DLL_22" )
			)
			( matchGroup "@baseboard_fab2_lib.baseboard_fab2(sch_1):\MG_DDR_CTRL_NG_DDR_F_DLL_23\"
				( memberType ( signal ) )
				( member ( pinPairRef "@baseboard_fab2_lib.baseboard_fab2(sch_1):\PP3664\") )
				( member ( pinPairRef "@baseboard_fab2_lib.baseboard_fab2(sch_1):\PP3665\") )
				( objectStatus "MG_DDR_CTRL_NG_DDR_F_DLL_23" )
			)
			( matchGroup "@baseboard_fab2_lib.baseboard_fab2(sch_1):\MG_DDR_CTRL_NG_DDR_F_DLL_24\"
				( memberType ( signal ) )
				( member ( pinPairRef "@baseboard_fab2_lib.baseboard_fab2(sch_1):\PP3663\") )
				( objectStatus "MG_DDR_CTRL_NG_DDR_F_DLL_24" )
			)
			( matchGroup "@crescent_city_bb_fab1_lib.crescent_city_bb_fab1(sch_1):\MG_DDR_FAR_DIMM-CLK0_CLS_DDR_E_CAC-CLKS\"
				( memberType ( signal ) )
				( member ( pinPairRef "@baseboard_fab2_lib.baseboard_fab2(sch_1):\PP3791\") )
				( member ( pinPairRef "@baseboard_fab2_lib.baseboard_fab2(sch_1):\PP3793\") )
				( member ( pinPairRef "@baseboard_fab2_lib.baseboard_fab2(sch_1):\PP3787\") )
				( member ( pinPairRef "@baseboard_fab2_lib.baseboard_fab2(sch_1):\PP3789\") )
				( member ( pinPairRef "@baseboard_fab2_lib.baseboard_fab2(sch_1):\PP3783\") )
				( member ( pinPairRef "@baseboard_fab2_lib.baseboard_fab2(sch_1):\PP3785\") )
				( member ( pinPairRef "@baseboard_fab2_lib.baseboard_fab2(sch_1):\PP3779\") )
				( member ( pinPairRef "@baseboard_fab2_lib.baseboard_fab2(sch_1):\PP3781\") )
				( member ( pinPairRef "@baseboard_fab2_lib.baseboard_fab2(sch_1):\PP3775\") )
				( member ( pinPairRef "@baseboard_fab2_lib.baseboard_fab2(sch_1):\PP3777\") )
				( member ( pinPairRef "@baseboard_fab2_lib.baseboard_fab2(sch_1):\PP3773\") )
				( member ( pinPairRef "@baseboard_fab2_lib.baseboard_fab2(sch_1):\PP3769\") )
				( member ( pinPairRef "@baseboard_fab2_lib.baseboard_fab2(sch_1):\PP3771\") )
				( member ( pinPairRef "@baseboard_fab2_lib.baseboard_fab2(sch_1):\PP3765\") )
				( member ( pinPairRef "@baseboard_fab2_lib.baseboard_fab2(sch_1):\PP3767\") )
				( member ( pinPairRef "@baseboard_fab2_lib.baseboard_fab2(sch_1):\PP3761\") )
				( member ( pinPairRef "@baseboard_fab2_lib.baseboard_fab2(sch_1):\PP3763\") )
				( member ( pinPairRef "@baseboard_fab2_lib.baseboard_fab2(sch_1):\PP3757\") )
				( member ( pinPairRef "@baseboard_fab2_lib.baseboard_fab2(sch_1):\PP3759\") )
				( member ( pinPairRef "@baseboard_fab2_lib.baseboard_fab2(sch_1):\PP3753\") )
				( member ( pinPairRef "@baseboard_fab2_lib.baseboard_fab2(sch_1):\PP3755\") )
				( member ( pinPairRef "@baseboard_fab2_lib.baseboard_fab2(sch_1):\PP3749\") )
				( member ( pinPairRef "@baseboard_fab2_lib.baseboard_fab2(sch_1):\PP3751\") )
				( member ( pinPairRef "@baseboard_fab2_lib.baseboard_fab2(sch_1):\PP3745\") )
				( member ( pinPairRef "@baseboard_fab2_lib.baseboard_fab2(sch_1):\PP3747\") )
				( member ( pinPairRef "@baseboard_fab2_lib.baseboard_fab2(sch_1):\PP3743\") )
				( member ( pinPairRef "@baseboard_fab2_lib.baseboard_fab2(sch_1):\PP3744\") )
				( member ( pinPairRef "@baseboard_fab2_lib.baseboard_fab2(sch_1):\PP3742\") )
				( member ( pinPairRef "@baseboard_fab2_lib.baseboard_fab2(sch_1):\PP3741\") )
				( member ( pinPairRef "@baseboard_fab2_lib.baseboard_fab2(sch_1):\PP3740\") )
				( member ( pinPairRef "@baseboard_fab2_lib.baseboard_fab2(sch_1):\PP3738\") )
				( member ( pinPairRef "@baseboard_fab2_lib.baseboard_fab2(sch_1):\PP3739\") )
				( member ( pinPairRef "@baseboard_fab2_lib.baseboard_fab2(sch_1):\PP3737\") )
				( member ( signalRef "@baseboard_fab2_lib.baseboard_fab2(sch_1):m_e_clk_dp(0)") )
				( objectStatus "MG_DDR_FAR_DIMM-CLK0_CLS_DDR_E_CAC-CLKS" )
			)
			( matchGroup "@baseboard_fab2_lib.baseboard_fab2(sch_1):\MG_DDR_FAR_DIMM_CMD_NG_DDR_E_DLL_1\"
				( memberType ( signal ) )
				( member ( pinPairRef "@baseboard_fab2_lib.baseboard_fab2(sch_1):\PP3791\") )
				( member ( pinPairRef "@baseboard_fab2_lib.baseboard_fab2(sch_1):\PP3793\") )
				( objectStatus "MG_DDR_FAR_DIMM_CMD_NG_DDR_E_DLL_1" )
			)
			( matchGroup "@baseboard_fab2_lib.baseboard_fab2(sch_1):\MG_DDR_CMD_NEAR_DIMM_NG_DDR_E_DLL_1\"
				( memberType ( signal ) )
				( member ( pinPairRef "@baseboard_fab2_lib.baseboard_fab2(sch_1):\PP3792\") )
				( member ( pinPairRef "@baseboard_fab2_lib.baseboard_fab2(sch_1):\PP3794\") )
				( objectStatus "MG_DDR_CMD_NEAR_DIMM_NG_DDR_E_DLL_1" )
			)
			( matchGroup "@crescent_city_bb_fab1_lib.crescent_city_bb_fab1(sch_1):\MG_DDR_NEAR_DIMM-CLK1_CLS_DDR_E_CAC-CLKS\"
				( memberType ( signal ) )
				( member ( pinPairRef "@baseboard_fab2_lib.baseboard_fab2(sch_1):\PP3792\") )
				( member ( pinPairRef "@baseboard_fab2_lib.baseboard_fab2(sch_1):\PP3794\") )
				( member ( pinPairRef "@baseboard_fab2_lib.baseboard_fab2(sch_1):\PP3788\") )
				( member ( pinPairRef "@baseboard_fab2_lib.baseboard_fab2(sch_1):\PP3790\") )
				( member ( pinPairRef "@baseboard_fab2_lib.baseboard_fab2(sch_1):\PP3784\") )
				( member ( pinPairRef "@baseboard_fab2_lib.baseboard_fab2(sch_1):\PP3786\") )
				( member ( pinPairRef "@baseboard_fab2_lib.baseboard_fab2(sch_1):\PP3780\") )
				( member ( pinPairRef "@baseboard_fab2_lib.baseboard_fab2(sch_1):\PP3782\") )
				( member ( pinPairRef "@baseboard_fab2_lib.baseboard_fab2(sch_1):\PP3776\") )
				( member ( pinPairRef "@baseboard_fab2_lib.baseboard_fab2(sch_1):\PP3778\") )
				( member ( pinPairRef "@baseboard_fab2_lib.baseboard_fab2(sch_1):\PP3774\") )
				( member ( pinPairRef "@baseboard_fab2_lib.baseboard_fab2(sch_1):\PP3770\") )
				( member ( pinPairRef "@baseboard_fab2_lib.baseboard_fab2(sch_1):\PP3772\") )
				( member ( pinPairRef "@baseboard_fab2_lib.baseboard_fab2(sch_1):\PP3766\") )
				( member ( pinPairRef "@baseboard_fab2_lib.baseboard_fab2(sch_1):\PP3768\") )
				( member ( pinPairRef "@baseboard_fab2_lib.baseboard_fab2(sch_1):\PP3762\") )
				( member ( pinPairRef "@baseboard_fab2_lib.baseboard_fab2(sch_1):\PP3764\") )
				( member ( pinPairRef "@baseboard_fab2_lib.baseboard_fab2(sch_1):\PP3758\") )
				( member ( pinPairRef "@baseboard_fab2_lib.baseboard_fab2(sch_1):\PP3760\") )
				( member ( pinPairRef "@baseboard_fab2_lib.baseboard_fab2(sch_1):\PP3754\") )
				( member ( pinPairRef "@baseboard_fab2_lib.baseboard_fab2(sch_1):\PP3756\") )
				( member ( pinPairRef "@baseboard_fab2_lib.baseboard_fab2(sch_1):\PP3750\") )
				( member ( pinPairRef "@baseboard_fab2_lib.baseboard_fab2(sch_1):\PP3752\") )
				( member ( pinPairRef "@baseboard_fab2_lib.baseboard_fab2(sch_1):\PP3746\") )
				( member ( pinPairRef "@baseboard_fab2_lib.baseboard_fab2(sch_1):\PP3748\") )
				( member ( pinPairRef "@baseboard_fab2_lib.baseboard_fab2(sch_1):\PP3735\") )
				( member ( pinPairRef "@baseboard_fab2_lib.baseboard_fab2(sch_1):\PP3736\") )
				( member ( pinPairRef "@baseboard_fab2_lib.baseboard_fab2(sch_1):\PP3734\") )
				( member ( pinPairRef "@baseboard_fab2_lib.baseboard_fab2(sch_1):\PP3732\") )
				( member ( pinPairRef "@baseboard_fab2_lib.baseboard_fab2(sch_1):\PP3733\") )
				( member ( pinPairRef "@baseboard_fab2_lib.baseboard_fab2(sch_1):\PP3730\") )
				( member ( pinPairRef "@baseboard_fab2_lib.baseboard_fab2(sch_1):\PP3731\") )
				( member ( pinPairRef "@baseboard_fab2_lib.baseboard_fab2(sch_1):\PP3729\") )
				( member ( signalRef "@baseboard_fab2_lib.baseboard_fab2(sch_1):m_e_clk_dp(2)") )
				( objectStatus "MG_DDR_NEAR_DIMM-CLK1_CLS_DDR_E_CAC-CLKS" )
			)
			( matchGroup "@baseboard_fab2_lib.baseboard_fab2(sch_1):\MG_DDR_FAR_DIMM_CMD_NG_DDR_E_DLL_2\"
				( memberType ( signal ) )
				( member ( pinPairRef "@baseboard_fab2_lib.baseboard_fab2(sch_1):\PP3787\") )
				( member ( pinPairRef "@baseboard_fab2_lib.baseboard_fab2(sch_1):\PP3789\") )
				( objectStatus "MG_DDR_FAR_DIMM_CMD_NG_DDR_E_DLL_2" )
			)
			( matchGroup "@baseboard_fab2_lib.baseboard_fab2(sch_1):\MG_DDR_CMD_NEAR_DIMM_NG_DDR_E_DLL_2\"
				( memberType ( signal ) )
				( member ( pinPairRef "@baseboard_fab2_lib.baseboard_fab2(sch_1):\PP3788\") )
				( member ( pinPairRef "@baseboard_fab2_lib.baseboard_fab2(sch_1):\PP3790\") )
				( objectStatus "MG_DDR_CMD_NEAR_DIMM_NG_DDR_E_DLL_2" )
			)
			( matchGroup "@baseboard_fab2_lib.baseboard_fab2(sch_1):\MG_DDR_FAR_DIMM_CMD_NG_DDR_E_DLL_3\"
				( memberType ( signal ) )
				( member ( pinPairRef "@baseboard_fab2_lib.baseboard_fab2(sch_1):\PP3783\") )
				( member ( pinPairRef "@baseboard_fab2_lib.baseboard_fab2(sch_1):\PP3785\") )
				( objectStatus "MG_DDR_FAR_DIMM_CMD_NG_DDR_E_DLL_3" )
			)
			( matchGroup "@baseboard_fab2_lib.baseboard_fab2(sch_1):\MG_DDR_CMD_NEAR_DIMM_NG_DDR_E_DLL_3\"
				( memberType ( signal ) )
				( member ( pinPairRef "@baseboard_fab2_lib.baseboard_fab2(sch_1):\PP3784\") )
				( member ( pinPairRef "@baseboard_fab2_lib.baseboard_fab2(sch_1):\PP3786\") )
				( objectStatus "MG_DDR_CMD_NEAR_DIMM_NG_DDR_E_DLL_3" )
			)
			( matchGroup "@baseboard_fab2_lib.baseboard_fab2(sch_1):\MG_DDR_FAR_DIMM_CMD_NG_DDR_E_DLL_4\"
				( memberType ( signal ) )
				( member ( pinPairRef "@baseboard_fab2_lib.baseboard_fab2(sch_1):\PP3779\") )
				( member ( pinPairRef "@baseboard_fab2_lib.baseboard_fab2(sch_1):\PP3781\") )
				( objectStatus "MG_DDR_FAR_DIMM_CMD_NG_DDR_E_DLL_4" )
			)
			( matchGroup "@baseboard_fab2_lib.baseboard_fab2(sch_1):\MG_DDR_CMD_NEAR_DIMM_NG_DDR_E_DLL_4\"
				( memberType ( signal ) )
				( member ( pinPairRef "@baseboard_fab2_lib.baseboard_fab2(sch_1):\PP3780\") )
				( member ( pinPairRef "@baseboard_fab2_lib.baseboard_fab2(sch_1):\PP3782\") )
				( objectStatus "MG_DDR_CMD_NEAR_DIMM_NG_DDR_E_DLL_4" )
			)
			( matchGroup "@baseboard_fab2_lib.baseboard_fab2(sch_1):\MG_DDR_FAR_DIMM_CMD_NG_DDR_E_DLL_5\"
				( memberType ( signal ) )
				( member ( pinPairRef "@baseboard_fab2_lib.baseboard_fab2(sch_1):\PP3775\") )
				( member ( pinPairRef "@baseboard_fab2_lib.baseboard_fab2(sch_1):\PP3777\") )
				( objectStatus "MG_DDR_FAR_DIMM_CMD_NG_DDR_E_DLL_5" )
			)
			( matchGroup "@baseboard_fab2_lib.baseboard_fab2(sch_1):\MG_DDR_CMD_NEAR_DIMM_NG_DDR_E_DLL_5\"
				( memberType ( signal ) )
				( member ( pinPairRef "@baseboard_fab2_lib.baseboard_fab2(sch_1):\PP3776\") )
				( member ( pinPairRef "@baseboard_fab2_lib.baseboard_fab2(sch_1):\PP3778\") )
				( objectStatus "MG_DDR_CMD_NEAR_DIMM_NG_DDR_E_DLL_5" )
			)
			( matchGroup "@baseboard_fab2_lib.baseboard_fab2(sch_1):\MG_DDR_FAR_DIMM_CMD_NG_DDR_E_DLL_6\"
				( memberType ( signal ) )
				( member ( pinPairRef "@baseboard_fab2_lib.baseboard_fab2(sch_1):\PP3773\") )
				( objectStatus "MG_DDR_FAR_DIMM_CMD_NG_DDR_E_DLL_6" )
			)
			( matchGroup "@baseboard_fab2_lib.baseboard_fab2(sch_1):\MG_DDR_CMD_NEAR_DIMM_NG_DDR_E_DLL_6\"
				( memberType ( signal ) )
				( member ( pinPairRef "@baseboard_fab2_lib.baseboard_fab2(sch_1):\PP3774\") )
				( objectStatus "MG_DDR_CMD_NEAR_DIMM_NG_DDR_E_DLL_6" )
			)
			( matchGroup "@baseboard_fab2_lib.baseboard_fab2(sch_1):\MG_DDR_FAR_DIMM_CMD_NG_DDR_E_DLL_7\"
				( memberType ( signal ) )
				( member ( pinPairRef "@baseboard_fab2_lib.baseboard_fab2(sch_1):\PP3769\") )
				( member ( pinPairRef "@baseboard_fab2_lib.baseboard_fab2(sch_1):\PP3771\") )
				( objectStatus "MG_DDR_FAR_DIMM_CMD_NG_DDR_E_DLL_7" )
			)
			( matchGroup "@baseboard_fab2_lib.baseboard_fab2(sch_1):\MG_DDR_CMD_NEAR_DIMM_NG_DDR_E_DLL_7\"
				( memberType ( signal ) )
				( member ( pinPairRef "@baseboard_fab2_lib.baseboard_fab2(sch_1):\PP3770\") )
				( member ( pinPairRef "@baseboard_fab2_lib.baseboard_fab2(sch_1):\PP3772\") )
				( objectStatus "MG_DDR_CMD_NEAR_DIMM_NG_DDR_E_DLL_7" )
			)
			( matchGroup "@baseboard_fab2_lib.baseboard_fab2(sch_1):\MG_DDR_FAR_DIMM_CMD_NG_DDR_E_DLL_8\"
				( memberType ( signal ) )
				( member ( pinPairRef "@baseboard_fab2_lib.baseboard_fab2(sch_1):\PP3765\") )
				( member ( pinPairRef "@baseboard_fab2_lib.baseboard_fab2(sch_1):\PP3767\") )
				( objectStatus "MG_DDR_FAR_DIMM_CMD_NG_DDR_E_DLL_8" )
			)
			( matchGroup "@baseboard_fab2_lib.baseboard_fab2(sch_1):\MG_DDR_CMD_NEAR_DIMM_NG_DDR_E_DLL_8\"
				( memberType ( signal ) )
				( member ( pinPairRef "@baseboard_fab2_lib.baseboard_fab2(sch_1):\PP3766\") )
				( member ( pinPairRef "@baseboard_fab2_lib.baseboard_fab2(sch_1):\PP3768\") )
				( objectStatus "MG_DDR_CMD_NEAR_DIMM_NG_DDR_E_DLL_8" )
			)
			( matchGroup "@baseboard_fab2_lib.baseboard_fab2(sch_1):\MG_DDR_FAR_DIMM_CMD_NG_DDR_E_DLL_9\"
				( memberType ( signal ) )
				( member ( pinPairRef "@baseboard_fab2_lib.baseboard_fab2(sch_1):\PP3761\") )
				( member ( pinPairRef "@baseboard_fab2_lib.baseboard_fab2(sch_1):\PP3763\") )
				( objectStatus "MG_DDR_FAR_DIMM_CMD_NG_DDR_E_DLL_9" )
			)
			( matchGroup "@baseboard_fab2_lib.baseboard_fab2(sch_1):\MG_DDR_CMD_NEAR_DIMM_NG_DDR_E_DLL_9\"
				( memberType ( signal ) )
				( member ( pinPairRef "@baseboard_fab2_lib.baseboard_fab2(sch_1):\PP3762\") )
				( member ( pinPairRef "@baseboard_fab2_lib.baseboard_fab2(sch_1):\PP3764\") )
				( objectStatus "MG_DDR_CMD_NEAR_DIMM_NG_DDR_E_DLL_9" )
			)
			( matchGroup "@baseboard_fab2_lib.baseboard_fab2(sch_1):\MG_DDR_FAR_DIMM_CMD_NG_DDR_E_DLL_10\"
				( memberType ( signal ) )
				( member ( pinPairRef "@baseboard_fab2_lib.baseboard_fab2(sch_1):\PP3757\") )
				( member ( pinPairRef "@baseboard_fab2_lib.baseboard_fab2(sch_1):\PP3759\") )
				( objectStatus "MG_DDR_FAR_DIMM_CMD_NG_DDR_E_DLL_10" )
			)
			( matchGroup "@baseboard_fab2_lib.baseboard_fab2(sch_1):\MG_DDR_CMD_NEAR_DIMM_NG_DDR_E_DLL_10\"
				( memberType ( signal ) )
				( member ( pinPairRef "@baseboard_fab2_lib.baseboard_fab2(sch_1):\PP3758\") )
				( member ( pinPairRef "@baseboard_fab2_lib.baseboard_fab2(sch_1):\PP3760\") )
				( objectStatus "MG_DDR_CMD_NEAR_DIMM_NG_DDR_E_DLL_10" )
			)
			( matchGroup "@baseboard_fab2_lib.baseboard_fab2(sch_1):\MG_DDR_FAR_DIMM_CMD_NG_DDR_E_DLL_11\"
				( memberType ( signal ) )
				( member ( pinPairRef "@baseboard_fab2_lib.baseboard_fab2(sch_1):\PP3753\") )
				( member ( pinPairRef "@baseboard_fab2_lib.baseboard_fab2(sch_1):\PP3755\") )
				( objectStatus "MG_DDR_FAR_DIMM_CMD_NG_DDR_E_DLL_11" )
			)
			( matchGroup "@baseboard_fab2_lib.baseboard_fab2(sch_1):\MG_DDR_CMD_NEAR_DIMM_NG_DDR_E_DLL_11\"
				( memberType ( signal ) )
				( member ( pinPairRef "@baseboard_fab2_lib.baseboard_fab2(sch_1):\PP3754\") )
				( member ( pinPairRef "@baseboard_fab2_lib.baseboard_fab2(sch_1):\PP3756\") )
				( objectStatus "MG_DDR_CMD_NEAR_DIMM_NG_DDR_E_DLL_11" )
			)
			( matchGroup "@baseboard_fab2_lib.baseboard_fab2(sch_1):\MG_DDR_FAR_DIMM_CMD_NG_DDR_E_DLL_12\"
				( memberType ( signal ) )
				( member ( pinPairRef "@baseboard_fab2_lib.baseboard_fab2(sch_1):\PP3749\") )
				( member ( pinPairRef "@baseboard_fab2_lib.baseboard_fab2(sch_1):\PP3751\") )
				( objectStatus "MG_DDR_FAR_DIMM_CMD_NG_DDR_E_DLL_12" )
			)
			( matchGroup "@baseboard_fab2_lib.baseboard_fab2(sch_1):\MG_DDR_CMD_NEAR_DIMM_NG_DDR_E_DLL_12\"
				( memberType ( signal ) )
				( member ( pinPairRef "@baseboard_fab2_lib.baseboard_fab2(sch_1):\PP3750\") )
				( member ( pinPairRef "@baseboard_fab2_lib.baseboard_fab2(sch_1):\PP3752\") )
				( objectStatus "MG_DDR_CMD_NEAR_DIMM_NG_DDR_E_DLL_12" )
			)
			( matchGroup "@baseboard_fab2_lib.baseboard_fab2(sch_1):\MG_DDR_FAR_DIMM_CMD_NG_DDR_E_DLL_13\"
				( memberType ( signal ) )
				( member ( pinPairRef "@baseboard_fab2_lib.baseboard_fab2(sch_1):\PP3745\") )
				( member ( pinPairRef "@baseboard_fab2_lib.baseboard_fab2(sch_1):\PP3747\") )
				( objectStatus "MG_DDR_FAR_DIMM_CMD_NG_DDR_E_DLL_13" )
			)
			( matchGroup "@baseboard_fab2_lib.baseboard_fab2(sch_1):\MG_DDR_CMD_NEAR_DIMM_NG_DDR_E_DLL_13\"
				( memberType ( signal ) )
				( member ( pinPairRef "@baseboard_fab2_lib.baseboard_fab2(sch_1):\PP3746\") )
				( member ( pinPairRef "@baseboard_fab2_lib.baseboard_fab2(sch_1):\PP3748\") )
				( objectStatus "MG_DDR_CMD_NEAR_DIMM_NG_DDR_E_DLL_13" )
			)
			( matchGroup "@baseboard_fab2_lib.baseboard_fab2(sch_1):\MG_DDR_CTRL_NG_DDR_E_DLL_14\"
				( memberType ( signal ) )
				( member ( pinPairRef "@baseboard_fab2_lib.baseboard_fab2(sch_1):\PP3743\") )
				( member ( pinPairRef "@baseboard_fab2_lib.baseboard_fab2(sch_1):\PP3744\") )
				( objectStatus "MG_DDR_CTRL_NG_DDR_E_DLL_14" )
			)
			( matchGroup "@baseboard_fab2_lib.baseboard_fab2(sch_1):\MG_DDR_CTRL_NG_DDR_E_DLL_15\"
				( memberType ( signal ) )
				( member ( pinPairRef "@baseboard_fab2_lib.baseboard_fab2(sch_1):\PP3742\") )
				( objectStatus "MG_DDR_CTRL_NG_DDR_E_DLL_15" )
			)
			( matchGroup "@baseboard_fab2_lib.baseboard_fab2(sch_1):\MG_DDR_CTRL_NG_DDR_E_DLL_16\"
				( memberType ( signal ) )
				( member ( pinPairRef "@baseboard_fab2_lib.baseboard_fab2(sch_1):\PP3741\") )
				( objectStatus "MG_DDR_CTRL_NG_DDR_E_DLL_16" )
			)
			( matchGroup "@baseboard_fab2_lib.baseboard_fab2(sch_1):\MG_DDR_CTRL_NG_DDR_E_DLL_17\"
				( memberType ( signal ) )
				( member ( pinPairRef "@baseboard_fab2_lib.baseboard_fab2(sch_1):\PP3740\") )
				( objectStatus "MG_DDR_CTRL_NG_DDR_E_DLL_17" )
			)
			( matchGroup "@baseboard_fab2_lib.baseboard_fab2(sch_1):\MG_DDR_CTRL_NG_DDR_E_DLL_18\"
				( memberType ( signal ) )
				( member ( pinPairRef "@baseboard_fab2_lib.baseboard_fab2(sch_1):\PP3738\") )
				( member ( pinPairRef "@baseboard_fab2_lib.baseboard_fab2(sch_1):\PP3739\") )
				( objectStatus "MG_DDR_CTRL_NG_DDR_E_DLL_18" )
			)
			( matchGroup "@baseboard_fab2_lib.baseboard_fab2(sch_1):\MG_DDR_CTRL_NG_DDR_E_DLL_19\"
				( memberType ( signal ) )
				( member ( pinPairRef "@baseboard_fab2_lib.baseboard_fab2(sch_1):\PP3737\") )
				( objectStatus "MG_DDR_CTRL_NG_DDR_E_DLL_19" )
			)
			( matchGroup "@baseboard_fab2_lib.baseboard_fab2(sch_1):\MG_DDR_CTRL_NG_DDR_E_DLL_20\"
				( memberType ( signal ) )
				( member ( pinPairRef "@baseboard_fab2_lib.baseboard_fab2(sch_1):\PP3735\") )
				( member ( pinPairRef "@baseboard_fab2_lib.baseboard_fab2(sch_1):\PP3736\") )
				( objectStatus "MG_DDR_CTRL_NG_DDR_E_DLL_20" )
			)
			( matchGroup "@baseboard_fab2_lib.baseboard_fab2(sch_1):\MG_DDR_CTRL_NG_DDR_E_DLL_21\"
				( memberType ( signal ) )
				( member ( pinPairRef "@baseboard_fab2_lib.baseboard_fab2(sch_1):\PP3734\") )
				( objectStatus "MG_DDR_CTRL_NG_DDR_E_DLL_21" )
			)
			( matchGroup "@baseboard_fab2_lib.baseboard_fab2(sch_1):\MG_DDR_CTRL_NG_DDR_E_DLL_22\"
				( memberType ( signal ) )
				( member ( pinPairRef "@baseboard_fab2_lib.baseboard_fab2(sch_1):\PP3732\") )
				( member ( pinPairRef "@baseboard_fab2_lib.baseboard_fab2(sch_1):\PP3733\") )
				( objectStatus "MG_DDR_CTRL_NG_DDR_E_DLL_22" )
			)
			( matchGroup "@baseboard_fab2_lib.baseboard_fab2(sch_1):\MG_DDR_CTRL_NG_DDR_E_DLL_23\"
				( memberType ( signal ) )
				( member ( pinPairRef "@baseboard_fab2_lib.baseboard_fab2(sch_1):\PP3730\") )
				( member ( pinPairRef "@baseboard_fab2_lib.baseboard_fab2(sch_1):\PP3731\") )
				( objectStatus "MG_DDR_CTRL_NG_DDR_E_DLL_23" )
			)
			( matchGroup "@baseboard_fab2_lib.baseboard_fab2(sch_1):\MG_DDR_CTRL_NG_DDR_E_DLL_24\"
				( memberType ( signal ) )
				( member ( pinPairRef "@baseboard_fab2_lib.baseboard_fab2(sch_1):\PP3729\") )
				( objectStatus "MG_DDR_CTRL_NG_DDR_E_DLL_24" )
			)
			( matchGroup "@crescent_city_bb_fab1_lib.crescent_city_bb_fab1(sch_1):\MG_DDR_FAR_DIMM-CLK0_CLS_DDR_D_CAC-CLKS\"
				( memberType ( signal ) )
				( member ( pinPairRef "@baseboard_fab2_lib.baseboard_fab2(sch_1):\PP3857\") )
				( member ( pinPairRef "@baseboard_fab2_lib.baseboard_fab2(sch_1):\PP3859\") )
				( member ( pinPairRef "@baseboard_fab2_lib.baseboard_fab2(sch_1):\PP3853\") )
				( member ( pinPairRef "@baseboard_fab2_lib.baseboard_fab2(sch_1):\PP3855\") )
				( member ( pinPairRef "@baseboard_fab2_lib.baseboard_fab2(sch_1):\PP3849\") )
				( member ( pinPairRef "@baseboard_fab2_lib.baseboard_fab2(sch_1):\PP3851\") )
				( member ( pinPairRef "@baseboard_fab2_lib.baseboard_fab2(sch_1):\PP3845\") )
				( member ( pinPairRef "@baseboard_fab2_lib.baseboard_fab2(sch_1):\PP3847\") )
				( member ( pinPairRef "@baseboard_fab2_lib.baseboard_fab2(sch_1):\PP3841\") )
				( member ( pinPairRef "@baseboard_fab2_lib.baseboard_fab2(sch_1):\PP3843\") )
				( member ( pinPairRef "@baseboard_fab2_lib.baseboard_fab2(sch_1):\PP3839\") )
				( member ( pinPairRef "@baseboard_fab2_lib.baseboard_fab2(sch_1):\PP3835\") )
				( member ( pinPairRef "@baseboard_fab2_lib.baseboard_fab2(sch_1):\PP3837\") )
				( member ( pinPairRef "@baseboard_fab2_lib.baseboard_fab2(sch_1):\PP3831\") )
				( member ( pinPairRef "@baseboard_fab2_lib.baseboard_fab2(sch_1):\PP3833\") )
				( member ( pinPairRef "@baseboard_fab2_lib.baseboard_fab2(sch_1):\PP3827\") )
				( member ( pinPairRef "@baseboard_fab2_lib.baseboard_fab2(sch_1):\PP3829\") )
				( member ( pinPairRef "@baseboard_fab2_lib.baseboard_fab2(sch_1):\PP3823\") )
				( member ( pinPairRef "@baseboard_fab2_lib.baseboard_fab2(sch_1):\PP3825\") )
				( member ( pinPairRef "@baseboard_fab2_lib.baseboard_fab2(sch_1):\PP3819\") )
				( member ( pinPairRef "@baseboard_fab2_lib.baseboard_fab2(sch_1):\PP3821\") )
				( member ( pinPairRef "@baseboard_fab2_lib.baseboard_fab2(sch_1):\PP3815\") )
				( member ( pinPairRef "@baseboard_fab2_lib.baseboard_fab2(sch_1):\PP3817\") )
				( member ( pinPairRef "@baseboard_fab2_lib.baseboard_fab2(sch_1):\PP3811\") )
				( member ( pinPairRef "@baseboard_fab2_lib.baseboard_fab2(sch_1):\PP3813\") )
				( member ( pinPairRef "@baseboard_fab2_lib.baseboard_fab2(sch_1):\PP3809\") )
				( member ( pinPairRef "@baseboard_fab2_lib.baseboard_fab2(sch_1):\PP3810\") )
				( member ( pinPairRef "@baseboard_fab2_lib.baseboard_fab2(sch_1):\PP3808\") )
				( member ( pinPairRef "@baseboard_fab2_lib.baseboard_fab2(sch_1):\PP3807\") )
				( member ( pinPairRef "@baseboard_fab2_lib.baseboard_fab2(sch_1):\PP3806\") )
				( member ( pinPairRef "@baseboard_fab2_lib.baseboard_fab2(sch_1):\PP3804\") )
				( member ( pinPairRef "@baseboard_fab2_lib.baseboard_fab2(sch_1):\PP3805\") )
				( member ( pinPairRef "@baseboard_fab2_lib.baseboard_fab2(sch_1):\PP3803\") )
				( member ( signalRef "@baseboard_fab2_lib.baseboard_fab2(sch_1):m_d_clk_dp(0)") )
				( objectStatus "MG_DDR_FAR_DIMM-CLK0_CLS_DDR_D_CAC-CLKS" )
			)
			( matchGroup "@baseboard_fab2_lib.baseboard_fab2(sch_1):\MG_DDR_FAR_DIMM_CMD_NG_DDR_D_DLL_1\"
				( memberType ( signal ) )
				( member ( pinPairRef "@baseboard_fab2_lib.baseboard_fab2(sch_1):\PP3857\") )
				( member ( pinPairRef "@baseboard_fab2_lib.baseboard_fab2(sch_1):\PP3859\") )
				( objectStatus "MG_DDR_FAR_DIMM_CMD_NG_DDR_D_DLL_1" )
			)
			( matchGroup "@baseboard_fab2_lib.baseboard_fab2(sch_1):\MG_DDR_CMD_NEAR_DIMM_NG_DDR_D_DLL_1\"
				( memberType ( signal ) )
				( member ( pinPairRef "@baseboard_fab2_lib.baseboard_fab2(sch_1):\PP3858\") )
				( member ( pinPairRef "@baseboard_fab2_lib.baseboard_fab2(sch_1):\PP3860\") )
				( objectStatus "MG_DDR_CMD_NEAR_DIMM_NG_DDR_D_DLL_1" )
			)
			( matchGroup "@crescent_city_bb_fab1_lib.crescent_city_bb_fab1(sch_1):\MG_DDR_NEAR_DIMM-CLK1_CLS_DDR_D_CAC-CLKS\"
				( memberType ( signal ) )
				( member ( pinPairRef "@baseboard_fab2_lib.baseboard_fab2(sch_1):\PP3858\") )
				( member ( pinPairRef "@baseboard_fab2_lib.baseboard_fab2(sch_1):\PP3860\") )
				( member ( pinPairRef "@baseboard_fab2_lib.baseboard_fab2(sch_1):\PP3854\") )
				( member ( pinPairRef "@baseboard_fab2_lib.baseboard_fab2(sch_1):\PP3856\") )
				( member ( pinPairRef "@baseboard_fab2_lib.baseboard_fab2(sch_1):\PP3850\") )
				( member ( pinPairRef "@baseboard_fab2_lib.baseboard_fab2(sch_1):\PP3852\") )
				( member ( pinPairRef "@baseboard_fab2_lib.baseboard_fab2(sch_1):\PP3846\") )
				( member ( pinPairRef "@baseboard_fab2_lib.baseboard_fab2(sch_1):\PP3848\") )
				( member ( pinPairRef "@baseboard_fab2_lib.baseboard_fab2(sch_1):\PP3842\") )
				( member ( pinPairRef "@baseboard_fab2_lib.baseboard_fab2(sch_1):\PP3844\") )
				( member ( pinPairRef "@baseboard_fab2_lib.baseboard_fab2(sch_1):\PP3840\") )
				( member ( pinPairRef "@baseboard_fab2_lib.baseboard_fab2(sch_1):\PP3836\") )
				( member ( pinPairRef "@baseboard_fab2_lib.baseboard_fab2(sch_1):\PP3838\") )
				( member ( pinPairRef "@baseboard_fab2_lib.baseboard_fab2(sch_1):\PP3832\") )
				( member ( pinPairRef "@baseboard_fab2_lib.baseboard_fab2(sch_1):\PP3834\") )
				( member ( pinPairRef "@baseboard_fab2_lib.baseboard_fab2(sch_1):\PP3828\") )
				( member ( pinPairRef "@baseboard_fab2_lib.baseboard_fab2(sch_1):\PP3830\") )
				( member ( pinPairRef "@baseboard_fab2_lib.baseboard_fab2(sch_1):\PP3824\") )
				( member ( pinPairRef "@baseboard_fab2_lib.baseboard_fab2(sch_1):\PP3826\") )
				( member ( pinPairRef "@baseboard_fab2_lib.baseboard_fab2(sch_1):\PP3820\") )
				( member ( pinPairRef "@baseboard_fab2_lib.baseboard_fab2(sch_1):\PP3822\") )
				( member ( pinPairRef "@baseboard_fab2_lib.baseboard_fab2(sch_1):\PP3816\") )
				( member ( pinPairRef "@baseboard_fab2_lib.baseboard_fab2(sch_1):\PP3818\") )
				( member ( pinPairRef "@baseboard_fab2_lib.baseboard_fab2(sch_1):\PP3812\") )
				( member ( pinPairRef "@baseboard_fab2_lib.baseboard_fab2(sch_1):\PP3814\") )
				( member ( pinPairRef "@baseboard_fab2_lib.baseboard_fab2(sch_1):\PP3801\") )
				( member ( pinPairRef "@baseboard_fab2_lib.baseboard_fab2(sch_1):\PP3802\") )
				( member ( pinPairRef "@baseboard_fab2_lib.baseboard_fab2(sch_1):\PP3800\") )
				( member ( pinPairRef "@baseboard_fab2_lib.baseboard_fab2(sch_1):\PP3798\") )
				( member ( pinPairRef "@baseboard_fab2_lib.baseboard_fab2(sch_1):\PP3799\") )
				( member ( pinPairRef "@baseboard_fab2_lib.baseboard_fab2(sch_1):\PP3796\") )
				( member ( pinPairRef "@baseboard_fab2_lib.baseboard_fab2(sch_1):\PP3797\") )
				( member ( pinPairRef "@baseboard_fab2_lib.baseboard_fab2(sch_1):\PP3795\") )
				( member ( signalRef "@baseboard_fab2_lib.baseboard_fab2(sch_1):m_d_clk_dp(2)") )
				( objectStatus "MG_DDR_NEAR_DIMM-CLK1_CLS_DDR_D_CAC-CLKS" )
			)
			( matchGroup "@baseboard_fab2_lib.baseboard_fab2(sch_1):\MG_DDR_FAR_DIMM_CMD_NG_DDR_D_DLL_2\"
				( memberType ( signal ) )
				( member ( pinPairRef "@baseboard_fab2_lib.baseboard_fab2(sch_1):\PP3853\") )
				( member ( pinPairRef "@baseboard_fab2_lib.baseboard_fab2(sch_1):\PP3855\") )
				( objectStatus "MG_DDR_FAR_DIMM_CMD_NG_DDR_D_DLL_2" )
			)
			( matchGroup "@baseboard_fab2_lib.baseboard_fab2(sch_1):\MG_DDR_CMD_NEAR_DIMM_NG_DDR_D_DLL_2\"
				( memberType ( signal ) )
				( member ( pinPairRef "@baseboard_fab2_lib.baseboard_fab2(sch_1):\PP3854\") )
				( member ( pinPairRef "@baseboard_fab2_lib.baseboard_fab2(sch_1):\PP3856\") )
				( objectStatus "MG_DDR_CMD_NEAR_DIMM_NG_DDR_D_DLL_2" )
			)
			( matchGroup "@baseboard_fab2_lib.baseboard_fab2(sch_1):\MG_DDR_FAR_DIMM_CMD_NG_DDR_D_DLL_3\"
				( memberType ( signal ) )
				( member ( pinPairRef "@baseboard_fab2_lib.baseboard_fab2(sch_1):\PP3849\") )
				( member ( pinPairRef "@baseboard_fab2_lib.baseboard_fab2(sch_1):\PP3851\") )
				( objectStatus "MG_DDR_FAR_DIMM_CMD_NG_DDR_D_DLL_3" )
			)
			( matchGroup "@baseboard_fab2_lib.baseboard_fab2(sch_1):\MG_DDR_CMD_NEAR_DIMM_NG_DDR_D_DLL_3\"
				( memberType ( signal ) )
				( member ( pinPairRef "@baseboard_fab2_lib.baseboard_fab2(sch_1):\PP3850\") )
				( member ( pinPairRef "@baseboard_fab2_lib.baseboard_fab2(sch_1):\PP3852\") )
				( objectStatus "MG_DDR_CMD_NEAR_DIMM_NG_DDR_D_DLL_3" )
			)
			( matchGroup "@baseboard_fab2_lib.baseboard_fab2(sch_1):\MG_DDR_FAR_DIMM_CMD_NG_DDR_D_DLL_4\"
				( memberType ( signal ) )
				( member ( pinPairRef "@baseboard_fab2_lib.baseboard_fab2(sch_1):\PP3845\") )
				( member ( pinPairRef "@baseboard_fab2_lib.baseboard_fab2(sch_1):\PP3847\") )
				( objectStatus "MG_DDR_FAR_DIMM_CMD_NG_DDR_D_DLL_4" )
			)
			( matchGroup "@baseboard_fab2_lib.baseboard_fab2(sch_1):\MG_DDR_CMD_NEAR_DIMM_NG_DDR_D_DLL_4\"
				( memberType ( signal ) )
				( member ( pinPairRef "@baseboard_fab2_lib.baseboard_fab2(sch_1):\PP3846\") )
				( member ( pinPairRef "@baseboard_fab2_lib.baseboard_fab2(sch_1):\PP3848\") )
				( objectStatus "MG_DDR_CMD_NEAR_DIMM_NG_DDR_D_DLL_4" )
			)
			( matchGroup "@baseboard_fab2_lib.baseboard_fab2(sch_1):\MG_DDR_FAR_DIMM_CMD_NG_DDR_D_DLL_5\"
				( memberType ( signal ) )
				( member ( pinPairRef "@baseboard_fab2_lib.baseboard_fab2(sch_1):\PP3841\") )
				( member ( pinPairRef "@baseboard_fab2_lib.baseboard_fab2(sch_1):\PP3843\") )
				( objectStatus "MG_DDR_FAR_DIMM_CMD_NG_DDR_D_DLL_5" )
			)
			( matchGroup "@baseboard_fab2_lib.baseboard_fab2(sch_1):\MG_DDR_CMD_NEAR_DIMM_NG_DDR_D_DLL_5\"
				( memberType ( signal ) )
				( member ( pinPairRef "@baseboard_fab2_lib.baseboard_fab2(sch_1):\PP3842\") )
				( member ( pinPairRef "@baseboard_fab2_lib.baseboard_fab2(sch_1):\PP3844\") )
				( objectStatus "MG_DDR_CMD_NEAR_DIMM_NG_DDR_D_DLL_5" )
			)
			( matchGroup "@baseboard_fab2_lib.baseboard_fab2(sch_1):\MG_DDR_FAR_DIMM_CMD_NG_DDR_D_DLL_6\"
				( memberType ( signal ) )
				( member ( pinPairRef "@baseboard_fab2_lib.baseboard_fab2(sch_1):\PP3839\") )
				( objectStatus "MG_DDR_FAR_DIMM_CMD_NG_DDR_D_DLL_6" )
			)
			( matchGroup "@baseboard_fab2_lib.baseboard_fab2(sch_1):\MG_DDR_CMD_NEAR_DIMM_NG_DDR_D_DLL_6\"
				( memberType ( signal ) )
				( member ( pinPairRef "@baseboard_fab2_lib.baseboard_fab2(sch_1):\PP3840\") )
				( objectStatus "MG_DDR_CMD_NEAR_DIMM_NG_DDR_D_DLL_6" )
			)
			( matchGroup "@baseboard_fab2_lib.baseboard_fab2(sch_1):\MG_DDR_FAR_DIMM_CMD_NG_DDR_D_DLL_7\"
				( memberType ( signal ) )
				( member ( pinPairRef "@baseboard_fab2_lib.baseboard_fab2(sch_1):\PP3835\") )
				( member ( pinPairRef "@baseboard_fab2_lib.baseboard_fab2(sch_1):\PP3837\") )
				( objectStatus "MG_DDR_FAR_DIMM_CMD_NG_DDR_D_DLL_7" )
			)
			( matchGroup "@baseboard_fab2_lib.baseboard_fab2(sch_1):\MG_DDR_CMD_NEAR_DIMM_NG_DDR_D_DLL_7\"
				( memberType ( signal ) )
				( member ( pinPairRef "@baseboard_fab2_lib.baseboard_fab2(sch_1):\PP3836\") )
				( member ( pinPairRef "@baseboard_fab2_lib.baseboard_fab2(sch_1):\PP3838\") )
				( objectStatus "MG_DDR_CMD_NEAR_DIMM_NG_DDR_D_DLL_7" )
			)
			( matchGroup "@baseboard_fab2_lib.baseboard_fab2(sch_1):\MG_DDR_FAR_DIMM_CMD_NG_DDR_D_DLL_8\"
				( memberType ( signal ) )
				( member ( pinPairRef "@baseboard_fab2_lib.baseboard_fab2(sch_1):\PP3831\") )
				( member ( pinPairRef "@baseboard_fab2_lib.baseboard_fab2(sch_1):\PP3833\") )
				( objectStatus "MG_DDR_FAR_DIMM_CMD_NG_DDR_D_DLL_8" )
			)
			( matchGroup "@baseboard_fab2_lib.baseboard_fab2(sch_1):\MG_DDR_CMD_NEAR_DIMM_NG_DDR_D_DLL_8\"
				( memberType ( signal ) )
				( member ( pinPairRef "@baseboard_fab2_lib.baseboard_fab2(sch_1):\PP3832\") )
				( member ( pinPairRef "@baseboard_fab2_lib.baseboard_fab2(sch_1):\PP3834\") )
				( objectStatus "MG_DDR_CMD_NEAR_DIMM_NG_DDR_D_DLL_8" )
			)
			( matchGroup "@baseboard_fab2_lib.baseboard_fab2(sch_1):\MG_DDR_FAR_DIMM_CMD_NG_DDR_D_DLL_9\"
				( memberType ( signal ) )
				( member ( pinPairRef "@baseboard_fab2_lib.baseboard_fab2(sch_1):\PP3827\") )
				( member ( pinPairRef "@baseboard_fab2_lib.baseboard_fab2(sch_1):\PP3829\") )
				( objectStatus "MG_DDR_FAR_DIMM_CMD_NG_DDR_D_DLL_9" )
			)
			( matchGroup "@baseboard_fab2_lib.baseboard_fab2(sch_1):\MG_DDR_CMD_NEAR_DIMM_NG_DDR_D_DLL_9\"
				( memberType ( signal ) )
				( member ( pinPairRef "@baseboard_fab2_lib.baseboard_fab2(sch_1):\PP3828\") )
				( member ( pinPairRef "@baseboard_fab2_lib.baseboard_fab2(sch_1):\PP3830\") )
				( objectStatus "MG_DDR_CMD_NEAR_DIMM_NG_DDR_D_DLL_9" )
			)
			( matchGroup "@baseboard_fab2_lib.baseboard_fab2(sch_1):\MG_DDR_FAR_DIMM_CMD_NG_DDR_D_DLL_10\"
				( memberType ( signal ) )
				( member ( pinPairRef "@baseboard_fab2_lib.baseboard_fab2(sch_1):\PP3823\") )
				( member ( pinPairRef "@baseboard_fab2_lib.baseboard_fab2(sch_1):\PP3825\") )
				( objectStatus "MG_DDR_FAR_DIMM_CMD_NG_DDR_D_DLL_10" )
			)
			( matchGroup "@baseboard_fab2_lib.baseboard_fab2(sch_1):\MG_DDR_CMD_NEAR_DIMM_NG_DDR_D_DLL_10\"
				( memberType ( signal ) )
				( member ( pinPairRef "@baseboard_fab2_lib.baseboard_fab2(sch_1):\PP3824\") )
				( member ( pinPairRef "@baseboard_fab2_lib.baseboard_fab2(sch_1):\PP3826\") )
				( objectStatus "MG_DDR_CMD_NEAR_DIMM_NG_DDR_D_DLL_10" )
			)
			( matchGroup "@baseboard_fab2_lib.baseboard_fab2(sch_1):\MG_DDR_FAR_DIMM_CMD_NG_DDR_D_DLL_11\"
				( memberType ( signal ) )
				( member ( pinPairRef "@baseboard_fab2_lib.baseboard_fab2(sch_1):\PP3819\") )
				( member ( pinPairRef "@baseboard_fab2_lib.baseboard_fab2(sch_1):\PP3821\") )
				( objectStatus "MG_DDR_FAR_DIMM_CMD_NG_DDR_D_DLL_11" )
			)
			( matchGroup "@baseboard_fab2_lib.baseboard_fab2(sch_1):\MG_DDR_CMD_NEAR_DIMM_NG_DDR_D_DLL_11\"
				( memberType ( signal ) )
				( member ( pinPairRef "@baseboard_fab2_lib.baseboard_fab2(sch_1):\PP3820\") )
				( member ( pinPairRef "@baseboard_fab2_lib.baseboard_fab2(sch_1):\PP3822\") )
				( objectStatus "MG_DDR_CMD_NEAR_DIMM_NG_DDR_D_DLL_11" )
			)
			( matchGroup "@baseboard_fab2_lib.baseboard_fab2(sch_1):\MG_DDR_FAR_DIMM_CMD_NG_DDR_D_DLL_12\"
				( memberType ( signal ) )
				( member ( pinPairRef "@baseboard_fab2_lib.baseboard_fab2(sch_1):\PP3815\") )
				( member ( pinPairRef "@baseboard_fab2_lib.baseboard_fab2(sch_1):\PP3817\") )
				( objectStatus "MG_DDR_FAR_DIMM_CMD_NG_DDR_D_DLL_12" )
			)
			( matchGroup "@baseboard_fab2_lib.baseboard_fab2(sch_1):\MG_DDR_CMD_NEAR_DIMM_NG_DDR_D_DLL_12\"
				( memberType ( signal ) )
				( member ( pinPairRef "@baseboard_fab2_lib.baseboard_fab2(sch_1):\PP3816\") )
				( member ( pinPairRef "@baseboard_fab2_lib.baseboard_fab2(sch_1):\PP3818\") )
				( objectStatus "MG_DDR_CMD_NEAR_DIMM_NG_DDR_D_DLL_12" )
			)
			( matchGroup "@baseboard_fab2_lib.baseboard_fab2(sch_1):\MG_DDR_FAR_DIMM_CMD_NG_DDR_D_DLL_13\"
				( memberType ( signal ) )
				( member ( pinPairRef "@baseboard_fab2_lib.baseboard_fab2(sch_1):\PP3811\") )
				( member ( pinPairRef "@baseboard_fab2_lib.baseboard_fab2(sch_1):\PP3813\") )
				( objectStatus "MG_DDR_FAR_DIMM_CMD_NG_DDR_D_DLL_13" )
			)
			( matchGroup "@baseboard_fab2_lib.baseboard_fab2(sch_1):\MG_DDR_CMD_NEAR_DIMM_NG_DDR_D_DLL_13\"
				( memberType ( signal ) )
				( member ( pinPairRef "@baseboard_fab2_lib.baseboard_fab2(sch_1):\PP3812\") )
				( member ( pinPairRef "@baseboard_fab2_lib.baseboard_fab2(sch_1):\PP3814\") )
				( objectStatus "MG_DDR_CMD_NEAR_DIMM_NG_DDR_D_DLL_13" )
			)
			( matchGroup "@baseboard_fab2_lib.baseboard_fab2(sch_1):\MG_DDR_CTRL_NG_DDR_D_DLL_14\"
				( memberType ( signal ) )
				( member ( pinPairRef "@baseboard_fab2_lib.baseboard_fab2(sch_1):\PP3809\") )
				( member ( pinPairRef "@baseboard_fab2_lib.baseboard_fab2(sch_1):\PP3810\") )
				( objectStatus "MG_DDR_CTRL_NG_DDR_D_DLL_14" )
			)
			( matchGroup "@baseboard_fab2_lib.baseboard_fab2(sch_1):\MG_DDR_CTRL_NG_DDR_D_DLL_15\"
				( memberType ( signal ) )
				( member ( pinPairRef "@baseboard_fab2_lib.baseboard_fab2(sch_1):\PP3808\") )
				( objectStatus "MG_DDR_CTRL_NG_DDR_D_DLL_15" )
			)
			( matchGroup "@baseboard_fab2_lib.baseboard_fab2(sch_1):\MG_DDR_CTRL_NG_DDR_D_DLL_16\"
				( memberType ( signal ) )
				( member ( pinPairRef "@baseboard_fab2_lib.baseboard_fab2(sch_1):\PP3807\") )
				( objectStatus "MG_DDR_CTRL_NG_DDR_D_DLL_16" )
			)
			( matchGroup "@baseboard_fab2_lib.baseboard_fab2(sch_1):\MG_DDR_CTRL_NG_DDR_D_DLL_17\"
				( memberType ( signal ) )
				( member ( pinPairRef "@baseboard_fab2_lib.baseboard_fab2(sch_1):\PP3806\") )
				( objectStatus "MG_DDR_CTRL_NG_DDR_D_DLL_17" )
			)
			( matchGroup "@baseboard_fab2_lib.baseboard_fab2(sch_1):\MG_DDR_CTRL_NG_DDR_D_DLL_18\"
				( memberType ( signal ) )
				( member ( pinPairRef "@baseboard_fab2_lib.baseboard_fab2(sch_1):\PP3804\") )
				( member ( pinPairRef "@baseboard_fab2_lib.baseboard_fab2(sch_1):\PP3805\") )
				( objectStatus "MG_DDR_CTRL_NG_DDR_D_DLL_18" )
			)
			( matchGroup "@baseboard_fab2_lib.baseboard_fab2(sch_1):\MG_DDR_CTRL_NG_DDR_D_DLL_19\"
				( memberType ( signal ) )
				( member ( pinPairRef "@baseboard_fab2_lib.baseboard_fab2(sch_1):\PP3803\") )
				( objectStatus "MG_DDR_CTRL_NG_DDR_D_DLL_19" )
			)
			( matchGroup "@baseboard_fab2_lib.baseboard_fab2(sch_1):\MG_DDR_CTRL_NG_DDR_D_DLL_20\"
				( memberType ( signal ) )
				( member ( pinPairRef "@baseboard_fab2_lib.baseboard_fab2(sch_1):\PP3801\") )
				( member ( pinPairRef "@baseboard_fab2_lib.baseboard_fab2(sch_1):\PP3802\") )
				( objectStatus "MG_DDR_CTRL_NG_DDR_D_DLL_20" )
			)
			( matchGroup "@baseboard_fab2_lib.baseboard_fab2(sch_1):\MG_DDR_CTRL_NG_DDR_D_DLL_21\"
				( memberType ( signal ) )
				( member ( pinPairRef "@baseboard_fab2_lib.baseboard_fab2(sch_1):\PP3800\") )
				( objectStatus "MG_DDR_CTRL_NG_DDR_D_DLL_21" )
			)
			( matchGroup "@baseboard_fab2_lib.baseboard_fab2(sch_1):\MG_DDR_CTRL_NG_DDR_D_DLL_22\"
				( memberType ( signal ) )
				( member ( pinPairRef "@baseboard_fab2_lib.baseboard_fab2(sch_1):\PP3798\") )
				( member ( pinPairRef "@baseboard_fab2_lib.baseboard_fab2(sch_1):\PP3799\") )
				( objectStatus "MG_DDR_CTRL_NG_DDR_D_DLL_22" )
			)
			( matchGroup "@baseboard_fab2_lib.baseboard_fab2(sch_1):\MG_DDR_CTRL_NG_DDR_D_DLL_23\"
				( memberType ( signal ) )
				( member ( pinPairRef "@baseboard_fab2_lib.baseboard_fab2(sch_1):\PP3796\") )
				( member ( pinPairRef "@baseboard_fab2_lib.baseboard_fab2(sch_1):\PP3797\") )
				( objectStatus "MG_DDR_CTRL_NG_DDR_D_DLL_23" )
			)
			( matchGroup "@baseboard_fab2_lib.baseboard_fab2(sch_1):\MG_DDR_CTRL_NG_DDR_D_DLL_24\"
				( memberType ( signal ) )
				( member ( pinPairRef "@baseboard_fab2_lib.baseboard_fab2(sch_1):\PP3795\") )
				( objectStatus "MG_DDR_CTRL_NG_DDR_D_DLL_24" )
			)
			( matchGroup "@crescent_city_bb_fab1_lib.crescent_city_bb_fab1(sch_1):\MG_DDR_FAR_DIMM-CLK0_CLS_DDR_C_CAC-CLKS\"
				( memberType ( signal ) )
				( member ( pinPairRef "@baseboard_fab2_lib.baseboard_fab2(sch_1):\PP3923\") )
				( member ( pinPairRef "@baseboard_fab2_lib.baseboard_fab2(sch_1):\PP3925\") )
				( member ( pinPairRef "@baseboard_fab2_lib.baseboard_fab2(sch_1):\PP3919\") )
				( member ( pinPairRef "@baseboard_fab2_lib.baseboard_fab2(sch_1):\PP3921\") )
				( member ( pinPairRef "@baseboard_fab2_lib.baseboard_fab2(sch_1):\PP3915\") )
				( member ( pinPairRef "@baseboard_fab2_lib.baseboard_fab2(sch_1):\PP3917\") )
				( member ( pinPairRef "@baseboard_fab2_lib.baseboard_fab2(sch_1):\PP3911\") )
				( member ( pinPairRef "@baseboard_fab2_lib.baseboard_fab2(sch_1):\PP3913\") )
				( member ( pinPairRef "@baseboard_fab2_lib.baseboard_fab2(sch_1):\PP3907\") )
				( member ( pinPairRef "@baseboard_fab2_lib.baseboard_fab2(sch_1):\PP3909\") )
				( member ( pinPairRef "@baseboard_fab2_lib.baseboard_fab2(sch_1):\PP3905\") )
				( member ( pinPairRef "@baseboard_fab2_lib.baseboard_fab2(sch_1):\PP3901\") )
				( member ( pinPairRef "@baseboard_fab2_lib.baseboard_fab2(sch_1):\PP3903\") )
				( member ( pinPairRef "@baseboard_fab2_lib.baseboard_fab2(sch_1):\PP3897\") )
				( member ( pinPairRef "@baseboard_fab2_lib.baseboard_fab2(sch_1):\PP3899\") )
				( member ( pinPairRef "@baseboard_fab2_lib.baseboard_fab2(sch_1):\PP3893\") )
				( member ( pinPairRef "@baseboard_fab2_lib.baseboard_fab2(sch_1):\PP3895\") )
				( member ( pinPairRef "@baseboard_fab2_lib.baseboard_fab2(sch_1):\PP3889\") )
				( member ( pinPairRef "@baseboard_fab2_lib.baseboard_fab2(sch_1):\PP3891\") )
				( member ( pinPairRef "@baseboard_fab2_lib.baseboard_fab2(sch_1):\PP3885\") )
				( member ( pinPairRef "@baseboard_fab2_lib.baseboard_fab2(sch_1):\PP3887\") )
				( member ( pinPairRef "@baseboard_fab2_lib.baseboard_fab2(sch_1):\PP3881\") )
				( member ( pinPairRef "@baseboard_fab2_lib.baseboard_fab2(sch_1):\PP3883\") )
				( member ( pinPairRef "@baseboard_fab2_lib.baseboard_fab2(sch_1):\PP3877\") )
				( member ( pinPairRef "@baseboard_fab2_lib.baseboard_fab2(sch_1):\PP3879\") )
				( member ( pinPairRef "@baseboard_fab2_lib.baseboard_fab2(sch_1):\PP3875\") )
				( member ( pinPairRef "@baseboard_fab2_lib.baseboard_fab2(sch_1):\PP3876\") )
				( member ( pinPairRef "@baseboard_fab2_lib.baseboard_fab2(sch_1):\PP3874\") )
				( member ( pinPairRef "@baseboard_fab2_lib.baseboard_fab2(sch_1):\PP3873\") )
				( member ( pinPairRef "@baseboard_fab2_lib.baseboard_fab2(sch_1):\PP3872\") )
				( member ( pinPairRef "@baseboard_fab2_lib.baseboard_fab2(sch_1):\PP3870\") )
				( member ( pinPairRef "@baseboard_fab2_lib.baseboard_fab2(sch_1):\PP3871\") )
				( member ( pinPairRef "@baseboard_fab2_lib.baseboard_fab2(sch_1):\PP3869\") )
				( member ( signalRef "@baseboard_fab2_lib.baseboard_fab2(sch_1):m_c_clk_dp(0)") )
				( objectStatus "MG_DDR_FAR_DIMM-CLK0_CLS_DDR_C_CAC-CLKS" )
			)
			( matchGroup "@baseboard_fab2_lib.baseboard_fab2(sch_1):\MG_DDR_FAR_DIMM_CMD_NG_DDR_C_DLL_1\"
				( memberType ( signal ) )
				( member ( pinPairRef "@baseboard_fab2_lib.baseboard_fab2(sch_1):\PP3923\") )
				( member ( pinPairRef "@baseboard_fab2_lib.baseboard_fab2(sch_1):\PP3925\") )
				( objectStatus "MG_DDR_FAR_DIMM_CMD_NG_DDR_C_DLL_1" )
			)
			( matchGroup "@baseboard_fab2_lib.baseboard_fab2(sch_1):\MG_DDR_CMD_NEAR_DIMM_NG_DDR_C_DLL_1\"
				( memberType ( signal ) )
				( member ( pinPairRef "@baseboard_fab2_lib.baseboard_fab2(sch_1):\PP3924\") )
				( member ( pinPairRef "@baseboard_fab2_lib.baseboard_fab2(sch_1):\PP3926\") )
				( objectStatus "MG_DDR_CMD_NEAR_DIMM_NG_DDR_C_DLL_1" )
			)
			( matchGroup "@crescent_city_bb_fab1_lib.crescent_city_bb_fab1(sch_1):\MG_DDR_NEAR_DIMM-CLK1_CLS_DDR_C_CAC-CLKS\"
				( memberType ( signal ) )
				( member ( pinPairRef "@baseboard_fab2_lib.baseboard_fab2(sch_1):\PP3924\") )
				( member ( pinPairRef "@baseboard_fab2_lib.baseboard_fab2(sch_1):\PP3926\") )
				( member ( pinPairRef "@baseboard_fab2_lib.baseboard_fab2(sch_1):\PP3920\") )
				( member ( pinPairRef "@baseboard_fab2_lib.baseboard_fab2(sch_1):\PP3922\") )
				( member ( pinPairRef "@baseboard_fab2_lib.baseboard_fab2(sch_1):\PP3916\") )
				( member ( pinPairRef "@baseboard_fab2_lib.baseboard_fab2(sch_1):\PP3918\") )
				( member ( pinPairRef "@baseboard_fab2_lib.baseboard_fab2(sch_1):\PP3912\") )
				( member ( pinPairRef "@baseboard_fab2_lib.baseboard_fab2(sch_1):\PP3914\") )
				( member ( pinPairRef "@baseboard_fab2_lib.baseboard_fab2(sch_1):\PP3908\") )
				( member ( pinPairRef "@baseboard_fab2_lib.baseboard_fab2(sch_1):\PP3910\") )
				( member ( pinPairRef "@baseboard_fab2_lib.baseboard_fab2(sch_1):\PP3906\") )
				( member ( pinPairRef "@baseboard_fab2_lib.baseboard_fab2(sch_1):\PP3902\") )
				( member ( pinPairRef "@baseboard_fab2_lib.baseboard_fab2(sch_1):\PP3904\") )
				( member ( pinPairRef "@baseboard_fab2_lib.baseboard_fab2(sch_1):\PP3898\") )
				( member ( pinPairRef "@baseboard_fab2_lib.baseboard_fab2(sch_1):\PP3900\") )
				( member ( pinPairRef "@baseboard_fab2_lib.baseboard_fab2(sch_1):\PP3894\") )
				( member ( pinPairRef "@baseboard_fab2_lib.baseboard_fab2(sch_1):\PP3896\") )
				( member ( pinPairRef "@baseboard_fab2_lib.baseboard_fab2(sch_1):\PP3890\") )
				( member ( pinPairRef "@baseboard_fab2_lib.baseboard_fab2(sch_1):\PP3892\") )
				( member ( pinPairRef "@baseboard_fab2_lib.baseboard_fab2(sch_1):\PP3886\") )
				( member ( pinPairRef "@baseboard_fab2_lib.baseboard_fab2(sch_1):\PP3888\") )
				( member ( pinPairRef "@baseboard_fab2_lib.baseboard_fab2(sch_1):\PP3882\") )
				( member ( pinPairRef "@baseboard_fab2_lib.baseboard_fab2(sch_1):\PP3884\") )
				( member ( pinPairRef "@baseboard_fab2_lib.baseboard_fab2(sch_1):\PP3878\") )
				( member ( pinPairRef "@baseboard_fab2_lib.baseboard_fab2(sch_1):\PP3880\") )
				( member ( pinPairRef "@baseboard_fab2_lib.baseboard_fab2(sch_1):\PP3867\") )
				( member ( pinPairRef "@baseboard_fab2_lib.baseboard_fab2(sch_1):\PP3868\") )
				( member ( pinPairRef "@baseboard_fab2_lib.baseboard_fab2(sch_1):\PP3866\") )
				( member ( pinPairRef "@baseboard_fab2_lib.baseboard_fab2(sch_1):\PP3864\") )
				( member ( pinPairRef "@baseboard_fab2_lib.baseboard_fab2(sch_1):\PP3865\") )
				( member ( pinPairRef "@baseboard_fab2_lib.baseboard_fab2(sch_1):\PP3862\") )
				( member ( pinPairRef "@baseboard_fab2_lib.baseboard_fab2(sch_1):\PP3863\") )
				( member ( pinPairRef "@baseboard_fab2_lib.baseboard_fab2(sch_1):\PP3861\") )
				( member ( signalRef "@baseboard_fab2_lib.baseboard_fab2(sch_1):m_c_clk_dp(2)") )
				( objectStatus "MG_DDR_NEAR_DIMM-CLK1_CLS_DDR_C_CAC-CLKS" )
			)
			( matchGroup "@baseboard_fab2_lib.baseboard_fab2(sch_1):\MG_DDR_FAR_DIMM_CMD_NG_DDR_C_DLL_2\"
				( memberType ( signal ) )
				( member ( pinPairRef "@baseboard_fab2_lib.baseboard_fab2(sch_1):\PP3919\") )
				( member ( pinPairRef "@baseboard_fab2_lib.baseboard_fab2(sch_1):\PP3921\") )
				( objectStatus "MG_DDR_FAR_DIMM_CMD_NG_DDR_C_DLL_2" )
			)
			( matchGroup "@baseboard_fab2_lib.baseboard_fab2(sch_1):\MG_DDR_CMD_NEAR_DIMM_NG_DDR_C_DLL_2\"
				( memberType ( signal ) )
				( member ( pinPairRef "@baseboard_fab2_lib.baseboard_fab2(sch_1):\PP3920\") )
				( member ( pinPairRef "@baseboard_fab2_lib.baseboard_fab2(sch_1):\PP3922\") )
				( objectStatus "MG_DDR_CMD_NEAR_DIMM_NG_DDR_C_DLL_2" )
			)
			( matchGroup "@baseboard_fab2_lib.baseboard_fab2(sch_1):\MG_DDR_FAR_DIMM_CMD_NG_DDR_C_DLL_3\"
				( memberType ( signal ) )
				( member ( pinPairRef "@baseboard_fab2_lib.baseboard_fab2(sch_1):\PP3915\") )
				( member ( pinPairRef "@baseboard_fab2_lib.baseboard_fab2(sch_1):\PP3917\") )
				( objectStatus "MG_DDR_FAR_DIMM_CMD_NG_DDR_C_DLL_3" )
			)
			( matchGroup "@baseboard_fab2_lib.baseboard_fab2(sch_1):\MG_DDR_CMD_NEAR_DIMM_NG_DDR_C_DLL_3\"
				( memberType ( signal ) )
				( member ( pinPairRef "@baseboard_fab2_lib.baseboard_fab2(sch_1):\PP3916\") )
				( member ( pinPairRef "@baseboard_fab2_lib.baseboard_fab2(sch_1):\PP3918\") )
				( objectStatus "MG_DDR_CMD_NEAR_DIMM_NG_DDR_C_DLL_3" )
			)
			( matchGroup "@baseboard_fab2_lib.baseboard_fab2(sch_1):\MG_DDR_FAR_DIMM_CMD_NG_DDR_C_DLL_4\"
				( memberType ( signal ) )
				( member ( pinPairRef "@baseboard_fab2_lib.baseboard_fab2(sch_1):\PP3911\") )
				( member ( pinPairRef "@baseboard_fab2_lib.baseboard_fab2(sch_1):\PP3913\") )
				( objectStatus "MG_DDR_FAR_DIMM_CMD_NG_DDR_C_DLL_4" )
			)
			( matchGroup "@baseboard_fab2_lib.baseboard_fab2(sch_1):\MG_DDR_CMD_NEAR_DIMM_NG_DDR_C_DLL_4\"
				( memberType ( signal ) )
				( member ( pinPairRef "@baseboard_fab2_lib.baseboard_fab2(sch_1):\PP3912\") )
				( member ( pinPairRef "@baseboard_fab2_lib.baseboard_fab2(sch_1):\PP3914\") )
				( objectStatus "MG_DDR_CMD_NEAR_DIMM_NG_DDR_C_DLL_4" )
			)
			( matchGroup "@baseboard_fab2_lib.baseboard_fab2(sch_1):\MG_DDR_FAR_DIMM_CMD_NG_DDR_C_DLL_5\"
				( memberType ( signal ) )
				( member ( pinPairRef "@baseboard_fab2_lib.baseboard_fab2(sch_1):\PP3907\") )
				( member ( pinPairRef "@baseboard_fab2_lib.baseboard_fab2(sch_1):\PP3909\") )
				( objectStatus "MG_DDR_FAR_DIMM_CMD_NG_DDR_C_DLL_5" )
			)
			( matchGroup "@baseboard_fab2_lib.baseboard_fab2(sch_1):\MG_DDR_CMD_NEAR_DIMM_NG_DDR_C_DLL_5\"
				( memberType ( signal ) )
				( member ( pinPairRef "@baseboard_fab2_lib.baseboard_fab2(sch_1):\PP3908\") )
				( member ( pinPairRef "@baseboard_fab2_lib.baseboard_fab2(sch_1):\PP3910\") )
				( objectStatus "MG_DDR_CMD_NEAR_DIMM_NG_DDR_C_DLL_5" )
			)
			( matchGroup "@baseboard_fab2_lib.baseboard_fab2(sch_1):\MG_DDR_FAR_DIMM_CMD_NG_DDR_C_DLL_6\"
				( memberType ( signal ) )
				( member ( pinPairRef "@baseboard_fab2_lib.baseboard_fab2(sch_1):\PP3905\") )
				( objectStatus "MG_DDR_FAR_DIMM_CMD_NG_DDR_C_DLL_6" )
			)
			( matchGroup "@baseboard_fab2_lib.baseboard_fab2(sch_1):\MG_DDR_CMD_NEAR_DIMM_NG_DDR_C_DLL_6\"
				( memberType ( signal ) )
				( member ( pinPairRef "@baseboard_fab2_lib.baseboard_fab2(sch_1):\PP3906\") )
				( objectStatus "MG_DDR_CMD_NEAR_DIMM_NG_DDR_C_DLL_6" )
			)
			( matchGroup "@baseboard_fab2_lib.baseboard_fab2(sch_1):\MG_DDR_FAR_DIMM_CMD_NG_DDR_C_DLL_7\"
				( memberType ( signal ) )
				( member ( pinPairRef "@baseboard_fab2_lib.baseboard_fab2(sch_1):\PP3901\") )
				( member ( pinPairRef "@baseboard_fab2_lib.baseboard_fab2(sch_1):\PP3903\") )
				( objectStatus "MG_DDR_FAR_DIMM_CMD_NG_DDR_C_DLL_7" )
			)
			( matchGroup "@baseboard_fab2_lib.baseboard_fab2(sch_1):\MG_DDR_CMD_NEAR_DIMM_NG_DDR_C_DLL_7\"
				( memberType ( signal ) )
				( member ( pinPairRef "@baseboard_fab2_lib.baseboard_fab2(sch_1):\PP3902\") )
				( member ( pinPairRef "@baseboard_fab2_lib.baseboard_fab2(sch_1):\PP3904\") )
				( objectStatus "MG_DDR_CMD_NEAR_DIMM_NG_DDR_C_DLL_7" )
			)
			( matchGroup "@baseboard_fab2_lib.baseboard_fab2(sch_1):\MG_DDR_FAR_DIMM_CMD_NG_DDR_C_DLL_8\"
				( memberType ( signal ) )
				( member ( pinPairRef "@baseboard_fab2_lib.baseboard_fab2(sch_1):\PP3897\") )
				( member ( pinPairRef "@baseboard_fab2_lib.baseboard_fab2(sch_1):\PP3899\") )
				( objectStatus "MG_DDR_FAR_DIMM_CMD_NG_DDR_C_DLL_8" )
			)
			( matchGroup "@baseboard_fab2_lib.baseboard_fab2(sch_1):\MG_DDR_CMD_NEAR_DIMM_NG_DDR_C_DLL_8\"
				( memberType ( signal ) )
				( member ( pinPairRef "@baseboard_fab2_lib.baseboard_fab2(sch_1):\PP3898\") )
				( member ( pinPairRef "@baseboard_fab2_lib.baseboard_fab2(sch_1):\PP3900\") )
				( objectStatus "MG_DDR_CMD_NEAR_DIMM_NG_DDR_C_DLL_8" )
			)
			( matchGroup "@baseboard_fab2_lib.baseboard_fab2(sch_1):\MG_DDR_FAR_DIMM_CMD_NG_DDR_C_DLL_9\"
				( memberType ( signal ) )
				( member ( pinPairRef "@baseboard_fab2_lib.baseboard_fab2(sch_1):\PP3893\") )
				( member ( pinPairRef "@baseboard_fab2_lib.baseboard_fab2(sch_1):\PP3895\") )
				( objectStatus "MG_DDR_FAR_DIMM_CMD_NG_DDR_C_DLL_9" )
			)
			( matchGroup "@baseboard_fab2_lib.baseboard_fab2(sch_1):\MG_DDR_CMD_NEAR_DIMM_NG_DDR_C_DLL_9\"
				( memberType ( signal ) )
				( member ( pinPairRef "@baseboard_fab2_lib.baseboard_fab2(sch_1):\PP3894\") )
				( member ( pinPairRef "@baseboard_fab2_lib.baseboard_fab2(sch_1):\PP3896\") )
				( objectStatus "MG_DDR_CMD_NEAR_DIMM_NG_DDR_C_DLL_9" )
			)
			( matchGroup "@baseboard_fab2_lib.baseboard_fab2(sch_1):\MG_DDR_FAR_DIMM_CMD_NG_DDR_C_DLL_10\"
				( memberType ( signal ) )
				( member ( pinPairRef "@baseboard_fab2_lib.baseboard_fab2(sch_1):\PP3889\") )
				( member ( pinPairRef "@baseboard_fab2_lib.baseboard_fab2(sch_1):\PP3891\") )
				( objectStatus "MG_DDR_FAR_DIMM_CMD_NG_DDR_C_DLL_10" )
			)
			( matchGroup "@baseboard_fab2_lib.baseboard_fab2(sch_1):\MG_DDR_CMD_NEAR_DIMM_NG_DDR_C_DLL_10\"
				( memberType ( signal ) )
				( member ( pinPairRef "@baseboard_fab2_lib.baseboard_fab2(sch_1):\PP3890\") )
				( member ( pinPairRef "@baseboard_fab2_lib.baseboard_fab2(sch_1):\PP3892\") )
				( objectStatus "MG_DDR_CMD_NEAR_DIMM_NG_DDR_C_DLL_10" )
			)
			( matchGroup "@baseboard_fab2_lib.baseboard_fab2(sch_1):\MG_DDR_FAR_DIMM_CMD_NG_DDR_C_DLL_11\"
				( memberType ( signal ) )
				( member ( pinPairRef "@baseboard_fab2_lib.baseboard_fab2(sch_1):\PP3885\") )
				( member ( pinPairRef "@baseboard_fab2_lib.baseboard_fab2(sch_1):\PP3887\") )
				( objectStatus "MG_DDR_FAR_DIMM_CMD_NG_DDR_C_DLL_11" )
			)
			( matchGroup "@baseboard_fab2_lib.baseboard_fab2(sch_1):\MG_DDR_CMD_NEAR_DIMM_NG_DDR_C_DLL_11\"
				( memberType ( signal ) )
				( member ( pinPairRef "@baseboard_fab2_lib.baseboard_fab2(sch_1):\PP3886\") )
				( member ( pinPairRef "@baseboard_fab2_lib.baseboard_fab2(sch_1):\PP3888\") )
				( objectStatus "MG_DDR_CMD_NEAR_DIMM_NG_DDR_C_DLL_11" )
			)
			( matchGroup "@baseboard_fab2_lib.baseboard_fab2(sch_1):\MG_DDR_FAR_DIMM_CMD_NG_DDR_C_DLL_12\"
				( memberType ( signal ) )
				( member ( pinPairRef "@baseboard_fab2_lib.baseboard_fab2(sch_1):\PP3881\") )
				( member ( pinPairRef "@baseboard_fab2_lib.baseboard_fab2(sch_1):\PP3883\") )
				( objectStatus "MG_DDR_FAR_DIMM_CMD_NG_DDR_C_DLL_12" )
			)
			( matchGroup "@baseboard_fab2_lib.baseboard_fab2(sch_1):\MG_DDR_CMD_NEAR_DIMM_NG_DDR_C_DLL_12\"
				( memberType ( signal ) )
				( member ( pinPairRef "@baseboard_fab2_lib.baseboard_fab2(sch_1):\PP3882\") )
				( member ( pinPairRef "@baseboard_fab2_lib.baseboard_fab2(sch_1):\PP3884\") )
				( objectStatus "MG_DDR_CMD_NEAR_DIMM_NG_DDR_C_DLL_12" )
			)
			( matchGroup "@baseboard_fab2_lib.baseboard_fab2(sch_1):\MG_DDR_FAR_DIMM_CMD_NG_DDR_C_DLL_13\"
				( memberType ( signal ) )
				( member ( pinPairRef "@baseboard_fab2_lib.baseboard_fab2(sch_1):\PP3877\") )
				( member ( pinPairRef "@baseboard_fab2_lib.baseboard_fab2(sch_1):\PP3879\") )
				( objectStatus "MG_DDR_FAR_DIMM_CMD_NG_DDR_C_DLL_13" )
			)
			( matchGroup "@baseboard_fab2_lib.baseboard_fab2(sch_1):\MG_DDR_CMD_NEAR_DIMM_NG_DDR_C_DLL_13\"
				( memberType ( signal ) )
				( member ( pinPairRef "@baseboard_fab2_lib.baseboard_fab2(sch_1):\PP3878\") )
				( member ( pinPairRef "@baseboard_fab2_lib.baseboard_fab2(sch_1):\PP3880\") )
				( objectStatus "MG_DDR_CMD_NEAR_DIMM_NG_DDR_C_DLL_13" )
			)
			( matchGroup "@baseboard_fab2_lib.baseboard_fab2(sch_1):\MG_DDR_CTRL_NG_DDR_C_DLL_14\"
				( memberType ( signal ) )
				( member ( pinPairRef "@baseboard_fab2_lib.baseboard_fab2(sch_1):\PP3875\") )
				( member ( pinPairRef "@baseboard_fab2_lib.baseboard_fab2(sch_1):\PP3876\") )
				( objectStatus "MG_DDR_CTRL_NG_DDR_C_DLL_14" )
			)
			( matchGroup "@baseboard_fab2_lib.baseboard_fab2(sch_1):\MG_DDR_CTRL_NG_DDR_C_DLL_15\"
				( memberType ( signal ) )
				( member ( pinPairRef "@baseboard_fab2_lib.baseboard_fab2(sch_1):\PP3874\") )
				( objectStatus "MG_DDR_CTRL_NG_DDR_C_DLL_15" )
			)
			( matchGroup "@baseboard_fab2_lib.baseboard_fab2(sch_1):\MG_DDR_CTRL_NG_DDR_C_DLL_16\"
				( memberType ( signal ) )
				( member ( pinPairRef "@baseboard_fab2_lib.baseboard_fab2(sch_1):\PP3873\") )
				( objectStatus "MG_DDR_CTRL_NG_DDR_C_DLL_16" )
			)
			( matchGroup "@baseboard_fab2_lib.baseboard_fab2(sch_1):\MG_DDR_CTRL_NG_DDR_C_DLL_17\"
				( memberType ( signal ) )
				( member ( pinPairRef "@baseboard_fab2_lib.baseboard_fab2(sch_1):\PP3872\") )
				( objectStatus "MG_DDR_CTRL_NG_DDR_C_DLL_17" )
			)
			( matchGroup "@baseboard_fab2_lib.baseboard_fab2(sch_1):\MG_DDR_CTRL_NG_DDR_C_DLL_18\"
				( memberType ( signal ) )
				( member ( pinPairRef "@baseboard_fab2_lib.baseboard_fab2(sch_1):\PP3870\") )
				( member ( pinPairRef "@baseboard_fab2_lib.baseboard_fab2(sch_1):\PP3871\") )
				( objectStatus "MG_DDR_CTRL_NG_DDR_C_DLL_18" )
			)
			( matchGroup "@baseboard_fab2_lib.baseboard_fab2(sch_1):\MG_DDR_CTRL_NG_DDR_C_DLL_19\"
				( memberType ( signal ) )
				( member ( pinPairRef "@baseboard_fab2_lib.baseboard_fab2(sch_1):\PP3869\") )
				( objectStatus "MG_DDR_CTRL_NG_DDR_C_DLL_19" )
			)
			( matchGroup "@baseboard_fab2_lib.baseboard_fab2(sch_1):\MG_DDR_CTRL_NG_DDR_C_DLL_20\"
				( memberType ( signal ) )
				( member ( pinPairRef "@baseboard_fab2_lib.baseboard_fab2(sch_1):\PP3867\") )
				( member ( pinPairRef "@baseboard_fab2_lib.baseboard_fab2(sch_1):\PP3868\") )
				( objectStatus "MG_DDR_CTRL_NG_DDR_C_DLL_20" )
			)
			( matchGroup "@baseboard_fab2_lib.baseboard_fab2(sch_1):\MG_DDR_CTRL_NG_DDR_C_DLL_21\"
				( memberType ( signal ) )
				( member ( pinPairRef "@baseboard_fab2_lib.baseboard_fab2(sch_1):\PP3866\") )
				( objectStatus "MG_DDR_CTRL_NG_DDR_C_DLL_21" )
			)
			( matchGroup "@baseboard_fab2_lib.baseboard_fab2(sch_1):\MG_DDR_CTRL_NG_DDR_C_DLL_22\"
				( memberType ( signal ) )
				( member ( pinPairRef "@baseboard_fab2_lib.baseboard_fab2(sch_1):\PP3864\") )
				( member ( pinPairRef "@baseboard_fab2_lib.baseboard_fab2(sch_1):\PP3865\") )
				( objectStatus "MG_DDR_CTRL_NG_DDR_C_DLL_22" )
			)
			( matchGroup "@baseboard_fab2_lib.baseboard_fab2(sch_1):\MG_DDR_CTRL_NG_DDR_C_DLL_23\"
				( memberType ( signal ) )
				( member ( pinPairRef "@baseboard_fab2_lib.baseboard_fab2(sch_1):\PP3862\") )
				( member ( pinPairRef "@baseboard_fab2_lib.baseboard_fab2(sch_1):\PP3863\") )
				( objectStatus "MG_DDR_CTRL_NG_DDR_C_DLL_23" )
			)
			( matchGroup "@baseboard_fab2_lib.baseboard_fab2(sch_1):\MG_DDR_CTRL_NG_DDR_C_DLL_24\"
				( memberType ( signal ) )
				( member ( pinPairRef "@baseboard_fab2_lib.baseboard_fab2(sch_1):\PP3861\") )
				( objectStatus "MG_DDR_CTRL_NG_DDR_C_DLL_24" )
			)
			( matchGroup "@crescent_city_bb_fab1_lib.crescent_city_bb_fab1(sch_1):\MG_DDR_FAR_DIMM-CLK0_CLS_DDR_B_CAC-CLKS\"
				( memberType ( signal ) )
				( member ( pinPairRef "@baseboard_fab2_lib.baseboard_fab2(sch_1):\PP3989\") )
				( member ( pinPairRef "@baseboard_fab2_lib.baseboard_fab2(sch_1):\PP3991\") )
				( member ( pinPairRef "@baseboard_fab2_lib.baseboard_fab2(sch_1):\PP3985\") )
				( member ( pinPairRef "@baseboard_fab2_lib.baseboard_fab2(sch_1):\PP3987\") )
				( member ( pinPairRef "@baseboard_fab2_lib.baseboard_fab2(sch_1):\PP3981\") )
				( member ( pinPairRef "@baseboard_fab2_lib.baseboard_fab2(sch_1):\PP3983\") )
				( member ( pinPairRef "@baseboard_fab2_lib.baseboard_fab2(sch_1):\PP3977\") )
				( member ( pinPairRef "@baseboard_fab2_lib.baseboard_fab2(sch_1):\PP3979\") )
				( member ( pinPairRef "@baseboard_fab2_lib.baseboard_fab2(sch_1):\PP3973\") )
				( member ( pinPairRef "@baseboard_fab2_lib.baseboard_fab2(sch_1):\PP3975\") )
				( member ( pinPairRef "@baseboard_fab2_lib.baseboard_fab2(sch_1):\PP3971\") )
				( member ( pinPairRef "@baseboard_fab2_lib.baseboard_fab2(sch_1):\PP3967\") )
				( member ( pinPairRef "@baseboard_fab2_lib.baseboard_fab2(sch_1):\PP3969\") )
				( member ( pinPairRef "@baseboard_fab2_lib.baseboard_fab2(sch_1):\PP3963\") )
				( member ( pinPairRef "@baseboard_fab2_lib.baseboard_fab2(sch_1):\PP3965\") )
				( member ( pinPairRef "@baseboard_fab2_lib.baseboard_fab2(sch_1):\PP3959\") )
				( member ( pinPairRef "@baseboard_fab2_lib.baseboard_fab2(sch_1):\PP3961\") )
				( member ( pinPairRef "@baseboard_fab2_lib.baseboard_fab2(sch_1):\PP3955\") )
				( member ( pinPairRef "@baseboard_fab2_lib.baseboard_fab2(sch_1):\PP3957\") )
				( member ( pinPairRef "@baseboard_fab2_lib.baseboard_fab2(sch_1):\PP3951\") )
				( member ( pinPairRef "@baseboard_fab2_lib.baseboard_fab2(sch_1):\PP3953\") )
				( member ( pinPairRef "@baseboard_fab2_lib.baseboard_fab2(sch_1):\PP3947\") )
				( member ( pinPairRef "@baseboard_fab2_lib.baseboard_fab2(sch_1):\PP3949\") )
				( member ( pinPairRef "@baseboard_fab2_lib.baseboard_fab2(sch_1):\PP3943\") )
				( member ( pinPairRef "@baseboard_fab2_lib.baseboard_fab2(sch_1):\PP3945\") )
				( member ( pinPairRef "@baseboard_fab2_lib.baseboard_fab2(sch_1):\PP3941\") )
				( member ( pinPairRef "@baseboard_fab2_lib.baseboard_fab2(sch_1):\PP3942\") )
				( member ( pinPairRef "@baseboard_fab2_lib.baseboard_fab2(sch_1):\PP3940\") )
				( member ( pinPairRef "@baseboard_fab2_lib.baseboard_fab2(sch_1):\PP3939\") )
				( member ( pinPairRef "@baseboard_fab2_lib.baseboard_fab2(sch_1):\PP3938\") )
				( member ( pinPairRef "@baseboard_fab2_lib.baseboard_fab2(sch_1):\PP3936\") )
				( member ( pinPairRef "@baseboard_fab2_lib.baseboard_fab2(sch_1):\PP3937\") )
				( member ( pinPairRef "@baseboard_fab2_lib.baseboard_fab2(sch_1):\PP3935\") )
				( member ( signalRef "@baseboard_fab2_lib.baseboard_fab2(sch_1):m_b_clk_dp(0)") )
				( objectStatus "MG_DDR_FAR_DIMM-CLK0_CLS_DDR_B_CAC-CLKS" )
			)
			( matchGroup "@baseboard_fab2_lib.baseboard_fab2(sch_1):\MG_DDR_FAR_DIMM_CMD_NG_DDR_B_DLL_1\"
				( memberType ( signal ) )
				( member ( pinPairRef "@baseboard_fab2_lib.baseboard_fab2(sch_1):\PP3989\") )
				( member ( pinPairRef "@baseboard_fab2_lib.baseboard_fab2(sch_1):\PP3991\") )
				( objectStatus "MG_DDR_FAR_DIMM_CMD_NG_DDR_B_DLL_1" )
			)
			( matchGroup "@baseboard_fab2_lib.baseboard_fab2(sch_1):\MG_DDR_CMD_NEAR_DIMM_NG_DDR_B_DLL_1\"
				( memberType ( signal ) )
				( member ( pinPairRef "@baseboard_fab2_lib.baseboard_fab2(sch_1):\PP3990\") )
				( member ( pinPairRef "@baseboard_fab2_lib.baseboard_fab2(sch_1):\PP3992\") )
				( objectStatus "MG_DDR_CMD_NEAR_DIMM_NG_DDR_B_DLL_1" )
			)
			( matchGroup "@crescent_city_bb_fab1_lib.crescent_city_bb_fab1(sch_1):\MG_DDR_NEAR_DIMM-CLK1_CLS_DDR_B_CAC-CLKS\"
				( memberType ( signal ) )
				( member ( pinPairRef "@baseboard_fab2_lib.baseboard_fab2(sch_1):\PP3990\") )
				( member ( pinPairRef "@baseboard_fab2_lib.baseboard_fab2(sch_1):\PP3992\") )
				( member ( pinPairRef "@baseboard_fab2_lib.baseboard_fab2(sch_1):\PP3986\") )
				( member ( pinPairRef "@baseboard_fab2_lib.baseboard_fab2(sch_1):\PP3988\") )
				( member ( pinPairRef "@baseboard_fab2_lib.baseboard_fab2(sch_1):\PP3982\") )
				( member ( pinPairRef "@baseboard_fab2_lib.baseboard_fab2(sch_1):\PP3984\") )
				( member ( pinPairRef "@baseboard_fab2_lib.baseboard_fab2(sch_1):\PP3978\") )
				( member ( pinPairRef "@baseboard_fab2_lib.baseboard_fab2(sch_1):\PP3980\") )
				( member ( pinPairRef "@baseboard_fab2_lib.baseboard_fab2(sch_1):\PP3974\") )
				( member ( pinPairRef "@baseboard_fab2_lib.baseboard_fab2(sch_1):\PP3976\") )
				( member ( pinPairRef "@baseboard_fab2_lib.baseboard_fab2(sch_1):\PP3972\") )
				( member ( pinPairRef "@baseboard_fab2_lib.baseboard_fab2(sch_1):\PP3968\") )
				( member ( pinPairRef "@baseboard_fab2_lib.baseboard_fab2(sch_1):\PP3970\") )
				( member ( pinPairRef "@baseboard_fab2_lib.baseboard_fab2(sch_1):\PP3964\") )
				( member ( pinPairRef "@baseboard_fab2_lib.baseboard_fab2(sch_1):\PP3966\") )
				( member ( pinPairRef "@baseboard_fab2_lib.baseboard_fab2(sch_1):\PP3960\") )
				( member ( pinPairRef "@baseboard_fab2_lib.baseboard_fab2(sch_1):\PP3962\") )
				( member ( pinPairRef "@baseboard_fab2_lib.baseboard_fab2(sch_1):\PP3956\") )
				( member ( pinPairRef "@baseboard_fab2_lib.baseboard_fab2(sch_1):\PP3958\") )
				( member ( pinPairRef "@baseboard_fab2_lib.baseboard_fab2(sch_1):\PP3952\") )
				( member ( pinPairRef "@baseboard_fab2_lib.baseboard_fab2(sch_1):\PP3954\") )
				( member ( pinPairRef "@baseboard_fab2_lib.baseboard_fab2(sch_1):\PP3948\") )
				( member ( pinPairRef "@baseboard_fab2_lib.baseboard_fab2(sch_1):\PP3950\") )
				( member ( pinPairRef "@baseboard_fab2_lib.baseboard_fab2(sch_1):\PP3944\") )
				( member ( pinPairRef "@baseboard_fab2_lib.baseboard_fab2(sch_1):\PP3946\") )
				( member ( pinPairRef "@baseboard_fab2_lib.baseboard_fab2(sch_1):\PP3933\") )
				( member ( pinPairRef "@baseboard_fab2_lib.baseboard_fab2(sch_1):\PP3934\") )
				( member ( pinPairRef "@baseboard_fab2_lib.baseboard_fab2(sch_1):\PP3932\") )
				( member ( pinPairRef "@baseboard_fab2_lib.baseboard_fab2(sch_1):\PP3930\") )
				( member ( pinPairRef "@baseboard_fab2_lib.baseboard_fab2(sch_1):\PP3931\") )
				( member ( pinPairRef "@baseboard_fab2_lib.baseboard_fab2(sch_1):\PP3928\") )
				( member ( pinPairRef "@baseboard_fab2_lib.baseboard_fab2(sch_1):\PP3929\") )
				( member ( pinPairRef "@baseboard_fab2_lib.baseboard_fab2(sch_1):\PP3927\") )
				( member ( signalRef "@baseboard_fab2_lib.baseboard_fab2(sch_1):m_b_clk_dp(2)") )
				( objectStatus "MG_DDR_NEAR_DIMM-CLK1_CLS_DDR_B_CAC-CLKS" )
			)
			( matchGroup "@baseboard_fab2_lib.baseboard_fab2(sch_1):\MG_DDR_FAR_DIMM_CMD_NG_DDR_B_DLL_2\"
				( memberType ( signal ) )
				( member ( pinPairRef "@baseboard_fab2_lib.baseboard_fab2(sch_1):\PP3985\") )
				( member ( pinPairRef "@baseboard_fab2_lib.baseboard_fab2(sch_1):\PP3987\") )
				( objectStatus "MG_DDR_FAR_DIMM_CMD_NG_DDR_B_DLL_2" )
			)
			( matchGroup "@baseboard_fab2_lib.baseboard_fab2(sch_1):\MG_DDR_CMD_NEAR_DIMM_NG_DDR_B_DLL_2\"
				( memberType ( signal ) )
				( member ( pinPairRef "@baseboard_fab2_lib.baseboard_fab2(sch_1):\PP3986\") )
				( member ( pinPairRef "@baseboard_fab2_lib.baseboard_fab2(sch_1):\PP3988\") )
				( objectStatus "MG_DDR_CMD_NEAR_DIMM_NG_DDR_B_DLL_2" )
			)
			( matchGroup "@baseboard_fab2_lib.baseboard_fab2(sch_1):\MG_DDR_FAR_DIMM_CMD_NG_DDR_B_DLL_3\"
				( memberType ( signal ) )
				( member ( pinPairRef "@baseboard_fab2_lib.baseboard_fab2(sch_1):\PP3981\") )
				( member ( pinPairRef "@baseboard_fab2_lib.baseboard_fab2(sch_1):\PP3983\") )
				( objectStatus "MG_DDR_FAR_DIMM_CMD_NG_DDR_B_DLL_3" )
			)
			( matchGroup "@baseboard_fab2_lib.baseboard_fab2(sch_1):\MG_DDR_CMD_NEAR_DIMM_NG_DDR_B_DLL_3\"
				( memberType ( signal ) )
				( member ( pinPairRef "@baseboard_fab2_lib.baseboard_fab2(sch_1):\PP3982\") )
				( member ( pinPairRef "@baseboard_fab2_lib.baseboard_fab2(sch_1):\PP3984\") )
				( objectStatus "MG_DDR_CMD_NEAR_DIMM_NG_DDR_B_DLL_3" )
			)
			( matchGroup "@baseboard_fab2_lib.baseboard_fab2(sch_1):\MG_DDR_FAR_DIMM_CMD_NG_DDR_B_DLL_4\"
				( memberType ( signal ) )
				( member ( pinPairRef "@baseboard_fab2_lib.baseboard_fab2(sch_1):\PP3977\") )
				( member ( pinPairRef "@baseboard_fab2_lib.baseboard_fab2(sch_1):\PP3979\") )
				( objectStatus "MG_DDR_FAR_DIMM_CMD_NG_DDR_B_DLL_4" )
			)
			( matchGroup "@baseboard_fab2_lib.baseboard_fab2(sch_1):\MG_DDR_CMD_NEAR_DIMM_NG_DDR_B_DLL_4\"
				( memberType ( signal ) )
				( member ( pinPairRef "@baseboard_fab2_lib.baseboard_fab2(sch_1):\PP3978\") )
				( member ( pinPairRef "@baseboard_fab2_lib.baseboard_fab2(sch_1):\PP3980\") )
				( objectStatus "MG_DDR_CMD_NEAR_DIMM_NG_DDR_B_DLL_4" )
			)
			( matchGroup "@baseboard_fab2_lib.baseboard_fab2(sch_1):\MG_DDR_FAR_DIMM_CMD_NG_DDR_B_DLL_5\"
				( memberType ( signal ) )
				( member ( pinPairRef "@baseboard_fab2_lib.baseboard_fab2(sch_1):\PP3973\") )
				( member ( pinPairRef "@baseboard_fab2_lib.baseboard_fab2(sch_1):\PP3975\") )
				( objectStatus "MG_DDR_FAR_DIMM_CMD_NG_DDR_B_DLL_5" )
			)
			( matchGroup "@baseboard_fab2_lib.baseboard_fab2(sch_1):\MG_DDR_CMD_NEAR_DIMM_NG_DDR_B_DLL_5\"
				( memberType ( signal ) )
				( member ( pinPairRef "@baseboard_fab2_lib.baseboard_fab2(sch_1):\PP3974\") )
				( member ( pinPairRef "@baseboard_fab2_lib.baseboard_fab2(sch_1):\PP3976\") )
				( objectStatus "MG_DDR_CMD_NEAR_DIMM_NG_DDR_B_DLL_5" )
			)
			( matchGroup "@baseboard_fab2_lib.baseboard_fab2(sch_1):\MG_DDR_FAR_DIMM_CMD_NG_DDR_B_DLL_6\"
				( memberType ( signal ) )
				( member ( pinPairRef "@baseboard_fab2_lib.baseboard_fab2(sch_1):\PP3971\") )
				( objectStatus "MG_DDR_FAR_DIMM_CMD_NG_DDR_B_DLL_6" )
			)
			( matchGroup "@baseboard_fab2_lib.baseboard_fab2(sch_1):\MG_DDR_CMD_NEAR_DIMM_NG_DDR_B_DLL_6\"
				( memberType ( signal ) )
				( member ( pinPairRef "@baseboard_fab2_lib.baseboard_fab2(sch_1):\PP3972\") )
				( objectStatus "MG_DDR_CMD_NEAR_DIMM_NG_DDR_B_DLL_6" )
			)
			( matchGroup "@baseboard_fab2_lib.baseboard_fab2(sch_1):\MG_DDR_FAR_DIMM_CMD_NG_DDR_B_DLL_7\"
				( memberType ( signal ) )
				( member ( pinPairRef "@baseboard_fab2_lib.baseboard_fab2(sch_1):\PP3967\") )
				( member ( pinPairRef "@baseboard_fab2_lib.baseboard_fab2(sch_1):\PP3969\") )
				( objectStatus "MG_DDR_FAR_DIMM_CMD_NG_DDR_B_DLL_7" )
			)
			( matchGroup "@baseboard_fab2_lib.baseboard_fab2(sch_1):\MG_DDR_CMD_NEAR_DIMM_NG_DDR_B_DLL_7\"
				( memberType ( signal ) )
				( member ( pinPairRef "@baseboard_fab2_lib.baseboard_fab2(sch_1):\PP3968\") )
				( member ( pinPairRef "@baseboard_fab2_lib.baseboard_fab2(sch_1):\PP3970\") )
				( objectStatus "MG_DDR_CMD_NEAR_DIMM_NG_DDR_B_DLL_7" )
			)
			( matchGroup "@baseboard_fab2_lib.baseboard_fab2(sch_1):\MG_DDR_FAR_DIMM_CMD_NG_DDR_B_DLL_8\"
				( memberType ( signal ) )
				( member ( pinPairRef "@baseboard_fab2_lib.baseboard_fab2(sch_1):\PP3963\") )
				( member ( pinPairRef "@baseboard_fab2_lib.baseboard_fab2(sch_1):\PP3965\") )
				( objectStatus "MG_DDR_FAR_DIMM_CMD_NG_DDR_B_DLL_8" )
			)
			( matchGroup "@baseboard_fab2_lib.baseboard_fab2(sch_1):\MG_DDR_CMD_NEAR_DIMM_NG_DDR_B_DLL_8\"
				( memberType ( signal ) )
				( member ( pinPairRef "@baseboard_fab2_lib.baseboard_fab2(sch_1):\PP3964\") )
				( member ( pinPairRef "@baseboard_fab2_lib.baseboard_fab2(sch_1):\PP3966\") )
				( objectStatus "MG_DDR_CMD_NEAR_DIMM_NG_DDR_B_DLL_8" )
			)
			( matchGroup "@baseboard_fab2_lib.baseboard_fab2(sch_1):\MG_DDR_FAR_DIMM_CMD_NG_DDR_B_DLL_9\"
				( memberType ( signal ) )
				( member ( pinPairRef "@baseboard_fab2_lib.baseboard_fab2(sch_1):\PP3959\") )
				( member ( pinPairRef "@baseboard_fab2_lib.baseboard_fab2(sch_1):\PP3961\") )
				( objectStatus "MG_DDR_FAR_DIMM_CMD_NG_DDR_B_DLL_9" )
			)
			( matchGroup "@baseboard_fab2_lib.baseboard_fab2(sch_1):\MG_DDR_CMD_NEAR_DIMM_NG_DDR_B_DLL_9\"
				( memberType ( signal ) )
				( member ( pinPairRef "@baseboard_fab2_lib.baseboard_fab2(sch_1):\PP3960\") )
				( member ( pinPairRef "@baseboard_fab2_lib.baseboard_fab2(sch_1):\PP3962\") )
				( objectStatus "MG_DDR_CMD_NEAR_DIMM_NG_DDR_B_DLL_9" )
			)
			( matchGroup "@baseboard_fab2_lib.baseboard_fab2(sch_1):\MG_DDR_FAR_DIMM_CMD_NG_DDR_B_DLL_10\"
				( memberType ( signal ) )
				( member ( pinPairRef "@baseboard_fab2_lib.baseboard_fab2(sch_1):\PP3955\") )
				( member ( pinPairRef "@baseboard_fab2_lib.baseboard_fab2(sch_1):\PP3957\") )
				( objectStatus "MG_DDR_FAR_DIMM_CMD_NG_DDR_B_DLL_10" )
			)
			( matchGroup "@baseboard_fab2_lib.baseboard_fab2(sch_1):\MG_DDR_CMD_NEAR_DIMM_NG_DDR_B_DLL_10\"
				( memberType ( signal ) )
				( member ( pinPairRef "@baseboard_fab2_lib.baseboard_fab2(sch_1):\PP3956\") )
				( member ( pinPairRef "@baseboard_fab2_lib.baseboard_fab2(sch_1):\PP3958\") )
				( objectStatus "MG_DDR_CMD_NEAR_DIMM_NG_DDR_B_DLL_10" )
			)
			( matchGroup "@baseboard_fab2_lib.baseboard_fab2(sch_1):\MG_DDR_FAR_DIMM_CMD_NG_DDR_B_DLL_11\"
				( memberType ( signal ) )
				( member ( pinPairRef "@baseboard_fab2_lib.baseboard_fab2(sch_1):\PP3951\") )
				( member ( pinPairRef "@baseboard_fab2_lib.baseboard_fab2(sch_1):\PP3953\") )
				( objectStatus "MG_DDR_FAR_DIMM_CMD_NG_DDR_B_DLL_11" )
			)
			( matchGroup "@baseboard_fab2_lib.baseboard_fab2(sch_1):\MG_DDR_CMD_NEAR_DIMM_NG_DDR_B_DLL_11\"
				( memberType ( signal ) )
				( member ( pinPairRef "@baseboard_fab2_lib.baseboard_fab2(sch_1):\PP3952\") )
				( member ( pinPairRef "@baseboard_fab2_lib.baseboard_fab2(sch_1):\PP3954\") )
				( objectStatus "MG_DDR_CMD_NEAR_DIMM_NG_DDR_B_DLL_11" )
			)
			( matchGroup "@baseboard_fab2_lib.baseboard_fab2(sch_1):\MG_DDR_FAR_DIMM_CMD_NG_DDR_B_DLL_12\"
				( memberType ( signal ) )
				( member ( pinPairRef "@baseboard_fab2_lib.baseboard_fab2(sch_1):\PP3947\") )
				( member ( pinPairRef "@baseboard_fab2_lib.baseboard_fab2(sch_1):\PP3949\") )
				( objectStatus "MG_DDR_FAR_DIMM_CMD_NG_DDR_B_DLL_12" )
			)
			( matchGroup "@baseboard_fab2_lib.baseboard_fab2(sch_1):\MG_DDR_CMD_NEAR_DIMM_NG_DDR_B_DLL_12\"
				( memberType ( signal ) )
				( member ( pinPairRef "@baseboard_fab2_lib.baseboard_fab2(sch_1):\PP3948\") )
				( member ( pinPairRef "@baseboard_fab2_lib.baseboard_fab2(sch_1):\PP3950\") )
				( objectStatus "MG_DDR_CMD_NEAR_DIMM_NG_DDR_B_DLL_12" )
			)
			( matchGroup "@baseboard_fab2_lib.baseboard_fab2(sch_1):\MG_DDR_FAR_DIMM_CMD_NG_DDR_B_DLL_13\"
				( memberType ( signal ) )
				( member ( pinPairRef "@baseboard_fab2_lib.baseboard_fab2(sch_1):\PP3943\") )
				( member ( pinPairRef "@baseboard_fab2_lib.baseboard_fab2(sch_1):\PP3945\") )
				( objectStatus "MG_DDR_FAR_DIMM_CMD_NG_DDR_B_DLL_13" )
			)
			( matchGroup "@baseboard_fab2_lib.baseboard_fab2(sch_1):\MG_DDR_CMD_NEAR_DIMM_NG_DDR_B_DLL_13\"
				( memberType ( signal ) )
				( member ( pinPairRef "@baseboard_fab2_lib.baseboard_fab2(sch_1):\PP3944\") )
				( member ( pinPairRef "@baseboard_fab2_lib.baseboard_fab2(sch_1):\PP3946\") )
				( objectStatus "MG_DDR_CMD_NEAR_DIMM_NG_DDR_B_DLL_13" )
			)
			( matchGroup "@baseboard_fab2_lib.baseboard_fab2(sch_1):\MG_DDR_CTRL_NG_DDR_B_DLL_14\"
				( memberType ( signal ) )
				( member ( pinPairRef "@baseboard_fab2_lib.baseboard_fab2(sch_1):\PP3941\") )
				( member ( pinPairRef "@baseboard_fab2_lib.baseboard_fab2(sch_1):\PP3942\") )
				( objectStatus "MG_DDR_CTRL_NG_DDR_B_DLL_14" )
			)
			( matchGroup "@baseboard_fab2_lib.baseboard_fab2(sch_1):\MG_DDR_CTRL_NG_DDR_B_DLL_15\"
				( memberType ( signal ) )
				( member ( pinPairRef "@baseboard_fab2_lib.baseboard_fab2(sch_1):\PP3940\") )
				( objectStatus "MG_DDR_CTRL_NG_DDR_B_DLL_15" )
			)
			( matchGroup "@baseboard_fab2_lib.baseboard_fab2(sch_1):\MG_DDR_CTRL_NG_DDR_B_DLL_16\"
				( memberType ( signal ) )
				( member ( pinPairRef "@baseboard_fab2_lib.baseboard_fab2(sch_1):\PP3939\") )
				( objectStatus "MG_DDR_CTRL_NG_DDR_B_DLL_16" )
			)
			( matchGroup "@baseboard_fab2_lib.baseboard_fab2(sch_1):\MG_DDR_CTRL_NG_DDR_B_DLL_17\"
				( memberType ( signal ) )
				( member ( pinPairRef "@baseboard_fab2_lib.baseboard_fab2(sch_1):\PP3938\") )
				( objectStatus "MG_DDR_CTRL_NG_DDR_B_DLL_17" )
			)
			( matchGroup "@baseboard_fab2_lib.baseboard_fab2(sch_1):\MG_DDR_CTRL_NG_DDR_B_DLL_18\"
				( memberType ( signal ) )
				( member ( pinPairRef "@baseboard_fab2_lib.baseboard_fab2(sch_1):\PP3936\") )
				( member ( pinPairRef "@baseboard_fab2_lib.baseboard_fab2(sch_1):\PP3937\") )
				( objectStatus "MG_DDR_CTRL_NG_DDR_B_DLL_18" )
			)
			( matchGroup "@baseboard_fab2_lib.baseboard_fab2(sch_1):\MG_DDR_CTRL_NG_DDR_B_DLL_19\"
				( memberType ( signal ) )
				( member ( pinPairRef "@baseboard_fab2_lib.baseboard_fab2(sch_1):\PP3935\") )
				( objectStatus "MG_DDR_CTRL_NG_DDR_B_DLL_19" )
			)
			( matchGroup "@baseboard_fab2_lib.baseboard_fab2(sch_1):\MG_DDR_CTRL_NG_DDR_B_DLL_20\"
				( memberType ( signal ) )
				( member ( pinPairRef "@baseboard_fab2_lib.baseboard_fab2(sch_1):\PP3933\") )
				( member ( pinPairRef "@baseboard_fab2_lib.baseboard_fab2(sch_1):\PP3934\") )
				( objectStatus "MG_DDR_CTRL_NG_DDR_B_DLL_20" )
			)
			( matchGroup "@baseboard_fab2_lib.baseboard_fab2(sch_1):\MG_DDR_CTRL_NG_DDR_B_DLL_21\"
				( memberType ( signal ) )
				( member ( pinPairRef "@baseboard_fab2_lib.baseboard_fab2(sch_1):\PP3932\") )
				( objectStatus "MG_DDR_CTRL_NG_DDR_B_DLL_21" )
			)
			( matchGroup "@baseboard_fab2_lib.baseboard_fab2(sch_1):\MG_DDR_CTRL_NG_DDR_B_DLL_22\"
				( memberType ( signal ) )
				( member ( pinPairRef "@baseboard_fab2_lib.baseboard_fab2(sch_1):\PP3930\") )
				( member ( pinPairRef "@baseboard_fab2_lib.baseboard_fab2(sch_1):\PP3931\") )
				( objectStatus "MG_DDR_CTRL_NG_DDR_B_DLL_22" )
			)
			( matchGroup "@baseboard_fab2_lib.baseboard_fab2(sch_1):\MG_DDR_CTRL_NG_DDR_B_DLL_23\"
				( memberType ( signal ) )
				( member ( pinPairRef "@baseboard_fab2_lib.baseboard_fab2(sch_1):\PP3928\") )
				( member ( pinPairRef "@baseboard_fab2_lib.baseboard_fab2(sch_1):\PP3929\") )
				( objectStatus "MG_DDR_CTRL_NG_DDR_B_DLL_23" )
			)
			( matchGroup "@baseboard_fab2_lib.baseboard_fab2(sch_1):\MG_DDR_CTRL_NG_DDR_B_DLL_24\"
				( memberType ( signal ) )
				( member ( pinPairRef "@baseboard_fab2_lib.baseboard_fab2(sch_1):\PP3927\") )
				( objectStatus "MG_DDR_CTRL_NG_DDR_B_DLL_24" )
			)
			( matchGroup "@baseboard_fab2_lib.baseboard_fab2(sch_1):\MG_DDR_FAR_DIMM_CMD_NG_DDR_A_DLL_1\"
				( memberType ( signal ) )
				( member ( pinPairRef "@baseboard_fab2_lib.baseboard_fab2(sch_1):\PP4055\") )
				( member ( pinPairRef "@baseboard_fab2_lib.baseboard_fab2(sch_1):\PP4057\") )
				( objectStatus "MG_DDR_FAR_DIMM_CMD_NG_DDR_A_DLL_1" )
			)
			( matchGroup "@crescent_city_bb_fab1_lib.crescent_city_bb_fab1(sch_1):\MG_DDR_FAR_DIMM-CLK0_CLS_DDR_A_CAC-CLKS\"
				( memberType ( signal ) )
				( member ( pinPairRef "@baseboard_fab2_lib.baseboard_fab2(sch_1):\PP4055\") )
				( member ( pinPairRef "@baseboard_fab2_lib.baseboard_fab2(sch_1):\PP4057\") )
				( member ( pinPairRef "@baseboard_fab2_lib.baseboard_fab2(sch_1):\PP4051\") )
				( member ( pinPairRef "@baseboard_fab2_lib.baseboard_fab2(sch_1):\PP4053\") )
				( member ( pinPairRef "@baseboard_fab2_lib.baseboard_fab2(sch_1):\PP4047\") )
				( member ( pinPairRef "@baseboard_fab2_lib.baseboard_fab2(sch_1):\PP4049\") )
				( member ( pinPairRef "@baseboard_fab2_lib.baseboard_fab2(sch_1):\PP4043\") )
				( member ( pinPairRef "@baseboard_fab2_lib.baseboard_fab2(sch_1):\PP4045\") )
				( member ( pinPairRef "@baseboard_fab2_lib.baseboard_fab2(sch_1):\PP4039\") )
				( member ( pinPairRef "@baseboard_fab2_lib.baseboard_fab2(sch_1):\PP4041\") )
				( member ( pinPairRef "@baseboard_fab2_lib.baseboard_fab2(sch_1):\PP4037\") )
				( member ( pinPairRef "@baseboard_fab2_lib.baseboard_fab2(sch_1):\PP4033\") )
				( member ( pinPairRef "@baseboard_fab2_lib.baseboard_fab2(sch_1):\PP4035\") )
				( member ( pinPairRef "@baseboard_fab2_lib.baseboard_fab2(sch_1):\PP4029\") )
				( member ( pinPairRef "@baseboard_fab2_lib.baseboard_fab2(sch_1):\PP4031\") )
				( member ( pinPairRef "@baseboard_fab2_lib.baseboard_fab2(sch_1):\PP4025\") )
				( member ( pinPairRef "@baseboard_fab2_lib.baseboard_fab2(sch_1):\PP4027\") )
				( member ( pinPairRef "@baseboard_fab2_lib.baseboard_fab2(sch_1):\PP4021\") )
				( member ( pinPairRef "@baseboard_fab2_lib.baseboard_fab2(sch_1):\PP4023\") )
				( member ( pinPairRef "@baseboard_fab2_lib.baseboard_fab2(sch_1):\PP4017\") )
				( member ( pinPairRef "@baseboard_fab2_lib.baseboard_fab2(sch_1):\PP4019\") )
				( member ( pinPairRef "@baseboard_fab2_lib.baseboard_fab2(sch_1):\PP4013\") )
				( member ( pinPairRef "@baseboard_fab2_lib.baseboard_fab2(sch_1):\PP4015\") )
				( member ( pinPairRef "@baseboard_fab2_lib.baseboard_fab2(sch_1):\PP4009\") )
				( member ( pinPairRef "@baseboard_fab2_lib.baseboard_fab2(sch_1):\PP4011\") )
				( member ( pinPairRef "@baseboard_fab2_lib.baseboard_fab2(sch_1):\PP4007\") )
				( member ( pinPairRef "@baseboard_fab2_lib.baseboard_fab2(sch_1):\PP4008\") )
				( member ( pinPairRef "@baseboard_fab2_lib.baseboard_fab2(sch_1):\PP4006\") )
				( member ( pinPairRef "@baseboard_fab2_lib.baseboard_fab2(sch_1):\PP4005\") )
				( member ( pinPairRef "@baseboard_fab2_lib.baseboard_fab2(sch_1):\PP4004\") )
				( member ( pinPairRef "@baseboard_fab2_lib.baseboard_fab2(sch_1):\PP4002\") )
				( member ( pinPairRef "@baseboard_fab2_lib.baseboard_fab2(sch_1):\PP4003\") )
				( member ( pinPairRef "@baseboard_fab2_lib.baseboard_fab2(sch_1):\PP4001\") )
				( member ( signalRef "@baseboard_fab2_lib.baseboard_fab2(sch_1):m_a_clk_dp(0)") )
				( objectStatus "MG_DDR_FAR_DIMM-CLK0_CLS_DDR_A_CAC-CLKS" )
			)
			( matchGroup "@crescent_city_bb_fab1_lib.crescent_city_bb_fab1(sch_1):\MG_DDR_NEAR_DIMM-CLK1_CLS_DDR_A_CAC-CLKS\"
				( memberType ( signal ) )
				( member ( pinPairRef "@baseboard_fab2_lib.baseboard_fab2(sch_1):\PP4056\") )
				( member ( pinPairRef "@baseboard_fab2_lib.baseboard_fab2(sch_1):\PP4058\") )
				( member ( pinPairRef "@baseboard_fab2_lib.baseboard_fab2(sch_1):\PP4052\") )
				( member ( pinPairRef "@baseboard_fab2_lib.baseboard_fab2(sch_1):\PP4054\") )
				( member ( pinPairRef "@baseboard_fab2_lib.baseboard_fab2(sch_1):\PP4048\") )
				( member ( pinPairRef "@baseboard_fab2_lib.baseboard_fab2(sch_1):\PP4050\") )
				( member ( pinPairRef "@baseboard_fab2_lib.baseboard_fab2(sch_1):\PP4044\") )
				( member ( pinPairRef "@baseboard_fab2_lib.baseboard_fab2(sch_1):\PP4046\") )
				( member ( pinPairRef "@baseboard_fab2_lib.baseboard_fab2(sch_1):\PP4040\") )
				( member ( pinPairRef "@baseboard_fab2_lib.baseboard_fab2(sch_1):\PP4042\") )
				( member ( pinPairRef "@baseboard_fab2_lib.baseboard_fab2(sch_1):\PP4038\") )
				( member ( pinPairRef "@baseboard_fab2_lib.baseboard_fab2(sch_1):\PP4034\") )
				( member ( pinPairRef "@baseboard_fab2_lib.baseboard_fab2(sch_1):\PP4036\") )
				( member ( pinPairRef "@baseboard_fab2_lib.baseboard_fab2(sch_1):\PP4030\") )
				( member ( pinPairRef "@baseboard_fab2_lib.baseboard_fab2(sch_1):\PP4032\") )
				( member ( pinPairRef "@baseboard_fab2_lib.baseboard_fab2(sch_1):\PP4026\") )
				( member ( pinPairRef "@baseboard_fab2_lib.baseboard_fab2(sch_1):\PP4028\") )
				( member ( pinPairRef "@baseboard_fab2_lib.baseboard_fab2(sch_1):\PP4022\") )
				( member ( pinPairRef "@baseboard_fab2_lib.baseboard_fab2(sch_1):\PP4024\") )
				( member ( pinPairRef "@baseboard_fab2_lib.baseboard_fab2(sch_1):\PP4018\") )
				( member ( pinPairRef "@baseboard_fab2_lib.baseboard_fab2(sch_1):\PP4020\") )
				( member ( pinPairRef "@baseboard_fab2_lib.baseboard_fab2(sch_1):\PP4014\") )
				( member ( pinPairRef "@baseboard_fab2_lib.baseboard_fab2(sch_1):\PP4016\") )
				( member ( pinPairRef "@baseboard_fab2_lib.baseboard_fab2(sch_1):\PP4010\") )
				( member ( pinPairRef "@baseboard_fab2_lib.baseboard_fab2(sch_1):\PP4012\") )
				( member ( pinPairRef "@baseboard_fab2_lib.baseboard_fab2(sch_1):\PP3999\") )
				( member ( pinPairRef "@baseboard_fab2_lib.baseboard_fab2(sch_1):\PP4000\") )
				( member ( pinPairRef "@baseboard_fab2_lib.baseboard_fab2(sch_1):\PP3998\") )
				( member ( pinPairRef "@baseboard_fab2_lib.baseboard_fab2(sch_1):\PP3996\") )
				( member ( pinPairRef "@baseboard_fab2_lib.baseboard_fab2(sch_1):\PP3997\") )
				( member ( pinPairRef "@baseboard_fab2_lib.baseboard_fab2(sch_1):\PP3994\") )
				( member ( pinPairRef "@baseboard_fab2_lib.baseboard_fab2(sch_1):\PP3995\") )
				( member ( pinPairRef "@baseboard_fab2_lib.baseboard_fab2(sch_1):\PP3993\") )
				( member ( signalRef "@baseboard_fab2_lib.baseboard_fab2(sch_1):m_a_clk_dn(2)") )
				( objectStatus "MG_DDR_NEAR_DIMM-CLK1_CLS_DDR_A_CAC-CLKS" )
			)
			( matchGroup "@baseboard_fab2_lib.baseboard_fab2(sch_1):\MG_DDR_CMD_NEAR_DIMM_NG_DDR_A_DLL_1\"
				( memberType ( signal ) )
				( member ( pinPairRef "@baseboard_fab2_lib.baseboard_fab2(sch_1):\PP4056\") )
				( member ( pinPairRef "@baseboard_fab2_lib.baseboard_fab2(sch_1):\PP4058\") )
				( objectStatus "MG_DDR_CMD_NEAR_DIMM_NG_DDR_A_DLL_1" )
			)
			( matchGroup "@baseboard_fab2_lib.baseboard_fab2(sch_1):\MG_DDR_FAR_DIMM_CMD_NG_DDR_A_DLL_2\"
				( memberType ( signal ) )
				( member ( pinPairRef "@baseboard_fab2_lib.baseboard_fab2(sch_1):\PP4051\") )
				( member ( pinPairRef "@baseboard_fab2_lib.baseboard_fab2(sch_1):\PP4053\") )
				( objectStatus "MG_DDR_FAR_DIMM_CMD_NG_DDR_A_DLL_2" )
			)
			( matchGroup "@baseboard_fab2_lib.baseboard_fab2(sch_1):\MG_DDR_CMD_NEAR_DIMM_NG_DDR_A_DLL_2\"
				( memberType ( signal ) )
				( member ( pinPairRef "@baseboard_fab2_lib.baseboard_fab2(sch_1):\PP4052\") )
				( member ( pinPairRef "@baseboard_fab2_lib.baseboard_fab2(sch_1):\PP4054\") )
				( objectStatus "MG_DDR_CMD_NEAR_DIMM_NG_DDR_A_DLL_2" )
			)
			( matchGroup "@baseboard_fab2_lib.baseboard_fab2(sch_1):\MG_DDR_FAR_DIMM_CMD_NG_DDR_A_DLL_3\"
				( memberType ( signal ) )
				( member ( pinPairRef "@baseboard_fab2_lib.baseboard_fab2(sch_1):\PP4047\") )
				( member ( pinPairRef "@baseboard_fab2_lib.baseboard_fab2(sch_1):\PP4049\") )
				( objectStatus "MG_DDR_FAR_DIMM_CMD_NG_DDR_A_DLL_3" )
			)
			( matchGroup "@baseboard_fab2_lib.baseboard_fab2(sch_1):\MG_DDR_CMD_NEAR_DIMM_NG_DDR_A_DLL_3\"
				( memberType ( signal ) )
				( member ( pinPairRef "@baseboard_fab2_lib.baseboard_fab2(sch_1):\PP4048\") )
				( member ( pinPairRef "@baseboard_fab2_lib.baseboard_fab2(sch_1):\PP4050\") )
				( objectStatus "MG_DDR_CMD_NEAR_DIMM_NG_DDR_A_DLL_3" )
			)
			( matchGroup "@baseboard_fab2_lib.baseboard_fab2(sch_1):\MG_DDR_FAR_DIMM_CMD_NG_DDR_A_DLL_4\"
				( memberType ( signal ) )
				( member ( pinPairRef "@baseboard_fab2_lib.baseboard_fab2(sch_1):\PP4043\") )
				( member ( pinPairRef "@baseboard_fab2_lib.baseboard_fab2(sch_1):\PP4045\") )
				( objectStatus "MG_DDR_FAR_DIMM_CMD_NG_DDR_A_DLL_4" )
			)
			( matchGroup "@baseboard_fab2_lib.baseboard_fab2(sch_1):\MG_DDR_CMD_NEAR_DIMM_NG_DDR_A_DLL_4\"
				( memberType ( signal ) )
				( member ( pinPairRef "@baseboard_fab2_lib.baseboard_fab2(sch_1):\PP4044\") )
				( member ( pinPairRef "@baseboard_fab2_lib.baseboard_fab2(sch_1):\PP4046\") )
				( objectStatus "MG_DDR_CMD_NEAR_DIMM_NG_DDR_A_DLL_4" )
			)
			( matchGroup "@baseboard_fab2_lib.baseboard_fab2(sch_1):\MG_DDR_FAR_DIMM_CMD_NG_DDR_A_DLL_5\"
				( memberType ( signal ) )
				( member ( pinPairRef "@baseboard_fab2_lib.baseboard_fab2(sch_1):\PP4039\") )
				( member ( pinPairRef "@baseboard_fab2_lib.baseboard_fab2(sch_1):\PP4041\") )
				( objectStatus "MG_DDR_FAR_DIMM_CMD_NG_DDR_A_DLL_5" )
			)
			( matchGroup "@baseboard_fab2_lib.baseboard_fab2(sch_1):\MG_DDR_CMD_NEAR_DIMM_NG_DDR_A_DLL_5\"
				( memberType ( signal ) )
				( member ( pinPairRef "@baseboard_fab2_lib.baseboard_fab2(sch_1):\PP4040\") )
				( member ( pinPairRef "@baseboard_fab2_lib.baseboard_fab2(sch_1):\PP4042\") )
				( objectStatus "MG_DDR_CMD_NEAR_DIMM_NG_DDR_A_DLL_5" )
			)
			( matchGroup "@baseboard_fab2_lib.baseboard_fab2(sch_1):\MG_DDR_FAR_DIMM_CMD_NG_DDR_A_DLL_6\"
				( memberType ( signal ) )
				( member ( pinPairRef "@baseboard_fab2_lib.baseboard_fab2(sch_1):\PP4037\") )
				( objectStatus "MG_DDR_FAR_DIMM_CMD_NG_DDR_A_DLL_6" )
			)
			( matchGroup "@baseboard_fab2_lib.baseboard_fab2(sch_1):\MG_DDR_CMD_NEAR_DIMM_NG_DDR_A_DLL_6\"
				( memberType ( signal ) )
				( member ( pinPairRef "@baseboard_fab2_lib.baseboard_fab2(sch_1):\PP4038\") )
				( objectStatus "MG_DDR_CMD_NEAR_DIMM_NG_DDR_A_DLL_6" )
			)
			( matchGroup "@baseboard_fab2_lib.baseboard_fab2(sch_1):\MG_DDR_FAR_DIMM_CMD_NG_DDR_A_DLL_7\"
				( memberType ( signal ) )
				( member ( pinPairRef "@baseboard_fab2_lib.baseboard_fab2(sch_1):\PP4033\") )
				( member ( pinPairRef "@baseboard_fab2_lib.baseboard_fab2(sch_1):\PP4035\") )
				( objectStatus "MG_DDR_FAR_DIMM_CMD_NG_DDR_A_DLL_7" )
			)
			( matchGroup "@baseboard_fab2_lib.baseboard_fab2(sch_1):\MG_DDR_CMD_NEAR_DIMM_NG_DDR_A_DLL_7\"
				( memberType ( signal ) )
				( member ( pinPairRef "@baseboard_fab2_lib.baseboard_fab2(sch_1):\PP4034\") )
				( member ( pinPairRef "@baseboard_fab2_lib.baseboard_fab2(sch_1):\PP4036\") )
				( objectStatus "MG_DDR_CMD_NEAR_DIMM_NG_DDR_A_DLL_7" )
			)
			( matchGroup "@baseboard_fab2_lib.baseboard_fab2(sch_1):\MG_DDR_FAR_DIMM_CMD_NG_DDR_A_DLL_8\"
				( memberType ( signal ) )
				( member ( pinPairRef "@baseboard_fab2_lib.baseboard_fab2(sch_1):\PP4029\") )
				( member ( pinPairRef "@baseboard_fab2_lib.baseboard_fab2(sch_1):\PP4031\") )
				( objectStatus "MG_DDR_FAR_DIMM_CMD_NG_DDR_A_DLL_8" )
			)
			( matchGroup "@baseboard_fab2_lib.baseboard_fab2(sch_1):\MG_DDR_CMD_NEAR_DIMM_NG_DDR_A_DLL_8\"
				( memberType ( signal ) )
				( member ( pinPairRef "@baseboard_fab2_lib.baseboard_fab2(sch_1):\PP4030\") )
				( member ( pinPairRef "@baseboard_fab2_lib.baseboard_fab2(sch_1):\PP4032\") )
				( objectStatus "MG_DDR_CMD_NEAR_DIMM_NG_DDR_A_DLL_8" )
			)
			( matchGroup "@baseboard_fab2_lib.baseboard_fab2(sch_1):\MG_DDR_FAR_DIMM_CMD_NG_DDR_A_DLL_9\"
				( memberType ( signal ) )
				( member ( pinPairRef "@baseboard_fab2_lib.baseboard_fab2(sch_1):\PP4025\") )
				( member ( pinPairRef "@baseboard_fab2_lib.baseboard_fab2(sch_1):\PP4027\") )
				( objectStatus "MG_DDR_FAR_DIMM_CMD_NG_DDR_A_DLL_9" )
			)
			( matchGroup "@baseboard_fab2_lib.baseboard_fab2(sch_1):\MG_DDR_CMD_NEAR_DIMM_NG_DDR_A_DLL_9\"
				( memberType ( signal ) )
				( member ( pinPairRef "@baseboard_fab2_lib.baseboard_fab2(sch_1):\PP4026\") )
				( member ( pinPairRef "@baseboard_fab2_lib.baseboard_fab2(sch_1):\PP4028\") )
				( objectStatus "MG_DDR_CMD_NEAR_DIMM_NG_DDR_A_DLL_9" )
			)
			( matchGroup "@baseboard_fab2_lib.baseboard_fab2(sch_1):\MG_DDR_FAR_DIMM_CMD_NG_DDR_A_DLL_10\"
				( memberType ( signal ) )
				( member ( pinPairRef "@baseboard_fab2_lib.baseboard_fab2(sch_1):\PP4021\") )
				( member ( pinPairRef "@baseboard_fab2_lib.baseboard_fab2(sch_1):\PP4023\") )
				( objectStatus "MG_DDR_FAR_DIMM_CMD_NG_DDR_A_DLL_10" )
			)
			( matchGroup "@baseboard_fab2_lib.baseboard_fab2(sch_1):\MG_DDR_CMD_NEAR_DIMM_NG_DDR_A_DLL_10\"
				( memberType ( signal ) )
				( member ( pinPairRef "@baseboard_fab2_lib.baseboard_fab2(sch_1):\PP4022\") )
				( member ( pinPairRef "@baseboard_fab2_lib.baseboard_fab2(sch_1):\PP4024\") )
				( objectStatus "MG_DDR_CMD_NEAR_DIMM_NG_DDR_A_DLL_10" )
			)
			( matchGroup "@baseboard_fab2_lib.baseboard_fab2(sch_1):\MG_DDR_FAR_DIMM_CMD_NG_DDR_A_DLL_11\"
				( memberType ( signal ) )
				( member ( pinPairRef "@baseboard_fab2_lib.baseboard_fab2(sch_1):\PP4017\") )
				( member ( pinPairRef "@baseboard_fab2_lib.baseboard_fab2(sch_1):\PP4019\") )
				( objectStatus "MG_DDR_FAR_DIMM_CMD_NG_DDR_A_DLL_11" )
			)
			( matchGroup "@baseboard_fab2_lib.baseboard_fab2(sch_1):\MG_DDR_CMD_NEAR_DIMM_NG_DDR_A_DLL_11\"
				( memberType ( signal ) )
				( member ( pinPairRef "@baseboard_fab2_lib.baseboard_fab2(sch_1):\PP4018\") )
				( member ( pinPairRef "@baseboard_fab2_lib.baseboard_fab2(sch_1):\PP4020\") )
				( objectStatus "MG_DDR_CMD_NEAR_DIMM_NG_DDR_A_DLL_11" )
			)
			( matchGroup "@baseboard_fab2_lib.baseboard_fab2(sch_1):\MG_DDR_FAR_DIMM_CMD_NG_DDR_A_DLL_12\"
				( memberType ( signal ) )
				( member ( pinPairRef "@baseboard_fab2_lib.baseboard_fab2(sch_1):\PP4013\") )
				( member ( pinPairRef "@baseboard_fab2_lib.baseboard_fab2(sch_1):\PP4015\") )
				( objectStatus "MG_DDR_FAR_DIMM_CMD_NG_DDR_A_DLL_12" )
			)
			( matchGroup "@baseboard_fab2_lib.baseboard_fab2(sch_1):\MG_DDR_CMD_NEAR_DIMM_NG_DDR_A_DLL_12\"
				( memberType ( signal ) )
				( member ( pinPairRef "@baseboard_fab2_lib.baseboard_fab2(sch_1):\PP4014\") )
				( member ( pinPairRef "@baseboard_fab2_lib.baseboard_fab2(sch_1):\PP4016\") )
				( objectStatus "MG_DDR_CMD_NEAR_DIMM_NG_DDR_A_DLL_12" )
			)
			( matchGroup "@baseboard_fab2_lib.baseboard_fab2(sch_1):\MG_DDR_FAR_DIMM_CMD_NG_DDR_A_DLL_13\"
				( memberType ( signal ) )
				( member ( pinPairRef "@baseboard_fab2_lib.baseboard_fab2(sch_1):\PP4009\") )
				( member ( pinPairRef "@baseboard_fab2_lib.baseboard_fab2(sch_1):\PP4011\") )
				( objectStatus "MG_DDR_FAR_DIMM_CMD_NG_DDR_A_DLL_13" )
			)
			( matchGroup "@baseboard_fab2_lib.baseboard_fab2(sch_1):\MG_DDR_CMD_NEAR_DIMM_NG_DDR_A_DLL_13\"
				( memberType ( signal ) )
				( member ( pinPairRef "@baseboard_fab2_lib.baseboard_fab2(sch_1):\PP4010\") )
				( member ( pinPairRef "@baseboard_fab2_lib.baseboard_fab2(sch_1):\PP4012\") )
				( objectStatus "MG_DDR_CMD_NEAR_DIMM_NG_DDR_A_DLL_13" )
			)
			( matchGroup "@baseboard_fab2_lib.baseboard_fab2(sch_1):\MG_DDR_CTRL_NG_DDR_A_DLL_14\"
				( memberType ( signal ) )
				( member ( pinPairRef "@baseboard_fab2_lib.baseboard_fab2(sch_1):\PP4007\") )
				( member ( pinPairRef "@baseboard_fab2_lib.baseboard_fab2(sch_1):\PP4008\") )
				( objectStatus "MG_DDR_CTRL_NG_DDR_A_DLL_14" )
			)
			( matchGroup "@baseboard_fab2_lib.baseboard_fab2(sch_1):\MG_DDR_CTRL_NG_DDR_A_DLL_15\"
				( memberType ( signal ) )
				( member ( pinPairRef "@baseboard_fab2_lib.baseboard_fab2(sch_1):\PP4006\") )
				( objectStatus "MG_DDR_CTRL_NG_DDR_A_DLL_15" )
			)
			( matchGroup "@baseboard_fab2_lib.baseboard_fab2(sch_1):\MG_DDR_CTRL_NG_DDR_A_DLL_16\"
				( memberType ( signal ) )
				( member ( pinPairRef "@baseboard_fab2_lib.baseboard_fab2(sch_1):\PP4005\") )
				( objectStatus "MG_DDR_CTRL_NG_DDR_A_DLL_16" )
			)
			( matchGroup "@baseboard_fab2_lib.baseboard_fab2(sch_1):\MG_DDR_CTRL_NG_DDR_A_DLL_17\"
				( memberType ( signal ) )
				( member ( pinPairRef "@baseboard_fab2_lib.baseboard_fab2(sch_1):\PP4004\") )
				( objectStatus "MG_DDR_CTRL_NG_DDR_A_DLL_17" )
			)
			( matchGroup "@baseboard_fab2_lib.baseboard_fab2(sch_1):\MG_DDR_CTRL_NG_DDR_A_DLL_18\"
				( memberType ( signal ) )
				( member ( pinPairRef "@baseboard_fab2_lib.baseboard_fab2(sch_1):\PP4002\") )
				( member ( pinPairRef "@baseboard_fab2_lib.baseboard_fab2(sch_1):\PP4003\") )
				( objectStatus "MG_DDR_CTRL_NG_DDR_A_DLL_18" )
			)
			( matchGroup "@baseboard_fab2_lib.baseboard_fab2(sch_1):\MG_DDR_CTRL_NG_DDR_A_DLL_19\"
				( memberType ( signal ) )
				( member ( pinPairRef "@baseboard_fab2_lib.baseboard_fab2(sch_1):\PP4001\") )
				( objectStatus "MG_DDR_CTRL_NG_DDR_A_DLL_19" )
			)
			( matchGroup "@baseboard_fab2_lib.baseboard_fab2(sch_1):\MG_DDR_CTRL_NG_DDR_A_DLL_20\"
				( memberType ( signal ) )
				( member ( pinPairRef "@baseboard_fab2_lib.baseboard_fab2(sch_1):\PP3999\") )
				( member ( pinPairRef "@baseboard_fab2_lib.baseboard_fab2(sch_1):\PP4000\") )
				( objectStatus "MG_DDR_CTRL_NG_DDR_A_DLL_20" )
			)
			( matchGroup "@baseboard_fab2_lib.baseboard_fab2(sch_1):\MG_DDR_CTRL_NG_DDR_A_DLL_21\"
				( memberType ( signal ) )
				( member ( pinPairRef "@baseboard_fab2_lib.baseboard_fab2(sch_1):\PP3998\") )
				( objectStatus "MG_DDR_CTRL_NG_DDR_A_DLL_21" )
			)
			( matchGroup "@baseboard_fab2_lib.baseboard_fab2(sch_1):\MG_DDR_CTRL_NG_DDR_A_DLL_22\"
				( memberType ( signal ) )
				( member ( pinPairRef "@baseboard_fab2_lib.baseboard_fab2(sch_1):\PP3996\") )
				( member ( pinPairRef "@baseboard_fab2_lib.baseboard_fab2(sch_1):\PP3997\") )
				( objectStatus "MG_DDR_CTRL_NG_DDR_A_DLL_22" )
			)
			( matchGroup "@baseboard_fab2_lib.baseboard_fab2(sch_1):\MG_DDR_CTRL_NG_DDR_A_DLL_23\"
				( memberType ( signal ) )
				( member ( pinPairRef "@baseboard_fab2_lib.baseboard_fab2(sch_1):\PP3994\") )
				( member ( pinPairRef "@baseboard_fab2_lib.baseboard_fab2(sch_1):\PP3995\") )
				( objectStatus "MG_DDR_CTRL_NG_DDR_A_DLL_23" )
			)
			( matchGroup "@baseboard_fab2_lib.baseboard_fab2(sch_1):\MG_DDR_CTRL_NG_DDR_A_DLL_24\"
				( memberType ( signal ) )
				( member ( pinPairRef "@baseboard_fab2_lib.baseboard_fab2(sch_1):\PP3993\") )
				( objectStatus "MG_DDR_CTRL_NG_DDR_A_DLL_24" )
			)
			( matchGroup "@baseboard_fab2_lib.baseboard_fab2(sch_1):\MG_DQ-DQS_FAR_DIMM_NG_M_F_BYTE-ECC\"
				( memberType ( signal ) )
				( member ( pinPairRef "@baseboard_fab2_lib.baseboard_fab2(sch_1):\PP4059\") )
				( member ( pinPairRef "@baseboard_fab2_lib.baseboard_fab2(sch_1):\PP4062\") )
				( member ( pinPairRef "@baseboard_fab2_lib.baseboard_fab2(sch_1):\PP4065\") )
				( member ( pinPairRef "@baseboard_fab2_lib.baseboard_fab2(sch_1):\PP4068\") )
				( member ( pinPairRef "@baseboard_fab2_lib.baseboard_fab2(sch_1):\PP4071\") )
				( member ( pinPairRef "@baseboard_fab2_lib.baseboard_fab2(sch_1):\PP4074\") )
				( member ( pinPairRef "@baseboard_fab2_lib.baseboard_fab2(sch_1):\PP4077\") )
				( member ( pinPairRef "@baseboard_fab2_lib.baseboard_fab2(sch_1):\PP4080\") )
				( member ( pinPairRef "@baseboard_fab2_lib.baseboard_fab2(sch_1):\PP985\") )
				( member ( pinPairRef "@baseboard_fab2_lib.baseboard_fab2(sch_1):\PP979\") )
				( member ( pinPairRef "@baseboard_fab2_lib.baseboard_fab2(sch_1):\PP988\") )
				( member ( pinPairRef "@baseboard_fab2_lib.baseboard_fab2(sch_1):\PP982\") )
				( objectStatus "MG_DQ-DQS_FAR_DIMM_NG_M_F_BYTE-ECC" )
			)
			( matchGroup "@baseboard_fab2_lib.baseboard_fab2(sch_1):\MG_DQ_FAR_DIMM_NG_M_F_BYTE-ECC\"
				( memberType ( signal ) )
				( member ( pinPairRef "@baseboard_fab2_lib.baseboard_fab2(sch_1):\PP4059\") )
				( member ( pinPairRef "@baseboard_fab2_lib.baseboard_fab2(sch_1):\PP4062\") )
				( member ( pinPairRef "@baseboard_fab2_lib.baseboard_fab2(sch_1):\PP4065\") )
				( member ( pinPairRef "@baseboard_fab2_lib.baseboard_fab2(sch_1):\PP4068\") )
				( member ( pinPairRef "@baseboard_fab2_lib.baseboard_fab2(sch_1):\PP4071\") )
				( member ( pinPairRef "@baseboard_fab2_lib.baseboard_fab2(sch_1):\PP4074\") )
				( member ( pinPairRef "@baseboard_fab2_lib.baseboard_fab2(sch_1):\PP4077\") )
				( member ( pinPairRef "@baseboard_fab2_lib.baseboard_fab2(sch_1):\PP4080\") )
				( objectStatus "MG_DQ_FAR_DIMM_NG_M_F_BYTE-ECC" )
			)
			( matchGroup "@baseboard_fab2_lib.baseboard_fab2(sch_1):\MG_DQ-DQS_NEAR_DIMM_NG_M_F_BYTE-ECC\"
				( memberType ( signal ) )
				( member ( pinPairRef "@baseboard_fab2_lib.baseboard_fab2(sch_1):\PP4061\") )
				( member ( pinPairRef "@baseboard_fab2_lib.baseboard_fab2(sch_1):\PP4064\") )
				( member ( pinPairRef "@baseboard_fab2_lib.baseboard_fab2(sch_1):\PP4067\") )
				( member ( pinPairRef "@baseboard_fab2_lib.baseboard_fab2(sch_1):\PP4070\") )
				( member ( pinPairRef "@baseboard_fab2_lib.baseboard_fab2(sch_1):\PP4073\") )
				( member ( pinPairRef "@baseboard_fab2_lib.baseboard_fab2(sch_1):\PP4076\") )
				( member ( pinPairRef "@baseboard_fab2_lib.baseboard_fab2(sch_1):\PP4079\") )
				( member ( pinPairRef "@baseboard_fab2_lib.baseboard_fab2(sch_1):\PP4082\") )
				( member ( pinPairRef "@baseboard_fab2_lib.baseboard_fab2(sch_1):\PP986\") )
				( member ( pinPairRef "@baseboard_fab2_lib.baseboard_fab2(sch_1):\PP980\") )
				( member ( pinPairRef "@baseboard_fab2_lib.baseboard_fab2(sch_1):\PP989\") )
				( member ( pinPairRef "@baseboard_fab2_lib.baseboard_fab2(sch_1):\PP983\") )
				( objectStatus "MG_DQ-DQS_NEAR_DIMM_NG_M_F_BYTE-ECC" )
			)
			( matchGroup "@crescent_city_bb_fab1_lib.crescent_city_bb_fab1(sch_1):\MG_DQ_NEAR_DIMM_NG_M_F_BYTE-ECC\"
				( memberType ( signal ) )
				( member ( pinPairRef "@baseboard_fab2_lib.baseboard_fab2(sch_1):\PP4061\") )
				( member ( pinPairRef "@baseboard_fab2_lib.baseboard_fab2(sch_1):\PP4064\") )
				( member ( pinPairRef "@baseboard_fab2_lib.baseboard_fab2(sch_1):\PP4067\") )
				( member ( pinPairRef "@baseboard_fab2_lib.baseboard_fab2(sch_1):\PP4070\") )
				( member ( pinPairRef "@baseboard_fab2_lib.baseboard_fab2(sch_1):\PP4073\") )
				( member ( pinPairRef "@baseboard_fab2_lib.baseboard_fab2(sch_1):\PP4076\") )
				( member ( pinPairRef "@baseboard_fab2_lib.baseboard_fab2(sch_1):\PP4079\") )
				( member ( pinPairRef "@baseboard_fab2_lib.baseboard_fab2(sch_1):\PP4082\") )
				( objectStatus "MG_DQ_NEAR_DIMM_NG_M_F_BYTE-ECC" )
			)
			( matchGroup "@baseboard_fab2_lib.baseboard_fab2(sch_1):\MG_DQ-DQS_FAR_DIMM_NG_M_G_BYTE-ECC\"
				( memberType ( signal ) )
				( member ( pinPairRef "@baseboard_fab2_lib.baseboard_fab2(sch_1):\PP2947\") )
				( member ( pinPairRef "@baseboard_fab2_lib.baseboard_fab2(sch_1):\PP2950\") )
				( member ( pinPairRef "@baseboard_fab2_lib.baseboard_fab2(sch_1):\PP2953\") )
				( member ( pinPairRef "@baseboard_fab2_lib.baseboard_fab2(sch_1):\PP2956\") )
				( member ( pinPairRef "@baseboard_fab2_lib.baseboard_fab2(sch_1):\PP2959\") )
				( member ( pinPairRef "@baseboard_fab2_lib.baseboard_fab2(sch_1):\PP2962\") )
				( member ( pinPairRef "@baseboard_fab2_lib.baseboard_fab2(sch_1):\PP2965\") )
				( member ( pinPairRef "@baseboard_fab2_lib.baseboard_fab2(sch_1):\PP2968\") )
				( member ( pinPairRef "@baseboard_fab2_lib.baseboard_fab2(sch_1):\PP877\") )
				( member ( pinPairRef "@baseboard_fab2_lib.baseboard_fab2(sch_1):\PP880\") )
				( member ( pinPairRef "@baseboard_fab2_lib.baseboard_fab2(sch_1):\PP871\") )
				( member ( pinPairRef "@baseboard_fab2_lib.baseboard_fab2(sch_1):\PP874\") )
				( objectStatus "MG_DQ-DQS_FAR_DIMM_NG_M_G_BYTE-ECC" )
			)
			( matchGroup "@crescent_city_bb_fab1_lib.crescent_city_bb_fab1(sch_1):\MG_DQ_FAR_DIMM_NG_M_G_BYTE-ECC\"
				( memberType ( signal ) )
				( member ( pinPairRef "@baseboard_fab2_lib.baseboard_fab2(sch_1):\PP2947\") )
				( member ( pinPairRef "@baseboard_fab2_lib.baseboard_fab2(sch_1):\PP2950\") )
				( member ( pinPairRef "@baseboard_fab2_lib.baseboard_fab2(sch_1):\PP2953\") )
				( member ( pinPairRef "@baseboard_fab2_lib.baseboard_fab2(sch_1):\PP2956\") )
				( member ( pinPairRef "@baseboard_fab2_lib.baseboard_fab2(sch_1):\PP2959\") )
				( member ( pinPairRef "@baseboard_fab2_lib.baseboard_fab2(sch_1):\PP2962\") )
				( member ( pinPairRef "@baseboard_fab2_lib.baseboard_fab2(sch_1):\PP2965\") )
				( member ( pinPairRef "@baseboard_fab2_lib.baseboard_fab2(sch_1):\PP2968\") )
				( objectStatus "MG_DQ_FAR_DIMM_NG_M_G_BYTE-ECC" )
			)
			( matchGroup "@baseboard_fab2_lib.baseboard_fab2(sch_1):\MG_DQ-DQS_NEAR_DIMM_NG_M_G_BYTE-ECC\"
				( memberType ( signal ) )
				( member ( pinPairRef "@baseboard_fab2_lib.baseboard_fab2(sch_1):\PP2948\") )
				( member ( pinPairRef "@baseboard_fab2_lib.baseboard_fab2(sch_1):\PP2951\") )
				( member ( pinPairRef "@baseboard_fab2_lib.baseboard_fab2(sch_1):\PP2954\") )
				( member ( pinPairRef "@baseboard_fab2_lib.baseboard_fab2(sch_1):\PP2957\") )
				( member ( pinPairRef "@baseboard_fab2_lib.baseboard_fab2(sch_1):\PP2960\") )
				( member ( pinPairRef "@baseboard_fab2_lib.baseboard_fab2(sch_1):\PP2963\") )
				( member ( pinPairRef "@baseboard_fab2_lib.baseboard_fab2(sch_1):\PP2966\") )
				( member ( pinPairRef "@baseboard_fab2_lib.baseboard_fab2(sch_1):\PP2969\") )
				( member ( pinPairRef "@baseboard_fab2_lib.baseboard_fab2(sch_1):\PP878\") )
				( member ( pinPairRef "@baseboard_fab2_lib.baseboard_fab2(sch_1):\PP881\") )
				( member ( pinPairRef "@baseboard_fab2_lib.baseboard_fab2(sch_1):\PP872\") )
				( member ( pinPairRef "@baseboard_fab2_lib.baseboard_fab2(sch_1):\PP875\") )
				( objectStatus "MG_DQ-DQS_NEAR_DIMM_NG_M_G_BYTE-ECC" )
			)
			( matchGroup "@crescent_city_bb_fab1_lib.crescent_city_bb_fab1(sch_1):\MG_DQ_NEAR_DIMM_NG_M_G_BYTE-ECC\"
				( memberType ( signal ) )
				( member ( pinPairRef "@baseboard_fab2_lib.baseboard_fab2(sch_1):\PP2948\") )
				( member ( pinPairRef "@baseboard_fab2_lib.baseboard_fab2(sch_1):\PP2951\") )
				( member ( pinPairRef "@baseboard_fab2_lib.baseboard_fab2(sch_1):\PP2954\") )
				( member ( pinPairRef "@baseboard_fab2_lib.baseboard_fab2(sch_1):\PP2957\") )
				( member ( pinPairRef "@baseboard_fab2_lib.baseboard_fab2(sch_1):\PP2960\") )
				( member ( pinPairRef "@baseboard_fab2_lib.baseboard_fab2(sch_1):\PP2963\") )
				( member ( pinPairRef "@baseboard_fab2_lib.baseboard_fab2(sch_1):\PP2966\") )
				( member ( pinPairRef "@baseboard_fab2_lib.baseboard_fab2(sch_1):\PP2969\") )
				( objectStatus "MG_DQ_NEAR_DIMM_NG_M_G_BYTE-ECC" )
			)
			( matchGroup "@baseboard_fab2_lib.baseboard_fab2(sch_1):\MG_DQ-DQS_FAR_DIMM_NG_M_H_BYTE-ECC\"
				( memberType ( signal ) )
				( member ( pinPairRef "@baseboard_fab2_lib.baseboard_fab2(sch_1):\PP2731\") )
				( member ( pinPairRef "@baseboard_fab2_lib.baseboard_fab2(sch_1):\PP2734\") )
				( member ( pinPairRef "@baseboard_fab2_lib.baseboard_fab2(sch_1):\PP2737\") )
				( member ( pinPairRef "@baseboard_fab2_lib.baseboard_fab2(sch_1):\PP2740\") )
				( member ( pinPairRef "@baseboard_fab2_lib.baseboard_fab2(sch_1):\PP2743\") )
				( member ( pinPairRef "@baseboard_fab2_lib.baseboard_fab2(sch_1):\PP2746\") )
				( member ( pinPairRef "@baseboard_fab2_lib.baseboard_fab2(sch_1):\PP2749\") )
				( member ( pinPairRef "@baseboard_fab2_lib.baseboard_fab2(sch_1):\PP2752\") )
				( member ( pinPairRef "@baseboard_fab2_lib.baseboard_fab2(sch_1):\PP769\") )
				( member ( pinPairRef "@baseboard_fab2_lib.baseboard_fab2(sch_1):\PP772\") )
				( member ( pinPairRef "@baseboard_fab2_lib.baseboard_fab2(sch_1):\PP763\") )
				( member ( pinPairRef "@baseboard_fab2_lib.baseboard_fab2(sch_1):\PP766\") )
				( objectStatus "MG_DQ-DQS_FAR_DIMM_NG_M_H_BYTE-ECC" )
			)
			( matchGroup "@crescent_city_bb_fab1_lib.crescent_city_bb_fab1(sch_1):\MG_DQ_FAR_DIMM_NG_M_H_BYTE-ECC\"
				( memberType ( signal ) )
				( member ( pinPairRef "@baseboard_fab2_lib.baseboard_fab2(sch_1):\PP2731\") )
				( member ( pinPairRef "@baseboard_fab2_lib.baseboard_fab2(sch_1):\PP2734\") )
				( member ( pinPairRef "@baseboard_fab2_lib.baseboard_fab2(sch_1):\PP2737\") )
				( member ( pinPairRef "@baseboard_fab2_lib.baseboard_fab2(sch_1):\PP2740\") )
				( member ( pinPairRef "@baseboard_fab2_lib.baseboard_fab2(sch_1):\PP2743\") )
				( member ( pinPairRef "@baseboard_fab2_lib.baseboard_fab2(sch_1):\PP2746\") )
				( member ( pinPairRef "@baseboard_fab2_lib.baseboard_fab2(sch_1):\PP2749\") )
				( member ( pinPairRef "@baseboard_fab2_lib.baseboard_fab2(sch_1):\PP2752\") )
				( objectStatus "MG_DQ_FAR_DIMM_NG_M_H_BYTE-ECC" )
			)
			( matchGroup "@baseboard_fab2_lib.baseboard_fab2(sch_1):\MG_DQ-DQS_NEAR_DIMM_NG_M_H_BYTE-ECC\"
				( memberType ( signal ) )
				( member ( pinPairRef "@baseboard_fab2_lib.baseboard_fab2(sch_1):\PP2732\") )
				( member ( pinPairRef "@baseboard_fab2_lib.baseboard_fab2(sch_1):\PP2735\") )
				( member ( pinPairRef "@baseboard_fab2_lib.baseboard_fab2(sch_1):\PP2738\") )
				( member ( pinPairRef "@baseboard_fab2_lib.baseboard_fab2(sch_1):\PP2741\") )
				( member ( pinPairRef "@baseboard_fab2_lib.baseboard_fab2(sch_1):\PP2744\") )
				( member ( pinPairRef "@baseboard_fab2_lib.baseboard_fab2(sch_1):\PP2747\") )
				( member ( pinPairRef "@baseboard_fab2_lib.baseboard_fab2(sch_1):\PP2750\") )
				( member ( pinPairRef "@baseboard_fab2_lib.baseboard_fab2(sch_1):\PP2753\") )
				( member ( pinPairRef "@baseboard_fab2_lib.baseboard_fab2(sch_1):\PP770\") )
				( member ( pinPairRef "@baseboard_fab2_lib.baseboard_fab2(sch_1):\PP773\") )
				( member ( pinPairRef "@baseboard_fab2_lib.baseboard_fab2(sch_1):\PP764\") )
				( member ( pinPairRef "@baseboard_fab2_lib.baseboard_fab2(sch_1):\PP767\") )
				( objectStatus "MG_DQ-DQS_NEAR_DIMM_NG_M_H_BYTE-ECC" )
			)
			( matchGroup "@crescent_city_bb_fab1_lib.crescent_city_bb_fab1(sch_1):\MG_DQ_NEAR_DIMM_NG_M_H_BYTE-ECC\"
				( memberType ( signal ) )
				( member ( pinPairRef "@baseboard_fab2_lib.baseboard_fab2(sch_1):\PP2732\") )
				( member ( pinPairRef "@baseboard_fab2_lib.baseboard_fab2(sch_1):\PP2735\") )
				( member ( pinPairRef "@baseboard_fab2_lib.baseboard_fab2(sch_1):\PP2738\") )
				( member ( pinPairRef "@baseboard_fab2_lib.baseboard_fab2(sch_1):\PP2741\") )
				( member ( pinPairRef "@baseboard_fab2_lib.baseboard_fab2(sch_1):\PP2744\") )
				( member ( pinPairRef "@baseboard_fab2_lib.baseboard_fab2(sch_1):\PP2747\") )
				( member ( pinPairRef "@baseboard_fab2_lib.baseboard_fab2(sch_1):\PP2750\") )
				( member ( pinPairRef "@baseboard_fab2_lib.baseboard_fab2(sch_1):\PP2753\") )
				( objectStatus "MG_DQ_NEAR_DIMM_NG_M_H_BYTE-ECC" )
			)
			( matchGroup "@baseboard_fab2_lib.baseboard_fab2(sch_1):\MG_DQ-DQS_FAR_DIMM_NG_M_J_BYTE-ECC\"
				( memberType ( signal ) )
				( member ( pinPairRef "@baseboard_fab2_lib.baseboard_fab2(sch_1):\PP2515\") )
				( member ( pinPairRef "@baseboard_fab2_lib.baseboard_fab2(sch_1):\PP2518\") )
				( member ( pinPairRef "@baseboard_fab2_lib.baseboard_fab2(sch_1):\PP2521\") )
				( member ( pinPairRef "@baseboard_fab2_lib.baseboard_fab2(sch_1):\PP2524\") )
				( member ( pinPairRef "@baseboard_fab2_lib.baseboard_fab2(sch_1):\PP2527\") )
				( member ( pinPairRef "@baseboard_fab2_lib.baseboard_fab2(sch_1):\PP2530\") )
				( member ( pinPairRef "@baseboard_fab2_lib.baseboard_fab2(sch_1):\PP2533\") )
				( member ( pinPairRef "@baseboard_fab2_lib.baseboard_fab2(sch_1):\PP2536\") )
				( member ( pinPairRef "@baseboard_fab2_lib.baseboard_fab2(sch_1):\PP1249\") )
				( member ( pinPairRef "@baseboard_fab2_lib.baseboard_fab2(sch_1):\PP1252\") )
				( member ( pinPairRef "@baseboard_fab2_lib.baseboard_fab2(sch_1):\PP1243\") )
				( member ( pinPairRef "@baseboard_fab2_lib.baseboard_fab2(sch_1):\PP1246\") )
				( objectStatus "MG_DQ-DQS_FAR_DIMM_NG_M_J_BYTE-ECC" )
			)
			( matchGroup "@baseboard_fab2_lib.baseboard_fab2(sch_1):\MG_DQ_FAR_DIMM_NG_M_J_BYTE-ECC\"
				( memberType ( signal ) )
				( member ( pinPairRef "@baseboard_fab2_lib.baseboard_fab2(sch_1):\PP2515\") )
				( member ( pinPairRef "@baseboard_fab2_lib.baseboard_fab2(sch_1):\PP2518\") )
				( member ( pinPairRef "@baseboard_fab2_lib.baseboard_fab2(sch_1):\PP2521\") )
				( member ( pinPairRef "@baseboard_fab2_lib.baseboard_fab2(sch_1):\PP2524\") )
				( member ( pinPairRef "@baseboard_fab2_lib.baseboard_fab2(sch_1):\PP2527\") )
				( member ( pinPairRef "@baseboard_fab2_lib.baseboard_fab2(sch_1):\PP2530\") )
				( member ( pinPairRef "@baseboard_fab2_lib.baseboard_fab2(sch_1):\PP2533\") )
				( member ( pinPairRef "@baseboard_fab2_lib.baseboard_fab2(sch_1):\PP2536\") )
				( objectStatus "MG_DQ_FAR_DIMM_NG_M_J_BYTE-ECC" )
			)
			( matchGroup "@baseboard_fab2_lib.baseboard_fab2(sch_1):\MG_DQ-DQS_NEAR_DIMM_NG_M_J_BYTE-ECC\"
				( memberType ( signal ) )
				( member ( pinPairRef "@baseboard_fab2_lib.baseboard_fab2(sch_1):\PP2516\") )
				( member ( pinPairRef "@baseboard_fab2_lib.baseboard_fab2(sch_1):\PP2519\") )
				( member ( pinPairRef "@baseboard_fab2_lib.baseboard_fab2(sch_1):\PP2522\") )
				( member ( pinPairRef "@baseboard_fab2_lib.baseboard_fab2(sch_1):\PP2525\") )
				( member ( pinPairRef "@baseboard_fab2_lib.baseboard_fab2(sch_1):\PP2528\") )
				( member ( pinPairRef "@baseboard_fab2_lib.baseboard_fab2(sch_1):\PP2531\") )
				( member ( pinPairRef "@baseboard_fab2_lib.baseboard_fab2(sch_1):\PP2534\") )
				( member ( pinPairRef "@baseboard_fab2_lib.baseboard_fab2(sch_1):\PP2537\") )
				( member ( pinPairRef "@baseboard_fab2_lib.baseboard_fab2(sch_1):\PP1250\") )
				( member ( pinPairRef "@baseboard_fab2_lib.baseboard_fab2(sch_1):\PP1253\") )
				( member ( pinPairRef "@baseboard_fab2_lib.baseboard_fab2(sch_1):\PP1244\") )
				( member ( pinPairRef "@baseboard_fab2_lib.baseboard_fab2(sch_1):\PP1247\") )
				( objectStatus "MG_DQ-DQS_NEAR_DIMM_NG_M_J_BYTE-ECC" )
			)
			( matchGroup "@baseboard_fab2_lib.baseboard_fab2(sch_1):\MG_DQ_NEAR_DIMM_NG_M_J_BYTE-ECC\"
				( memberType ( signal ) )
				( member ( pinPairRef "@baseboard_fab2_lib.baseboard_fab2(sch_1):\PP2516\") )
				( member ( pinPairRef "@baseboard_fab2_lib.baseboard_fab2(sch_1):\PP2519\") )
				( member ( pinPairRef "@baseboard_fab2_lib.baseboard_fab2(sch_1):\PP2522\") )
				( member ( pinPairRef "@baseboard_fab2_lib.baseboard_fab2(sch_1):\PP2525\") )
				( member ( pinPairRef "@baseboard_fab2_lib.baseboard_fab2(sch_1):\PP2528\") )
				( member ( pinPairRef "@baseboard_fab2_lib.baseboard_fab2(sch_1):\PP2531\") )
				( member ( pinPairRef "@baseboard_fab2_lib.baseboard_fab2(sch_1):\PP2534\") )
				( member ( pinPairRef "@baseboard_fab2_lib.baseboard_fab2(sch_1):\PP2537\") )
				( objectStatus "MG_DQ_NEAR_DIMM_NG_M_J_BYTE-ECC" )
			)
			( matchGroup "@baseboard_fab2_lib.baseboard_fab2(sch_1):\MG_DQ-DQS_FAR_DIMM_NG_M_K_BYTE-ECC\"
				( memberType ( signal ) )
				( member ( pinPairRef "@baseboard_fab2_lib.baseboard_fab2(sch_1):\PP2299\") )
				( member ( pinPairRef "@baseboard_fab2_lib.baseboard_fab2(sch_1):\PP2302\") )
				( member ( pinPairRef "@baseboard_fab2_lib.baseboard_fab2(sch_1):\PP2305\") )
				( member ( pinPairRef "@baseboard_fab2_lib.baseboard_fab2(sch_1):\PP2308\") )
				( member ( pinPairRef "@baseboard_fab2_lib.baseboard_fab2(sch_1):\PP2311\") )
				( member ( pinPairRef "@baseboard_fab2_lib.baseboard_fab2(sch_1):\PP2314\") )
				( member ( pinPairRef "@baseboard_fab2_lib.baseboard_fab2(sch_1):\PP2317\") )
				( member ( pinPairRef "@baseboard_fab2_lib.baseboard_fab2(sch_1):\PP2320\") )
				( member ( pinPairRef "@baseboard_fab2_lib.baseboard_fab2(sch_1):\PP1261\") )
				( member ( pinPairRef "@baseboard_fab2_lib.baseboard_fab2(sch_1):\PP1264\") )
				( member ( pinPairRef "@baseboard_fab2_lib.baseboard_fab2(sch_1):\PP1255\") )
				( member ( pinPairRef "@baseboard_fab2_lib.baseboard_fab2(sch_1):\PP1258\") )
				( objectStatus "MG_DQ-DQS_FAR_DIMM_NG_M_K_BYTE-ECC" )
			)
			( matchGroup "@baseboard_fab2_lib.baseboard_fab2(sch_1):\MG_DQ_FAR_DIMM_NG_M_K_BYTE-ECC\"
				( memberType ( signal ) )
				( member ( pinPairRef "@baseboard_fab2_lib.baseboard_fab2(sch_1):\PP2299\") )
				( member ( pinPairRef "@baseboard_fab2_lib.baseboard_fab2(sch_1):\PP2302\") )
				( member ( pinPairRef "@baseboard_fab2_lib.baseboard_fab2(sch_1):\PP2305\") )
				( member ( pinPairRef "@baseboard_fab2_lib.baseboard_fab2(sch_1):\PP2308\") )
				( member ( pinPairRef "@baseboard_fab2_lib.baseboard_fab2(sch_1):\PP2311\") )
				( member ( pinPairRef "@baseboard_fab2_lib.baseboard_fab2(sch_1):\PP2314\") )
				( member ( pinPairRef "@baseboard_fab2_lib.baseboard_fab2(sch_1):\PP2317\") )
				( member ( pinPairRef "@baseboard_fab2_lib.baseboard_fab2(sch_1):\PP2320\") )
				( objectStatus "MG_DQ_FAR_DIMM_NG_M_K_BYTE-ECC" )
			)
			( matchGroup "@baseboard_fab2_lib.baseboard_fab2(sch_1):\MG_DQ-DQS_NEAR_DIMM_NG_M_K_BYTE-ECC\"
				( memberType ( signal ) )
				( member ( pinPairRef "@baseboard_fab2_lib.baseboard_fab2(sch_1):\PP2300\") )
				( member ( pinPairRef "@baseboard_fab2_lib.baseboard_fab2(sch_1):\PP2303\") )
				( member ( pinPairRef "@baseboard_fab2_lib.baseboard_fab2(sch_1):\PP2306\") )
				( member ( pinPairRef "@baseboard_fab2_lib.baseboard_fab2(sch_1):\PP2309\") )
				( member ( pinPairRef "@baseboard_fab2_lib.baseboard_fab2(sch_1):\PP2312\") )
				( member ( pinPairRef "@baseboard_fab2_lib.baseboard_fab2(sch_1):\PP2315\") )
				( member ( pinPairRef "@baseboard_fab2_lib.baseboard_fab2(sch_1):\PP2318\") )
				( member ( pinPairRef "@baseboard_fab2_lib.baseboard_fab2(sch_1):\PP2321\") )
				( member ( pinPairRef "@baseboard_fab2_lib.baseboard_fab2(sch_1):\PP1262\") )
				( member ( pinPairRef "@baseboard_fab2_lib.baseboard_fab2(sch_1):\PP1265\") )
				( member ( pinPairRef "@baseboard_fab2_lib.baseboard_fab2(sch_1):\PP1256\") )
				( member ( pinPairRef "@baseboard_fab2_lib.baseboard_fab2(sch_1):\PP1259\") )
				( objectStatus "MG_DQ-DQS_NEAR_DIMM_NG_M_K_BYTE-ECC" )
			)
			( matchGroup "@baseboard_fab2_lib.baseboard_fab2(sch_1):\MG_DQ_NEAR_DIMM_NG_M_K_BYTE-ECC\"
				( memberType ( signal ) )
				( member ( pinPairRef "@baseboard_fab2_lib.baseboard_fab2(sch_1):\PP2300\") )
				( member ( pinPairRef "@baseboard_fab2_lib.baseboard_fab2(sch_1):\PP2303\") )
				( member ( pinPairRef "@baseboard_fab2_lib.baseboard_fab2(sch_1):\PP2306\") )
				( member ( pinPairRef "@baseboard_fab2_lib.baseboard_fab2(sch_1):\PP2309\") )
				( member ( pinPairRef "@baseboard_fab2_lib.baseboard_fab2(sch_1):\PP2312\") )
				( member ( pinPairRef "@baseboard_fab2_lib.baseboard_fab2(sch_1):\PP2315\") )
				( member ( pinPairRef "@baseboard_fab2_lib.baseboard_fab2(sch_1):\PP2318\") )
				( member ( pinPairRef "@baseboard_fab2_lib.baseboard_fab2(sch_1):\PP2321\") )
				( objectStatus "MG_DQ_NEAR_DIMM_NG_M_K_BYTE-ECC" )
			)
			( matchGroup "@baseboard_fab2_lib.baseboard_fab2(sch_1):\MG_DQ-DQS_FAR_DIMM_NG_M_L_BYTE-ECC\"
				( memberType ( signal ) )
				( member ( pinPairRef "@baseboard_fab2_lib.baseboard_fab2(sch_1):\PP2083\") )
				( member ( pinPairRef "@baseboard_fab2_lib.baseboard_fab2(sch_1):\PP2086\") )
				( member ( pinPairRef "@baseboard_fab2_lib.baseboard_fab2(sch_1):\PP2089\") )
				( member ( pinPairRef "@baseboard_fab2_lib.baseboard_fab2(sch_1):\PP2092\") )
				( member ( pinPairRef "@baseboard_fab2_lib.baseboard_fab2(sch_1):\PP2095\") )
				( member ( pinPairRef "@baseboard_fab2_lib.baseboard_fab2(sch_1):\PP2098\") )
				( member ( pinPairRef "@baseboard_fab2_lib.baseboard_fab2(sch_1):\PP2101\") )
				( member ( pinPairRef "@baseboard_fab2_lib.baseboard_fab2(sch_1):\PP2104\") )
				( member ( pinPairRef "@baseboard_fab2_lib.baseboard_fab2(sch_1):\PP1273\") )
				( member ( pinPairRef "@baseboard_fab2_lib.baseboard_fab2(sch_1):\PP1276\") )
				( member ( pinPairRef "@baseboard_fab2_lib.baseboard_fab2(sch_1):\PP1267\") )
				( member ( pinPairRef "@baseboard_fab2_lib.baseboard_fab2(sch_1):\PP1270\") )
				( objectStatus "MG_DQ-DQS_FAR_DIMM_NG_M_L_BYTE-ECC" )
			)
			( matchGroup "@crescent_city_bb_fab1_lib.crescent_city_bb_fab1(sch_1):\MG_DQ_FAR_DIMM_NG_M_L_BYTE-ECC\"
				( memberType ( signal ) )
				( member ( pinPairRef "@baseboard_fab2_lib.baseboard_fab2(sch_1):\PP2083\") )
				( member ( pinPairRef "@baseboard_fab2_lib.baseboard_fab2(sch_1):\PP2086\") )
				( member ( pinPairRef "@baseboard_fab2_lib.baseboard_fab2(sch_1):\PP2089\") )
				( member ( pinPairRef "@baseboard_fab2_lib.baseboard_fab2(sch_1):\PP2092\") )
				( member ( pinPairRef "@baseboard_fab2_lib.baseboard_fab2(sch_1):\PP2095\") )
				( member ( pinPairRef "@baseboard_fab2_lib.baseboard_fab2(sch_1):\PP2098\") )
				( member ( pinPairRef "@baseboard_fab2_lib.baseboard_fab2(sch_1):\PP2101\") )
				( member ( pinPairRef "@baseboard_fab2_lib.baseboard_fab2(sch_1):\PP2104\") )
				( objectStatus "MG_DQ_FAR_DIMM_NG_M_L_BYTE-ECC" )
			)
			( matchGroup "@baseboard_fab2_lib.baseboard_fab2(sch_1):\MG_DQ-DQS_NEAR_DIMM_NG_M_L_BYTE-ECC\"
				( memberType ( signal ) )
				( member ( pinPairRef "@baseboard_fab2_lib.baseboard_fab2(sch_1):\PP2084\") )
				( member ( pinPairRef "@baseboard_fab2_lib.baseboard_fab2(sch_1):\PP2087\") )
				( member ( pinPairRef "@baseboard_fab2_lib.baseboard_fab2(sch_1):\PP2090\") )
				( member ( pinPairRef "@baseboard_fab2_lib.baseboard_fab2(sch_1):\PP2093\") )
				( member ( pinPairRef "@baseboard_fab2_lib.baseboard_fab2(sch_1):\PP2096\") )
				( member ( pinPairRef "@baseboard_fab2_lib.baseboard_fab2(sch_1):\PP2099\") )
				( member ( pinPairRef "@baseboard_fab2_lib.baseboard_fab2(sch_1):\PP2102\") )
				( member ( pinPairRef "@baseboard_fab2_lib.baseboard_fab2(sch_1):\PP2105\") )
				( member ( pinPairRef "@baseboard_fab2_lib.baseboard_fab2(sch_1):\PP1274\") )
				( member ( pinPairRef "@baseboard_fab2_lib.baseboard_fab2(sch_1):\PP1277\") )
				( member ( pinPairRef "@baseboard_fab2_lib.baseboard_fab2(sch_1):\PP1268\") )
				( member ( pinPairRef "@baseboard_fab2_lib.baseboard_fab2(sch_1):\PP1271\") )
				( objectStatus "MG_DQ-DQS_NEAR_DIMM_NG_M_L_BYTE-ECC" )
			)
			( matchGroup "@crescent_city_bb_fab1_lib.crescent_city_bb_fab1(sch_1):\MG_DQ_NEAR_DIMM_NG_M_L_BYTE-ECC\"
				( memberType ( signal ) )
				( member ( pinPairRef "@baseboard_fab2_lib.baseboard_fab2(sch_1):\PP2084\") )
				( member ( pinPairRef "@baseboard_fab2_lib.baseboard_fab2(sch_1):\PP2087\") )
				( member ( pinPairRef "@baseboard_fab2_lib.baseboard_fab2(sch_1):\PP2090\") )
				( member ( pinPairRef "@baseboard_fab2_lib.baseboard_fab2(sch_1):\PP2093\") )
				( member ( pinPairRef "@baseboard_fab2_lib.baseboard_fab2(sch_1):\PP2096\") )
				( member ( pinPairRef "@baseboard_fab2_lib.baseboard_fab2(sch_1):\PP2099\") )
				( member ( pinPairRef "@baseboard_fab2_lib.baseboard_fab2(sch_1):\PP2102\") )
				( member ( pinPairRef "@baseboard_fab2_lib.baseboard_fab2(sch_1):\PP2105\") )
				( objectStatus "MG_DQ_NEAR_DIMM_NG_M_L_BYTE-ECC" )
			)
			( matchGroup "@baseboard_fab2_lib.baseboard_fab2(sch_1):\MG_DQ-DQS_FAR_DIMM_NG_M_M_BYTE-ECC\"
				( memberType ( signal ) )
				( member ( pinPairRef "@baseboard_fab2_lib.baseboard_fab2(sch_1):\PP1867\") )
				( member ( pinPairRef "@baseboard_fab2_lib.baseboard_fab2(sch_1):\PP1870\") )
				( member ( pinPairRef "@baseboard_fab2_lib.baseboard_fab2(sch_1):\PP1873\") )
				( member ( pinPairRef "@baseboard_fab2_lib.baseboard_fab2(sch_1):\PP1876\") )
				( member ( pinPairRef "@baseboard_fab2_lib.baseboard_fab2(sch_1):\PP1879\") )
				( member ( pinPairRef "@baseboard_fab2_lib.baseboard_fab2(sch_1):\PP1882\") )
				( member ( pinPairRef "@baseboard_fab2_lib.baseboard_fab2(sch_1):\PP1885\") )
				( member ( pinPairRef "@baseboard_fab2_lib.baseboard_fab2(sch_1):\PP1888\") )
				( member ( pinPairRef "@baseboard_fab2_lib.baseboard_fab2(sch_1):\PP1285\") )
				( member ( pinPairRef "@baseboard_fab2_lib.baseboard_fab2(sch_1):\PP1288\") )
				( member ( pinPairRef "@baseboard_fab2_lib.baseboard_fab2(sch_1):\PP1279\") )
				( member ( pinPairRef "@baseboard_fab2_lib.baseboard_fab2(sch_1):\PP1282\") )
				( objectStatus "MG_DQ-DQS_FAR_DIMM_NG_M_M_BYTE-ECC" )
			)
			( matchGroup "@baseboard_fab2_lib.baseboard_fab2(sch_1):\MG_DQ_FAR_DIMM_NG_M_M_BYTE-ECC\"
				( memberType ( signal ) )
				( member ( pinPairRef "@baseboard_fab2_lib.baseboard_fab2(sch_1):\PP1867\") )
				( member ( pinPairRef "@baseboard_fab2_lib.baseboard_fab2(sch_1):\PP1870\") )
				( member ( pinPairRef "@baseboard_fab2_lib.baseboard_fab2(sch_1):\PP1873\") )
				( member ( pinPairRef "@baseboard_fab2_lib.baseboard_fab2(sch_1):\PP1876\") )
				( member ( pinPairRef "@baseboard_fab2_lib.baseboard_fab2(sch_1):\PP1879\") )
				( member ( pinPairRef "@baseboard_fab2_lib.baseboard_fab2(sch_1):\PP1882\") )
				( member ( pinPairRef "@baseboard_fab2_lib.baseboard_fab2(sch_1):\PP1885\") )
				( member ( pinPairRef "@baseboard_fab2_lib.baseboard_fab2(sch_1):\PP1888\") )
				( objectStatus "MG_DQ_FAR_DIMM_NG_M_M_BYTE-ECC" )
			)
			( matchGroup "@baseboard_fab2_lib.baseboard_fab2(sch_1):\MG_DQ-DQS_NEAR_DIMM_NG_M_M_BYTE-ECC\"
				( memberType ( signal ) )
				( member ( pinPairRef "@baseboard_fab2_lib.baseboard_fab2(sch_1):\PP1868\") )
				( member ( pinPairRef "@baseboard_fab2_lib.baseboard_fab2(sch_1):\PP1871\") )
				( member ( pinPairRef "@baseboard_fab2_lib.baseboard_fab2(sch_1):\PP1874\") )
				( member ( pinPairRef "@baseboard_fab2_lib.baseboard_fab2(sch_1):\PP1877\") )
				( member ( pinPairRef "@baseboard_fab2_lib.baseboard_fab2(sch_1):\PP1880\") )
				( member ( pinPairRef "@baseboard_fab2_lib.baseboard_fab2(sch_1):\PP1883\") )
				( member ( pinPairRef "@baseboard_fab2_lib.baseboard_fab2(sch_1):\PP1886\") )
				( member ( pinPairRef "@baseboard_fab2_lib.baseboard_fab2(sch_1):\PP1889\") )
				( member ( pinPairRef "@baseboard_fab2_lib.baseboard_fab2(sch_1):\PP1286\") )
				( member ( pinPairRef "@baseboard_fab2_lib.baseboard_fab2(sch_1):\PP1289\") )
				( member ( pinPairRef "@baseboard_fab2_lib.baseboard_fab2(sch_1):\PP1280\") )
				( member ( pinPairRef "@baseboard_fab2_lib.baseboard_fab2(sch_1):\PP1283\") )
				( objectStatus "MG_DQ-DQS_NEAR_DIMM_NG_M_M_BYTE-ECC" )
			)
			( matchGroup "@crescent_city_bb_fab1_lib.crescent_city_bb_fab1(sch_1):\MG_DQ_NEAR_DIMM_NG_M_M_BYTE-ECC\"
				( memberType ( signal ) )
				( member ( pinPairRef "@baseboard_fab2_lib.baseboard_fab2(sch_1):\PP1868\") )
				( member ( pinPairRef "@baseboard_fab2_lib.baseboard_fab2(sch_1):\PP1871\") )
				( member ( pinPairRef "@baseboard_fab2_lib.baseboard_fab2(sch_1):\PP1874\") )
				( member ( pinPairRef "@baseboard_fab2_lib.baseboard_fab2(sch_1):\PP1877\") )
				( member ( pinPairRef "@baseboard_fab2_lib.baseboard_fab2(sch_1):\PP1880\") )
				( member ( pinPairRef "@baseboard_fab2_lib.baseboard_fab2(sch_1):\PP1883\") )
				( member ( pinPairRef "@baseboard_fab2_lib.baseboard_fab2(sch_1):\PP1886\") )
				( member ( pinPairRef "@baseboard_fab2_lib.baseboard_fab2(sch_1):\PP1889\") )
				( objectStatus "MG_DQ_NEAR_DIMM_NG_M_M_BYTE-ECC" )
			)
			( matchGroup "@baseboard_fab2_lib.baseboard_fab2(sch_1):\MG_DQ-DQS_FAR_DIMM_NG_M_F_BYTE1\"
				( memberType ( signal ) )
				( member ( pinPairRef "@baseboard_fab2_lib.baseboard_fab2(sch_1):\PP4230\") )
				( member ( pinPairRef "@baseboard_fab2_lib.baseboard_fab2(sch_1):\PP4233\") )
				( member ( pinPairRef "@baseboard_fab2_lib.baseboard_fab2(sch_1):\PP4236\") )
				( member ( pinPairRef "@baseboard_fab2_lib.baseboard_fab2(sch_1):\PP4239\") )
				( member ( pinPairRef "@baseboard_fab2_lib.baseboard_fab2(sch_1):\PP4242\") )
				( member ( pinPairRef "@baseboard_fab2_lib.baseboard_fab2(sch_1):\PP4245\") )
				( member ( pinPairRef "@baseboard_fab2_lib.baseboard_fab2(sch_1):\PP4248\") )
				( member ( pinPairRef "@baseboard_fab2_lib.baseboard_fab2(sch_1):\PP4227\") )
				( member ( pinPairRef "@baseboard_fab2_lib.baseboard_fab2(sch_1):\PP1069\") )
				( member ( pinPairRef "@baseboard_fab2_lib.baseboard_fab2(sch_1):\PP1063\") )
				( member ( pinPairRef "@baseboard_fab2_lib.baseboard_fab2(sch_1):\PP1072\") )
				( member ( pinPairRef "@baseboard_fab2_lib.baseboard_fab2(sch_1):\PP1066\") )
				( objectStatus "MG_DQ-DQS_FAR_DIMM_NG_M_F_BYTE1" )
			)
			( matchGroup "@crescent_city_bb_fab1_lib.crescent_city_bb_fab1(sch_1):\MG_DQ_FAR_DIMM_NG_M_F_BYTE1\"
				( memberType ( signal ) )
				( member ( pinPairRef "@baseboard_fab2_lib.baseboard_fab2(sch_1):\PP4230\") )
				( member ( pinPairRef "@baseboard_fab2_lib.baseboard_fab2(sch_1):\PP4233\") )
				( member ( pinPairRef "@baseboard_fab2_lib.baseboard_fab2(sch_1):\PP4236\") )
				( member ( pinPairRef "@baseboard_fab2_lib.baseboard_fab2(sch_1):\PP4239\") )
				( member ( pinPairRef "@baseboard_fab2_lib.baseboard_fab2(sch_1):\PP4242\") )
				( member ( pinPairRef "@baseboard_fab2_lib.baseboard_fab2(sch_1):\PP4245\") )
				( member ( pinPairRef "@baseboard_fab2_lib.baseboard_fab2(sch_1):\PP4248\") )
				( member ( pinPairRef "@baseboard_fab2_lib.baseboard_fab2(sch_1):\PP4227\") )
				( objectStatus "MG_DQ_FAR_DIMM_NG_M_F_BYTE1" )
			)
			( matchGroup "@baseboard_fab2_lib.baseboard_fab2(sch_1):\MG_DQ-DQS_NEAR_DIMM_NG_M_F_BYTE1\"
				( memberType ( signal ) )
				( member ( pinPairRef "@baseboard_fab2_lib.baseboard_fab2(sch_1):\PP4232\") )
				( member ( pinPairRef "@baseboard_fab2_lib.baseboard_fab2(sch_1):\PP4235\") )
				( member ( pinPairRef "@baseboard_fab2_lib.baseboard_fab2(sch_1):\PP4238\") )
				( member ( pinPairRef "@baseboard_fab2_lib.baseboard_fab2(sch_1):\PP4241\") )
				( member ( pinPairRef "@baseboard_fab2_lib.baseboard_fab2(sch_1):\PP4244\") )
				( member ( pinPairRef "@baseboard_fab2_lib.baseboard_fab2(sch_1):\PP4247\") )
				( member ( pinPairRef "@baseboard_fab2_lib.baseboard_fab2(sch_1):\PP4250\") )
				( member ( pinPairRef "@baseboard_fab2_lib.baseboard_fab2(sch_1):\PP4229\") )
				( member ( pinPairRef "@baseboard_fab2_lib.baseboard_fab2(sch_1):\PP1070\") )
				( member ( pinPairRef "@baseboard_fab2_lib.baseboard_fab2(sch_1):\PP1064\") )
				( member ( pinPairRef "@baseboard_fab2_lib.baseboard_fab2(sch_1):\PP1073\") )
				( member ( pinPairRef "@baseboard_fab2_lib.baseboard_fab2(sch_1):\PP1067\") )
				( objectStatus "MG_DQ-DQS_NEAR_DIMM_NG_M_F_BYTE1" )
			)
			( matchGroup "@baseboard_fab2_lib.baseboard_fab2(sch_1):\MG_DQ_NEAR_DIMM_NG_M_F_BYTE1\"
				( memberType ( signal ) )
				( member ( pinPairRef "@baseboard_fab2_lib.baseboard_fab2(sch_1):\PP4232\") )
				( member ( pinPairRef "@baseboard_fab2_lib.baseboard_fab2(sch_1):\PP4235\") )
				( member ( pinPairRef "@baseboard_fab2_lib.baseboard_fab2(sch_1):\PP4238\") )
				( member ( pinPairRef "@baseboard_fab2_lib.baseboard_fab2(sch_1):\PP4241\") )
				( member ( pinPairRef "@baseboard_fab2_lib.baseboard_fab2(sch_1):\PP4244\") )
				( member ( pinPairRef "@baseboard_fab2_lib.baseboard_fab2(sch_1):\PP4247\") )
				( member ( pinPairRef "@baseboard_fab2_lib.baseboard_fab2(sch_1):\PP4250\") )
				( member ( pinPairRef "@baseboard_fab2_lib.baseboard_fab2(sch_1):\PP4229\") )
				( objectStatus "MG_DQ_NEAR_DIMM_NG_M_F_BYTE1" )
			)
			( matchGroup "@baseboard_fab2_lib.baseboard_fab2(sch_1):\MG_DQ-DQS_FAR_DIMM_NG_M_F_BYTE2\"
				( memberType ( signal ) )
				( member ( pinPairRef "@baseboard_fab2_lib.baseboard_fab2(sch_1):\PP4203\") )
				( member ( pinPairRef "@baseboard_fab2_lib.baseboard_fab2(sch_1):\PP4206\") )
				( member ( pinPairRef "@baseboard_fab2_lib.baseboard_fab2(sch_1):\PP4209\") )
				( member ( pinPairRef "@baseboard_fab2_lib.baseboard_fab2(sch_1):\PP4212\") )
				( member ( pinPairRef "@baseboard_fab2_lib.baseboard_fab2(sch_1):\PP4215\") )
				( member ( pinPairRef "@baseboard_fab2_lib.baseboard_fab2(sch_1):\PP4218\") )
				( member ( pinPairRef "@baseboard_fab2_lib.baseboard_fab2(sch_1):\PP4221\") )
				( member ( pinPairRef "@baseboard_fab2_lib.baseboard_fab2(sch_1):\PP4224\") )
				( member ( pinPairRef "@baseboard_fab2_lib.baseboard_fab2(sch_1):\PP1057\") )
				( member ( pinPairRef "@baseboard_fab2_lib.baseboard_fab2(sch_1):\PP1051\") )
				( member ( pinPairRef "@baseboard_fab2_lib.baseboard_fab2(sch_1):\PP1060\") )
				( member ( pinPairRef "@baseboard_fab2_lib.baseboard_fab2(sch_1):\PP1054\") )
				( objectStatus "MG_DQ-DQS_FAR_DIMM_NG_M_F_BYTE2" )
			)
			( matchGroup "@crescent_city_bb_fab1_lib.crescent_city_bb_fab1(sch_1):\MG_DQ_FAR_DIMM_NG_M_F_BYTE2\"
				( memberType ( signal ) )
				( member ( pinPairRef "@baseboard_fab2_lib.baseboard_fab2(sch_1):\PP4203\") )
				( member ( pinPairRef "@baseboard_fab2_lib.baseboard_fab2(sch_1):\PP4206\") )
				( member ( pinPairRef "@baseboard_fab2_lib.baseboard_fab2(sch_1):\PP4209\") )
				( member ( pinPairRef "@baseboard_fab2_lib.baseboard_fab2(sch_1):\PP4212\") )
				( member ( pinPairRef "@baseboard_fab2_lib.baseboard_fab2(sch_1):\PP4215\") )
				( member ( pinPairRef "@baseboard_fab2_lib.baseboard_fab2(sch_1):\PP4218\") )
				( member ( pinPairRef "@baseboard_fab2_lib.baseboard_fab2(sch_1):\PP4221\") )
				( member ( pinPairRef "@baseboard_fab2_lib.baseboard_fab2(sch_1):\PP4224\") )
				( objectStatus "MG_DQ_FAR_DIMM_NG_M_F_BYTE2" )
			)
			( matchGroup "@baseboard_fab2_lib.baseboard_fab2(sch_1):\MG_DQ-DQS_NEAR_DIMM_NG_M_F_BYTE2\"
				( memberType ( signal ) )
				( member ( pinPairRef "@baseboard_fab2_lib.baseboard_fab2(sch_1):\PP4205\") )
				( member ( pinPairRef "@baseboard_fab2_lib.baseboard_fab2(sch_1):\PP4208\") )
				( member ( pinPairRef "@baseboard_fab2_lib.baseboard_fab2(sch_1):\PP4211\") )
				( member ( pinPairRef "@baseboard_fab2_lib.baseboard_fab2(sch_1):\PP4214\") )
				( member ( pinPairRef "@baseboard_fab2_lib.baseboard_fab2(sch_1):\PP4217\") )
				( member ( pinPairRef "@baseboard_fab2_lib.baseboard_fab2(sch_1):\PP4220\") )
				( member ( pinPairRef "@baseboard_fab2_lib.baseboard_fab2(sch_1):\PP4223\") )
				( member ( pinPairRef "@baseboard_fab2_lib.baseboard_fab2(sch_1):\PP4226\") )
				( member ( pinPairRef "@baseboard_fab2_lib.baseboard_fab2(sch_1):\PP1058\") )
				( member ( pinPairRef "@baseboard_fab2_lib.baseboard_fab2(sch_1):\PP1052\") )
				( member ( pinPairRef "@baseboard_fab2_lib.baseboard_fab2(sch_1):\PP1061\") )
				( member ( pinPairRef "@baseboard_fab2_lib.baseboard_fab2(sch_1):\PP1055\") )
				( objectStatus "MG_DQ-DQS_NEAR_DIMM_NG_M_F_BYTE2" )
			)
			( matchGroup "@baseboard_fab2_lib.baseboard_fab2(sch_1):\MG_DQ_NEAR_DIMM_NG_M_F_BYTE2\"
				( memberType ( signal ) )
				( member ( pinPairRef "@baseboard_fab2_lib.baseboard_fab2(sch_1):\PP4205\") )
				( member ( pinPairRef "@baseboard_fab2_lib.baseboard_fab2(sch_1):\PP4208\") )
				( member ( pinPairRef "@baseboard_fab2_lib.baseboard_fab2(sch_1):\PP4211\") )
				( member ( pinPairRef "@baseboard_fab2_lib.baseboard_fab2(sch_1):\PP4214\") )
				( member ( pinPairRef "@baseboard_fab2_lib.baseboard_fab2(sch_1):\PP4217\") )
				( member ( pinPairRef "@baseboard_fab2_lib.baseboard_fab2(sch_1):\PP4220\") )
				( member ( pinPairRef "@baseboard_fab2_lib.baseboard_fab2(sch_1):\PP4223\") )
				( member ( pinPairRef "@baseboard_fab2_lib.baseboard_fab2(sch_1):\PP4226\") )
				( objectStatus "MG_DQ_NEAR_DIMM_NG_M_F_BYTE2" )
			)
			( matchGroup "@baseboard_fab2_lib.baseboard_fab2(sch_1):\MG_DQ-DQS_FAR_DIMM_NG_M_F_BYTE3\"
				( memberType ( signal ) )
				( member ( pinPairRef "@baseboard_fab2_lib.baseboard_fab2(sch_1):\PP4179\") )
				( member ( pinPairRef "@baseboard_fab2_lib.baseboard_fab2(sch_1):\PP4182\") )
				( member ( pinPairRef "@baseboard_fab2_lib.baseboard_fab2(sch_1):\PP4185\") )
				( member ( pinPairRef "@baseboard_fab2_lib.baseboard_fab2(sch_1):\PP4188\") )
				( member ( pinPairRef "@baseboard_fab2_lib.baseboard_fab2(sch_1):\PP4191\") )
				( member ( pinPairRef "@baseboard_fab2_lib.baseboard_fab2(sch_1):\PP4194\") )
				( member ( pinPairRef "@baseboard_fab2_lib.baseboard_fab2(sch_1):\PP4197\") )
				( member ( pinPairRef "@baseboard_fab2_lib.baseboard_fab2(sch_1):\PP4200\") )
				( member ( pinPairRef "@baseboard_fab2_lib.baseboard_fab2(sch_1):\PP1045\") )
				( member ( pinPairRef "@baseboard_fab2_lib.baseboard_fab2(sch_1):\PP1039\") )
				( member ( pinPairRef "@baseboard_fab2_lib.baseboard_fab2(sch_1):\PP1048\") )
				( member ( pinPairRef "@baseboard_fab2_lib.baseboard_fab2(sch_1):\PP1042\") )
				( objectStatus "MG_DQ-DQS_FAR_DIMM_NG_M_F_BYTE3" )
			)
			( matchGroup "@baseboard_fab2_lib.baseboard_fab2(sch_1):\MG_DQ_FAR_DIMM_NG_M_F_BYTE3\"
				( memberType ( signal ) )
				( member ( pinPairRef "@baseboard_fab2_lib.baseboard_fab2(sch_1):\PP4179\") )
				( member ( pinPairRef "@baseboard_fab2_lib.baseboard_fab2(sch_1):\PP4182\") )
				( member ( pinPairRef "@baseboard_fab2_lib.baseboard_fab2(sch_1):\PP4185\") )
				( member ( pinPairRef "@baseboard_fab2_lib.baseboard_fab2(sch_1):\PP4188\") )
				( member ( pinPairRef "@baseboard_fab2_lib.baseboard_fab2(sch_1):\PP4191\") )
				( member ( pinPairRef "@baseboard_fab2_lib.baseboard_fab2(sch_1):\PP4194\") )
				( member ( pinPairRef "@baseboard_fab2_lib.baseboard_fab2(sch_1):\PP4197\") )
				( member ( pinPairRef "@baseboard_fab2_lib.baseboard_fab2(sch_1):\PP4200\") )
				( objectStatus "MG_DQ_FAR_DIMM_NG_M_F_BYTE3" )
			)
			( matchGroup "@baseboard_fab2_lib.baseboard_fab2(sch_1):\MG_DQ-DQS_NEAR_DIMM_NG_M_F_BYTE3\"
				( memberType ( signal ) )
				( member ( pinPairRef "@baseboard_fab2_lib.baseboard_fab2(sch_1):\PP4181\") )
				( member ( pinPairRef "@baseboard_fab2_lib.baseboard_fab2(sch_1):\PP4184\") )
				( member ( pinPairRef "@baseboard_fab2_lib.baseboard_fab2(sch_1):\PP4187\") )
				( member ( pinPairRef "@baseboard_fab2_lib.baseboard_fab2(sch_1):\PP4190\") )
				( member ( pinPairRef "@baseboard_fab2_lib.baseboard_fab2(sch_1):\PP4193\") )
				( member ( pinPairRef "@baseboard_fab2_lib.baseboard_fab2(sch_1):\PP4196\") )
				( member ( pinPairRef "@baseboard_fab2_lib.baseboard_fab2(sch_1):\PP4199\") )
				( member ( pinPairRef "@baseboard_fab2_lib.baseboard_fab2(sch_1):\PP4202\") )
				( member ( pinPairRef "@baseboard_fab2_lib.baseboard_fab2(sch_1):\PP1046\") )
				( member ( pinPairRef "@baseboard_fab2_lib.baseboard_fab2(sch_1):\PP1040\") )
				( member ( pinPairRef "@baseboard_fab2_lib.baseboard_fab2(sch_1):\PP1049\") )
				( member ( pinPairRef "@baseboard_fab2_lib.baseboard_fab2(sch_1):\PP1043\") )
				( objectStatus "MG_DQ-DQS_NEAR_DIMM_NG_M_F_BYTE3" )
			)
			( matchGroup "@crescent_city_bb_fab1_lib.crescent_city_bb_fab1(sch_1):\MG_DQ_NEAR_DIMM_NG_M_F_BYTE3\"
				( memberType ( signal ) )
				( member ( pinPairRef "@baseboard_fab2_lib.baseboard_fab2(sch_1):\PP4181\") )
				( member ( pinPairRef "@baseboard_fab2_lib.baseboard_fab2(sch_1):\PP4184\") )
				( member ( pinPairRef "@baseboard_fab2_lib.baseboard_fab2(sch_1):\PP4187\") )
				( member ( pinPairRef "@baseboard_fab2_lib.baseboard_fab2(sch_1):\PP4190\") )
				( member ( pinPairRef "@baseboard_fab2_lib.baseboard_fab2(sch_1):\PP4193\") )
				( member ( pinPairRef "@baseboard_fab2_lib.baseboard_fab2(sch_1):\PP4196\") )
				( member ( pinPairRef "@baseboard_fab2_lib.baseboard_fab2(sch_1):\PP4199\") )
				( member ( pinPairRef "@baseboard_fab2_lib.baseboard_fab2(sch_1):\PP4202\") )
				( objectStatus "MG_DQ_NEAR_DIMM_NG_M_F_BYTE3" )
			)
			( matchGroup "@baseboard_fab2_lib.baseboard_fab2(sch_1):\MG_DQ-DQS_FAR_DIMM_NG_M_F_BYTE4\"
				( memberType ( signal ) )
				( member ( pinPairRef "@baseboard_fab2_lib.baseboard_fab2(sch_1):\PP4155\") )
				( member ( pinPairRef "@baseboard_fab2_lib.baseboard_fab2(sch_1):\PP4158\") )
				( member ( pinPairRef "@baseboard_fab2_lib.baseboard_fab2(sch_1):\PP4161\") )
				( member ( pinPairRef "@baseboard_fab2_lib.baseboard_fab2(sch_1):\PP4164\") )
				( member ( pinPairRef "@baseboard_fab2_lib.baseboard_fab2(sch_1):\PP4167\") )
				( member ( pinPairRef "@baseboard_fab2_lib.baseboard_fab2(sch_1):\PP4170\") )
				( member ( pinPairRef "@baseboard_fab2_lib.baseboard_fab2(sch_1):\PP4173\") )
				( member ( pinPairRef "@baseboard_fab2_lib.baseboard_fab2(sch_1):\PP4176\") )
				( member ( pinPairRef "@baseboard_fab2_lib.baseboard_fab2(sch_1):\PP1033\") )
				( member ( pinPairRef "@baseboard_fab2_lib.baseboard_fab2(sch_1):\PP1027\") )
				( member ( pinPairRef "@baseboard_fab2_lib.baseboard_fab2(sch_1):\PP1036\") )
				( member ( pinPairRef "@baseboard_fab2_lib.baseboard_fab2(sch_1):\PP1030\") )
				( objectStatus "MG_DQ-DQS_FAR_DIMM_NG_M_F_BYTE4" )
			)
			( matchGroup "@crescent_city_bb_fab1_lib.crescent_city_bb_fab1(sch_1):\MG_DQ_FAR_DIMM_NG_M_F_BYTE4\"
				( memberType ( signal ) )
				( member ( pinPairRef "@baseboard_fab2_lib.baseboard_fab2(sch_1):\PP4155\") )
				( member ( pinPairRef "@baseboard_fab2_lib.baseboard_fab2(sch_1):\PP4158\") )
				( member ( pinPairRef "@baseboard_fab2_lib.baseboard_fab2(sch_1):\PP4161\") )
				( member ( pinPairRef "@baseboard_fab2_lib.baseboard_fab2(sch_1):\PP4164\") )
				( member ( pinPairRef "@baseboard_fab2_lib.baseboard_fab2(sch_1):\PP4167\") )
				( member ( pinPairRef "@baseboard_fab2_lib.baseboard_fab2(sch_1):\PP4170\") )
				( member ( pinPairRef "@baseboard_fab2_lib.baseboard_fab2(sch_1):\PP4173\") )
				( member ( pinPairRef "@baseboard_fab2_lib.baseboard_fab2(sch_1):\PP4176\") )
				( objectStatus "MG_DQ_FAR_DIMM_NG_M_F_BYTE4" )
			)
			( matchGroup "@baseboard_fab2_lib.baseboard_fab2(sch_1):\MG_DQ-DQS_NEAR_DIMM_NG_M_F_BYTE4\"
				( memberType ( signal ) )
				( member ( pinPairRef "@baseboard_fab2_lib.baseboard_fab2(sch_1):\PP4156\") )
				( member ( pinPairRef "@baseboard_fab2_lib.baseboard_fab2(sch_1):\PP4159\") )
				( member ( pinPairRef "@baseboard_fab2_lib.baseboard_fab2(sch_1):\PP4163\") )
				( member ( pinPairRef "@baseboard_fab2_lib.baseboard_fab2(sch_1):\PP4166\") )
				( member ( pinPairRef "@baseboard_fab2_lib.baseboard_fab2(sch_1):\PP4168\") )
				( member ( pinPairRef "@baseboard_fab2_lib.baseboard_fab2(sch_1):\PP4172\") )
				( member ( pinPairRef "@baseboard_fab2_lib.baseboard_fab2(sch_1):\PP4175\") )
				( member ( pinPairRef "@baseboard_fab2_lib.baseboard_fab2(sch_1):\PP4178\") )
				( member ( pinPairRef "@baseboard_fab2_lib.baseboard_fab2(sch_1):\PP1035\") )
				( member ( pinPairRef "@baseboard_fab2_lib.baseboard_fab2(sch_1):\PP1029\") )
				( member ( pinPairRef "@baseboard_fab2_lib.baseboard_fab2(sch_1):\PP1038\") )
				( member ( pinPairRef "@baseboard_fab2_lib.baseboard_fab2(sch_1):\PP1032\") )
				( objectStatus "MG_DQ-DQS_NEAR_DIMM_NG_M_F_BYTE4" )
			)
			( matchGroup "@crescent_city_bb_fab1_lib.crescent_city_bb_fab1(sch_1):\MG_DQ_NEAR_DIMM_NG_M_F_BYTE4\"
				( memberType ( signal ) )
				( member ( pinPairRef "@baseboard_fab2_lib.baseboard_fab2(sch_1):\PP4156\") )
				( member ( pinPairRef "@baseboard_fab2_lib.baseboard_fab2(sch_1):\PP4159\") )
				( member ( pinPairRef "@baseboard_fab2_lib.baseboard_fab2(sch_1):\PP4163\") )
				( member ( pinPairRef "@baseboard_fab2_lib.baseboard_fab2(sch_1):\PP4166\") )
				( member ( pinPairRef "@baseboard_fab2_lib.baseboard_fab2(sch_1):\PP4168\") )
				( member ( pinPairRef "@baseboard_fab2_lib.baseboard_fab2(sch_1):\PP4172\") )
				( member ( pinPairRef "@baseboard_fab2_lib.baseboard_fab2(sch_1):\PP4175\") )
				( member ( pinPairRef "@baseboard_fab2_lib.baseboard_fab2(sch_1):\PP4178\") )
				( objectStatus "MG_DQ_NEAR_DIMM_NG_M_F_BYTE4" )
			)
			( matchGroup "@baseboard_fab2_lib.baseboard_fab2(sch_1):\MG_DQ-DQS_FAR_DIMM_NG_M_F_BYTE5\"
				( memberType ( signal ) )
				( member ( pinPairRef "@baseboard_fab2_lib.baseboard_fab2(sch_1):\PP4131\") )
				( member ( pinPairRef "@baseboard_fab2_lib.baseboard_fab2(sch_1):\PP4134\") )
				( member ( pinPairRef "@baseboard_fab2_lib.baseboard_fab2(sch_1):\PP4137\") )
				( member ( pinPairRef "@baseboard_fab2_lib.baseboard_fab2(sch_1):\PP4140\") )
				( member ( pinPairRef "@baseboard_fab2_lib.baseboard_fab2(sch_1):\PP4143\") )
				( member ( pinPairRef "@baseboard_fab2_lib.baseboard_fab2(sch_1):\PP4146\") )
				( member ( pinPairRef "@baseboard_fab2_lib.baseboard_fab2(sch_1):\PP4149\") )
				( member ( pinPairRef "@baseboard_fab2_lib.baseboard_fab2(sch_1):\PP4152\") )
				( member ( pinPairRef "@baseboard_fab2_lib.baseboard_fab2(sch_1):\PP1021\") )
				( member ( pinPairRef "@baseboard_fab2_lib.baseboard_fab2(sch_1):\PP1015\") )
				( member ( pinPairRef "@baseboard_fab2_lib.baseboard_fab2(sch_1):\PP1024\") )
				( member ( pinPairRef "@baseboard_fab2_lib.baseboard_fab2(sch_1):\PP1018\") )
				( objectStatus "MG_DQ-DQS_FAR_DIMM_NG_M_F_BYTE5" )
			)
			( matchGroup "@baseboard_fab2_lib.baseboard_fab2(sch_1):\MG_DQ_FAR_DIMM_NG_M_F_BYTE5\"
				( memberType ( signal ) )
				( member ( pinPairRef "@baseboard_fab2_lib.baseboard_fab2(sch_1):\PP4131\") )
				( member ( pinPairRef "@baseboard_fab2_lib.baseboard_fab2(sch_1):\PP4134\") )
				( member ( pinPairRef "@baseboard_fab2_lib.baseboard_fab2(sch_1):\PP4137\") )
				( member ( pinPairRef "@baseboard_fab2_lib.baseboard_fab2(sch_1):\PP4140\") )
				( member ( pinPairRef "@baseboard_fab2_lib.baseboard_fab2(sch_1):\PP4143\") )
				( member ( pinPairRef "@baseboard_fab2_lib.baseboard_fab2(sch_1):\PP4146\") )
				( member ( pinPairRef "@baseboard_fab2_lib.baseboard_fab2(sch_1):\PP4149\") )
				( member ( pinPairRef "@baseboard_fab2_lib.baseboard_fab2(sch_1):\PP4152\") )
				( objectStatus "MG_DQ_FAR_DIMM_NG_M_F_BYTE5" )
			)
			( matchGroup "@baseboard_fab2_lib.baseboard_fab2(sch_1):\MG_DQ-DQS_NEAR_DIMM_NG_M_F_BYTE5\"
				( memberType ( signal ) )
				( member ( pinPairRef "@baseboard_fab2_lib.baseboard_fab2(sch_1):\PP4133\") )
				( member ( pinPairRef "@baseboard_fab2_lib.baseboard_fab2(sch_1):\PP4136\") )
				( member ( pinPairRef "@baseboard_fab2_lib.baseboard_fab2(sch_1):\PP4139\") )
				( member ( pinPairRef "@baseboard_fab2_lib.baseboard_fab2(sch_1):\PP4142\") )
				( member ( pinPairRef "@baseboard_fab2_lib.baseboard_fab2(sch_1):\PP4145\") )
				( member ( pinPairRef "@baseboard_fab2_lib.baseboard_fab2(sch_1):\PP4148\") )
				( member ( pinPairRef "@baseboard_fab2_lib.baseboard_fab2(sch_1):\PP4151\") )
				( member ( pinPairRef "@baseboard_fab2_lib.baseboard_fab2(sch_1):\PP4154\") )
				( member ( pinPairRef "@baseboard_fab2_lib.baseboard_fab2(sch_1):\PP1023\") )
				( member ( pinPairRef "@baseboard_fab2_lib.baseboard_fab2(sch_1):\PP1017\") )
				( member ( pinPairRef "@baseboard_fab2_lib.baseboard_fab2(sch_1):\PP1026\") )
				( member ( pinPairRef "@baseboard_fab2_lib.baseboard_fab2(sch_1):\PP1020\") )
				( objectStatus "MG_DQ-DQS_NEAR_DIMM_NG_M_F_BYTE5" )
			)
			( matchGroup "@crescent_city_bb_fab1_lib.crescent_city_bb_fab1(sch_1):\MG_DQ_NEAR_DIMM_NG_M_F_BYTE5\"
				( memberType ( signal ) )
				( member ( pinPairRef "@baseboard_fab2_lib.baseboard_fab2(sch_1):\PP4133\") )
				( member ( pinPairRef "@baseboard_fab2_lib.baseboard_fab2(sch_1):\PP4136\") )
				( member ( pinPairRef "@baseboard_fab2_lib.baseboard_fab2(sch_1):\PP4139\") )
				( member ( pinPairRef "@baseboard_fab2_lib.baseboard_fab2(sch_1):\PP4142\") )
				( member ( pinPairRef "@baseboard_fab2_lib.baseboard_fab2(sch_1):\PP4145\") )
				( member ( pinPairRef "@baseboard_fab2_lib.baseboard_fab2(sch_1):\PP4148\") )
				( member ( pinPairRef "@baseboard_fab2_lib.baseboard_fab2(sch_1):\PP4151\") )
				( member ( pinPairRef "@baseboard_fab2_lib.baseboard_fab2(sch_1):\PP4154\") )
				( objectStatus "MG_DQ_NEAR_DIMM_NG_M_F_BYTE5" )
			)
			( matchGroup "@baseboard_fab2_lib.baseboard_fab2(sch_1):\MG_DQ-DQS_FAR_DIMM_NG_M_F_BYTE6\"
				( memberType ( signal ) )
				( member ( pinPairRef "@baseboard_fab2_lib.baseboard_fab2(sch_1):\PP4107\") )
				( member ( pinPairRef "@baseboard_fab2_lib.baseboard_fab2(sch_1):\PP4110\") )
				( member ( pinPairRef "@baseboard_fab2_lib.baseboard_fab2(sch_1):\PP4113\") )
				( member ( pinPairRef "@baseboard_fab2_lib.baseboard_fab2(sch_1):\PP4116\") )
				( member ( pinPairRef "@baseboard_fab2_lib.baseboard_fab2(sch_1):\PP4119\") )
				( member ( pinPairRef "@baseboard_fab2_lib.baseboard_fab2(sch_1):\PP4122\") )
				( member ( pinPairRef "@baseboard_fab2_lib.baseboard_fab2(sch_1):\PP4125\") )
				( member ( pinPairRef "@baseboard_fab2_lib.baseboard_fab2(sch_1):\PP4128\") )
				( member ( pinPairRef "@baseboard_fab2_lib.baseboard_fab2(sch_1):\PP1009\") )
				( member ( pinPairRef "@baseboard_fab2_lib.baseboard_fab2(sch_1):\PP1003\") )
				( member ( pinPairRef "@baseboard_fab2_lib.baseboard_fab2(sch_1):\PP1012\") )
				( member ( pinPairRef "@baseboard_fab2_lib.baseboard_fab2(sch_1):\PP1006\") )
				( objectStatus "MG_DQ-DQS_FAR_DIMM_NG_M_F_BYTE6" )
			)
			( matchGroup "@baseboard_fab2_lib.baseboard_fab2(sch_1):\MG_DQ_FAR_DIMM_NG_M_F_BYTE6\"
				( memberType ( signal ) )
				( member ( pinPairRef "@baseboard_fab2_lib.baseboard_fab2(sch_1):\PP4107\") )
				( member ( pinPairRef "@baseboard_fab2_lib.baseboard_fab2(sch_1):\PP4110\") )
				( member ( pinPairRef "@baseboard_fab2_lib.baseboard_fab2(sch_1):\PP4113\") )
				( member ( pinPairRef "@baseboard_fab2_lib.baseboard_fab2(sch_1):\PP4116\") )
				( member ( pinPairRef "@baseboard_fab2_lib.baseboard_fab2(sch_1):\PP4119\") )
				( member ( pinPairRef "@baseboard_fab2_lib.baseboard_fab2(sch_1):\PP4122\") )
				( member ( pinPairRef "@baseboard_fab2_lib.baseboard_fab2(sch_1):\PP4125\") )
				( member ( pinPairRef "@baseboard_fab2_lib.baseboard_fab2(sch_1):\PP4128\") )
				( objectStatus "MG_DQ_FAR_DIMM_NG_M_F_BYTE6" )
			)
			( matchGroup "@baseboard_fab2_lib.baseboard_fab2(sch_1):\MG_DQ-DQS_NEAR_DIMM_NG_M_F_BYTE6\"
				( memberType ( signal ) )
				( member ( pinPairRef "@baseboard_fab2_lib.baseboard_fab2(sch_1):\PP4109\") )
				( member ( pinPairRef "@baseboard_fab2_lib.baseboard_fab2(sch_1):\PP4112\") )
				( member ( pinPairRef "@baseboard_fab2_lib.baseboard_fab2(sch_1):\PP4115\") )
				( member ( pinPairRef "@baseboard_fab2_lib.baseboard_fab2(sch_1):\PP4118\") )
				( member ( pinPairRef "@baseboard_fab2_lib.baseboard_fab2(sch_1):\PP4121\") )
				( member ( pinPairRef "@baseboard_fab2_lib.baseboard_fab2(sch_1):\PP4124\") )
				( member ( pinPairRef "@baseboard_fab2_lib.baseboard_fab2(sch_1):\PP4127\") )
				( member ( pinPairRef "@baseboard_fab2_lib.baseboard_fab2(sch_1):\PP4130\") )
				( member ( pinPairRef "@baseboard_fab2_lib.baseboard_fab2(sch_1):\PP1011\") )
				( member ( pinPairRef "@baseboard_fab2_lib.baseboard_fab2(sch_1):\PP1005\") )
				( member ( pinPairRef "@baseboard_fab2_lib.baseboard_fab2(sch_1):\PP1014\") )
				( member ( pinPairRef "@baseboard_fab2_lib.baseboard_fab2(sch_1):\PP1008\") )
				( objectStatus "MG_DQ-DQS_NEAR_DIMM_NG_M_F_BYTE6" )
			)
			( matchGroup "@crescent_city_bb_fab1_lib.crescent_city_bb_fab1(sch_1):\MG_DQ_NEAR_DIMM_NG_M_F_BYTE6\"
				( memberType ( signal ) )
				( member ( pinPairRef "@baseboard_fab2_lib.baseboard_fab2(sch_1):\PP4109\") )
				( member ( pinPairRef "@baseboard_fab2_lib.baseboard_fab2(sch_1):\PP4112\") )
				( member ( pinPairRef "@baseboard_fab2_lib.baseboard_fab2(sch_1):\PP4115\") )
				( member ( pinPairRef "@baseboard_fab2_lib.baseboard_fab2(sch_1):\PP4118\") )
				( member ( pinPairRef "@baseboard_fab2_lib.baseboard_fab2(sch_1):\PP4121\") )
				( member ( pinPairRef "@baseboard_fab2_lib.baseboard_fab2(sch_1):\PP4124\") )
				( member ( pinPairRef "@baseboard_fab2_lib.baseboard_fab2(sch_1):\PP4127\") )
				( member ( pinPairRef "@baseboard_fab2_lib.baseboard_fab2(sch_1):\PP4130\") )
				( objectStatus "MG_DQ_NEAR_DIMM_NG_M_F_BYTE6" )
			)
			( matchGroup "@baseboard_fab2_lib.baseboard_fab2(sch_1):\MG_DQ-DQS_FAR_DIMM_NG_M_F_BYTE7\"
				( memberType ( signal ) )
				( member ( pinPairRef "@baseboard_fab2_lib.baseboard_fab2(sch_1):\PP4083\") )
				( member ( pinPairRef "@baseboard_fab2_lib.baseboard_fab2(sch_1):\PP4086\") )
				( member ( pinPairRef "@baseboard_fab2_lib.baseboard_fab2(sch_1):\PP4089\") )
				( member ( pinPairRef "@baseboard_fab2_lib.baseboard_fab2(sch_1):\PP4092\") )
				( member ( pinPairRef "@baseboard_fab2_lib.baseboard_fab2(sch_1):\PP4095\") )
				( member ( pinPairRef "@baseboard_fab2_lib.baseboard_fab2(sch_1):\PP4098\") )
				( member ( pinPairRef "@baseboard_fab2_lib.baseboard_fab2(sch_1):\PP4101\") )
				( member ( pinPairRef "@baseboard_fab2_lib.baseboard_fab2(sch_1):\PP4104\") )
				( member ( pinPairRef "@baseboard_fab2_lib.baseboard_fab2(sch_1):\PP997\") )
				( member ( pinPairRef "@baseboard_fab2_lib.baseboard_fab2(sch_1):\PP991\") )
				( member ( pinPairRef "@baseboard_fab2_lib.baseboard_fab2(sch_1):\PP1000\") )
				( member ( pinPairRef "@baseboard_fab2_lib.baseboard_fab2(sch_1):\PP994\") )
				( objectStatus "MG_DQ-DQS_FAR_DIMM_NG_M_F_BYTE7" )
			)
			( matchGroup "@crescent_city_bb_fab1_lib.crescent_city_bb_fab1(sch_1):\MG_DQ_FAR_DIMM_NG_M_F_BYTE7\"
				( memberType ( signal ) )
				( member ( pinPairRef "@baseboard_fab2_lib.baseboard_fab2(sch_1):\PP4083\") )
				( member ( pinPairRef "@baseboard_fab2_lib.baseboard_fab2(sch_1):\PP4086\") )
				( member ( pinPairRef "@baseboard_fab2_lib.baseboard_fab2(sch_1):\PP4089\") )
				( member ( pinPairRef "@baseboard_fab2_lib.baseboard_fab2(sch_1):\PP4092\") )
				( member ( pinPairRef "@baseboard_fab2_lib.baseboard_fab2(sch_1):\PP4095\") )
				( member ( pinPairRef "@baseboard_fab2_lib.baseboard_fab2(sch_1):\PP4098\") )
				( member ( pinPairRef "@baseboard_fab2_lib.baseboard_fab2(sch_1):\PP4101\") )
				( member ( pinPairRef "@baseboard_fab2_lib.baseboard_fab2(sch_1):\PP4104\") )
				( objectStatus "MG_DQ_FAR_DIMM_NG_M_F_BYTE7" )
			)
			( matchGroup "@baseboard_fab2_lib.baseboard_fab2(sch_1):\MG_DQ-DQS_NEAR_DIMM_NG_M_F_BYTE7\"
				( memberType ( signal ) )
				( member ( pinPairRef "@baseboard_fab2_lib.baseboard_fab2(sch_1):\PP4085\") )
				( member ( pinPairRef "@baseboard_fab2_lib.baseboard_fab2(sch_1):\PP4088\") )
				( member ( pinPairRef "@baseboard_fab2_lib.baseboard_fab2(sch_1):\PP4091\") )
				( member ( pinPairRef "@baseboard_fab2_lib.baseboard_fab2(sch_1):\PP4094\") )
				( member ( pinPairRef "@baseboard_fab2_lib.baseboard_fab2(sch_1):\PP4097\") )
				( member ( pinPairRef "@baseboard_fab2_lib.baseboard_fab2(sch_1):\PP4100\") )
				( member ( pinPairRef "@baseboard_fab2_lib.baseboard_fab2(sch_1):\PP4103\") )
				( member ( pinPairRef "@baseboard_fab2_lib.baseboard_fab2(sch_1):\PP4106\") )
				( member ( pinPairRef "@baseboard_fab2_lib.baseboard_fab2(sch_1):\PP999\") )
				( member ( pinPairRef "@baseboard_fab2_lib.baseboard_fab2(sch_1):\PP993\") )
				( member ( pinPairRef "@baseboard_fab2_lib.baseboard_fab2(sch_1):\PP1002\") )
				( member ( pinPairRef "@baseboard_fab2_lib.baseboard_fab2(sch_1):\PP996\") )
				( objectStatus "MG_DQ-DQS_NEAR_DIMM_NG_M_F_BYTE7" )
			)
			( matchGroup "@crescent_city_bb_fab1_lib.crescent_city_bb_fab1(sch_1):\MG_DQ_NEAR_DIMM_NG_M_F_BYTE7\"
				( memberType ( signal ) )
				( member ( pinPairRef "@baseboard_fab2_lib.baseboard_fab2(sch_1):\PP4085\") )
				( member ( pinPairRef "@baseboard_fab2_lib.baseboard_fab2(sch_1):\PP4088\") )
				( member ( pinPairRef "@baseboard_fab2_lib.baseboard_fab2(sch_1):\PP4091\") )
				( member ( pinPairRef "@baseboard_fab2_lib.baseboard_fab2(sch_1):\PP4094\") )
				( member ( pinPairRef "@baseboard_fab2_lib.baseboard_fab2(sch_1):\PP4097\") )
				( member ( pinPairRef "@baseboard_fab2_lib.baseboard_fab2(sch_1):\PP4100\") )
				( member ( pinPairRef "@baseboard_fab2_lib.baseboard_fab2(sch_1):\PP4103\") )
				( member ( pinPairRef "@baseboard_fab2_lib.baseboard_fab2(sch_1):\PP4106\") )
				( objectStatus "MG_DQ_NEAR_DIMM_NG_M_F_BYTE7" )
			)
			( matchGroup "@baseboard_fab2_lib.baseboard_fab2(sch_1):\MG_DQ-DQS_FAR_DIMM_NG_M_G_BYTE1\"
				( memberType ( signal ) )
				( member ( pinPairRef "@baseboard_fab2_lib.baseboard_fab2(sch_1):\PP2905\") )
				( member ( pinPairRef "@baseboard_fab2_lib.baseboard_fab2(sch_1):\PP2899\") )
				( member ( pinPairRef "@baseboard_fab2_lib.baseboard_fab2(sch_1):\PP2902\") )
				( member ( pinPairRef "@baseboard_fab2_lib.baseboard_fab2(sch_1):\PP2908\") )
				( member ( pinPairRef "@baseboard_fab2_lib.baseboard_fab2(sch_1):\PP2911\") )
				( member ( pinPairRef "@baseboard_fab2_lib.baseboard_fab2(sch_1):\PP2914\") )
				( member ( pinPairRef "@baseboard_fab2_lib.baseboard_fab2(sch_1):\PP2917\") )
				( member ( pinPairRef "@baseboard_fab2_lib.baseboard_fab2(sch_1):\PP2920\") )
				( member ( pinPairRef "@baseboard_fab2_lib.baseboard_fab2(sch_1):\PP961\") )
				( member ( pinPairRef "@baseboard_fab2_lib.baseboard_fab2(sch_1):\PP964\") )
				( member ( pinPairRef "@baseboard_fab2_lib.baseboard_fab2(sch_1):\PP955\") )
				( member ( pinPairRef "@baseboard_fab2_lib.baseboard_fab2(sch_1):\PP958\") )
				( objectStatus "MG_DQ-DQS_FAR_DIMM_NG_M_G_BYTE1" )
			)
			( matchGroup "@baseboard_fab2_lib.baseboard_fab2(sch_1):\MG_DQ_FAR_DIMM_NG_M_G_BYTE1\"
				( memberType ( signal ) )
				( member ( pinPairRef "@baseboard_fab2_lib.baseboard_fab2(sch_1):\PP2905\") )
				( member ( pinPairRef "@baseboard_fab2_lib.baseboard_fab2(sch_1):\PP2899\") )
				( member ( pinPairRef "@baseboard_fab2_lib.baseboard_fab2(sch_1):\PP2902\") )
				( member ( pinPairRef "@baseboard_fab2_lib.baseboard_fab2(sch_1):\PP2908\") )
				( member ( pinPairRef "@baseboard_fab2_lib.baseboard_fab2(sch_1):\PP2911\") )
				( member ( pinPairRef "@baseboard_fab2_lib.baseboard_fab2(sch_1):\PP2914\") )
				( member ( pinPairRef "@baseboard_fab2_lib.baseboard_fab2(sch_1):\PP2917\") )
				( member ( pinPairRef "@baseboard_fab2_lib.baseboard_fab2(sch_1):\PP2920\") )
				( objectStatus "MG_DQ_FAR_DIMM_NG_M_G_BYTE1" )
			)
			( matchGroup "@baseboard_fab2_lib.baseboard_fab2(sch_1):\MG_DQ-DQS_NEAR_DIMM_NG_M_G_BYTE1\"
				( memberType ( signal ) )
				( member ( pinPairRef "@baseboard_fab2_lib.baseboard_fab2(sch_1):\PP2907\") )
				( member ( pinPairRef "@baseboard_fab2_lib.baseboard_fab2(sch_1):\PP2900\") )
				( member ( pinPairRef "@baseboard_fab2_lib.baseboard_fab2(sch_1):\PP2903\") )
				( member ( pinPairRef "@baseboard_fab2_lib.baseboard_fab2(sch_1):\PP2909\") )
				( member ( pinPairRef "@baseboard_fab2_lib.baseboard_fab2(sch_1):\PP2912\") )
				( member ( pinPairRef "@baseboard_fab2_lib.baseboard_fab2(sch_1):\PP2915\") )
				( member ( pinPairRef "@baseboard_fab2_lib.baseboard_fab2(sch_1):\PP2918\") )
				( member ( pinPairRef "@baseboard_fab2_lib.baseboard_fab2(sch_1):\PP2921\") )
				( member ( pinPairRef "@baseboard_fab2_lib.baseboard_fab2(sch_1):\PP962\") )
				( member ( pinPairRef "@baseboard_fab2_lib.baseboard_fab2(sch_1):\PP965\") )
				( member ( pinPairRef "@baseboard_fab2_lib.baseboard_fab2(sch_1):\PP956\") )
				( member ( pinPairRef "@baseboard_fab2_lib.baseboard_fab2(sch_1):\PP959\") )
				( objectStatus "MG_DQ-DQS_NEAR_DIMM_NG_M_G_BYTE1" )
			)
			( matchGroup "@baseboard_fab2_lib.baseboard_fab2(sch_1):\MG_DQ_NEAR_DIMM_NG_M_G_BYTE1\"
				( memberType ( signal ) )
				( member ( pinPairRef "@baseboard_fab2_lib.baseboard_fab2(sch_1):\PP2907\") )
				( member ( pinPairRef "@baseboard_fab2_lib.baseboard_fab2(sch_1):\PP2900\") )
				( member ( pinPairRef "@baseboard_fab2_lib.baseboard_fab2(sch_1):\PP2903\") )
				( member ( pinPairRef "@baseboard_fab2_lib.baseboard_fab2(sch_1):\PP2909\") )
				( member ( pinPairRef "@baseboard_fab2_lib.baseboard_fab2(sch_1):\PP2912\") )
				( member ( pinPairRef "@baseboard_fab2_lib.baseboard_fab2(sch_1):\PP2915\") )
				( member ( pinPairRef "@baseboard_fab2_lib.baseboard_fab2(sch_1):\PP2918\") )
				( member ( pinPairRef "@baseboard_fab2_lib.baseboard_fab2(sch_1):\PP2921\") )
				( objectStatus "MG_DQ_NEAR_DIMM_NG_M_G_BYTE1" )
			)
			( matchGroup "@baseboard_fab2_lib.baseboard_fab2(sch_1):\MG_DQ-DQS_FAR_DIMM_NG_M_H_BYTE1\"
				( memberType ( signal ) )
				( member ( pinPairRef "@baseboard_fab2_lib.baseboard_fab2(sch_1):\PP2698\") )
				( member ( pinPairRef "@baseboard_fab2_lib.baseboard_fab2(sch_1):\PP2701\") )
				( member ( pinPairRef "@baseboard_fab2_lib.baseboard_fab2(sch_1):\PP2704\") )
				( member ( pinPairRef "@baseboard_fab2_lib.baseboard_fab2(sch_1):\PP2683\") )
				( member ( pinPairRef "@baseboard_fab2_lib.baseboard_fab2(sch_1):\PP2686\") )
				( member ( pinPairRef "@baseboard_fab2_lib.baseboard_fab2(sch_1):\PP2689\") )
				( member ( pinPairRef "@baseboard_fab2_lib.baseboard_fab2(sch_1):\PP2692\") )
				( member ( pinPairRef "@baseboard_fab2_lib.baseboard_fab2(sch_1):\PP2695\") )
				( member ( pinPairRef "@baseboard_fab2_lib.baseboard_fab2(sch_1):\PP847\") )
				( member ( pinPairRef "@baseboard_fab2_lib.baseboard_fab2(sch_1):\PP850\") )
				( member ( pinPairRef "@baseboard_fab2_lib.baseboard_fab2(sch_1):\PP853\") )
				( member ( pinPairRef "@baseboard_fab2_lib.baseboard_fab2(sch_1):\PP856\") )
				( objectStatus "MG_DQ-DQS_FAR_DIMM_NG_M_H_BYTE1" )
			)
			( matchGroup "@baseboard_fab2_lib.baseboard_fab2(sch_1):\MG_DQ_FAR_DIMM_NG_M_H_BYTE1\"
				( memberType ( signal ) )
				( member ( pinPairRef "@baseboard_fab2_lib.baseboard_fab2(sch_1):\PP2698\") )
				( member ( pinPairRef "@baseboard_fab2_lib.baseboard_fab2(sch_1):\PP2701\") )
				( member ( pinPairRef "@baseboard_fab2_lib.baseboard_fab2(sch_1):\PP2704\") )
				( member ( pinPairRef "@baseboard_fab2_lib.baseboard_fab2(sch_1):\PP2683\") )
				( member ( pinPairRef "@baseboard_fab2_lib.baseboard_fab2(sch_1):\PP2686\") )
				( member ( pinPairRef "@baseboard_fab2_lib.baseboard_fab2(sch_1):\PP2689\") )
				( member ( pinPairRef "@baseboard_fab2_lib.baseboard_fab2(sch_1):\PP2692\") )
				( member ( pinPairRef "@baseboard_fab2_lib.baseboard_fab2(sch_1):\PP2695\") )
				( objectStatus "MG_DQ_FAR_DIMM_NG_M_H_BYTE1" )
			)
			( matchGroup "@baseboard_fab2_lib.baseboard_fab2(sch_1):\MG_DQ-DQS_NEAR_DIMM_NG_M_H_BYTE1\"
				( memberType ( signal ) )
				( member ( pinPairRef "@baseboard_fab2_lib.baseboard_fab2(sch_1):\PP2700\") )
				( member ( pinPairRef "@baseboard_fab2_lib.baseboard_fab2(sch_1):\PP2703\") )
				( member ( pinPairRef "@baseboard_fab2_lib.baseboard_fab2(sch_1):\PP2706\") )
				( member ( pinPairRef "@baseboard_fab2_lib.baseboard_fab2(sch_1):\PP2684\") )
				( member ( pinPairRef "@baseboard_fab2_lib.baseboard_fab2(sch_1):\PP2687\") )
				( member ( pinPairRef "@baseboard_fab2_lib.baseboard_fab2(sch_1):\PP2690\") )
				( member ( pinPairRef "@baseboard_fab2_lib.baseboard_fab2(sch_1):\PP2693\") )
				( member ( pinPairRef "@baseboard_fab2_lib.baseboard_fab2(sch_1):\PP2696\") )
				( member ( pinPairRef "@baseboard_fab2_lib.baseboard_fab2(sch_1):\PP848\") )
				( member ( pinPairRef "@baseboard_fab2_lib.baseboard_fab2(sch_1):\PP851\") )
				( member ( pinPairRef "@baseboard_fab2_lib.baseboard_fab2(sch_1):\PP854\") )
				( member ( pinPairRef "@baseboard_fab2_lib.baseboard_fab2(sch_1):\PP857\") )
				( objectStatus "MG_DQ-DQS_NEAR_DIMM_NG_M_H_BYTE1" )
			)
			( matchGroup "@baseboard_fab2_lib.baseboard_fab2(sch_1):\MG_DQ_NEAR_DIMM_NG_M_H_BYTE1\"
				( memberType ( signal ) )
				( member ( pinPairRef "@baseboard_fab2_lib.baseboard_fab2(sch_1):\PP2700\") )
				( member ( pinPairRef "@baseboard_fab2_lib.baseboard_fab2(sch_1):\PP2703\") )
				( member ( pinPairRef "@baseboard_fab2_lib.baseboard_fab2(sch_1):\PP2706\") )
				( member ( pinPairRef "@baseboard_fab2_lib.baseboard_fab2(sch_1):\PP2684\") )
				( member ( pinPairRef "@baseboard_fab2_lib.baseboard_fab2(sch_1):\PP2687\") )
				( member ( pinPairRef "@baseboard_fab2_lib.baseboard_fab2(sch_1):\PP2690\") )
				( member ( pinPairRef "@baseboard_fab2_lib.baseboard_fab2(sch_1):\PP2693\") )
				( member ( pinPairRef "@baseboard_fab2_lib.baseboard_fab2(sch_1):\PP2696\") )
				( objectStatus "MG_DQ_NEAR_DIMM_NG_M_H_BYTE1" )
			)
			( matchGroup "@baseboard_fab2_lib.baseboard_fab2(sch_1):\MG_DQ-DQS_FAR_DIMM_NG_M_H_BYTE2\"
				( memberType ( signal ) )
				( member ( pinPairRef "@baseboard_fab2_lib.baseboard_fab2(sch_1):\PP2659\") )
				( member ( pinPairRef "@baseboard_fab2_lib.baseboard_fab2(sch_1):\PP2662\") )
				( member ( pinPairRef "@baseboard_fab2_lib.baseboard_fab2(sch_1):\PP2665\") )
				( member ( pinPairRef "@baseboard_fab2_lib.baseboard_fab2(sch_1):\PP2668\") )
				( member ( pinPairRef "@baseboard_fab2_lib.baseboard_fab2(sch_1):\PP2671\") )
				( member ( pinPairRef "@baseboard_fab2_lib.baseboard_fab2(sch_1):\PP2674\") )
				( member ( pinPairRef "@baseboard_fab2_lib.baseboard_fab2(sch_1):\PP2677\") )
				( member ( pinPairRef "@baseboard_fab2_lib.baseboard_fab2(sch_1):\PP2680\") )
				( member ( pinPairRef "@baseboard_fab2_lib.baseboard_fab2(sch_1):\PP841\") )
				( member ( pinPairRef "@baseboard_fab2_lib.baseboard_fab2(sch_1):\PP844\") )
				( member ( pinPairRef "@baseboard_fab2_lib.baseboard_fab2(sch_1):\PP835\") )
				( member ( pinPairRef "@baseboard_fab2_lib.baseboard_fab2(sch_1):\PP838\") )
				( objectStatus "MG_DQ-DQS_FAR_DIMM_NG_M_H_BYTE2" )
			)
			( matchGroup "@baseboard_fab2_lib.baseboard_fab2(sch_1):\MG_DQ_FAR_DIMM_NG_M_H_BYTE2\"
				( memberType ( signal ) )
				( member ( pinPairRef "@baseboard_fab2_lib.baseboard_fab2(sch_1):\PP2659\") )
				( member ( pinPairRef "@baseboard_fab2_lib.baseboard_fab2(sch_1):\PP2662\") )
				( member ( pinPairRef "@baseboard_fab2_lib.baseboard_fab2(sch_1):\PP2665\") )
				( member ( pinPairRef "@baseboard_fab2_lib.baseboard_fab2(sch_1):\PP2668\") )
				( member ( pinPairRef "@baseboard_fab2_lib.baseboard_fab2(sch_1):\PP2671\") )
				( member ( pinPairRef "@baseboard_fab2_lib.baseboard_fab2(sch_1):\PP2674\") )
				( member ( pinPairRef "@baseboard_fab2_lib.baseboard_fab2(sch_1):\PP2677\") )
				( member ( pinPairRef "@baseboard_fab2_lib.baseboard_fab2(sch_1):\PP2680\") )
				( objectStatus "MG_DQ_FAR_DIMM_NG_M_H_BYTE2" )
			)
			( matchGroup "@baseboard_fab2_lib.baseboard_fab2(sch_1):\MG_DQ-DQS_NEAR_DIMM_NG_M_H_BYTE2\"
				( memberType ( signal ) )
				( member ( pinPairRef "@baseboard_fab2_lib.baseboard_fab2(sch_1):\PP2661\") )
				( member ( pinPairRef "@baseboard_fab2_lib.baseboard_fab2(sch_1):\PP2663\") )
				( member ( pinPairRef "@baseboard_fab2_lib.baseboard_fab2(sch_1):\PP2666\") )
				( member ( pinPairRef "@baseboard_fab2_lib.baseboard_fab2(sch_1):\PP2669\") )
				( member ( pinPairRef "@baseboard_fab2_lib.baseboard_fab2(sch_1):\PP2672\") )
				( member ( pinPairRef "@baseboard_fab2_lib.baseboard_fab2(sch_1):\PP2675\") )
				( member ( pinPairRef "@baseboard_fab2_lib.baseboard_fab2(sch_1):\PP2678\") )
				( member ( pinPairRef "@baseboard_fab2_lib.baseboard_fab2(sch_1):\PP2681\") )
				( member ( pinPairRef "@baseboard_fab2_lib.baseboard_fab2(sch_1):\PP842\") )
				( member ( pinPairRef "@baseboard_fab2_lib.baseboard_fab2(sch_1):\PP845\") )
				( member ( pinPairRef "@baseboard_fab2_lib.baseboard_fab2(sch_1):\PP836\") )
				( member ( pinPairRef "@baseboard_fab2_lib.baseboard_fab2(sch_1):\PP839\") )
				( objectStatus "MG_DQ-DQS_NEAR_DIMM_NG_M_H_BYTE2" )
			)
			( matchGroup "@baseboard_fab2_lib.baseboard_fab2(sch_1):\MG_DQ_NEAR_DIMM_NG_M_H_BYTE2\"
				( memberType ( signal ) )
				( member ( pinPairRef "@baseboard_fab2_lib.baseboard_fab2(sch_1):\PP2661\") )
				( member ( pinPairRef "@baseboard_fab2_lib.baseboard_fab2(sch_1):\PP2663\") )
				( member ( pinPairRef "@baseboard_fab2_lib.baseboard_fab2(sch_1):\PP2666\") )
				( member ( pinPairRef "@baseboard_fab2_lib.baseboard_fab2(sch_1):\PP2669\") )
				( member ( pinPairRef "@baseboard_fab2_lib.baseboard_fab2(sch_1):\PP2672\") )
				( member ( pinPairRef "@baseboard_fab2_lib.baseboard_fab2(sch_1):\PP2675\") )
				( member ( pinPairRef "@baseboard_fab2_lib.baseboard_fab2(sch_1):\PP2678\") )
				( member ( pinPairRef "@baseboard_fab2_lib.baseboard_fab2(sch_1):\PP2681\") )
				( objectStatus "MG_DQ_NEAR_DIMM_NG_M_H_BYTE2" )
			)
			( matchGroup "@baseboard_fab2_lib.baseboard_fab2(sch_1):\MG_DQ-DQS_FAR_DIMM_NG_M_A_BYTE-ECC\"
				( memberType ( signal ) )
				( member ( pinPairRef "@baseboard_fab2_lib.baseboard_fab2(sch_1):\PP5139\") )
				( member ( pinPairRef "@baseboard_fab2_lib.baseboard_fab2(sch_1):\PP5142\") )
				( member ( pinPairRef "@baseboard_fab2_lib.baseboard_fab2(sch_1):\PP5145\") )
				( member ( pinPairRef "@baseboard_fab2_lib.baseboard_fab2(sch_1):\PP5148\") )
				( member ( pinPairRef "@baseboard_fab2_lib.baseboard_fab2(sch_1):\PP5151\") )
				( member ( pinPairRef "@baseboard_fab2_lib.baseboard_fab2(sch_1):\PP5154\") )
				( member ( pinPairRef "@baseboard_fab2_lib.baseboard_fab2(sch_1):\PP5157\") )
				( member ( pinPairRef "@baseboard_fab2_lib.baseboard_fab2(sch_1):\PP5160\") )
				( member ( pinPairRef "@baseboard_fab2_lib.baseboard_fab2(sch_1):\PP1237\") )
				( member ( pinPairRef "@baseboard_fab2_lib.baseboard_fab2(sch_1):\PP1231\") )
				( member ( pinPairRef "@baseboard_fab2_lib.baseboard_fab2(sch_1):\PP1240\") )
				( member ( pinPairRef "@baseboard_fab2_lib.baseboard_fab2(sch_1):\PP1234\") )
				( objectStatus "MG_DQ-DQS_FAR_DIMM_NG_M_A_BYTE-ECC" )
			)
			( matchGroup "@crescent_city_bb_fab1_lib.crescent_city_bb_fab1(sch_1):\MG_DQ_FAR_DIMM_NG_M_A_BYTE-ECC\"
				( memberType ( signal ) )
				( member ( pinPairRef "@baseboard_fab2_lib.baseboard_fab2(sch_1):\PP5139\") )
				( member ( pinPairRef "@baseboard_fab2_lib.baseboard_fab2(sch_1):\PP5142\") )
				( member ( pinPairRef "@baseboard_fab2_lib.baseboard_fab2(sch_1):\PP5145\") )
				( member ( pinPairRef "@baseboard_fab2_lib.baseboard_fab2(sch_1):\PP5148\") )
				( member ( pinPairRef "@baseboard_fab2_lib.baseboard_fab2(sch_1):\PP5151\") )
				( member ( pinPairRef "@baseboard_fab2_lib.baseboard_fab2(sch_1):\PP5154\") )
				( member ( pinPairRef "@baseboard_fab2_lib.baseboard_fab2(sch_1):\PP5157\") )
				( member ( pinPairRef "@baseboard_fab2_lib.baseboard_fab2(sch_1):\PP5160\") )
				( objectStatus "MG_DQ_FAR_DIMM_NG_M_A_BYTE-ECC" )
			)
			( matchGroup "@baseboard_fab2_lib.baseboard_fab2(sch_1):\MG_DQ-DQS_NEAR_DIMM_NG_M_A_BYTE-ECC\"
				( memberType ( signal ) )
				( member ( pinPairRef "@baseboard_fab2_lib.baseboard_fab2(sch_1):\PP5141\") )
				( member ( pinPairRef "@baseboard_fab2_lib.baseboard_fab2(sch_1):\PP5144\") )
				( member ( pinPairRef "@baseboard_fab2_lib.baseboard_fab2(sch_1):\PP5147\") )
				( member ( pinPairRef "@baseboard_fab2_lib.baseboard_fab2(sch_1):\PP5150\") )
				( member ( pinPairRef "@baseboard_fab2_lib.baseboard_fab2(sch_1):\PP5153\") )
				( member ( pinPairRef "@baseboard_fab2_lib.baseboard_fab2(sch_1):\PP5156\") )
				( member ( pinPairRef "@baseboard_fab2_lib.baseboard_fab2(sch_1):\PP5159\") )
				( member ( pinPairRef "@baseboard_fab2_lib.baseboard_fab2(sch_1):\PP5162\") )
				( member ( pinPairRef "@baseboard_fab2_lib.baseboard_fab2(sch_1):\PP1239\") )
				( member ( pinPairRef "@baseboard_fab2_lib.baseboard_fab2(sch_1):\PP1233\") )
				( member ( pinPairRef "@baseboard_fab2_lib.baseboard_fab2(sch_1):\PP1242\") )
				( member ( pinPairRef "@baseboard_fab2_lib.baseboard_fab2(sch_1):\PP1236\") )
				( objectStatus "MG_DQ-DQS_NEAR_DIMM_NG_M_A_BYTE-ECC" )
			)
			( matchGroup "@crescent_city_bb_fab1_lib.crescent_city_bb_fab1(sch_1):\MG_DQ_NEAR_DIMM_NG_M_A_BYTE-ECC\"
				( memberType ( signal ) )
				( member ( pinPairRef "@baseboard_fab2_lib.baseboard_fab2(sch_1):\PP5141\") )
				( member ( pinPairRef "@baseboard_fab2_lib.baseboard_fab2(sch_1):\PP5144\") )
				( member ( pinPairRef "@baseboard_fab2_lib.baseboard_fab2(sch_1):\PP5147\") )
				( member ( pinPairRef "@baseboard_fab2_lib.baseboard_fab2(sch_1):\PP5150\") )
				( member ( pinPairRef "@baseboard_fab2_lib.baseboard_fab2(sch_1):\PP5153\") )
				( member ( pinPairRef "@baseboard_fab2_lib.baseboard_fab2(sch_1):\PP5156\") )
				( member ( pinPairRef "@baseboard_fab2_lib.baseboard_fab2(sch_1):\PP5159\") )
				( member ( pinPairRef "@baseboard_fab2_lib.baseboard_fab2(sch_1):\PP5162\") )
				( objectStatus "MG_DQ_NEAR_DIMM_NG_M_A_BYTE-ECC" )
			)
			( matchGroup "@baseboard_fab2_lib.baseboard_fab2(sch_1):\MG_DQ-DQS_FAR_DIMM_NG_M_B_BYTE-ECC\"
				( memberType ( signal ) )
				( member ( pinPairRef "@baseboard_fab2_lib.baseboard_fab2(sch_1):\PP5115\") )
				( member ( pinPairRef "@baseboard_fab2_lib.baseboard_fab2(sch_1):\PP5118\") )
				( member ( pinPairRef "@baseboard_fab2_lib.baseboard_fab2(sch_1):\PP5121\") )
				( member ( pinPairRef "@baseboard_fab2_lib.baseboard_fab2(sch_1):\PP5124\") )
				( member ( pinPairRef "@baseboard_fab2_lib.baseboard_fab2(sch_1):\PP5127\") )
				( member ( pinPairRef "@baseboard_fab2_lib.baseboard_fab2(sch_1):\PP5130\") )
				( member ( pinPairRef "@baseboard_fab2_lib.baseboard_fab2(sch_1):\PP5133\") )
				( member ( pinPairRef "@baseboard_fab2_lib.baseboard_fab2(sch_1):\PP5136\") )
				( member ( pinPairRef "@baseboard_fab2_lib.baseboard_fab2(sch_1):\PP1219\") )
				( member ( pinPairRef "@baseboard_fab2_lib.baseboard_fab2(sch_1):\PP1228\") )
				( member ( pinPairRef "@baseboard_fab2_lib.baseboard_fab2(sch_1):\PP1222\") )
				( member ( pinPairRef "@baseboard_fab2_lib.baseboard_fab2(sch_1):\PP1225\") )
				( objectStatus "MG_DQ-DQS_FAR_DIMM_NG_M_B_BYTE-ECC" )
			)
			( matchGroup "@crescent_city_bb_fab1_lib.crescent_city_bb_fab1(sch_1):\MG_DQ_FAR_DIMM_NG_M_B_BYTE-ECC\"
				( memberType ( signal ) )
				( member ( pinPairRef "@baseboard_fab2_lib.baseboard_fab2(sch_1):\PP5115\") )
				( member ( pinPairRef "@baseboard_fab2_lib.baseboard_fab2(sch_1):\PP5118\") )
				( member ( pinPairRef "@baseboard_fab2_lib.baseboard_fab2(sch_1):\PP5121\") )
				( member ( pinPairRef "@baseboard_fab2_lib.baseboard_fab2(sch_1):\PP5124\") )
				( member ( pinPairRef "@baseboard_fab2_lib.baseboard_fab2(sch_1):\PP5127\") )
				( member ( pinPairRef "@baseboard_fab2_lib.baseboard_fab2(sch_1):\PP5130\") )
				( member ( pinPairRef "@baseboard_fab2_lib.baseboard_fab2(sch_1):\PP5133\") )
				( member ( pinPairRef "@baseboard_fab2_lib.baseboard_fab2(sch_1):\PP5136\") )
				( objectStatus "MG_DQ_FAR_DIMM_NG_M_B_BYTE-ECC" )
			)
			( matchGroup "@baseboard_fab2_lib.baseboard_fab2(sch_1):\MG_DQ-DQS_NEAR_DIMM_NG_M_B_BYTE-ECC\"
				( memberType ( signal ) )
				( member ( pinPairRef "@baseboard_fab2_lib.baseboard_fab2(sch_1):\PP5117\") )
				( member ( pinPairRef "@baseboard_fab2_lib.baseboard_fab2(sch_1):\PP5120\") )
				( member ( pinPairRef "@baseboard_fab2_lib.baseboard_fab2(sch_1):\PP5123\") )
				( member ( pinPairRef "@baseboard_fab2_lib.baseboard_fab2(sch_1):\PP5126\") )
				( member ( pinPairRef "@baseboard_fab2_lib.baseboard_fab2(sch_1):\PP5129\") )
				( member ( pinPairRef "@baseboard_fab2_lib.baseboard_fab2(sch_1):\PP5132\") )
				( member ( pinPairRef "@baseboard_fab2_lib.baseboard_fab2(sch_1):\PP5135\") )
				( member ( pinPairRef "@baseboard_fab2_lib.baseboard_fab2(sch_1):\PP5138\") )
				( member ( pinPairRef "@baseboard_fab2_lib.baseboard_fab2(sch_1):\PP1220\") )
				( member ( pinPairRef "@baseboard_fab2_lib.baseboard_fab2(sch_1):\PP1229\") )
				( member ( pinPairRef "@baseboard_fab2_lib.baseboard_fab2(sch_1):\PP1223\") )
				( member ( pinPairRef "@baseboard_fab2_lib.baseboard_fab2(sch_1):\PP1226\") )
				( objectStatus "MG_DQ-DQS_NEAR_DIMM_NG_M_B_BYTE-ECC" )
			)
			( matchGroup "@crescent_city_bb_fab1_lib.crescent_city_bb_fab1(sch_1):\MG_DQ_NEAR_DIMM_NG_M_B_BYTE-ECC\"
				( memberType ( signal ) )
				( member ( pinPairRef "@baseboard_fab2_lib.baseboard_fab2(sch_1):\PP5117\") )
				( member ( pinPairRef "@baseboard_fab2_lib.baseboard_fab2(sch_1):\PP5120\") )
				( member ( pinPairRef "@baseboard_fab2_lib.baseboard_fab2(sch_1):\PP5123\") )
				( member ( pinPairRef "@baseboard_fab2_lib.baseboard_fab2(sch_1):\PP5126\") )
				( member ( pinPairRef "@baseboard_fab2_lib.baseboard_fab2(sch_1):\PP5129\") )
				( member ( pinPairRef "@baseboard_fab2_lib.baseboard_fab2(sch_1):\PP5132\") )
				( member ( pinPairRef "@baseboard_fab2_lib.baseboard_fab2(sch_1):\PP5135\") )
				( member ( pinPairRef "@baseboard_fab2_lib.baseboard_fab2(sch_1):\PP5138\") )
				( objectStatus "MG_DQ_NEAR_DIMM_NG_M_B_BYTE-ECC" )
			)
			( matchGroup "@baseboard_fab2_lib.baseboard_fab2(sch_1):\MG_DQ-DQS_FAR_DIMM_NG_M_C_BYTE-ECC\"
				( memberType ( signal ) )
				( member ( pinPairRef "@baseboard_fab2_lib.baseboard_fab2(sch_1):\PP4899\") )
				( member ( pinPairRef "@baseboard_fab2_lib.baseboard_fab2(sch_1):\PP4902\") )
				( member ( pinPairRef "@baseboard_fab2_lib.baseboard_fab2(sch_1):\PP4905\") )
				( member ( pinPairRef "@baseboard_fab2_lib.baseboard_fab2(sch_1):\PP4908\") )
				( member ( pinPairRef "@baseboard_fab2_lib.baseboard_fab2(sch_1):\PP4911\") )
				( member ( pinPairRef "@baseboard_fab2_lib.baseboard_fab2(sch_1):\PP4914\") )
				( member ( pinPairRef "@baseboard_fab2_lib.baseboard_fab2(sch_1):\PP4917\") )
				( member ( pinPairRef "@baseboard_fab2_lib.baseboard_fab2(sch_1):\PP4920\") )
				( member ( pinPairRef "@baseboard_fab2_lib.baseboard_fab2(sch_1):\PP1213\") )
				( member ( pinPairRef "@baseboard_fab2_lib.baseboard_fab2(sch_1):\PP1207\") )
				( member ( pinPairRef "@baseboard_fab2_lib.baseboard_fab2(sch_1):\PP1216\") )
				( member ( pinPairRef "@baseboard_fab2_lib.baseboard_fab2(sch_1):\PP1210\") )
				( objectStatus "MG_DQ-DQS_FAR_DIMM_NG_M_C_BYTE-ECC" )
			)
			( matchGroup "@baseboard_fab2_lib.baseboard_fab2(sch_1):\MG_DQ_FAR_DIMM_NG_M_C_BYTE-ECC\"
				( memberType ( signal ) )
				( member ( pinPairRef "@baseboard_fab2_lib.baseboard_fab2(sch_1):\PP4899\") )
				( member ( pinPairRef "@baseboard_fab2_lib.baseboard_fab2(sch_1):\PP4902\") )
				( member ( pinPairRef "@baseboard_fab2_lib.baseboard_fab2(sch_1):\PP4905\") )
				( member ( pinPairRef "@baseboard_fab2_lib.baseboard_fab2(sch_1):\PP4908\") )
				( member ( pinPairRef "@baseboard_fab2_lib.baseboard_fab2(sch_1):\PP4911\") )
				( member ( pinPairRef "@baseboard_fab2_lib.baseboard_fab2(sch_1):\PP4914\") )
				( member ( pinPairRef "@baseboard_fab2_lib.baseboard_fab2(sch_1):\PP4917\") )
				( member ( pinPairRef "@baseboard_fab2_lib.baseboard_fab2(sch_1):\PP4920\") )
				( objectStatus "MG_DQ_FAR_DIMM_NG_M_C_BYTE-ECC" )
			)
			( matchGroup "@baseboard_fab2_lib.baseboard_fab2(sch_1):\MG_DQ-DQS_NEAR_DIMM_NG_M_C_BYTE-ECC\"
				( memberType ( signal ) )
				( member ( pinPairRef "@baseboard_fab2_lib.baseboard_fab2(sch_1):\PP4901\") )
				( member ( pinPairRef "@baseboard_fab2_lib.baseboard_fab2(sch_1):\PP4904\") )
				( member ( pinPairRef "@baseboard_fab2_lib.baseboard_fab2(sch_1):\PP4907\") )
				( member ( pinPairRef "@baseboard_fab2_lib.baseboard_fab2(sch_1):\PP4910\") )
				( member ( pinPairRef "@baseboard_fab2_lib.baseboard_fab2(sch_1):\PP4913\") )
				( member ( pinPairRef "@baseboard_fab2_lib.baseboard_fab2(sch_1):\PP4916\") )
				( member ( pinPairRef "@baseboard_fab2_lib.baseboard_fab2(sch_1):\PP4919\") )
				( member ( pinPairRef "@baseboard_fab2_lib.baseboard_fab2(sch_1):\PP4922\") )
				( member ( pinPairRef "@baseboard_fab2_lib.baseboard_fab2(sch_1):\PP1214\") )
				( member ( pinPairRef "@baseboard_fab2_lib.baseboard_fab2(sch_1):\PP1208\") )
				( member ( pinPairRef "@baseboard_fab2_lib.baseboard_fab2(sch_1):\PP1217\") )
				( member ( pinPairRef "@baseboard_fab2_lib.baseboard_fab2(sch_1):\PP1211\") )
				( objectStatus "MG_DQ-DQS_NEAR_DIMM_NG_M_C_BYTE-ECC" )
			)
			( matchGroup "@baseboard_fab2_lib.baseboard_fab2(sch_1):\MG_DQ_NEAR_DIMM_NG_M_C_BYTE-ECC\"
				( memberType ( signal ) )
				( member ( pinPairRef "@baseboard_fab2_lib.baseboard_fab2(sch_1):\PP4901\") )
				( member ( pinPairRef "@baseboard_fab2_lib.baseboard_fab2(sch_1):\PP4904\") )
				( member ( pinPairRef "@baseboard_fab2_lib.baseboard_fab2(sch_1):\PP4907\") )
				( member ( pinPairRef "@baseboard_fab2_lib.baseboard_fab2(sch_1):\PP4910\") )
				( member ( pinPairRef "@baseboard_fab2_lib.baseboard_fab2(sch_1):\PP4913\") )
				( member ( pinPairRef "@baseboard_fab2_lib.baseboard_fab2(sch_1):\PP4916\") )
				( member ( pinPairRef "@baseboard_fab2_lib.baseboard_fab2(sch_1):\PP4919\") )
				( member ( pinPairRef "@baseboard_fab2_lib.baseboard_fab2(sch_1):\PP4922\") )
				( objectStatus "MG_DQ_NEAR_DIMM_NG_M_C_BYTE-ECC" )
			)
			( matchGroup "@baseboard_fab2_lib.baseboard_fab2(sch_1):\MG_DQ-DQS_FAR_DIMM_NG_M_D_BYTE-ECC\"
				( memberType ( signal ) )
				( member ( pinPairRef "@baseboard_fab2_lib.baseboard_fab2(sch_1):\PP4491\") )
				( member ( pinPairRef "@baseboard_fab2_lib.baseboard_fab2(sch_1):\PP4494\") )
				( member ( pinPairRef "@baseboard_fab2_lib.baseboard_fab2(sch_1):\PP4497\") )
				( member ( pinPairRef "@baseboard_fab2_lib.baseboard_fab2(sch_1):\PP4500\") )
				( member ( pinPairRef "@baseboard_fab2_lib.baseboard_fab2(sch_1):\PP4503\") )
				( member ( pinPairRef "@baseboard_fab2_lib.baseboard_fab2(sch_1):\PP4506\") )
				( member ( pinPairRef "@baseboard_fab2_lib.baseboard_fab2(sch_1):\PP4509\") )
				( member ( pinPairRef "@baseboard_fab2_lib.baseboard_fab2(sch_1):\PP4512\") )
				( member ( pinPairRef "@baseboard_fab2_lib.baseboard_fab2(sch_1):\PP1204\") )
				( member ( pinPairRef "@baseboard_fab2_lib.baseboard_fab2(sch_1):\PP1198\") )
				( member ( pinPairRef "@baseboard_fab2_lib.baseboard_fab2(sch_1):\PP1201\") )
				( member ( pinPairRef "@baseboard_fab2_lib.baseboard_fab2(sch_1):\PP1195\") )
				( objectStatus "MG_DQ-DQS_FAR_DIMM_NG_M_D_BYTE-ECC" )
			)
			( matchGroup "@baseboard_fab2_lib.baseboard_fab2(sch_1):\MG_DQ_FAR_DIMM_NG_M_D_BYTE-ECC\"
				( memberType ( signal ) )
				( member ( pinPairRef "@baseboard_fab2_lib.baseboard_fab2(sch_1):\PP4491\") )
				( member ( pinPairRef "@baseboard_fab2_lib.baseboard_fab2(sch_1):\PP4494\") )
				( member ( pinPairRef "@baseboard_fab2_lib.baseboard_fab2(sch_1):\PP4497\") )
				( member ( pinPairRef "@baseboard_fab2_lib.baseboard_fab2(sch_1):\PP4500\") )
				( member ( pinPairRef "@baseboard_fab2_lib.baseboard_fab2(sch_1):\PP4503\") )
				( member ( pinPairRef "@baseboard_fab2_lib.baseboard_fab2(sch_1):\PP4506\") )
				( member ( pinPairRef "@baseboard_fab2_lib.baseboard_fab2(sch_1):\PP4509\") )
				( member ( pinPairRef "@baseboard_fab2_lib.baseboard_fab2(sch_1):\PP4512\") )
				( objectStatus "MG_DQ_FAR_DIMM_NG_M_D_BYTE-ECC" )
			)
			( matchGroup "@baseboard_fab2_lib.baseboard_fab2(sch_1):\MG_DQ-DQS_NEAR_DIMM_NG_M_D_BYTE-ECC\"
				( memberType ( signal ) )
				( member ( pinPairRef "@baseboard_fab2_lib.baseboard_fab2(sch_1):\PP4493\") )
				( member ( pinPairRef "@baseboard_fab2_lib.baseboard_fab2(sch_1):\PP4496\") )
				( member ( pinPairRef "@baseboard_fab2_lib.baseboard_fab2(sch_1):\PP4499\") )
				( member ( pinPairRef "@baseboard_fab2_lib.baseboard_fab2(sch_1):\PP4502\") )
				( member ( pinPairRef "@baseboard_fab2_lib.baseboard_fab2(sch_1):\PP4505\") )
				( member ( pinPairRef "@baseboard_fab2_lib.baseboard_fab2(sch_1):\PP4508\") )
				( member ( pinPairRef "@baseboard_fab2_lib.baseboard_fab2(sch_1):\PP4511\") )
				( member ( pinPairRef "@baseboard_fab2_lib.baseboard_fab2(sch_1):\PP4514\") )
				( member ( pinPairRef "@baseboard_fab2_lib.baseboard_fab2(sch_1):\PP1205\") )
				( member ( pinPairRef "@baseboard_fab2_lib.baseboard_fab2(sch_1):\PP1199\") )
				( member ( pinPairRef "@baseboard_fab2_lib.baseboard_fab2(sch_1):\PP1202\") )
				( member ( pinPairRef "@baseboard_fab2_lib.baseboard_fab2(sch_1):\PP1196\") )
				( objectStatus "MG_DQ-DQS_NEAR_DIMM_NG_M_D_BYTE-ECC" )
			)
			( matchGroup "@baseboard_fab2_lib.baseboard_fab2(sch_1):\MG_DQ_NEAR_DIMM_NG_M_D_BYTE-ECC\"
				( memberType ( signal ) )
				( member ( pinPairRef "@baseboard_fab2_lib.baseboard_fab2(sch_1):\PP4493\") )
				( member ( pinPairRef "@baseboard_fab2_lib.baseboard_fab2(sch_1):\PP4496\") )
				( member ( pinPairRef "@baseboard_fab2_lib.baseboard_fab2(sch_1):\PP4499\") )
				( member ( pinPairRef "@baseboard_fab2_lib.baseboard_fab2(sch_1):\PP4502\") )
				( member ( pinPairRef "@baseboard_fab2_lib.baseboard_fab2(sch_1):\PP4505\") )
				( member ( pinPairRef "@baseboard_fab2_lib.baseboard_fab2(sch_1):\PP4508\") )
				( member ( pinPairRef "@baseboard_fab2_lib.baseboard_fab2(sch_1):\PP4511\") )
				( member ( pinPairRef "@baseboard_fab2_lib.baseboard_fab2(sch_1):\PP4514\") )
				( objectStatus "MG_DQ_NEAR_DIMM_NG_M_D_BYTE-ECC" )
			)
			( matchGroup "@baseboard_fab2_lib.baseboard_fab2(sch_1):\MG_DQ-DQS_FAR_DIMM_NG_M_E_BYTE-ECC\"
				( memberType ( signal ) )
				( member ( pinPairRef "@baseboard_fab2_lib.baseboard_fab2(sch_1):\PP4275\") )
				( member ( pinPairRef "@baseboard_fab2_lib.baseboard_fab2(sch_1):\PP4278\") )
				( member ( pinPairRef "@baseboard_fab2_lib.baseboard_fab2(sch_1):\PP4281\") )
				( member ( pinPairRef "@baseboard_fab2_lib.baseboard_fab2(sch_1):\PP4284\") )
				( member ( pinPairRef "@baseboard_fab2_lib.baseboard_fab2(sch_1):\PP4287\") )
				( member ( pinPairRef "@baseboard_fab2_lib.baseboard_fab2(sch_1):\PP4290\") )
				( member ( pinPairRef "@baseboard_fab2_lib.baseboard_fab2(sch_1):\PP4293\") )
				( member ( pinPairRef "@baseboard_fab2_lib.baseboard_fab2(sch_1):\PP4296\") )
				( member ( pinPairRef "@baseboard_fab2_lib.baseboard_fab2(sch_1):\PP1096\") )
				( member ( pinPairRef "@baseboard_fab2_lib.baseboard_fab2(sch_1):\PP1090\") )
				( member ( pinPairRef "@baseboard_fab2_lib.baseboard_fab2(sch_1):\PP1093\") )
				( member ( pinPairRef "@baseboard_fab2_lib.baseboard_fab2(sch_1):\PP1087\") )
				( objectStatus "MG_DQ-DQS_FAR_DIMM_NG_M_E_BYTE-ECC" )
			)
			( matchGroup "@crescent_city_bb_fab1_lib.crescent_city_bb_fab1(sch_1):\MG_DQ_FAR_DIMM_NG_M_E_BYTE-ECC\"
				( memberType ( signal ) )
				( member ( pinPairRef "@baseboard_fab2_lib.baseboard_fab2(sch_1):\PP4275\") )
				( member ( pinPairRef "@baseboard_fab2_lib.baseboard_fab2(sch_1):\PP4278\") )
				( member ( pinPairRef "@baseboard_fab2_lib.baseboard_fab2(sch_1):\PP4281\") )
				( member ( pinPairRef "@baseboard_fab2_lib.baseboard_fab2(sch_1):\PP4284\") )
				( member ( pinPairRef "@baseboard_fab2_lib.baseboard_fab2(sch_1):\PP4287\") )
				( member ( pinPairRef "@baseboard_fab2_lib.baseboard_fab2(sch_1):\PP4290\") )
				( member ( pinPairRef "@baseboard_fab2_lib.baseboard_fab2(sch_1):\PP4293\") )
				( member ( pinPairRef "@baseboard_fab2_lib.baseboard_fab2(sch_1):\PP4296\") )
				( objectStatus "MG_DQ_FAR_DIMM_NG_M_E_BYTE-ECC" )
			)
			( matchGroup "@baseboard_fab2_lib.baseboard_fab2(sch_1):\MG_DQ-DQS_NEAR_DIMM_NG_M_E_BYTE-ECC\"
				( memberType ( signal ) )
				( member ( pinPairRef "@baseboard_fab2_lib.baseboard_fab2(sch_1):\PP4277\") )
				( member ( pinPairRef "@baseboard_fab2_lib.baseboard_fab2(sch_1):\PP4280\") )
				( member ( pinPairRef "@baseboard_fab2_lib.baseboard_fab2(sch_1):\PP4283\") )
				( member ( pinPairRef "@baseboard_fab2_lib.baseboard_fab2(sch_1):\PP4286\") )
				( member ( pinPairRef "@baseboard_fab2_lib.baseboard_fab2(sch_1):\PP4289\") )
				( member ( pinPairRef "@baseboard_fab2_lib.baseboard_fab2(sch_1):\PP4292\") )
				( member ( pinPairRef "@baseboard_fab2_lib.baseboard_fab2(sch_1):\PP4295\") )
				( member ( pinPairRef "@baseboard_fab2_lib.baseboard_fab2(sch_1):\PP4298\") )
				( member ( pinPairRef "@baseboard_fab2_lib.baseboard_fab2(sch_1):\PP1097\") )
				( member ( pinPairRef "@baseboard_fab2_lib.baseboard_fab2(sch_1):\PP1091\") )
				( member ( pinPairRef "@baseboard_fab2_lib.baseboard_fab2(sch_1):\PP1094\") )
				( member ( pinPairRef "@baseboard_fab2_lib.baseboard_fab2(sch_1):\PP1088\") )
				( objectStatus "MG_DQ-DQS_NEAR_DIMM_NG_M_E_BYTE-ECC" )
			)
			( matchGroup "@crescent_city_bb_fab1_lib.crescent_city_bb_fab1(sch_1):\MG_DQ_NEAR_DIMM_NG_M_E_BYTE-ECC\"
				( memberType ( signal ) )
				( member ( pinPairRef "@baseboard_fab2_lib.baseboard_fab2(sch_1):\PP4277\") )
				( member ( pinPairRef "@baseboard_fab2_lib.baseboard_fab2(sch_1):\PP4280\") )
				( member ( pinPairRef "@baseboard_fab2_lib.baseboard_fab2(sch_1):\PP4283\") )
				( member ( pinPairRef "@baseboard_fab2_lib.baseboard_fab2(sch_1):\PP4286\") )
				( member ( pinPairRef "@baseboard_fab2_lib.baseboard_fab2(sch_1):\PP4289\") )
				( member ( pinPairRef "@baseboard_fab2_lib.baseboard_fab2(sch_1):\PP4292\") )
				( member ( pinPairRef "@baseboard_fab2_lib.baseboard_fab2(sch_1):\PP4295\") )
				( member ( pinPairRef "@baseboard_fab2_lib.baseboard_fab2(sch_1):\PP4298\") )
				( objectStatus "MG_DQ_NEAR_DIMM_NG_M_E_BYTE-ECC" )
			)
			( matchGroup "@baseboard_fab2_lib.baseboard_fab2(sch_1):\MG_DQ-DQS_FAR_DIMM_NG_M_D_BYTE4\"
				( memberType ( signal ) )
				( member ( pinPairRef "@baseboard_fab2_lib.baseboard_fab2(sch_1):\PP4602\") )
				( member ( pinPairRef "@baseboard_fab2_lib.baseboard_fab2(sch_1):\PP4605\") )
				( member ( pinPairRef "@baseboard_fab2_lib.baseboard_fab2(sch_1):\PP4608\") )
				( member ( pinPairRef "@baseboard_fab2_lib.baseboard_fab2(sch_1):\PP4587\") )
				( member ( pinPairRef "@baseboard_fab2_lib.baseboard_fab2(sch_1):\PP4590\") )
				( member ( pinPairRef "@baseboard_fab2_lib.baseboard_fab2(sch_1):\PP4593\") )
				( member ( pinPairRef "@baseboard_fab2_lib.baseboard_fab2(sch_1):\PP4596\") )
				( member ( pinPairRef "@baseboard_fab2_lib.baseboard_fab2(sch_1):\PP4599\") )
				( member ( pinPairRef "@baseboard_fab2_lib.baseboard_fab2(sch_1):\PP718\") )
				( member ( pinPairRef "@baseboard_fab2_lib.baseboard_fab2(sch_1):\PP721\") )
				( member ( pinPairRef "@baseboard_fab2_lib.baseboard_fab2(sch_1):\PP715\") )
				( member ( pinPairRef "@baseboard_fab2_lib.baseboard_fab2(sch_1):\PP724\") )
				( objectStatus "MG_DQ-DQS_FAR_DIMM_NG_M_D_BYTE4" )
			)
			( matchGroup "@baseboard_fab2_lib.baseboard_fab2(sch_1):\MG_DQ_FAR_DIMM_NG_M_D_BYTE4\"
				( memberType ( signal ) )
				( member ( pinPairRef "@baseboard_fab2_lib.baseboard_fab2(sch_1):\PP4602\") )
				( member ( pinPairRef "@baseboard_fab2_lib.baseboard_fab2(sch_1):\PP4605\") )
				( member ( pinPairRef "@baseboard_fab2_lib.baseboard_fab2(sch_1):\PP4608\") )
				( member ( pinPairRef "@baseboard_fab2_lib.baseboard_fab2(sch_1):\PP4587\") )
				( member ( pinPairRef "@baseboard_fab2_lib.baseboard_fab2(sch_1):\PP4590\") )
				( member ( pinPairRef "@baseboard_fab2_lib.baseboard_fab2(sch_1):\PP4593\") )
				( member ( pinPairRef "@baseboard_fab2_lib.baseboard_fab2(sch_1):\PP4596\") )
				( member ( pinPairRef "@baseboard_fab2_lib.baseboard_fab2(sch_1):\PP4599\") )
				( objectStatus "MG_DQ_FAR_DIMM_NG_M_D_BYTE4" )
			)
			( matchGroup "@baseboard_fab2_lib.baseboard_fab2(sch_1):\MG_DQ-DQS_NEAR_DIMM_NG_M_D_BYTE4\"
				( memberType ( signal ) )
				( member ( pinPairRef "@baseboard_fab2_lib.baseboard_fab2(sch_1):\PP4604\") )
				( member ( pinPairRef "@baseboard_fab2_lib.baseboard_fab2(sch_1):\PP4607\") )
				( member ( pinPairRef "@baseboard_fab2_lib.baseboard_fab2(sch_1):\PP4610\") )
				( member ( pinPairRef "@baseboard_fab2_lib.baseboard_fab2(sch_1):\PP4589\") )
				( member ( pinPairRef "@baseboard_fab2_lib.baseboard_fab2(sch_1):\PP4592\") )
				( member ( pinPairRef "@baseboard_fab2_lib.baseboard_fab2(sch_1):\PP4595\") )
				( member ( pinPairRef "@baseboard_fab2_lib.baseboard_fab2(sch_1):\PP4598\") )
				( member ( pinPairRef "@baseboard_fab2_lib.baseboard_fab2(sch_1):\PP4601\") )
				( member ( pinPairRef "@baseboard_fab2_lib.baseboard_fab2(sch_1):\PP720\") )
				( member ( pinPairRef "@baseboard_fab2_lib.baseboard_fab2(sch_1):\PP723\") )
				( member ( pinPairRef "@baseboard_fab2_lib.baseboard_fab2(sch_1):\PP717\") )
				( member ( pinPairRef "@baseboard_fab2_lib.baseboard_fab2(sch_1):\PP726\") )
				( objectStatus "MG_DQ-DQS_NEAR_DIMM_NG_M_D_BYTE4" )
			)
			( matchGroup "@crescent_city_bb_fab1_lib.crescent_city_bb_fab1(sch_1):\MG_DQ_NEAR_DIMM_NG_M_D_BYTE4\"
				( memberType ( signal ) )
				( member ( pinPairRef "@baseboard_fab2_lib.baseboard_fab2(sch_1):\PP4604\") )
				( member ( pinPairRef "@baseboard_fab2_lib.baseboard_fab2(sch_1):\PP4607\") )
				( member ( pinPairRef "@baseboard_fab2_lib.baseboard_fab2(sch_1):\PP4610\") )
				( member ( pinPairRef "@baseboard_fab2_lib.baseboard_fab2(sch_1):\PP4589\") )
				( member ( pinPairRef "@baseboard_fab2_lib.baseboard_fab2(sch_1):\PP4592\") )
				( member ( pinPairRef "@baseboard_fab2_lib.baseboard_fab2(sch_1):\PP4595\") )
				( member ( pinPairRef "@baseboard_fab2_lib.baseboard_fab2(sch_1):\PP4598\") )
				( member ( pinPairRef "@baseboard_fab2_lib.baseboard_fab2(sch_1):\PP4601\") )
				( objectStatus "MG_DQ_NEAR_DIMM_NG_M_D_BYTE4" )
			)
			( matchGroup "@baseboard_fab2_lib.baseboard_fab2(sch_1):\MG_DQ-DQS_FAR_DIMM_NG_M_D_BYTE5\"
				( memberType ( signal ) )
				( member ( pinPairRef "@baseboard_fab2_lib.baseboard_fab2(sch_1):\PP4563\") )
				( member ( pinPairRef "@baseboard_fab2_lib.baseboard_fab2(sch_1):\PP4566\") )
				( member ( pinPairRef "@baseboard_fab2_lib.baseboard_fab2(sch_1):\PP4569\") )
				( member ( pinPairRef "@baseboard_fab2_lib.baseboard_fab2(sch_1):\PP4572\") )
				( member ( pinPairRef "@baseboard_fab2_lib.baseboard_fab2(sch_1):\PP4575\") )
				( member ( pinPairRef "@baseboard_fab2_lib.baseboard_fab2(sch_1):\PP4578\") )
				( member ( pinPairRef "@baseboard_fab2_lib.baseboard_fab2(sch_1):\PP4581\") )
				( member ( pinPairRef "@baseboard_fab2_lib.baseboard_fab2(sch_1):\PP4584\") )
				( member ( pinPairRef "@baseboard_fab2_lib.baseboard_fab2(sch_1):\PP730\") )
				( member ( pinPairRef "@baseboard_fab2_lib.baseboard_fab2(sch_1):\PP733\") )
				( member ( pinPairRef "@baseboard_fab2_lib.baseboard_fab2(sch_1):\PP727\") )
				( member ( pinPairRef "@baseboard_fab2_lib.baseboard_fab2(sch_1):\PP736\") )
				( objectStatus "MG_DQ-DQS_FAR_DIMM_NG_M_D_BYTE5" )
			)
			( matchGroup "@crescent_city_bb_fab1_lib.crescent_city_bb_fab1(sch_1):\MG_DQ_FAR_DIMM_NG_M_D_BYTE5\"
				( memberType ( signal ) )
				( member ( pinPairRef "@baseboard_fab2_lib.baseboard_fab2(sch_1):\PP4563\") )
				( member ( pinPairRef "@baseboard_fab2_lib.baseboard_fab2(sch_1):\PP4566\") )
				( member ( pinPairRef "@baseboard_fab2_lib.baseboard_fab2(sch_1):\PP4569\") )
				( member ( pinPairRef "@baseboard_fab2_lib.baseboard_fab2(sch_1):\PP4572\") )
				( member ( pinPairRef "@baseboard_fab2_lib.baseboard_fab2(sch_1):\PP4575\") )
				( member ( pinPairRef "@baseboard_fab2_lib.baseboard_fab2(sch_1):\PP4578\") )
				( member ( pinPairRef "@baseboard_fab2_lib.baseboard_fab2(sch_1):\PP4581\") )
				( member ( pinPairRef "@baseboard_fab2_lib.baseboard_fab2(sch_1):\PP4584\") )
				( objectStatus "MG_DQ_FAR_DIMM_NG_M_D_BYTE5" )
			)
			( matchGroup "@baseboard_fab2_lib.baseboard_fab2(sch_1):\MG_DQ-DQS_NEAR_DIMM_NG_M_D_BYTE5\"
				( memberType ( signal ) )
				( member ( pinPairRef "@baseboard_fab2_lib.baseboard_fab2(sch_1):\PP4565\") )
				( member ( pinPairRef "@baseboard_fab2_lib.baseboard_fab2(sch_1):\PP4568\") )
				( member ( pinPairRef "@baseboard_fab2_lib.baseboard_fab2(sch_1):\PP4571\") )
				( member ( pinPairRef "@baseboard_fab2_lib.baseboard_fab2(sch_1):\PP4574\") )
				( member ( pinPairRef "@baseboard_fab2_lib.baseboard_fab2(sch_1):\PP4577\") )
				( member ( pinPairRef "@baseboard_fab2_lib.baseboard_fab2(sch_1):\PP4580\") )
				( member ( pinPairRef "@baseboard_fab2_lib.baseboard_fab2(sch_1):\PP4583\") )
				( member ( pinPairRef "@baseboard_fab2_lib.baseboard_fab2(sch_1):\PP4586\") )
				( member ( pinPairRef "@baseboard_fab2_lib.baseboard_fab2(sch_1):\PP732\") )
				( member ( pinPairRef "@baseboard_fab2_lib.baseboard_fab2(sch_1):\PP735\") )
				( member ( pinPairRef "@baseboard_fab2_lib.baseboard_fab2(sch_1):\PP729\") )
				( member ( pinPairRef "@baseboard_fab2_lib.baseboard_fab2(sch_1):\PP738\") )
				( objectStatus "MG_DQ-DQS_NEAR_DIMM_NG_M_D_BYTE5" )
			)
			( matchGroup "@crescent_city_bb_fab1_lib.crescent_city_bb_fab1(sch_1):\MG_DQ_NEAR_DIMM_NG_M_D_BYTE5\"
				( memberType ( signal ) )
				( member ( pinPairRef "@baseboard_fab2_lib.baseboard_fab2(sch_1):\PP4565\") )
				( member ( pinPairRef "@baseboard_fab2_lib.baseboard_fab2(sch_1):\PP4568\") )
				( member ( pinPairRef "@baseboard_fab2_lib.baseboard_fab2(sch_1):\PP4571\") )
				( member ( pinPairRef "@baseboard_fab2_lib.baseboard_fab2(sch_1):\PP4574\") )
				( member ( pinPairRef "@baseboard_fab2_lib.baseboard_fab2(sch_1):\PP4577\") )
				( member ( pinPairRef "@baseboard_fab2_lib.baseboard_fab2(sch_1):\PP4580\") )
				( member ( pinPairRef "@baseboard_fab2_lib.baseboard_fab2(sch_1):\PP4583\") )
				( member ( pinPairRef "@baseboard_fab2_lib.baseboard_fab2(sch_1):\PP4586\") )
				( objectStatus "MG_DQ_NEAR_DIMM_NG_M_D_BYTE5" )
			)
			( matchGroup "@baseboard_fab2_lib.baseboard_fab2(sch_1):\MG_DQ-DQS_FAR_DIMM_NG_M_D_BYTE6\"
				( memberType ( signal ) )
				( member ( pinPairRef "@baseboard_fab2_lib.baseboard_fab2(sch_1):\PP4539\") )
				( member ( pinPairRef "@baseboard_fab2_lib.baseboard_fab2(sch_1):\PP4542\") )
				( member ( pinPairRef "@baseboard_fab2_lib.baseboard_fab2(sch_1):\PP4545\") )
				( member ( pinPairRef "@baseboard_fab2_lib.baseboard_fab2(sch_1):\PP4548\") )
				( member ( pinPairRef "@baseboard_fab2_lib.baseboard_fab2(sch_1):\PP4551\") )
				( member ( pinPairRef "@baseboard_fab2_lib.baseboard_fab2(sch_1):\PP4554\") )
				( member ( pinPairRef "@baseboard_fab2_lib.baseboard_fab2(sch_1):\PP4557\") )
				( member ( pinPairRef "@baseboard_fab2_lib.baseboard_fab2(sch_1):\PP4560\") )
				( member ( pinPairRef "@baseboard_fab2_lib.baseboard_fab2(sch_1):\PP742\") )
				( member ( pinPairRef "@baseboard_fab2_lib.baseboard_fab2(sch_1):\PP745\") )
				( member ( pinPairRef "@baseboard_fab2_lib.baseboard_fab2(sch_1):\PP739\") )
				( member ( pinPairRef "@baseboard_fab2_lib.baseboard_fab2(sch_1):\PP748\") )
				( objectStatus "MG_DQ-DQS_FAR_DIMM_NG_M_D_BYTE6" )
			)
			( matchGroup "@crescent_city_bb_fab1_lib.crescent_city_bb_fab1(sch_1):\MG_DQ_FAR_DIMM_NG_M_D_BYTE6\"
				( memberType ( signal ) )
				( member ( pinPairRef "@baseboard_fab2_lib.baseboard_fab2(sch_1):\PP4539\") )
				( member ( pinPairRef "@baseboard_fab2_lib.baseboard_fab2(sch_1):\PP4542\") )
				( member ( pinPairRef "@baseboard_fab2_lib.baseboard_fab2(sch_1):\PP4545\") )
				( member ( pinPairRef "@baseboard_fab2_lib.baseboard_fab2(sch_1):\PP4548\") )
				( member ( pinPairRef "@baseboard_fab2_lib.baseboard_fab2(sch_1):\PP4551\") )
				( member ( pinPairRef "@baseboard_fab2_lib.baseboard_fab2(sch_1):\PP4554\") )
				( member ( pinPairRef "@baseboard_fab2_lib.baseboard_fab2(sch_1):\PP4557\") )
				( member ( pinPairRef "@baseboard_fab2_lib.baseboard_fab2(sch_1):\PP4560\") )
				( objectStatus "MG_DQ_FAR_DIMM_NG_M_D_BYTE6" )
			)
			( matchGroup "@baseboard_fab2_lib.baseboard_fab2(sch_1):\MG_DQ-DQS_NEAR_DIMM_NG_M_D_BYTE6\"
				( memberType ( signal ) )
				( member ( pinPairRef "@baseboard_fab2_lib.baseboard_fab2(sch_1):\PP4541\") )
				( member ( pinPairRef "@baseboard_fab2_lib.baseboard_fab2(sch_1):\PP4544\") )
				( member ( pinPairRef "@baseboard_fab2_lib.baseboard_fab2(sch_1):\PP4547\") )
				( member ( pinPairRef "@baseboard_fab2_lib.baseboard_fab2(sch_1):\PP4550\") )
				( member ( pinPairRef "@baseboard_fab2_lib.baseboard_fab2(sch_1):\PP4553\") )
				( member ( pinPairRef "@baseboard_fab2_lib.baseboard_fab2(sch_1):\PP4556\") )
				( member ( pinPairRef "@baseboard_fab2_lib.baseboard_fab2(sch_1):\PP4559\") )
				( member ( pinPairRef "@baseboard_fab2_lib.baseboard_fab2(sch_1):\PP4562\") )
				( member ( pinPairRef "@baseboard_fab2_lib.baseboard_fab2(sch_1):\PP744\") )
				( member ( pinPairRef "@baseboard_fab2_lib.baseboard_fab2(sch_1):\PP747\") )
				( member ( pinPairRef "@baseboard_fab2_lib.baseboard_fab2(sch_1):\PP741\") )
				( member ( pinPairRef "@baseboard_fab2_lib.baseboard_fab2(sch_1):\PP750\") )
				( objectStatus "MG_DQ-DQS_NEAR_DIMM_NG_M_D_BYTE6" )
			)
			( matchGroup "@crescent_city_bb_fab1_lib.crescent_city_bb_fab1(sch_1):\MG_DQ_NEAR_DIMM_NG_M_D_BYTE6\"
				( memberType ( signal ) )
				( member ( pinPairRef "@baseboard_fab2_lib.baseboard_fab2(sch_1):\PP4541\") )
				( member ( pinPairRef "@baseboard_fab2_lib.baseboard_fab2(sch_1):\PP4544\") )
				( member ( pinPairRef "@baseboard_fab2_lib.baseboard_fab2(sch_1):\PP4547\") )
				( member ( pinPairRef "@baseboard_fab2_lib.baseboard_fab2(sch_1):\PP4550\") )
				( member ( pinPairRef "@baseboard_fab2_lib.baseboard_fab2(sch_1):\PP4553\") )
				( member ( pinPairRef "@baseboard_fab2_lib.baseboard_fab2(sch_1):\PP4556\") )
				( member ( pinPairRef "@baseboard_fab2_lib.baseboard_fab2(sch_1):\PP4559\") )
				( member ( pinPairRef "@baseboard_fab2_lib.baseboard_fab2(sch_1):\PP4562\") )
				( objectStatus "MG_DQ_NEAR_DIMM_NG_M_D_BYTE6" )
			)
			( matchGroup "@baseboard_fab2_lib.baseboard_fab2(sch_1):\MG_DQ-DQS_FAR_DIMM_NG_M_D_BYTE7\"
				( memberType ( signal ) )
				( member ( pinPairRef "@baseboard_fab2_lib.baseboard_fab2(sch_1):\PP4515\") )
				( member ( pinPairRef "@baseboard_fab2_lib.baseboard_fab2(sch_1):\PP4518\") )
				( member ( pinPairRef "@baseboard_fab2_lib.baseboard_fab2(sch_1):\PP4521\") )
				( member ( pinPairRef "@baseboard_fab2_lib.baseboard_fab2(sch_1):\PP4524\") )
				( member ( pinPairRef "@baseboard_fab2_lib.baseboard_fab2(sch_1):\PP4527\") )
				( member ( pinPairRef "@baseboard_fab2_lib.baseboard_fab2(sch_1):\PP4530\") )
				( member ( pinPairRef "@baseboard_fab2_lib.baseboard_fab2(sch_1):\PP4533\") )
				( member ( pinPairRef "@baseboard_fab2_lib.baseboard_fab2(sch_1):\PP4536\") )
				( member ( pinPairRef "@baseboard_fab2_lib.baseboard_fab2(sch_1):\PP754\") )
				( member ( pinPairRef "@baseboard_fab2_lib.baseboard_fab2(sch_1):\PP757\") )
				( member ( pinPairRef "@baseboard_fab2_lib.baseboard_fab2(sch_1):\PP751\") )
				( member ( pinPairRef "@baseboard_fab2_lib.baseboard_fab2(sch_1):\PP760\") )
				( objectStatus "MG_DQ-DQS_FAR_DIMM_NG_M_D_BYTE7" )
			)
			( matchGroup "@crescent_city_bb_fab1_lib.crescent_city_bb_fab1(sch_1):\MG_DQ_FAR_DIMM_NG_M_D_BYTE7\"
				( memberType ( signal ) )
				( member ( pinPairRef "@baseboard_fab2_lib.baseboard_fab2(sch_1):\PP4515\") )
				( member ( pinPairRef "@baseboard_fab2_lib.baseboard_fab2(sch_1):\PP4518\") )
				( member ( pinPairRef "@baseboard_fab2_lib.baseboard_fab2(sch_1):\PP4521\") )
				( member ( pinPairRef "@baseboard_fab2_lib.baseboard_fab2(sch_1):\PP4524\") )
				( member ( pinPairRef "@baseboard_fab2_lib.baseboard_fab2(sch_1):\PP4527\") )
				( member ( pinPairRef "@baseboard_fab2_lib.baseboard_fab2(sch_1):\PP4530\") )
				( member ( pinPairRef "@baseboard_fab2_lib.baseboard_fab2(sch_1):\PP4533\") )
				( member ( pinPairRef "@baseboard_fab2_lib.baseboard_fab2(sch_1):\PP4536\") )
				( objectStatus "MG_DQ_FAR_DIMM_NG_M_D_BYTE7" )
			)
			( matchGroup "@baseboard_fab2_lib.baseboard_fab2(sch_1):\MG_DQ-DQS_NEAR_DIMM_NG_M_D_BYTE7\"
				( memberType ( signal ) )
				( member ( pinPairRef "@baseboard_fab2_lib.baseboard_fab2(sch_1):\PP4517\") )
				( member ( pinPairRef "@baseboard_fab2_lib.baseboard_fab2(sch_1):\PP4520\") )
				( member ( pinPairRef "@baseboard_fab2_lib.baseboard_fab2(sch_1):\PP4522\") )
				( member ( pinPairRef "@baseboard_fab2_lib.baseboard_fab2(sch_1):\PP4525\") )
				( member ( pinPairRef "@baseboard_fab2_lib.baseboard_fab2(sch_1):\PP4529\") )
				( member ( pinPairRef "@baseboard_fab2_lib.baseboard_fab2(sch_1):\PP4532\") )
				( member ( pinPairRef "@baseboard_fab2_lib.baseboard_fab2(sch_1):\PP4535\") )
				( member ( pinPairRef "@baseboard_fab2_lib.baseboard_fab2(sch_1):\PP4538\") )
				( member ( pinPairRef "@baseboard_fab2_lib.baseboard_fab2(sch_1):\PP756\") )
				( member ( pinPairRef "@baseboard_fab2_lib.baseboard_fab2(sch_1):\PP759\") )
				( member ( pinPairRef "@baseboard_fab2_lib.baseboard_fab2(sch_1):\PP753\") )
				( member ( pinPairRef "@baseboard_fab2_lib.baseboard_fab2(sch_1):\PP762\") )
				( objectStatus "MG_DQ-DQS_NEAR_DIMM_NG_M_D_BYTE7" )
			)
			( matchGroup "@crescent_city_bb_fab1_lib.crescent_city_bb_fab1(sch_1):\MG_DQ_NEAR_DIMM_NG_M_D_BYTE7\"
				( memberType ( signal ) )
				( member ( pinPairRef "@baseboard_fab2_lib.baseboard_fab2(sch_1):\PP4517\") )
				( member ( pinPairRef "@baseboard_fab2_lib.baseboard_fab2(sch_1):\PP4520\") )
				( member ( pinPairRef "@baseboard_fab2_lib.baseboard_fab2(sch_1):\PP4522\") )
				( member ( pinPairRef "@baseboard_fab2_lib.baseboard_fab2(sch_1):\PP4525\") )
				( member ( pinPairRef "@baseboard_fab2_lib.baseboard_fab2(sch_1):\PP4529\") )
				( member ( pinPairRef "@baseboard_fab2_lib.baseboard_fab2(sch_1):\PP4532\") )
				( member ( pinPairRef "@baseboard_fab2_lib.baseboard_fab2(sch_1):\PP4535\") )
				( member ( pinPairRef "@baseboard_fab2_lib.baseboard_fab2(sch_1):\PP4538\") )
				( objectStatus "MG_DQ_NEAR_DIMM_NG_M_D_BYTE7" )
			)
			( matchGroup "@baseboard_fab2_lib.baseboard_fab2(sch_1):\MG_DQ-DQS_FAR_DIMM_NG_M_E_BYTE0\"
				( memberType ( signal ) )
				( member ( pinPairRef "@baseboard_fab2_lib.baseboard_fab2(sch_1):\PP4467\") )
				( member ( pinPairRef "@baseboard_fab2_lib.baseboard_fab2(sch_1):\PP4470\") )
				( member ( pinPairRef "@baseboard_fab2_lib.baseboard_fab2(sch_1):\PP4473\") )
				( member ( pinPairRef "@baseboard_fab2_lib.baseboard_fab2(sch_1):\PP4476\") )
				( member ( pinPairRef "@baseboard_fab2_lib.baseboard_fab2(sch_1):\PP4479\") )
				( member ( pinPairRef "@baseboard_fab2_lib.baseboard_fab2(sch_1):\PP4482\") )
				( member ( pinPairRef "@baseboard_fab2_lib.baseboard_fab2(sch_1):\PP4485\") )
				( member ( pinPairRef "@baseboard_fab2_lib.baseboard_fab2(sch_1):\PP4488\") )
				( member ( pinPairRef "@baseboard_fab2_lib.baseboard_fab2(sch_1):\PP1192\") )
				( member ( pinPairRef "@baseboard_fab2_lib.baseboard_fab2(sch_1):\PP1186\") )
				( member ( pinPairRef "@baseboard_fab2_lib.baseboard_fab2(sch_1):\PP1189\") )
				( member ( pinPairRef "@baseboard_fab2_lib.baseboard_fab2(sch_1):\PP1183\") )
				( objectStatus "MG_DQ-DQS_FAR_DIMM_NG_M_E_BYTE0" )
			)
			( matchGroup "@crescent_city_bb_fab1_lib.crescent_city_bb_fab1(sch_1):\MG_DQ_FAR_DIMM_NG_M_E_BYTE0\"
				( memberType ( signal ) )
				( member ( pinPairRef "@baseboard_fab2_lib.baseboard_fab2(sch_1):\PP4467\") )
				( member ( pinPairRef "@baseboard_fab2_lib.baseboard_fab2(sch_1):\PP4470\") )
				( member ( pinPairRef "@baseboard_fab2_lib.baseboard_fab2(sch_1):\PP4473\") )
				( member ( pinPairRef "@baseboard_fab2_lib.baseboard_fab2(sch_1):\PP4476\") )
				( member ( pinPairRef "@baseboard_fab2_lib.baseboard_fab2(sch_1):\PP4479\") )
				( member ( pinPairRef "@baseboard_fab2_lib.baseboard_fab2(sch_1):\PP4482\") )
				( member ( pinPairRef "@baseboard_fab2_lib.baseboard_fab2(sch_1):\PP4485\") )
				( member ( pinPairRef "@baseboard_fab2_lib.baseboard_fab2(sch_1):\PP4488\") )
				( objectStatus "MG_DQ_FAR_DIMM_NG_M_E_BYTE0" )
			)
			( matchGroup "@baseboard_fab2_lib.baseboard_fab2(sch_1):\MG_DQ-DQS_NEAR_DIMM_NG_M_E_BYTE0\"
				( memberType ( signal ) )
				( member ( pinPairRef "@baseboard_fab2_lib.baseboard_fab2(sch_1):\PP4469\") )
				( member ( pinPairRef "@baseboard_fab2_lib.baseboard_fab2(sch_1):\PP4472\") )
				( member ( pinPairRef "@baseboard_fab2_lib.baseboard_fab2(sch_1):\PP4475\") )
				( member ( pinPairRef "@baseboard_fab2_lib.baseboard_fab2(sch_1):\PP4478\") )
				( member ( pinPairRef "@baseboard_fab2_lib.baseboard_fab2(sch_1):\PP4481\") )
				( member ( pinPairRef "@baseboard_fab2_lib.baseboard_fab2(sch_1):\PP4484\") )
				( member ( pinPairRef "@baseboard_fab2_lib.baseboard_fab2(sch_1):\PP4487\") )
				( member ( pinPairRef "@baseboard_fab2_lib.baseboard_fab2(sch_1):\PP4490\") )
				( member ( pinPairRef "@baseboard_fab2_lib.baseboard_fab2(sch_1):\PP1193\") )
				( member ( pinPairRef "@baseboard_fab2_lib.baseboard_fab2(sch_1):\PP1187\") )
				( member ( pinPairRef "@baseboard_fab2_lib.baseboard_fab2(sch_1):\PP1190\") )
				( member ( pinPairRef "@baseboard_fab2_lib.baseboard_fab2(sch_1):\PP1184\") )
				( objectStatus "MG_DQ-DQS_NEAR_DIMM_NG_M_E_BYTE0" )
			)
			( matchGroup "@crescent_city_bb_fab1_lib.crescent_city_bb_fab1(sch_1):\MG_DQ_NEAR_DIMM_NG_M_E_BYTE0\"
				( memberType ( signal ) )
				( member ( pinPairRef "@baseboard_fab2_lib.baseboard_fab2(sch_1):\PP4469\") )
				( member ( pinPairRef "@baseboard_fab2_lib.baseboard_fab2(sch_1):\PP4472\") )
				( member ( pinPairRef "@baseboard_fab2_lib.baseboard_fab2(sch_1):\PP4475\") )
				( member ( pinPairRef "@baseboard_fab2_lib.baseboard_fab2(sch_1):\PP4478\") )
				( member ( pinPairRef "@baseboard_fab2_lib.baseboard_fab2(sch_1):\PP4481\") )
				( member ( pinPairRef "@baseboard_fab2_lib.baseboard_fab2(sch_1):\PP4484\") )
				( member ( pinPairRef "@baseboard_fab2_lib.baseboard_fab2(sch_1):\PP4487\") )
				( member ( pinPairRef "@baseboard_fab2_lib.baseboard_fab2(sch_1):\PP4490\") )
				( objectStatus "MG_DQ_NEAR_DIMM_NG_M_E_BYTE0" )
			)
			( matchGroup "@baseboard_fab2_lib.baseboard_fab2(sch_1):\MG_DQ-DQS_FAR_DIMM_NG_M_E_BYTE1\"
				( memberType ( signal ) )
				( member ( pinPairRef "@baseboard_fab2_lib.baseboard_fab2(sch_1):\PP4443\") )
				( member ( pinPairRef "@baseboard_fab2_lib.baseboard_fab2(sch_1):\PP4446\") )
				( member ( pinPairRef "@baseboard_fab2_lib.baseboard_fab2(sch_1):\PP4449\") )
				( member ( pinPairRef "@baseboard_fab2_lib.baseboard_fab2(sch_1):\PP4452\") )
				( member ( pinPairRef "@baseboard_fab2_lib.baseboard_fab2(sch_1):\PP4455\") )
				( member ( pinPairRef "@baseboard_fab2_lib.baseboard_fab2(sch_1):\PP4458\") )
				( member ( pinPairRef "@baseboard_fab2_lib.baseboard_fab2(sch_1):\PP4461\") )
				( member ( pinPairRef "@baseboard_fab2_lib.baseboard_fab2(sch_1):\PP4464\") )
				( member ( pinPairRef "@baseboard_fab2_lib.baseboard_fab2(sch_1):\PP1180\") )
				( member ( pinPairRef "@baseboard_fab2_lib.baseboard_fab2(sch_1):\PP1174\") )
				( member ( pinPairRef "@baseboard_fab2_lib.baseboard_fab2(sch_1):\PP1177\") )
				( member ( pinPairRef "@baseboard_fab2_lib.baseboard_fab2(sch_1):\PP1171\") )
				( objectStatus "MG_DQ-DQS_FAR_DIMM_NG_M_E_BYTE1" )
			)
			( matchGroup "@baseboard_fab2_lib.baseboard_fab2(sch_1):\MG_DQ_FAR_DIMM_NG_M_E_BYTE1\"
				( memberType ( signal ) )
				( member ( pinPairRef "@baseboard_fab2_lib.baseboard_fab2(sch_1):\PP4443\") )
				( member ( pinPairRef "@baseboard_fab2_lib.baseboard_fab2(sch_1):\PP4446\") )
				( member ( pinPairRef "@baseboard_fab2_lib.baseboard_fab2(sch_1):\PP4449\") )
				( member ( pinPairRef "@baseboard_fab2_lib.baseboard_fab2(sch_1):\PP4452\") )
				( member ( pinPairRef "@baseboard_fab2_lib.baseboard_fab2(sch_1):\PP4455\") )
				( member ( pinPairRef "@baseboard_fab2_lib.baseboard_fab2(sch_1):\PP4458\") )
				( member ( pinPairRef "@baseboard_fab2_lib.baseboard_fab2(sch_1):\PP4461\") )
				( member ( pinPairRef "@baseboard_fab2_lib.baseboard_fab2(sch_1):\PP4464\") )
				( objectStatus "MG_DQ_FAR_DIMM_NG_M_E_BYTE1" )
			)
			( matchGroup "@baseboard_fab2_lib.baseboard_fab2(sch_1):\MG_DQ-DQS_NEAR_DIMM_NG_M_E_BYTE1\"
				( memberType ( signal ) )
				( member ( pinPairRef "@baseboard_fab2_lib.baseboard_fab2(sch_1):\PP4445\") )
				( member ( pinPairRef "@baseboard_fab2_lib.baseboard_fab2(sch_1):\PP4448\") )
				( member ( pinPairRef "@baseboard_fab2_lib.baseboard_fab2(sch_1):\PP4451\") )
				( member ( pinPairRef "@baseboard_fab2_lib.baseboard_fab2(sch_1):\PP4454\") )
				( member ( pinPairRef "@baseboard_fab2_lib.baseboard_fab2(sch_1):\PP4457\") )
				( member ( pinPairRef "@baseboard_fab2_lib.baseboard_fab2(sch_1):\PP4460\") )
				( member ( pinPairRef "@baseboard_fab2_lib.baseboard_fab2(sch_1):\PP4463\") )
				( member ( pinPairRef "@baseboard_fab2_lib.baseboard_fab2(sch_1):\PP4466\") )
				( member ( pinPairRef "@baseboard_fab2_lib.baseboard_fab2(sch_1):\PP1181\") )
				( member ( pinPairRef "@baseboard_fab2_lib.baseboard_fab2(sch_1):\PP1175\") )
				( member ( pinPairRef "@baseboard_fab2_lib.baseboard_fab2(sch_1):\PP1178\") )
				( member ( pinPairRef "@baseboard_fab2_lib.baseboard_fab2(sch_1):\PP1172\") )
				( objectStatus "MG_DQ-DQS_NEAR_DIMM_NG_M_E_BYTE1" )
			)
			( matchGroup "@baseboard_fab2_lib.baseboard_fab2(sch_1):\MG_DQ_NEAR_DIMM_NG_M_E_BYTE1\"
				( memberType ( signal ) )
				( member ( pinPairRef "@baseboard_fab2_lib.baseboard_fab2(sch_1):\PP4445\") )
				( member ( pinPairRef "@baseboard_fab2_lib.baseboard_fab2(sch_1):\PP4448\") )
				( member ( pinPairRef "@baseboard_fab2_lib.baseboard_fab2(sch_1):\PP4451\") )
				( member ( pinPairRef "@baseboard_fab2_lib.baseboard_fab2(sch_1):\PP4454\") )
				( member ( pinPairRef "@baseboard_fab2_lib.baseboard_fab2(sch_1):\PP4457\") )
				( member ( pinPairRef "@baseboard_fab2_lib.baseboard_fab2(sch_1):\PP4460\") )
				( member ( pinPairRef "@baseboard_fab2_lib.baseboard_fab2(sch_1):\PP4463\") )
				( member ( pinPairRef "@baseboard_fab2_lib.baseboard_fab2(sch_1):\PP4466\") )
				( objectStatus "MG_DQ_NEAR_DIMM_NG_M_E_BYTE1" )
			)
			( matchGroup "@baseboard_fab2_lib.baseboard_fab2(sch_1):\MG_DQ-DQS_FAR_DIMM_NG_M_E_BYTE2\"
				( memberType ( signal ) )
				( member ( pinPairRef "@baseboard_fab2_lib.baseboard_fab2(sch_1):\PP4419\") )
				( member ( pinPairRef "@baseboard_fab2_lib.baseboard_fab2(sch_1):\PP4422\") )
				( member ( pinPairRef "@baseboard_fab2_lib.baseboard_fab2(sch_1):\PP4425\") )
				( member ( pinPairRef "@baseboard_fab2_lib.baseboard_fab2(sch_1):\PP4428\") )
				( member ( pinPairRef "@baseboard_fab2_lib.baseboard_fab2(sch_1):\PP4431\") )
				( member ( pinPairRef "@baseboard_fab2_lib.baseboard_fab2(sch_1):\PP4434\") )
				( member ( pinPairRef "@baseboard_fab2_lib.baseboard_fab2(sch_1):\PP4437\") )
				( member ( pinPairRef "@baseboard_fab2_lib.baseboard_fab2(sch_1):\PP4440\") )
				( member ( pinPairRef "@baseboard_fab2_lib.baseboard_fab2(sch_1):\PP1168\") )
				( member ( pinPairRef "@baseboard_fab2_lib.baseboard_fab2(sch_1):\PP1162\") )
				( member ( pinPairRef "@baseboard_fab2_lib.baseboard_fab2(sch_1):\PP1165\") )
				( member ( pinPairRef "@baseboard_fab2_lib.baseboard_fab2(sch_1):\PP1159\") )
				( objectStatus "MG_DQ-DQS_FAR_DIMM_NG_M_E_BYTE2" )
			)
			( matchGroup "@crescent_city_bb_fab1_lib.crescent_city_bb_fab1(sch_1):\MG_DQ_FAR_DIMM_NG_M_E_BYTE2\"
				( memberType ( signal ) )
				( member ( pinPairRef "@baseboard_fab2_lib.baseboard_fab2(sch_1):\PP4419\") )
				( member ( pinPairRef "@baseboard_fab2_lib.baseboard_fab2(sch_1):\PP4422\") )
				( member ( pinPairRef "@baseboard_fab2_lib.baseboard_fab2(sch_1):\PP4425\") )
				( member ( pinPairRef "@baseboard_fab2_lib.baseboard_fab2(sch_1):\PP4428\") )
				( member ( pinPairRef "@baseboard_fab2_lib.baseboard_fab2(sch_1):\PP4431\") )
				( member ( pinPairRef "@baseboard_fab2_lib.baseboard_fab2(sch_1):\PP4434\") )
				( member ( pinPairRef "@baseboard_fab2_lib.baseboard_fab2(sch_1):\PP4437\") )
				( member ( pinPairRef "@baseboard_fab2_lib.baseboard_fab2(sch_1):\PP4440\") )
				( objectStatus "MG_DQ_FAR_DIMM_NG_M_E_BYTE2" )
			)
			( matchGroup "@baseboard_fab2_lib.baseboard_fab2(sch_1):\MG_DQ-DQS_NEAR_DIMM_NG_M_E_BYTE2\"
				( memberType ( signal ) )
				( member ( pinPairRef "@baseboard_fab2_lib.baseboard_fab2(sch_1):\PP4421\") )
				( member ( pinPairRef "@baseboard_fab2_lib.baseboard_fab2(sch_1):\PP4424\") )
				( member ( pinPairRef "@baseboard_fab2_lib.baseboard_fab2(sch_1):\PP4427\") )
				( member ( pinPairRef "@baseboard_fab2_lib.baseboard_fab2(sch_1):\PP4430\") )
				( member ( pinPairRef "@baseboard_fab2_lib.baseboard_fab2(sch_1):\PP4433\") )
				( member ( pinPairRef "@baseboard_fab2_lib.baseboard_fab2(sch_1):\PP4436\") )
				( member ( pinPairRef "@baseboard_fab2_lib.baseboard_fab2(sch_1):\PP4439\") )
				( member ( pinPairRef "@baseboard_fab2_lib.baseboard_fab2(sch_1):\PP4442\") )
				( member ( pinPairRef "@baseboard_fab2_lib.baseboard_fab2(sch_1):\PP1169\") )
				( member ( pinPairRef "@baseboard_fab2_lib.baseboard_fab2(sch_1):\PP1163\") )
				( member ( pinPairRef "@baseboard_fab2_lib.baseboard_fab2(sch_1):\PP1166\") )
				( member ( pinPairRef "@baseboard_fab2_lib.baseboard_fab2(sch_1):\PP1160\") )
				( objectStatus "MG_DQ-DQS_NEAR_DIMM_NG_M_E_BYTE2" )
			)
			( matchGroup "@crescent_city_bb_fab1_lib.crescent_city_bb_fab1(sch_1):\MG_DQ_NEAR_DIMM_NG_M_E_BYTE2\"
				( memberType ( signal ) )
				( member ( pinPairRef "@baseboard_fab2_lib.baseboard_fab2(sch_1):\PP4421\") )
				( member ( pinPairRef "@baseboard_fab2_lib.baseboard_fab2(sch_1):\PP4424\") )
				( member ( pinPairRef "@baseboard_fab2_lib.baseboard_fab2(sch_1):\PP4427\") )
				( member ( pinPairRef "@baseboard_fab2_lib.baseboard_fab2(sch_1):\PP4430\") )
				( member ( pinPairRef "@baseboard_fab2_lib.baseboard_fab2(sch_1):\PP4433\") )
				( member ( pinPairRef "@baseboard_fab2_lib.baseboard_fab2(sch_1):\PP4436\") )
				( member ( pinPairRef "@baseboard_fab2_lib.baseboard_fab2(sch_1):\PP4439\") )
				( member ( pinPairRef "@baseboard_fab2_lib.baseboard_fab2(sch_1):\PP4442\") )
				( objectStatus "MG_DQ_NEAR_DIMM_NG_M_E_BYTE2" )
			)
			( matchGroup "@baseboard_fab2_lib.baseboard_fab2(sch_1):\MG_DQ-DQS_FAR_DIMM_NG_M_E_BYTE3\"
				( memberType ( signal ) )
				( member ( pinPairRef "@baseboard_fab2_lib.baseboard_fab2(sch_1):\PP4299\") )
				( member ( pinPairRef "@baseboard_fab2_lib.baseboard_fab2(sch_1):\PP4302\") )
				( member ( pinPairRef "@baseboard_fab2_lib.baseboard_fab2(sch_1):\PP4305\") )
				( member ( pinPairRef "@baseboard_fab2_lib.baseboard_fab2(sch_1):\PP4308\") )
				( member ( pinPairRef "@baseboard_fab2_lib.baseboard_fab2(sch_1):\PP4311\") )
				( member ( pinPairRef "@baseboard_fab2_lib.baseboard_fab2(sch_1):\PP4314\") )
				( member ( pinPairRef "@baseboard_fab2_lib.baseboard_fab2(sch_1):\PP4317\") )
				( member ( pinPairRef "@baseboard_fab2_lib.baseboard_fab2(sch_1):\PP4320\") )
				( member ( pinPairRef "@baseboard_fab2_lib.baseboard_fab2(sch_1):\PP1156\") )
				( member ( pinPairRef "@baseboard_fab2_lib.baseboard_fab2(sch_1):\PP1150\") )
				( member ( pinPairRef "@baseboard_fab2_lib.baseboard_fab2(sch_1):\PP1153\") )
				( member ( pinPairRef "@baseboard_fab2_lib.baseboard_fab2(sch_1):\PP1147\") )
				( objectStatus "MG_DQ-DQS_FAR_DIMM_NG_M_E_BYTE3" )
			)
			( matchGroup "@crescent_city_bb_fab1_lib.crescent_city_bb_fab1(sch_1):\MG_DQ_FAR_DIMM_NG_M_E_BYTE3\"
				( memberType ( signal ) )
				( member ( pinPairRef "@baseboard_fab2_lib.baseboard_fab2(sch_1):\PP4299\") )
				( member ( pinPairRef "@baseboard_fab2_lib.baseboard_fab2(sch_1):\PP4302\") )
				( member ( pinPairRef "@baseboard_fab2_lib.baseboard_fab2(sch_1):\PP4305\") )
				( member ( pinPairRef "@baseboard_fab2_lib.baseboard_fab2(sch_1):\PP4308\") )
				( member ( pinPairRef "@baseboard_fab2_lib.baseboard_fab2(sch_1):\PP4311\") )
				( member ( pinPairRef "@baseboard_fab2_lib.baseboard_fab2(sch_1):\PP4314\") )
				( member ( pinPairRef "@baseboard_fab2_lib.baseboard_fab2(sch_1):\PP4317\") )
				( member ( pinPairRef "@baseboard_fab2_lib.baseboard_fab2(sch_1):\PP4320\") )
				( objectStatus "MG_DQ_FAR_DIMM_NG_M_E_BYTE3" )
			)
			( matchGroup "@baseboard_fab2_lib.baseboard_fab2(sch_1):\MG_DQ-DQS_NEAR_DIMM_NG_M_E_BYTE3\"
				( memberType ( signal ) )
				( member ( pinPairRef "@baseboard_fab2_lib.baseboard_fab2(sch_1):\PP4301\") )
				( member ( pinPairRef "@baseboard_fab2_lib.baseboard_fab2(sch_1):\PP4304\") )
				( member ( pinPairRef "@baseboard_fab2_lib.baseboard_fab2(sch_1):\PP4307\") )
				( member ( pinPairRef "@baseboard_fab2_lib.baseboard_fab2(sch_1):\PP4310\") )
				( member ( pinPairRef "@baseboard_fab2_lib.baseboard_fab2(sch_1):\PP4313\") )
				( member ( pinPairRef "@baseboard_fab2_lib.baseboard_fab2(sch_1):\PP4316\") )
				( member ( pinPairRef "@baseboard_fab2_lib.baseboard_fab2(sch_1):\PP4319\") )
				( member ( pinPairRef "@baseboard_fab2_lib.baseboard_fab2(sch_1):\PP4322\") )
				( member ( pinPairRef "@baseboard_fab2_lib.baseboard_fab2(sch_1):\PP1157\") )
				( member ( pinPairRef "@baseboard_fab2_lib.baseboard_fab2(sch_1):\PP1151\") )
				( member ( pinPairRef "@baseboard_fab2_lib.baseboard_fab2(sch_1):\PP1154\") )
				( member ( pinPairRef "@baseboard_fab2_lib.baseboard_fab2(sch_1):\PP1148\") )
				( objectStatus "MG_DQ-DQS_NEAR_DIMM_NG_M_E_BYTE3" )
			)
			( matchGroup "@crescent_city_bb_fab1_lib.crescent_city_bb_fab1(sch_1):\MG_DQ_NEAR_DIMM_NG_M_E_BYTE3\"
				( memberType ( signal ) )
				( member ( pinPairRef "@baseboard_fab2_lib.baseboard_fab2(sch_1):\PP4301\") )
				( member ( pinPairRef "@baseboard_fab2_lib.baseboard_fab2(sch_1):\PP4304\") )
				( member ( pinPairRef "@baseboard_fab2_lib.baseboard_fab2(sch_1):\PP4307\") )
				( member ( pinPairRef "@baseboard_fab2_lib.baseboard_fab2(sch_1):\PP4310\") )
				( member ( pinPairRef "@baseboard_fab2_lib.baseboard_fab2(sch_1):\PP4313\") )
				( member ( pinPairRef "@baseboard_fab2_lib.baseboard_fab2(sch_1):\PP4316\") )
				( member ( pinPairRef "@baseboard_fab2_lib.baseboard_fab2(sch_1):\PP4319\") )
				( member ( pinPairRef "@baseboard_fab2_lib.baseboard_fab2(sch_1):\PP4322\") )
				( objectStatus "MG_DQ_NEAR_DIMM_NG_M_E_BYTE3" )
			)
			( matchGroup "@baseboard_fab2_lib.baseboard_fab2(sch_1):\MG_DQ-DQS_FAR_DIMM_NG_M_E_BYTE4\"
				( memberType ( signal ) )
				( member ( pinPairRef "@baseboard_fab2_lib.baseboard_fab2(sch_1):\PP4395\") )
				( member ( pinPairRef "@baseboard_fab2_lib.baseboard_fab2(sch_1):\PP4398\") )
				( member ( pinPairRef "@baseboard_fab2_lib.baseboard_fab2(sch_1):\PP4401\") )
				( member ( pinPairRef "@baseboard_fab2_lib.baseboard_fab2(sch_1):\PP4404\") )
				( member ( pinPairRef "@baseboard_fab2_lib.baseboard_fab2(sch_1):\PP4407\") )
				( member ( pinPairRef "@baseboard_fab2_lib.baseboard_fab2(sch_1):\PP4410\") )
				( member ( pinPairRef "@baseboard_fab2_lib.baseboard_fab2(sch_1):\PP4413\") )
				( member ( pinPairRef "@baseboard_fab2_lib.baseboard_fab2(sch_1):\PP4416\") )
				( member ( pinPairRef "@baseboard_fab2_lib.baseboard_fab2(sch_1):\PP1144\") )
				( member ( pinPairRef "@baseboard_fab2_lib.baseboard_fab2(sch_1):\PP1138\") )
				( member ( pinPairRef "@baseboard_fab2_lib.baseboard_fab2(sch_1):\PP1141\") )
				( member ( pinPairRef "@baseboard_fab2_lib.baseboard_fab2(sch_1):\PP1135\") )
				( objectStatus "MG_DQ-DQS_FAR_DIMM_NG_M_E_BYTE4" )
			)
			( matchGroup "@crescent_city_bb_fab1_lib.crescent_city_bb_fab1(sch_1):\MG_DQ_FAR_DIMM_NG_M_E_BYTE4\"
				( memberType ( signal ) )
				( member ( pinPairRef "@baseboard_fab2_lib.baseboard_fab2(sch_1):\PP4395\") )
				( member ( pinPairRef "@baseboard_fab2_lib.baseboard_fab2(sch_1):\PP4398\") )
				( member ( pinPairRef "@baseboard_fab2_lib.baseboard_fab2(sch_1):\PP4401\") )
				( member ( pinPairRef "@baseboard_fab2_lib.baseboard_fab2(sch_1):\PP4404\") )
				( member ( pinPairRef "@baseboard_fab2_lib.baseboard_fab2(sch_1):\PP4407\") )
				( member ( pinPairRef "@baseboard_fab2_lib.baseboard_fab2(sch_1):\PP4410\") )
				( member ( pinPairRef "@baseboard_fab2_lib.baseboard_fab2(sch_1):\PP4413\") )
				( member ( pinPairRef "@baseboard_fab2_lib.baseboard_fab2(sch_1):\PP4416\") )
				( objectStatus "MG_DQ_FAR_DIMM_NG_M_E_BYTE4" )
			)
			( matchGroup "@baseboard_fab2_lib.baseboard_fab2(sch_1):\MG_DQ-DQS_NEAR_DIMM_NG_M_E_BYTE4\"
				( memberType ( signal ) )
				( member ( pinPairRef "@baseboard_fab2_lib.baseboard_fab2(sch_1):\PP4396\") )
				( member ( pinPairRef "@baseboard_fab2_lib.baseboard_fab2(sch_1):\PP4399\") )
				( member ( pinPairRef "@baseboard_fab2_lib.baseboard_fab2(sch_1):\PP4403\") )
				( member ( pinPairRef "@baseboard_fab2_lib.baseboard_fab2(sch_1):\PP4406\") )
				( member ( pinPairRef "@baseboard_fab2_lib.baseboard_fab2(sch_1):\PP4408\") )
				( member ( pinPairRef "@baseboard_fab2_lib.baseboard_fab2(sch_1):\PP4411\") )
				( member ( pinPairRef "@baseboard_fab2_lib.baseboard_fab2(sch_1):\PP4415\") )
				( member ( pinPairRef "@baseboard_fab2_lib.baseboard_fab2(sch_1):\PP4418\") )
				( member ( pinPairRef "@baseboard_fab2_lib.baseboard_fab2(sch_1):\PP1146\") )
				( member ( pinPairRef "@baseboard_fab2_lib.baseboard_fab2(sch_1):\PP1140\") )
				( member ( pinPairRef "@baseboard_fab2_lib.baseboard_fab2(sch_1):\PP1143\") )
				( member ( pinPairRef "@baseboard_fab2_lib.baseboard_fab2(sch_1):\PP1137\") )
				( objectStatus "MG_DQ-DQS_NEAR_DIMM_NG_M_E_BYTE4" )
			)
			( matchGroup "@crescent_city_bb_fab1_lib.crescent_city_bb_fab1(sch_1):\MG_DQ_NEAR_DIMM_NG_M_E_BYTE4\"
				( memberType ( signal ) )
				( member ( pinPairRef "@baseboard_fab2_lib.baseboard_fab2(sch_1):\PP4396\") )
				( member ( pinPairRef "@baseboard_fab2_lib.baseboard_fab2(sch_1):\PP4399\") )
				( member ( pinPairRef "@baseboard_fab2_lib.baseboard_fab2(sch_1):\PP4403\") )
				( member ( pinPairRef "@baseboard_fab2_lib.baseboard_fab2(sch_1):\PP4406\") )
				( member ( pinPairRef "@baseboard_fab2_lib.baseboard_fab2(sch_1):\PP4408\") )
				( member ( pinPairRef "@baseboard_fab2_lib.baseboard_fab2(sch_1):\PP4411\") )
				( member ( pinPairRef "@baseboard_fab2_lib.baseboard_fab2(sch_1):\PP4415\") )
				( member ( pinPairRef "@baseboard_fab2_lib.baseboard_fab2(sch_1):\PP4418\") )
				( objectStatus "MG_DQ_NEAR_DIMM_NG_M_E_BYTE4" )
			)
			( matchGroup "@baseboard_fab2_lib.baseboard_fab2(sch_1):\MG_DQ-DQS_FAR_DIMM_NG_M_E_BYTE5\"
				( memberType ( signal ) )
				( member ( pinPairRef "@baseboard_fab2_lib.baseboard_fab2(sch_1):\PP4371\") )
				( member ( pinPairRef "@baseboard_fab2_lib.baseboard_fab2(sch_1):\PP4374\") )
				( member ( pinPairRef "@baseboard_fab2_lib.baseboard_fab2(sch_1):\PP4377\") )
				( member ( pinPairRef "@baseboard_fab2_lib.baseboard_fab2(sch_1):\PP4380\") )
				( member ( pinPairRef "@baseboard_fab2_lib.baseboard_fab2(sch_1):\PP4383\") )
				( member ( pinPairRef "@baseboard_fab2_lib.baseboard_fab2(sch_1):\PP4386\") )
				( member ( pinPairRef "@baseboard_fab2_lib.baseboard_fab2(sch_1):\PP4389\") )
				( member ( pinPairRef "@baseboard_fab2_lib.baseboard_fab2(sch_1):\PP4392\") )
				( member ( pinPairRef "@baseboard_fab2_lib.baseboard_fab2(sch_1):\PP1132\") )
				( member ( pinPairRef "@baseboard_fab2_lib.baseboard_fab2(sch_1):\PP1126\") )
				( member ( pinPairRef "@baseboard_fab2_lib.baseboard_fab2(sch_1):\PP1129\") )
				( member ( pinPairRef "@baseboard_fab2_lib.baseboard_fab2(sch_1):\PP1123\") )
				( objectStatus "MG_DQ-DQS_FAR_DIMM_NG_M_E_BYTE5" )
			)
			( matchGroup "@baseboard_fab2_lib.baseboard_fab2(sch_1):\MG_DQ_FAR_DIMM_NG_M_E_BYTE5\"
				( memberType ( signal ) )
				( member ( pinPairRef "@baseboard_fab2_lib.baseboard_fab2(sch_1):\PP4371\") )
				( member ( pinPairRef "@baseboard_fab2_lib.baseboard_fab2(sch_1):\PP4374\") )
				( member ( pinPairRef "@baseboard_fab2_lib.baseboard_fab2(sch_1):\PP4377\") )
				( member ( pinPairRef "@baseboard_fab2_lib.baseboard_fab2(sch_1):\PP4380\") )
				( member ( pinPairRef "@baseboard_fab2_lib.baseboard_fab2(sch_1):\PP4383\") )
				( member ( pinPairRef "@baseboard_fab2_lib.baseboard_fab2(sch_1):\PP4386\") )
				( member ( pinPairRef "@baseboard_fab2_lib.baseboard_fab2(sch_1):\PP4389\") )
				( member ( pinPairRef "@baseboard_fab2_lib.baseboard_fab2(sch_1):\PP4392\") )
				( objectStatus "MG_DQ_FAR_DIMM_NG_M_E_BYTE5" )
			)
			( matchGroup "@baseboard_fab2_lib.baseboard_fab2(sch_1):\MG_DQ-DQS_NEAR_DIMM_NG_M_E_BYTE5\"
				( memberType ( signal ) )
				( member ( pinPairRef "@baseboard_fab2_lib.baseboard_fab2(sch_1):\PP4373\") )
				( member ( pinPairRef "@baseboard_fab2_lib.baseboard_fab2(sch_1):\PP4376\") )
				( member ( pinPairRef "@baseboard_fab2_lib.baseboard_fab2(sch_1):\PP4379\") )
				( member ( pinPairRef "@baseboard_fab2_lib.baseboard_fab2(sch_1):\PP4382\") )
				( member ( pinPairRef "@baseboard_fab2_lib.baseboard_fab2(sch_1):\PP4385\") )
				( member ( pinPairRef "@baseboard_fab2_lib.baseboard_fab2(sch_1):\PP4388\") )
				( member ( pinPairRef "@baseboard_fab2_lib.baseboard_fab2(sch_1):\PP4391\") )
				( member ( pinPairRef "@baseboard_fab2_lib.baseboard_fab2(sch_1):\PP4394\") )
				( member ( pinPairRef "@baseboard_fab2_lib.baseboard_fab2(sch_1):\PP1134\") )
				( member ( pinPairRef "@baseboard_fab2_lib.baseboard_fab2(sch_1):\PP1128\") )
				( member ( pinPairRef "@baseboard_fab2_lib.baseboard_fab2(sch_1):\PP1131\") )
				( member ( pinPairRef "@baseboard_fab2_lib.baseboard_fab2(sch_1):\PP1125\") )
				( objectStatus "MG_DQ-DQS_NEAR_DIMM_NG_M_E_BYTE5" )
			)
			( matchGroup "@baseboard_fab2_lib.baseboard_fab2(sch_1):\MG_DQ_NEAR_DIMM_NG_M_E_BYTE5\"
				( memberType ( signal ) )
				( member ( pinPairRef "@baseboard_fab2_lib.baseboard_fab2(sch_1):\PP4373\") )
				( member ( pinPairRef "@baseboard_fab2_lib.baseboard_fab2(sch_1):\PP4376\") )
				( member ( pinPairRef "@baseboard_fab2_lib.baseboard_fab2(sch_1):\PP4379\") )
				( member ( pinPairRef "@baseboard_fab2_lib.baseboard_fab2(sch_1):\PP4382\") )
				( member ( pinPairRef "@baseboard_fab2_lib.baseboard_fab2(sch_1):\PP4385\") )
				( member ( pinPairRef "@baseboard_fab2_lib.baseboard_fab2(sch_1):\PP4388\") )
				( member ( pinPairRef "@baseboard_fab2_lib.baseboard_fab2(sch_1):\PP4391\") )
				( member ( pinPairRef "@baseboard_fab2_lib.baseboard_fab2(sch_1):\PP4394\") )
				( objectStatus "MG_DQ_NEAR_DIMM_NG_M_E_BYTE5" )
			)
			( matchGroup "@baseboard_fab2_lib.baseboard_fab2(sch_1):\MG_DQ-DQS_FAR_DIMM_NG_M_E_BYTE6\"
				( memberType ( signal ) )
				( member ( pinPairRef "@baseboard_fab2_lib.baseboard_fab2(sch_1):\PP4347\") )
				( member ( pinPairRef "@baseboard_fab2_lib.baseboard_fab2(sch_1):\PP4350\") )
				( member ( pinPairRef "@baseboard_fab2_lib.baseboard_fab2(sch_1):\PP4353\") )
				( member ( pinPairRef "@baseboard_fab2_lib.baseboard_fab2(sch_1):\PP4356\") )
				( member ( pinPairRef "@baseboard_fab2_lib.baseboard_fab2(sch_1):\PP4359\") )
				( member ( pinPairRef "@baseboard_fab2_lib.baseboard_fab2(sch_1):\PP4362\") )
				( member ( pinPairRef "@baseboard_fab2_lib.baseboard_fab2(sch_1):\PP4365\") )
				( member ( pinPairRef "@baseboard_fab2_lib.baseboard_fab2(sch_1):\PP4368\") )
				( member ( pinPairRef "@baseboard_fab2_lib.baseboard_fab2(sch_1):\PP1120\") )
				( member ( pinPairRef "@baseboard_fab2_lib.baseboard_fab2(sch_1):\PP1114\") )
				( member ( pinPairRef "@baseboard_fab2_lib.baseboard_fab2(sch_1):\PP1117\") )
				( member ( pinPairRef "@baseboard_fab2_lib.baseboard_fab2(sch_1):\PP1111\") )
				( objectStatus "MG_DQ-DQS_FAR_DIMM_NG_M_E_BYTE6" )
			)
			( matchGroup "@baseboard_fab2_lib.baseboard_fab2(sch_1):\MG_DQ_FAR_DIMM_NG_M_E_BYTE6\"
				( memberType ( signal ) )
				( member ( pinPairRef "@baseboard_fab2_lib.baseboard_fab2(sch_1):\PP4347\") )
				( member ( pinPairRef "@baseboard_fab2_lib.baseboard_fab2(sch_1):\PP4350\") )
				( member ( pinPairRef "@baseboard_fab2_lib.baseboard_fab2(sch_1):\PP4353\") )
				( member ( pinPairRef "@baseboard_fab2_lib.baseboard_fab2(sch_1):\PP4356\") )
				( member ( pinPairRef "@baseboard_fab2_lib.baseboard_fab2(sch_1):\PP4359\") )
				( member ( pinPairRef "@baseboard_fab2_lib.baseboard_fab2(sch_1):\PP4362\") )
				( member ( pinPairRef "@baseboard_fab2_lib.baseboard_fab2(sch_1):\PP4365\") )
				( member ( pinPairRef "@baseboard_fab2_lib.baseboard_fab2(sch_1):\PP4368\") )
				( objectStatus "MG_DQ_FAR_DIMM_NG_M_E_BYTE6" )
			)
			( matchGroup "@baseboard_fab2_lib.baseboard_fab2(sch_1):\MG_DQ-DQS_NEAR_DIMM_NG_M_E_BYTE6\"
				( memberType ( signal ) )
				( member ( pinPairRef "@baseboard_fab2_lib.baseboard_fab2(sch_1):\PP4349\") )
				( member ( pinPairRef "@baseboard_fab2_lib.baseboard_fab2(sch_1):\PP4352\") )
				( member ( pinPairRef "@baseboard_fab2_lib.baseboard_fab2(sch_1):\PP4355\") )
				( member ( pinPairRef "@baseboard_fab2_lib.baseboard_fab2(sch_1):\PP4358\") )
				( member ( pinPairRef "@baseboard_fab2_lib.baseboard_fab2(sch_1):\PP4361\") )
				( member ( pinPairRef "@baseboard_fab2_lib.baseboard_fab2(sch_1):\PP4364\") )
				( member ( pinPairRef "@baseboard_fab2_lib.baseboard_fab2(sch_1):\PP4367\") )
				( member ( pinPairRef "@baseboard_fab2_lib.baseboard_fab2(sch_1):\PP4370\") )
				( member ( pinPairRef "@baseboard_fab2_lib.baseboard_fab2(sch_1):\PP1122\") )
				( member ( pinPairRef "@baseboard_fab2_lib.baseboard_fab2(sch_1):\PP1116\") )
				( member ( pinPairRef "@baseboard_fab2_lib.baseboard_fab2(sch_1):\PP1119\") )
				( member ( pinPairRef "@baseboard_fab2_lib.baseboard_fab2(sch_1):\PP1113\") )
				( objectStatus "MG_DQ-DQS_NEAR_DIMM_NG_M_E_BYTE6" )
			)
			( matchGroup "@baseboard_fab2_lib.baseboard_fab2(sch_1):\MG_DQ_NEAR_DIMM_NG_M_E_BYTE6\"
				( memberType ( signal ) )
				( member ( pinPairRef "@baseboard_fab2_lib.baseboard_fab2(sch_1):\PP4349\") )
				( member ( pinPairRef "@baseboard_fab2_lib.baseboard_fab2(sch_1):\PP4352\") )
				( member ( pinPairRef "@baseboard_fab2_lib.baseboard_fab2(sch_1):\PP4355\") )
				( member ( pinPairRef "@baseboard_fab2_lib.baseboard_fab2(sch_1):\PP4358\") )
				( member ( pinPairRef "@baseboard_fab2_lib.baseboard_fab2(sch_1):\PP4361\") )
				( member ( pinPairRef "@baseboard_fab2_lib.baseboard_fab2(sch_1):\PP4364\") )
				( member ( pinPairRef "@baseboard_fab2_lib.baseboard_fab2(sch_1):\PP4367\") )
				( member ( pinPairRef "@baseboard_fab2_lib.baseboard_fab2(sch_1):\PP4370\") )
				( objectStatus "MG_DQ_NEAR_DIMM_NG_M_E_BYTE6" )
			)
			( matchGroup "@baseboard_fab2_lib.baseboard_fab2(sch_1):\MG_DQ-DQS_FAR_DIMM_NG_M_E_BYTE7\"
				( memberType ( signal ) )
				( member ( pinPairRef "@baseboard_fab2_lib.baseboard_fab2(sch_1):\PP4323\") )
				( member ( pinPairRef "@baseboard_fab2_lib.baseboard_fab2(sch_1):\PP4326\") )
				( member ( pinPairRef "@baseboard_fab2_lib.baseboard_fab2(sch_1):\PP4329\") )
				( member ( pinPairRef "@baseboard_fab2_lib.baseboard_fab2(sch_1):\PP4332\") )
				( member ( pinPairRef "@baseboard_fab2_lib.baseboard_fab2(sch_1):\PP4335\") )
				( member ( pinPairRef "@baseboard_fab2_lib.baseboard_fab2(sch_1):\PP4338\") )
				( member ( pinPairRef "@baseboard_fab2_lib.baseboard_fab2(sch_1):\PP4341\") )
				( member ( pinPairRef "@baseboard_fab2_lib.baseboard_fab2(sch_1):\PP4344\") )
				( member ( pinPairRef "@baseboard_fab2_lib.baseboard_fab2(sch_1):\PP1108\") )
				( member ( pinPairRef "@baseboard_fab2_lib.baseboard_fab2(sch_1):\PP1102\") )
				( member ( pinPairRef "@baseboard_fab2_lib.baseboard_fab2(sch_1):\PP1105\") )
				( member ( pinPairRef "@baseboard_fab2_lib.baseboard_fab2(sch_1):\PP1099\") )
				( objectStatus "MG_DQ-DQS_FAR_DIMM_NG_M_E_BYTE7" )
			)
			( matchGroup "@baseboard_fab2_lib.baseboard_fab2(sch_1):\MG_DQ_FAR_DIMM_NG_M_E_BYTE7\"
				( memberType ( signal ) )
				( member ( pinPairRef "@baseboard_fab2_lib.baseboard_fab2(sch_1):\PP4323\") )
				( member ( pinPairRef "@baseboard_fab2_lib.baseboard_fab2(sch_1):\PP4326\") )
				( member ( pinPairRef "@baseboard_fab2_lib.baseboard_fab2(sch_1):\PP4329\") )
				( member ( pinPairRef "@baseboard_fab2_lib.baseboard_fab2(sch_1):\PP4332\") )
				( member ( pinPairRef "@baseboard_fab2_lib.baseboard_fab2(sch_1):\PP4335\") )
				( member ( pinPairRef "@baseboard_fab2_lib.baseboard_fab2(sch_1):\PP4338\") )
				( member ( pinPairRef "@baseboard_fab2_lib.baseboard_fab2(sch_1):\PP4341\") )
				( member ( pinPairRef "@baseboard_fab2_lib.baseboard_fab2(sch_1):\PP4344\") )
				( objectStatus "MG_DQ_FAR_DIMM_NG_M_E_BYTE7" )
			)
			( matchGroup "@baseboard_fab2_lib.baseboard_fab2(sch_1):\MG_DQ-DQS_NEAR_DIMM_NG_M_E_BYTE7\"
				( memberType ( signal ) )
				( member ( pinPairRef "@baseboard_fab2_lib.baseboard_fab2(sch_1):\PP4325\") )
				( member ( pinPairRef "@baseboard_fab2_lib.baseboard_fab2(sch_1):\PP4328\") )
				( member ( pinPairRef "@baseboard_fab2_lib.baseboard_fab2(sch_1):\PP4331\") )
				( member ( pinPairRef "@baseboard_fab2_lib.baseboard_fab2(sch_1):\PP4334\") )
				( member ( pinPairRef "@baseboard_fab2_lib.baseboard_fab2(sch_1):\PP4337\") )
				( member ( pinPairRef "@baseboard_fab2_lib.baseboard_fab2(sch_1):\PP4340\") )
				( member ( pinPairRef "@baseboard_fab2_lib.baseboard_fab2(sch_1):\PP4343\") )
				( member ( pinPairRef "@baseboard_fab2_lib.baseboard_fab2(sch_1):\PP4346\") )
				( member ( pinPairRef "@baseboard_fab2_lib.baseboard_fab2(sch_1):\PP1110\") )
				( member ( pinPairRef "@baseboard_fab2_lib.baseboard_fab2(sch_1):\PP1104\") )
				( member ( pinPairRef "@baseboard_fab2_lib.baseboard_fab2(sch_1):\PP1107\") )
				( member ( pinPairRef "@baseboard_fab2_lib.baseboard_fab2(sch_1):\PP1101\") )
				( objectStatus "MG_DQ-DQS_NEAR_DIMM_NG_M_E_BYTE7" )
			)
			( matchGroup "@baseboard_fab2_lib.baseboard_fab2(sch_1):\MG_DQ_NEAR_DIMM_NG_M_E_BYTE7\"
				( memberType ( signal ) )
				( member ( pinPairRef "@baseboard_fab2_lib.baseboard_fab2(sch_1):\PP4325\") )
				( member ( pinPairRef "@baseboard_fab2_lib.baseboard_fab2(sch_1):\PP4328\") )
				( member ( pinPairRef "@baseboard_fab2_lib.baseboard_fab2(sch_1):\PP4331\") )
				( member ( pinPairRef "@baseboard_fab2_lib.baseboard_fab2(sch_1):\PP4334\") )
				( member ( pinPairRef "@baseboard_fab2_lib.baseboard_fab2(sch_1):\PP4337\") )
				( member ( pinPairRef "@baseboard_fab2_lib.baseboard_fab2(sch_1):\PP4340\") )
				( member ( pinPairRef "@baseboard_fab2_lib.baseboard_fab2(sch_1):\PP4343\") )
				( member ( pinPairRef "@baseboard_fab2_lib.baseboard_fab2(sch_1):\PP4346\") )
				( objectStatus "MG_DQ_NEAR_DIMM_NG_M_E_BYTE7" )
			)
			( matchGroup "@baseboard_fab2_lib.baseboard_fab2(sch_1):\MG_DQ-DQS_FAR_DIMM_NG_M_F_BYTE0\"
				( memberType ( signal ) )
				( member ( pinPairRef "@baseboard_fab2_lib.baseboard_fab2(sch_1):\PP4251\") )
				( member ( pinPairRef "@baseboard_fab2_lib.baseboard_fab2(sch_1):\PP4254\") )
				( member ( pinPairRef "@baseboard_fab2_lib.baseboard_fab2(sch_1):\PP4257\") )
				( member ( pinPairRef "@baseboard_fab2_lib.baseboard_fab2(sch_1):\PP4260\") )
				( member ( pinPairRef "@baseboard_fab2_lib.baseboard_fab2(sch_1):\PP4263\") )
				( member ( pinPairRef "@baseboard_fab2_lib.baseboard_fab2(sch_1):\PP4266\") )
				( member ( pinPairRef "@baseboard_fab2_lib.baseboard_fab2(sch_1):\PP4269\") )
				( member ( pinPairRef "@baseboard_fab2_lib.baseboard_fab2(sch_1):\PP4272\") )
				( member ( pinPairRef "@baseboard_fab2_lib.baseboard_fab2(sch_1):\PP1081\") )
				( member ( pinPairRef "@baseboard_fab2_lib.baseboard_fab2(sch_1):\PP1075\") )
				( member ( pinPairRef "@baseboard_fab2_lib.baseboard_fab2(sch_1):\PP1084\") )
				( member ( pinPairRef "@baseboard_fab2_lib.baseboard_fab2(sch_1):\PP1078\") )
				( objectStatus "MG_DQ-DQS_FAR_DIMM_NG_M_F_BYTE0" )
			)
			( matchGroup "@crescent_city_bb_fab1_lib.crescent_city_bb_fab1(sch_1):\MG_DQ_FAR_DIMM_NG_M_F_BYTE0\"
				( memberType ( signal ) )
				( member ( pinPairRef "@baseboard_fab2_lib.baseboard_fab2(sch_1):\PP4251\") )
				( member ( pinPairRef "@baseboard_fab2_lib.baseboard_fab2(sch_1):\PP4254\") )
				( member ( pinPairRef "@baseboard_fab2_lib.baseboard_fab2(sch_1):\PP4257\") )
				( member ( pinPairRef "@baseboard_fab2_lib.baseboard_fab2(sch_1):\PP4260\") )
				( member ( pinPairRef "@baseboard_fab2_lib.baseboard_fab2(sch_1):\PP4263\") )
				( member ( pinPairRef "@baseboard_fab2_lib.baseboard_fab2(sch_1):\PP4266\") )
				( member ( pinPairRef "@baseboard_fab2_lib.baseboard_fab2(sch_1):\PP4269\") )
				( member ( pinPairRef "@baseboard_fab2_lib.baseboard_fab2(sch_1):\PP4272\") )
				( objectStatus "MG_DQ_FAR_DIMM_NG_M_F_BYTE0" )
			)
			( matchGroup "@baseboard_fab2_lib.baseboard_fab2(sch_1):\MG_DQ-DQS_NEAR_DIMM_NG_M_F_BYTE0\"
				( memberType ( signal ) )
				( member ( pinPairRef "@baseboard_fab2_lib.baseboard_fab2(sch_1):\PP4253\") )
				( member ( pinPairRef "@baseboard_fab2_lib.baseboard_fab2(sch_1):\PP4256\") )
				( member ( pinPairRef "@baseboard_fab2_lib.baseboard_fab2(sch_1):\PP4259\") )
				( member ( pinPairRef "@baseboard_fab2_lib.baseboard_fab2(sch_1):\PP4262\") )
				( member ( pinPairRef "@baseboard_fab2_lib.baseboard_fab2(sch_1):\PP4265\") )
				( member ( pinPairRef "@baseboard_fab2_lib.baseboard_fab2(sch_1):\PP4268\") )
				( member ( pinPairRef "@baseboard_fab2_lib.baseboard_fab2(sch_1):\PP4271\") )
				( member ( pinPairRef "@baseboard_fab2_lib.baseboard_fab2(sch_1):\PP4274\") )
				( member ( pinPairRef "@baseboard_fab2_lib.baseboard_fab2(sch_1):\PP1082\") )
				( member ( pinPairRef "@baseboard_fab2_lib.baseboard_fab2(sch_1):\PP1076\") )
				( member ( pinPairRef "@baseboard_fab2_lib.baseboard_fab2(sch_1):\PP1085\") )
				( member ( pinPairRef "@baseboard_fab2_lib.baseboard_fab2(sch_1):\PP1079\") )
				( objectStatus "MG_DQ-DQS_NEAR_DIMM_NG_M_F_BYTE0" )
			)
			( matchGroup "@baseboard_fab2_lib.baseboard_fab2(sch_1):\MG_DQ_NEAR_DIMM_NG_M_F_BYTE0\"
				( memberType ( signal ) )
				( member ( pinPairRef "@baseboard_fab2_lib.baseboard_fab2(sch_1):\PP4253\") )
				( member ( pinPairRef "@baseboard_fab2_lib.baseboard_fab2(sch_1):\PP4256\") )
				( member ( pinPairRef "@baseboard_fab2_lib.baseboard_fab2(sch_1):\PP4259\") )
				( member ( pinPairRef "@baseboard_fab2_lib.baseboard_fab2(sch_1):\PP4262\") )
				( member ( pinPairRef "@baseboard_fab2_lib.baseboard_fab2(sch_1):\PP4265\") )
				( member ( pinPairRef "@baseboard_fab2_lib.baseboard_fab2(sch_1):\PP4268\") )
				( member ( pinPairRef "@baseboard_fab2_lib.baseboard_fab2(sch_1):\PP4271\") )
				( member ( pinPairRef "@baseboard_fab2_lib.baseboard_fab2(sch_1):\PP4274\") )
				( objectStatus "MG_DQ_NEAR_DIMM_NG_M_F_BYTE0" )
			)
			( matchGroup "@baseboard_fab2_lib.baseboard_fab2(sch_1):\MG_DQ-DQS_FAR_DIMM_NG_M_C_BYTE0\"
				( memberType ( signal ) )
				( member ( pinPairRef "@baseboard_fab2_lib.baseboard_fab2(sch_1):\PP4878\") )
				( member ( pinPairRef "@baseboard_fab2_lib.baseboard_fab2(sch_1):\PP4881\") )
				( member ( pinPairRef "@baseboard_fab2_lib.baseboard_fab2(sch_1):\PP4884\") )
				( member ( pinPairRef "@baseboard_fab2_lib.baseboard_fab2(sch_1):\PP4887\") )
				( member ( pinPairRef "@baseboard_fab2_lib.baseboard_fab2(sch_1):\PP4890\") )
				( member ( pinPairRef "@baseboard_fab2_lib.baseboard_fab2(sch_1):\PP4893\") )
				( member ( pinPairRef "@baseboard_fab2_lib.baseboard_fab2(sch_1):\PP4896\") )
				( member ( pinPairRef "@baseboard_fab2_lib.baseboard_fab2(sch_1):\PP4875\") )
				( member ( pinPairRef "@baseboard_fab2_lib.baseboard_fab2(sch_1):\PP661\") )
				( member ( pinPairRef "@baseboard_fab2_lib.baseboard_fab2(sch_1):\PP655\") )
				( member ( pinPairRef "@baseboard_fab2_lib.baseboard_fab2(sch_1):\PP664\") )
				( member ( pinPairRef "@baseboard_fab2_lib.baseboard_fab2(sch_1):\PP658\") )
				( objectStatus "MG_DQ-DQS_FAR_DIMM_NG_M_C_BYTE0" )
			)
			( matchGroup "@baseboard_fab2_lib.baseboard_fab2(sch_1):\MG_DQ_FAR_DIMM_NG_M_C_BYTE0\"
				( memberType ( signal ) )
				( member ( pinPairRef "@baseboard_fab2_lib.baseboard_fab2(sch_1):\PP4878\") )
				( member ( pinPairRef "@baseboard_fab2_lib.baseboard_fab2(sch_1):\PP4881\") )
				( member ( pinPairRef "@baseboard_fab2_lib.baseboard_fab2(sch_1):\PP4884\") )
				( member ( pinPairRef "@baseboard_fab2_lib.baseboard_fab2(sch_1):\PP4887\") )
				( member ( pinPairRef "@baseboard_fab2_lib.baseboard_fab2(sch_1):\PP4890\") )
				( member ( pinPairRef "@baseboard_fab2_lib.baseboard_fab2(sch_1):\PP4893\") )
				( member ( pinPairRef "@baseboard_fab2_lib.baseboard_fab2(sch_1):\PP4896\") )
				( member ( pinPairRef "@baseboard_fab2_lib.baseboard_fab2(sch_1):\PP4875\") )
				( objectStatus "MG_DQ_FAR_DIMM_NG_M_C_BYTE0" )
			)
			( matchGroup "@baseboard_fab2_lib.baseboard_fab2(sch_1):\MG_DQ-DQS_NEAR_DIMM_NG_M_C_BYTE0\"
				( memberType ( signal ) )
				( member ( pinPairRef "@baseboard_fab2_lib.baseboard_fab2(sch_1):\PP4880\") )
				( member ( pinPairRef "@baseboard_fab2_lib.baseboard_fab2(sch_1):\PP4883\") )
				( member ( pinPairRef "@baseboard_fab2_lib.baseboard_fab2(sch_1):\PP4886\") )
				( member ( pinPairRef "@baseboard_fab2_lib.baseboard_fab2(sch_1):\PP4889\") )
				( member ( pinPairRef "@baseboard_fab2_lib.baseboard_fab2(sch_1):\PP4892\") )
				( member ( pinPairRef "@baseboard_fab2_lib.baseboard_fab2(sch_1):\PP4895\") )
				( member ( pinPairRef "@baseboard_fab2_lib.baseboard_fab2(sch_1):\PP4898\") )
				( member ( pinPairRef "@baseboard_fab2_lib.baseboard_fab2(sch_1):\PP4877\") )
				( member ( pinPairRef "@baseboard_fab2_lib.baseboard_fab2(sch_1):\PP662\") )
				( member ( pinPairRef "@baseboard_fab2_lib.baseboard_fab2(sch_1):\PP656\") )
				( member ( pinPairRef "@baseboard_fab2_lib.baseboard_fab2(sch_1):\PP665\") )
				( member ( pinPairRef "@baseboard_fab2_lib.baseboard_fab2(sch_1):\PP659\") )
				( objectStatus "MG_DQ-DQS_NEAR_DIMM_NG_M_C_BYTE0" )
			)
			( matchGroup "@baseboard_fab2_lib.baseboard_fab2(sch_1):\MG_DQ_NEAR_DIMM_NG_M_C_BYTE0\"
				( memberType ( signal ) )
				( member ( pinPairRef "@baseboard_fab2_lib.baseboard_fab2(sch_1):\PP4880\") )
				( member ( pinPairRef "@baseboard_fab2_lib.baseboard_fab2(sch_1):\PP4883\") )
				( member ( pinPairRef "@baseboard_fab2_lib.baseboard_fab2(sch_1):\PP4886\") )
				( member ( pinPairRef "@baseboard_fab2_lib.baseboard_fab2(sch_1):\PP4889\") )
				( member ( pinPairRef "@baseboard_fab2_lib.baseboard_fab2(sch_1):\PP4892\") )
				( member ( pinPairRef "@baseboard_fab2_lib.baseboard_fab2(sch_1):\PP4895\") )
				( member ( pinPairRef "@baseboard_fab2_lib.baseboard_fab2(sch_1):\PP4898\") )
				( member ( pinPairRef "@baseboard_fab2_lib.baseboard_fab2(sch_1):\PP4877\") )
				( objectStatus "MG_DQ_NEAR_DIMM_NG_M_C_BYTE0" )
			)
			( matchGroup "@baseboard_fab2_lib.baseboard_fab2(sch_1):\MG_DQ-DQS_FAR_DIMM_NG_M_C_BYTE1\"
				( memberType ( signal ) )
				( member ( pinPairRef "@baseboard_fab2_lib.baseboard_fab2(sch_1):\PP4851\") )
				( member ( pinPairRef "@baseboard_fab2_lib.baseboard_fab2(sch_1):\PP4854\") )
				( member ( pinPairRef "@baseboard_fab2_lib.baseboard_fab2(sch_1):\PP4857\") )
				( member ( pinPairRef "@baseboard_fab2_lib.baseboard_fab2(sch_1):\PP4860\") )
				( member ( pinPairRef "@baseboard_fab2_lib.baseboard_fab2(sch_1):\PP4863\") )
				( member ( pinPairRef "@baseboard_fab2_lib.baseboard_fab2(sch_1):\PP4866\") )
				( member ( pinPairRef "@baseboard_fab2_lib.baseboard_fab2(sch_1):\PP4869\") )
				( member ( pinPairRef "@baseboard_fab2_lib.baseboard_fab2(sch_1):\PP4872\") )
				( member ( pinPairRef "@baseboard_fab2_lib.baseboard_fab2(sch_1):\PP649\") )
				( member ( pinPairRef "@baseboard_fab2_lib.baseboard_fab2(sch_1):\PP643\") )
				( member ( pinPairRef "@baseboard_fab2_lib.baseboard_fab2(sch_1):\PP652\") )
				( member ( pinPairRef "@baseboard_fab2_lib.baseboard_fab2(sch_1):\PP646\") )
				( objectStatus "MG_DQ-DQS_FAR_DIMM_NG_M_C_BYTE1" )
			)
			( matchGroup "@baseboard_fab2_lib.baseboard_fab2(sch_1):\MG_DQ_FAR_DIMM_NG_M_C_BYTE1\"
				( memberType ( signal ) )
				( member ( pinPairRef "@baseboard_fab2_lib.baseboard_fab2(sch_1):\PP4851\") )
				( member ( pinPairRef "@baseboard_fab2_lib.baseboard_fab2(sch_1):\PP4854\") )
				( member ( pinPairRef "@baseboard_fab2_lib.baseboard_fab2(sch_1):\PP4857\") )
				( member ( pinPairRef "@baseboard_fab2_lib.baseboard_fab2(sch_1):\PP4860\") )
				( member ( pinPairRef "@baseboard_fab2_lib.baseboard_fab2(sch_1):\PP4863\") )
				( member ( pinPairRef "@baseboard_fab2_lib.baseboard_fab2(sch_1):\PP4866\") )
				( member ( pinPairRef "@baseboard_fab2_lib.baseboard_fab2(sch_1):\PP4869\") )
				( member ( pinPairRef "@baseboard_fab2_lib.baseboard_fab2(sch_1):\PP4872\") )
				( objectStatus "MG_DQ_FAR_DIMM_NG_M_C_BYTE1" )
			)
			( matchGroup "@baseboard_fab2_lib.baseboard_fab2(sch_1):\MG_DQ-DQS_NEAR_DIMM_NG_M_C_BYTE1\"
				( memberType ( signal ) )
				( member ( pinPairRef "@baseboard_fab2_lib.baseboard_fab2(sch_1):\PP4853\") )
				( member ( pinPairRef "@baseboard_fab2_lib.baseboard_fab2(sch_1):\PP4856\") )
				( member ( pinPairRef "@baseboard_fab2_lib.baseboard_fab2(sch_1):\PP4859\") )
				( member ( pinPairRef "@baseboard_fab2_lib.baseboard_fab2(sch_1):\PP4862\") )
				( member ( pinPairRef "@baseboard_fab2_lib.baseboard_fab2(sch_1):\PP4865\") )
				( member ( pinPairRef "@baseboard_fab2_lib.baseboard_fab2(sch_1):\PP4868\") )
				( member ( pinPairRef "@baseboard_fab2_lib.baseboard_fab2(sch_1):\PP4871\") )
				( member ( pinPairRef "@baseboard_fab2_lib.baseboard_fab2(sch_1):\PP4874\") )
				( member ( pinPairRef "@baseboard_fab2_lib.baseboard_fab2(sch_1):\PP650\") )
				( member ( pinPairRef "@baseboard_fab2_lib.baseboard_fab2(sch_1):\PP644\") )
				( member ( pinPairRef "@baseboard_fab2_lib.baseboard_fab2(sch_1):\PP653\") )
				( member ( pinPairRef "@baseboard_fab2_lib.baseboard_fab2(sch_1):\PP647\") )
				( objectStatus "MG_DQ-DQS_NEAR_DIMM_NG_M_C_BYTE1" )
			)
			( matchGroup "@baseboard_fab2_lib.baseboard_fab2(sch_1):\MG_DQ_NEAR_DIMM_NG_M_C_BYTE1\"
				( memberType ( signal ) )
				( member ( pinPairRef "@baseboard_fab2_lib.baseboard_fab2(sch_1):\PP4853\") )
				( member ( pinPairRef "@baseboard_fab2_lib.baseboard_fab2(sch_1):\PP4856\") )
				( member ( pinPairRef "@baseboard_fab2_lib.baseboard_fab2(sch_1):\PP4859\") )
				( member ( pinPairRef "@baseboard_fab2_lib.baseboard_fab2(sch_1):\PP4862\") )
				( member ( pinPairRef "@baseboard_fab2_lib.baseboard_fab2(sch_1):\PP4865\") )
				( member ( pinPairRef "@baseboard_fab2_lib.baseboard_fab2(sch_1):\PP4868\") )
				( member ( pinPairRef "@baseboard_fab2_lib.baseboard_fab2(sch_1):\PP4871\") )
				( member ( pinPairRef "@baseboard_fab2_lib.baseboard_fab2(sch_1):\PP4874\") )
				( objectStatus "MG_DQ_NEAR_DIMM_NG_M_C_BYTE1" )
			)
			( matchGroup "@baseboard_fab2_lib.baseboard_fab2(sch_1):\MG_DQ-DQS_FAR_DIMM_NG_M_C_BYTE2\"
				( memberType ( signal ) )
				( member ( pinPairRef "@baseboard_fab2_lib.baseboard_fab2(sch_1):\PP4827\") )
				( member ( pinPairRef "@baseboard_fab2_lib.baseboard_fab2(sch_1):\PP4830\") )
				( member ( pinPairRef "@baseboard_fab2_lib.baseboard_fab2(sch_1):\PP4833\") )
				( member ( pinPairRef "@baseboard_fab2_lib.baseboard_fab2(sch_1):\PP4836\") )
				( member ( pinPairRef "@baseboard_fab2_lib.baseboard_fab2(sch_1):\PP4839\") )
				( member ( pinPairRef "@baseboard_fab2_lib.baseboard_fab2(sch_1):\PP4842\") )
				( member ( pinPairRef "@baseboard_fab2_lib.baseboard_fab2(sch_1):\PP4845\") )
				( member ( pinPairRef "@baseboard_fab2_lib.baseboard_fab2(sch_1):\PP4848\") )
				( member ( pinPairRef "@baseboard_fab2_lib.baseboard_fab2(sch_1):\PP637\") )
				( member ( pinPairRef "@baseboard_fab2_lib.baseboard_fab2(sch_1):\PP631\") )
				( member ( pinPairRef "@baseboard_fab2_lib.baseboard_fab2(sch_1):\PP640\") )
				( member ( pinPairRef "@baseboard_fab2_lib.baseboard_fab2(sch_1):\PP634\") )
				( objectStatus "MG_DQ-DQS_FAR_DIMM_NG_M_C_BYTE2" )
			)
			( matchGroup "@baseboard_fab2_lib.baseboard_fab2(sch_1):\MG_DQ_FAR_DIMM_NG_M_C_BYTE2\"
				( memberType ( signal ) )
				( member ( pinPairRef "@baseboard_fab2_lib.baseboard_fab2(sch_1):\PP4827\") )
				( member ( pinPairRef "@baseboard_fab2_lib.baseboard_fab2(sch_1):\PP4830\") )
				( member ( pinPairRef "@baseboard_fab2_lib.baseboard_fab2(sch_1):\PP4833\") )
				( member ( pinPairRef "@baseboard_fab2_lib.baseboard_fab2(sch_1):\PP4836\") )
				( member ( pinPairRef "@baseboard_fab2_lib.baseboard_fab2(sch_1):\PP4839\") )
				( member ( pinPairRef "@baseboard_fab2_lib.baseboard_fab2(sch_1):\PP4842\") )
				( member ( pinPairRef "@baseboard_fab2_lib.baseboard_fab2(sch_1):\PP4845\") )
				( member ( pinPairRef "@baseboard_fab2_lib.baseboard_fab2(sch_1):\PP4848\") )
				( objectStatus "MG_DQ_FAR_DIMM_NG_M_C_BYTE2" )
			)
			( matchGroup "@baseboard_fab2_lib.baseboard_fab2(sch_1):\MG_DQ-DQS_NEAR_DIMM_NG_M_C_BYTE2\"
				( memberType ( signal ) )
				( member ( pinPairRef "@baseboard_fab2_lib.baseboard_fab2(sch_1):\PP4829\") )
				( member ( pinPairRef "@baseboard_fab2_lib.baseboard_fab2(sch_1):\PP4832\") )
				( member ( pinPairRef "@baseboard_fab2_lib.baseboard_fab2(sch_1):\PP4835\") )
				( member ( pinPairRef "@baseboard_fab2_lib.baseboard_fab2(sch_1):\PP4838\") )
				( member ( pinPairRef "@baseboard_fab2_lib.baseboard_fab2(sch_1):\PP4841\") )
				( member ( pinPairRef "@baseboard_fab2_lib.baseboard_fab2(sch_1):\PP4844\") )
				( member ( pinPairRef "@baseboard_fab2_lib.baseboard_fab2(sch_1):\PP4847\") )
				( member ( pinPairRef "@baseboard_fab2_lib.baseboard_fab2(sch_1):\PP4850\") )
				( member ( pinPairRef "@baseboard_fab2_lib.baseboard_fab2(sch_1):\PP638\") )
				( member ( pinPairRef "@baseboard_fab2_lib.baseboard_fab2(sch_1):\PP632\") )
				( member ( pinPairRef "@baseboard_fab2_lib.baseboard_fab2(sch_1):\PP641\") )
				( member ( pinPairRef "@baseboard_fab2_lib.baseboard_fab2(sch_1):\PP635\") )
				( objectStatus "MG_DQ-DQS_NEAR_DIMM_NG_M_C_BYTE2" )
			)
			( matchGroup "@baseboard_fab2_lib.baseboard_fab2(sch_1):\MG_DQ_NEAR_DIMM_NG_M_C_BYTE2\"
				( memberType ( signal ) )
				( member ( pinPairRef "@baseboard_fab2_lib.baseboard_fab2(sch_1):\PP4829\") )
				( member ( pinPairRef "@baseboard_fab2_lib.baseboard_fab2(sch_1):\PP4832\") )
				( member ( pinPairRef "@baseboard_fab2_lib.baseboard_fab2(sch_1):\PP4835\") )
				( member ( pinPairRef "@baseboard_fab2_lib.baseboard_fab2(sch_1):\PP4838\") )
				( member ( pinPairRef "@baseboard_fab2_lib.baseboard_fab2(sch_1):\PP4841\") )
				( member ( pinPairRef "@baseboard_fab2_lib.baseboard_fab2(sch_1):\PP4844\") )
				( member ( pinPairRef "@baseboard_fab2_lib.baseboard_fab2(sch_1):\PP4847\") )
				( member ( pinPairRef "@baseboard_fab2_lib.baseboard_fab2(sch_1):\PP4850\") )
				( objectStatus "MG_DQ_NEAR_DIMM_NG_M_C_BYTE2" )
			)
			( matchGroup "@baseboard_fab2_lib.baseboard_fab2(sch_1):\MG_DQ-DQS_FAR_DIMM_NG_M_C_BYTE3\"
				( memberType ( signal ) )
				( member ( pinPairRef "@baseboard_fab2_lib.baseboard_fab2(sch_1):\PP4803\") )
				( member ( pinPairRef "@baseboard_fab2_lib.baseboard_fab2(sch_1):\PP4806\") )
				( member ( pinPairRef "@baseboard_fab2_lib.baseboard_fab2(sch_1):\PP4809\") )
				( member ( pinPairRef "@baseboard_fab2_lib.baseboard_fab2(sch_1):\PP4812\") )
				( member ( pinPairRef "@baseboard_fab2_lib.baseboard_fab2(sch_1):\PP4815\") )
				( member ( pinPairRef "@baseboard_fab2_lib.baseboard_fab2(sch_1):\PP4818\") )
				( member ( pinPairRef "@baseboard_fab2_lib.baseboard_fab2(sch_1):\PP4821\") )
				( member ( pinPairRef "@baseboard_fab2_lib.baseboard_fab2(sch_1):\PP4824\") )
				( member ( pinPairRef "@baseboard_fab2_lib.baseboard_fab2(sch_1):\PP625\") )
				( member ( pinPairRef "@baseboard_fab2_lib.baseboard_fab2(sch_1):\PP619\") )
				( member ( pinPairRef "@baseboard_fab2_lib.baseboard_fab2(sch_1):\PP628\") )
				( member ( pinPairRef "@baseboard_fab2_lib.baseboard_fab2(sch_1):\PP622\") )
				( objectStatus "MG_DQ-DQS_FAR_DIMM_NG_M_C_BYTE3" )
			)
			( matchGroup "@baseboard_fab2_lib.baseboard_fab2(sch_1):\MG_DQ_FAR_DIMM_NG_M_C_BYTE3\"
				( memberType ( signal ) )
				( member ( pinPairRef "@baseboard_fab2_lib.baseboard_fab2(sch_1):\PP4803\") )
				( member ( pinPairRef "@baseboard_fab2_lib.baseboard_fab2(sch_1):\PP4806\") )
				( member ( pinPairRef "@baseboard_fab2_lib.baseboard_fab2(sch_1):\PP4809\") )
				( member ( pinPairRef "@baseboard_fab2_lib.baseboard_fab2(sch_1):\PP4812\") )
				( member ( pinPairRef "@baseboard_fab2_lib.baseboard_fab2(sch_1):\PP4815\") )
				( member ( pinPairRef "@baseboard_fab2_lib.baseboard_fab2(sch_1):\PP4818\") )
				( member ( pinPairRef "@baseboard_fab2_lib.baseboard_fab2(sch_1):\PP4821\") )
				( member ( pinPairRef "@baseboard_fab2_lib.baseboard_fab2(sch_1):\PP4824\") )
				( objectStatus "MG_DQ_FAR_DIMM_NG_M_C_BYTE3" )
			)
			( matchGroup "@baseboard_fab2_lib.baseboard_fab2(sch_1):\MG_DQ-DQS_NEAR_DIMM_NG_M_C_BYTE3\"
				( memberType ( signal ) )
				( member ( pinPairRef "@baseboard_fab2_lib.baseboard_fab2(sch_1):\PP4805\") )
				( member ( pinPairRef "@baseboard_fab2_lib.baseboard_fab2(sch_1):\PP4808\") )
				( member ( pinPairRef "@baseboard_fab2_lib.baseboard_fab2(sch_1):\PP4811\") )
				( member ( pinPairRef "@baseboard_fab2_lib.baseboard_fab2(sch_1):\PP4814\") )
				( member ( pinPairRef "@baseboard_fab2_lib.baseboard_fab2(sch_1):\PP4817\") )
				( member ( pinPairRef "@baseboard_fab2_lib.baseboard_fab2(sch_1):\PP4820\") )
				( member ( pinPairRef "@baseboard_fab2_lib.baseboard_fab2(sch_1):\PP4823\") )
				( member ( pinPairRef "@baseboard_fab2_lib.baseboard_fab2(sch_1):\PP4826\") )
				( member ( pinPairRef "@baseboard_fab2_lib.baseboard_fab2(sch_1):\PP626\") )
				( member ( pinPairRef "@baseboard_fab2_lib.baseboard_fab2(sch_1):\PP620\") )
				( member ( pinPairRef "@baseboard_fab2_lib.baseboard_fab2(sch_1):\PP629\") )
				( member ( pinPairRef "@baseboard_fab2_lib.baseboard_fab2(sch_1):\PP623\") )
				( objectStatus "MG_DQ-DQS_NEAR_DIMM_NG_M_C_BYTE3" )
			)
			( matchGroup "@baseboard_fab2_lib.baseboard_fab2(sch_1):\MG_DQ_NEAR_DIMM_NG_M_C_BYTE3\"
				( memberType ( signal ) )
				( member ( pinPairRef "@baseboard_fab2_lib.baseboard_fab2(sch_1):\PP4805\") )
				( member ( pinPairRef "@baseboard_fab2_lib.baseboard_fab2(sch_1):\PP4808\") )
				( member ( pinPairRef "@baseboard_fab2_lib.baseboard_fab2(sch_1):\PP4811\") )
				( member ( pinPairRef "@baseboard_fab2_lib.baseboard_fab2(sch_1):\PP4814\") )
				( member ( pinPairRef "@baseboard_fab2_lib.baseboard_fab2(sch_1):\PP4817\") )
				( member ( pinPairRef "@baseboard_fab2_lib.baseboard_fab2(sch_1):\PP4820\") )
				( member ( pinPairRef "@baseboard_fab2_lib.baseboard_fab2(sch_1):\PP4823\") )
				( member ( pinPairRef "@baseboard_fab2_lib.baseboard_fab2(sch_1):\PP4826\") )
				( objectStatus "MG_DQ_NEAR_DIMM_NG_M_C_BYTE3" )
			)
			( matchGroup "@baseboard_fab2_lib.baseboard_fab2(sch_1):\MG_DQ-DQS_FAR_DIMM_NG_M_C_BYTE4\"
				( memberType ( signal ) )
				( member ( pinPairRef "@baseboard_fab2_lib.baseboard_fab2(sch_1):\PP4779\") )
				( member ( pinPairRef "@baseboard_fab2_lib.baseboard_fab2(sch_1):\PP4782\") )
				( member ( pinPairRef "@baseboard_fab2_lib.baseboard_fab2(sch_1):\PP4785\") )
				( member ( pinPairRef "@baseboard_fab2_lib.baseboard_fab2(sch_1):\PP4788\") )
				( member ( pinPairRef "@baseboard_fab2_lib.baseboard_fab2(sch_1):\PP4791\") )
				( member ( pinPairRef "@baseboard_fab2_lib.baseboard_fab2(sch_1):\PP4794\") )
				( member ( pinPairRef "@baseboard_fab2_lib.baseboard_fab2(sch_1):\PP4797\") )
				( member ( pinPairRef "@baseboard_fab2_lib.baseboard_fab2(sch_1):\PP4800\") )
				( member ( pinPairRef "@baseboard_fab2_lib.baseboard_fab2(sch_1):\PP613\") )
				( member ( pinPairRef "@baseboard_fab2_lib.baseboard_fab2(sch_1):\PP607\") )
				( member ( pinPairRef "@baseboard_fab2_lib.baseboard_fab2(sch_1):\PP616\") )
				( member ( pinPairRef "@baseboard_fab2_lib.baseboard_fab2(sch_1):\PP610\") )
				( objectStatus "MG_DQ-DQS_FAR_DIMM_NG_M_C_BYTE4" )
			)
			( matchGroup "@baseboard_fab2_lib.baseboard_fab2(sch_1):\MG_DQ_FAR_DIMM_NG_M_C_BYTE4\"
				( memberType ( signal ) )
				( member ( pinPairRef "@baseboard_fab2_lib.baseboard_fab2(sch_1):\PP4779\") )
				( member ( pinPairRef "@baseboard_fab2_lib.baseboard_fab2(sch_1):\PP4782\") )
				( member ( pinPairRef "@baseboard_fab2_lib.baseboard_fab2(sch_1):\PP4785\") )
				( member ( pinPairRef "@baseboard_fab2_lib.baseboard_fab2(sch_1):\PP4788\") )
				( member ( pinPairRef "@baseboard_fab2_lib.baseboard_fab2(sch_1):\PP4791\") )
				( member ( pinPairRef "@baseboard_fab2_lib.baseboard_fab2(sch_1):\PP4794\") )
				( member ( pinPairRef "@baseboard_fab2_lib.baseboard_fab2(sch_1):\PP4797\") )
				( member ( pinPairRef "@baseboard_fab2_lib.baseboard_fab2(sch_1):\PP4800\") )
				( objectStatus "MG_DQ_FAR_DIMM_NG_M_C_BYTE4" )
			)
			( matchGroup "@baseboard_fab2_lib.baseboard_fab2(sch_1):\MG_DQ-DQS_NEAR_DIMM_NG_M_C_BYTE4\"
				( memberType ( signal ) )
				( member ( pinPairRef "@baseboard_fab2_lib.baseboard_fab2(sch_1):\PP4781\") )
				( member ( pinPairRef "@baseboard_fab2_lib.baseboard_fab2(sch_1):\PP4784\") )
				( member ( pinPairRef "@baseboard_fab2_lib.baseboard_fab2(sch_1):\PP4787\") )
				( member ( pinPairRef "@baseboard_fab2_lib.baseboard_fab2(sch_1):\PP4790\") )
				( member ( pinPairRef "@baseboard_fab2_lib.baseboard_fab2(sch_1):\PP4793\") )
				( member ( pinPairRef "@baseboard_fab2_lib.baseboard_fab2(sch_1):\PP4796\") )
				( member ( pinPairRef "@baseboard_fab2_lib.baseboard_fab2(sch_1):\PP4799\") )
				( member ( pinPairRef "@baseboard_fab2_lib.baseboard_fab2(sch_1):\PP4802\") )
				( member ( pinPairRef "@baseboard_fab2_lib.baseboard_fab2(sch_1):\PP615\") )
				( member ( pinPairRef "@baseboard_fab2_lib.baseboard_fab2(sch_1):\PP609\") )
				( member ( pinPairRef "@baseboard_fab2_lib.baseboard_fab2(sch_1):\PP618\") )
				( member ( pinPairRef "@baseboard_fab2_lib.baseboard_fab2(sch_1):\PP612\") )
				( objectStatus "MG_DQ-DQS_NEAR_DIMM_NG_M_C_BYTE4" )
			)
			( matchGroup "@baseboard_fab2_lib.baseboard_fab2(sch_1):\MG_DQ_NEAR_DIMM_NG_M_C_BYTE4\"
				( memberType ( signal ) )
				( member ( pinPairRef "@baseboard_fab2_lib.baseboard_fab2(sch_1):\PP4781\") )
				( member ( pinPairRef "@baseboard_fab2_lib.baseboard_fab2(sch_1):\PP4784\") )
				( member ( pinPairRef "@baseboard_fab2_lib.baseboard_fab2(sch_1):\PP4787\") )
				( member ( pinPairRef "@baseboard_fab2_lib.baseboard_fab2(sch_1):\PP4790\") )
				( member ( pinPairRef "@baseboard_fab2_lib.baseboard_fab2(sch_1):\PP4793\") )
				( member ( pinPairRef "@baseboard_fab2_lib.baseboard_fab2(sch_1):\PP4796\") )
				( member ( pinPairRef "@baseboard_fab2_lib.baseboard_fab2(sch_1):\PP4799\") )
				( member ( pinPairRef "@baseboard_fab2_lib.baseboard_fab2(sch_1):\PP4802\") )
				( objectStatus "MG_DQ_NEAR_DIMM_NG_M_C_BYTE4" )
			)
			( matchGroup "@baseboard_fab2_lib.baseboard_fab2(sch_1):\MG_DQ-DQS_FAR_DIMM_NG_M_C_BYTE5\"
				( memberType ( signal ) )
				( member ( pinPairRef "@baseboard_fab2_lib.baseboard_fab2(sch_1):\PP4755\") )
				( member ( pinPairRef "@baseboard_fab2_lib.baseboard_fab2(sch_1):\PP4758\") )
				( member ( pinPairRef "@baseboard_fab2_lib.baseboard_fab2(sch_1):\PP4761\") )
				( member ( pinPairRef "@baseboard_fab2_lib.baseboard_fab2(sch_1):\PP4764\") )
				( member ( pinPairRef "@baseboard_fab2_lib.baseboard_fab2(sch_1):\PP4767\") )
				( member ( pinPairRef "@baseboard_fab2_lib.baseboard_fab2(sch_1):\PP4770\") )
				( member ( pinPairRef "@baseboard_fab2_lib.baseboard_fab2(sch_1):\PP4773\") )
				( member ( pinPairRef "@baseboard_fab2_lib.baseboard_fab2(sch_1):\PP4776\") )
				( member ( pinPairRef "@baseboard_fab2_lib.baseboard_fab2(sch_1):\PP601\") )
				( member ( pinPairRef "@baseboard_fab2_lib.baseboard_fab2(sch_1):\PP595\") )
				( member ( pinPairRef "@baseboard_fab2_lib.baseboard_fab2(sch_1):\PP604\") )
				( member ( pinPairRef "@baseboard_fab2_lib.baseboard_fab2(sch_1):\PP598\") )
				( objectStatus "MG_DQ-DQS_FAR_DIMM_NG_M_C_BYTE5" )
			)
			( matchGroup "@baseboard_fab2_lib.baseboard_fab2(sch_1):\MG_DQ_FAR_DIMM_NG_M_C_BYTE5\"
				( memberType ( signal ) )
				( member ( pinPairRef "@baseboard_fab2_lib.baseboard_fab2(sch_1):\PP4755\") )
				( member ( pinPairRef "@baseboard_fab2_lib.baseboard_fab2(sch_1):\PP4758\") )
				( member ( pinPairRef "@baseboard_fab2_lib.baseboard_fab2(sch_1):\PP4761\") )
				( member ( pinPairRef "@baseboard_fab2_lib.baseboard_fab2(sch_1):\PP4764\") )
				( member ( pinPairRef "@baseboard_fab2_lib.baseboard_fab2(sch_1):\PP4767\") )
				( member ( pinPairRef "@baseboard_fab2_lib.baseboard_fab2(sch_1):\PP4770\") )
				( member ( pinPairRef "@baseboard_fab2_lib.baseboard_fab2(sch_1):\PP4773\") )
				( member ( pinPairRef "@baseboard_fab2_lib.baseboard_fab2(sch_1):\PP4776\") )
				( objectStatus "MG_DQ_FAR_DIMM_NG_M_C_BYTE5" )
			)
			( matchGroup "@baseboard_fab2_lib.baseboard_fab2(sch_1):\MG_DQ-DQS_NEAR_DIMM_NG_M_C_BYTE5\"
				( memberType ( signal ) )
				( member ( pinPairRef "@baseboard_fab2_lib.baseboard_fab2(sch_1):\PP4757\") )
				( member ( pinPairRef "@baseboard_fab2_lib.baseboard_fab2(sch_1):\PP4760\") )
				( member ( pinPairRef "@baseboard_fab2_lib.baseboard_fab2(sch_1):\PP4763\") )
				( member ( pinPairRef "@baseboard_fab2_lib.baseboard_fab2(sch_1):\PP4766\") )
				( member ( pinPairRef "@baseboard_fab2_lib.baseboard_fab2(sch_1):\PP4769\") )
				( member ( pinPairRef "@baseboard_fab2_lib.baseboard_fab2(sch_1):\PP4772\") )
				( member ( pinPairRef "@baseboard_fab2_lib.baseboard_fab2(sch_1):\PP4775\") )
				( member ( pinPairRef "@baseboard_fab2_lib.baseboard_fab2(sch_1):\PP4778\") )
				( member ( pinPairRef "@baseboard_fab2_lib.baseboard_fab2(sch_1):\PP603\") )
				( member ( pinPairRef "@baseboard_fab2_lib.baseboard_fab2(sch_1):\PP597\") )
				( member ( pinPairRef "@baseboard_fab2_lib.baseboard_fab2(sch_1):\PP606\") )
				( member ( pinPairRef "@baseboard_fab2_lib.baseboard_fab2(sch_1):\PP600\") )
				( objectStatus "MG_DQ-DQS_NEAR_DIMM_NG_M_C_BYTE5" )
			)
			( matchGroup "@baseboard_fab2_lib.baseboard_fab2(sch_1):\MG_DQ_NEAR_DIMM_NG_M_C_BYTE5\"
				( memberType ( signal ) )
				( member ( pinPairRef "@baseboard_fab2_lib.baseboard_fab2(sch_1):\PP4757\") )
				( member ( pinPairRef "@baseboard_fab2_lib.baseboard_fab2(sch_1):\PP4760\") )
				( member ( pinPairRef "@baseboard_fab2_lib.baseboard_fab2(sch_1):\PP4763\") )
				( member ( pinPairRef "@baseboard_fab2_lib.baseboard_fab2(sch_1):\PP4766\") )
				( member ( pinPairRef "@baseboard_fab2_lib.baseboard_fab2(sch_1):\PP4769\") )
				( member ( pinPairRef "@baseboard_fab2_lib.baseboard_fab2(sch_1):\PP4772\") )
				( member ( pinPairRef "@baseboard_fab2_lib.baseboard_fab2(sch_1):\PP4775\") )
				( member ( pinPairRef "@baseboard_fab2_lib.baseboard_fab2(sch_1):\PP4778\") )
				( objectStatus "MG_DQ_NEAR_DIMM_NG_M_C_BYTE5" )
			)
			( matchGroup "@baseboard_fab2_lib.baseboard_fab2(sch_1):\MG_DQ-DQS_FAR_DIMM_NG_M_C_BYTE6\"
				( memberType ( signal ) )
				( member ( pinPairRef "@baseboard_fab2_lib.baseboard_fab2(sch_1):\PP4731\") )
				( member ( pinPairRef "@baseboard_fab2_lib.baseboard_fab2(sch_1):\PP4734\") )
				( member ( pinPairRef "@baseboard_fab2_lib.baseboard_fab2(sch_1):\PP4737\") )
				( member ( pinPairRef "@baseboard_fab2_lib.baseboard_fab2(sch_1):\PP4740\") )
				( member ( pinPairRef "@baseboard_fab2_lib.baseboard_fab2(sch_1):\PP4743\") )
				( member ( pinPairRef "@baseboard_fab2_lib.baseboard_fab2(sch_1):\PP4746\") )
				( member ( pinPairRef "@baseboard_fab2_lib.baseboard_fab2(sch_1):\PP4749\") )
				( member ( pinPairRef "@baseboard_fab2_lib.baseboard_fab2(sch_1):\PP4752\") )
				( member ( pinPairRef "@baseboard_fab2_lib.baseboard_fab2(sch_1):\PP589\") )
				( member ( pinPairRef "@baseboard_fab2_lib.baseboard_fab2(sch_1):\PP583\") )
				( member ( pinPairRef "@baseboard_fab2_lib.baseboard_fab2(sch_1):\PP592\") )
				( member ( pinPairRef "@baseboard_fab2_lib.baseboard_fab2(sch_1):\PP586\") )
				( objectStatus "MG_DQ-DQS_FAR_DIMM_NG_M_C_BYTE6" )
			)
			( matchGroup "@crescent_city_bb_fab1_lib.crescent_city_bb_fab1(sch_1):\MG_DQ_FAR_DIMM_NG_M_C_BYTE6\"
				( memberType ( signal ) )
				( member ( pinPairRef "@baseboard_fab2_lib.baseboard_fab2(sch_1):\PP4731\") )
				( member ( pinPairRef "@baseboard_fab2_lib.baseboard_fab2(sch_1):\PP4734\") )
				( member ( pinPairRef "@baseboard_fab2_lib.baseboard_fab2(sch_1):\PP4737\") )
				( member ( pinPairRef "@baseboard_fab2_lib.baseboard_fab2(sch_1):\PP4740\") )
				( member ( pinPairRef "@baseboard_fab2_lib.baseboard_fab2(sch_1):\PP4743\") )
				( member ( pinPairRef "@baseboard_fab2_lib.baseboard_fab2(sch_1):\PP4746\") )
				( member ( pinPairRef "@baseboard_fab2_lib.baseboard_fab2(sch_1):\PP4749\") )
				( member ( pinPairRef "@baseboard_fab2_lib.baseboard_fab2(sch_1):\PP4752\") )
				( objectStatus "MG_DQ_FAR_DIMM_NG_M_C_BYTE6" )
			)
			( matchGroup "@baseboard_fab2_lib.baseboard_fab2(sch_1):\MG_DQ-DQS_NEAR_DIMM_NG_M_C_BYTE6\"
				( memberType ( signal ) )
				( member ( pinPairRef "@baseboard_fab2_lib.baseboard_fab2(sch_1):\PP4733\") )
				( member ( pinPairRef "@baseboard_fab2_lib.baseboard_fab2(sch_1):\PP4736\") )
				( member ( pinPairRef "@baseboard_fab2_lib.baseboard_fab2(sch_1):\PP4739\") )
				( member ( pinPairRef "@baseboard_fab2_lib.baseboard_fab2(sch_1):\PP4742\") )
				( member ( pinPairRef "@baseboard_fab2_lib.baseboard_fab2(sch_1):\PP4745\") )
				( member ( pinPairRef "@baseboard_fab2_lib.baseboard_fab2(sch_1):\PP4748\") )
				( member ( pinPairRef "@baseboard_fab2_lib.baseboard_fab2(sch_1):\PP4751\") )
				( member ( pinPairRef "@baseboard_fab2_lib.baseboard_fab2(sch_1):\PP4754\") )
				( member ( pinPairRef "@baseboard_fab2_lib.baseboard_fab2(sch_1):\PP591\") )
				( member ( pinPairRef "@baseboard_fab2_lib.baseboard_fab2(sch_1):\PP585\") )
				( member ( pinPairRef "@baseboard_fab2_lib.baseboard_fab2(sch_1):\PP594\") )
				( member ( pinPairRef "@baseboard_fab2_lib.baseboard_fab2(sch_1):\PP588\") )
				( objectStatus "MG_DQ-DQS_NEAR_DIMM_NG_M_C_BYTE6" )
			)
			( matchGroup "@crescent_city_bb_fab1_lib.crescent_city_bb_fab1(sch_1):\MG_DQ_NEAR_DIMM_NG_M_C_BYTE6\"
				( memberType ( signal ) )
				( member ( pinPairRef "@baseboard_fab2_lib.baseboard_fab2(sch_1):\PP4733\") )
				( member ( pinPairRef "@baseboard_fab2_lib.baseboard_fab2(sch_1):\PP4736\") )
				( member ( pinPairRef "@baseboard_fab2_lib.baseboard_fab2(sch_1):\PP4739\") )
				( member ( pinPairRef "@baseboard_fab2_lib.baseboard_fab2(sch_1):\PP4742\") )
				( member ( pinPairRef "@baseboard_fab2_lib.baseboard_fab2(sch_1):\PP4745\") )
				( member ( pinPairRef "@baseboard_fab2_lib.baseboard_fab2(sch_1):\PP4748\") )
				( member ( pinPairRef "@baseboard_fab2_lib.baseboard_fab2(sch_1):\PP4751\") )
				( member ( pinPairRef "@baseboard_fab2_lib.baseboard_fab2(sch_1):\PP4754\") )
				( objectStatus "MG_DQ_NEAR_DIMM_NG_M_C_BYTE6" )
			)
			( matchGroup "@baseboard_fab2_lib.baseboard_fab2(sch_1):\MG_DQ-DQS_FAR_DIMM_NG_M_C_BYTE7\"
				( memberType ( signal ) )
				( member ( pinPairRef "@baseboard_fab2_lib.baseboard_fab2(sch_1):\PP4707\") )
				( member ( pinPairRef "@baseboard_fab2_lib.baseboard_fab2(sch_1):\PP4710\") )
				( member ( pinPairRef "@baseboard_fab2_lib.baseboard_fab2(sch_1):\PP4713\") )
				( member ( pinPairRef "@baseboard_fab2_lib.baseboard_fab2(sch_1):\PP4716\") )
				( member ( pinPairRef "@baseboard_fab2_lib.baseboard_fab2(sch_1):\PP4719\") )
				( member ( pinPairRef "@baseboard_fab2_lib.baseboard_fab2(sch_1):\PP4722\") )
				( member ( pinPairRef "@baseboard_fab2_lib.baseboard_fab2(sch_1):\PP4725\") )
				( member ( pinPairRef "@baseboard_fab2_lib.baseboard_fab2(sch_1):\PP4728\") )
				( member ( pinPairRef "@baseboard_fab2_lib.baseboard_fab2(sch_1):\PP577\") )
				( member ( pinPairRef "@baseboard_fab2_lib.baseboard_fab2(sch_1):\PP571\") )
				( member ( pinPairRef "@baseboard_fab2_lib.baseboard_fab2(sch_1):\PP580\") )
				( member ( pinPairRef "@baseboard_fab2_lib.baseboard_fab2(sch_1):\PP574\") )
				( objectStatus "MG_DQ-DQS_FAR_DIMM_NG_M_C_BYTE7" )
			)
			( matchGroup "@baseboard_fab2_lib.baseboard_fab2(sch_1):\MG_DQ_FAR_DIMM_NG_M_C_BYTE7\"
				( memberType ( signal ) )
				( member ( pinPairRef "@baseboard_fab2_lib.baseboard_fab2(sch_1):\PP4707\") )
				( member ( pinPairRef "@baseboard_fab2_lib.baseboard_fab2(sch_1):\PP4710\") )
				( member ( pinPairRef "@baseboard_fab2_lib.baseboard_fab2(sch_1):\PP4713\") )
				( member ( pinPairRef "@baseboard_fab2_lib.baseboard_fab2(sch_1):\PP4716\") )
				( member ( pinPairRef "@baseboard_fab2_lib.baseboard_fab2(sch_1):\PP4719\") )
				( member ( pinPairRef "@baseboard_fab2_lib.baseboard_fab2(sch_1):\PP4722\") )
				( member ( pinPairRef "@baseboard_fab2_lib.baseboard_fab2(sch_1):\PP4725\") )
				( member ( pinPairRef "@baseboard_fab2_lib.baseboard_fab2(sch_1):\PP4728\") )
				( objectStatus "MG_DQ_FAR_DIMM_NG_M_C_BYTE7" )
			)
			( matchGroup "@baseboard_fab2_lib.baseboard_fab2(sch_1):\MG_DQ-DQS_NEAR_DIMM_NG_M_C_BYTE7\"
				( memberType ( signal ) )
				( member ( pinPairRef "@baseboard_fab2_lib.baseboard_fab2(sch_1):\PP4709\") )
				( member ( pinPairRef "@baseboard_fab2_lib.baseboard_fab2(sch_1):\PP4712\") )
				( member ( pinPairRef "@baseboard_fab2_lib.baseboard_fab2(sch_1):\PP4715\") )
				( member ( pinPairRef "@baseboard_fab2_lib.baseboard_fab2(sch_1):\PP4718\") )
				( member ( pinPairRef "@baseboard_fab2_lib.baseboard_fab2(sch_1):\PP4721\") )
				( member ( pinPairRef "@baseboard_fab2_lib.baseboard_fab2(sch_1):\PP4724\") )
				( member ( pinPairRef "@baseboard_fab2_lib.baseboard_fab2(sch_1):\PP4727\") )
				( member ( pinPairRef "@baseboard_fab2_lib.baseboard_fab2(sch_1):\PP4730\") )
				( member ( pinPairRef "@baseboard_fab2_lib.baseboard_fab2(sch_1):\PP579\") )
				( member ( pinPairRef "@baseboard_fab2_lib.baseboard_fab2(sch_1):\PP573\") )
				( member ( pinPairRef "@baseboard_fab2_lib.baseboard_fab2(sch_1):\PP582\") )
				( member ( pinPairRef "@baseboard_fab2_lib.baseboard_fab2(sch_1):\PP576\") )
				( objectStatus "MG_DQ-DQS_NEAR_DIMM_NG_M_C_BYTE7" )
			)
			( matchGroup "@baseboard_fab2_lib.baseboard_fab2(sch_1):\MG_DQ_NEAR_DIMM_NG_M_C_BYTE7\"
				( memberType ( signal ) )
				( member ( pinPairRef "@baseboard_fab2_lib.baseboard_fab2(sch_1):\PP4709\") )
				( member ( pinPairRef "@baseboard_fab2_lib.baseboard_fab2(sch_1):\PP4712\") )
				( member ( pinPairRef "@baseboard_fab2_lib.baseboard_fab2(sch_1):\PP4715\") )
				( member ( pinPairRef "@baseboard_fab2_lib.baseboard_fab2(sch_1):\PP4718\") )
				( member ( pinPairRef "@baseboard_fab2_lib.baseboard_fab2(sch_1):\PP4721\") )
				( member ( pinPairRef "@baseboard_fab2_lib.baseboard_fab2(sch_1):\PP4724\") )
				( member ( pinPairRef "@baseboard_fab2_lib.baseboard_fab2(sch_1):\PP4727\") )
				( member ( pinPairRef "@baseboard_fab2_lib.baseboard_fab2(sch_1):\PP4730\") )
				( objectStatus "MG_DQ_NEAR_DIMM_NG_M_C_BYTE7" )
			)
			( matchGroup "@baseboard_fab2_lib.baseboard_fab2(sch_1):\MG_DQ-DQS_FAR_DIMM_NG_M_D_BYTE0\"
				( memberType ( signal ) )
				( member ( pinPairRef "@baseboard_fab2_lib.baseboard_fab2(sch_1):\PP4683\") )
				( member ( pinPairRef "@baseboard_fab2_lib.baseboard_fab2(sch_1):\PP4686\") )
				( member ( pinPairRef "@baseboard_fab2_lib.baseboard_fab2(sch_1):\PP4689\") )
				( member ( pinPairRef "@baseboard_fab2_lib.baseboard_fab2(sch_1):\PP4692\") )
				( member ( pinPairRef "@baseboard_fab2_lib.baseboard_fab2(sch_1):\PP4695\") )
				( member ( pinPairRef "@baseboard_fab2_lib.baseboard_fab2(sch_1):\PP4698\") )
				( member ( pinPairRef "@baseboard_fab2_lib.baseboard_fab2(sch_1):\PP4701\") )
				( member ( pinPairRef "@baseboard_fab2_lib.baseboard_fab2(sch_1):\PP4704\") )
				( member ( pinPairRef "@baseboard_fab2_lib.baseboard_fab2(sch_1):\PP670\") )
				( member ( pinPairRef "@baseboard_fab2_lib.baseboard_fab2(sch_1):\PP673\") )
				( member ( pinPairRef "@baseboard_fab2_lib.baseboard_fab2(sch_1):\PP667\") )
				( member ( pinPairRef "@baseboard_fab2_lib.baseboard_fab2(sch_1):\PP676\") )
				( objectStatus "MG_DQ-DQS_FAR_DIMM_NG_M_D_BYTE0" )
			)
			( matchGroup "@baseboard_fab2_lib.baseboard_fab2(sch_1):\MG_DQ_FAR_DIMM_NG_M_D_BYTE0\"
				( memberType ( signal ) )
				( member ( pinPairRef "@baseboard_fab2_lib.baseboard_fab2(sch_1):\PP4683\") )
				( member ( pinPairRef "@baseboard_fab2_lib.baseboard_fab2(sch_1):\PP4686\") )
				( member ( pinPairRef "@baseboard_fab2_lib.baseboard_fab2(sch_1):\PP4689\") )
				( member ( pinPairRef "@baseboard_fab2_lib.baseboard_fab2(sch_1):\PP4692\") )
				( member ( pinPairRef "@baseboard_fab2_lib.baseboard_fab2(sch_1):\PP4695\") )
				( member ( pinPairRef "@baseboard_fab2_lib.baseboard_fab2(sch_1):\PP4698\") )
				( member ( pinPairRef "@baseboard_fab2_lib.baseboard_fab2(sch_1):\PP4701\") )
				( member ( pinPairRef "@baseboard_fab2_lib.baseboard_fab2(sch_1):\PP4704\") )
				( objectStatus "MG_DQ_FAR_DIMM_NG_M_D_BYTE0" )
			)
			( matchGroup "@baseboard_fab2_lib.baseboard_fab2(sch_1):\MG_DQ-DQS_NEAR_DIMM_NG_M_D_BYTE0\"
				( memberType ( signal ) )
				( member ( pinPairRef "@baseboard_fab2_lib.baseboard_fab2(sch_1):\PP4685\") )
				( member ( pinPairRef "@baseboard_fab2_lib.baseboard_fab2(sch_1):\PP4688\") )
				( member ( pinPairRef "@baseboard_fab2_lib.baseboard_fab2(sch_1):\PP4691\") )
				( member ( pinPairRef "@baseboard_fab2_lib.baseboard_fab2(sch_1):\PP4694\") )
				( member ( pinPairRef "@baseboard_fab2_lib.baseboard_fab2(sch_1):\PP4697\") )
				( member ( pinPairRef "@baseboard_fab2_lib.baseboard_fab2(sch_1):\PP4700\") )
				( member ( pinPairRef "@baseboard_fab2_lib.baseboard_fab2(sch_1):\PP4703\") )
				( member ( pinPairRef "@baseboard_fab2_lib.baseboard_fab2(sch_1):\PP4706\") )
				( member ( pinPairRef "@baseboard_fab2_lib.baseboard_fab2(sch_1):\PP671\") )
				( member ( pinPairRef "@baseboard_fab2_lib.baseboard_fab2(sch_1):\PP674\") )
				( member ( pinPairRef "@baseboard_fab2_lib.baseboard_fab2(sch_1):\PP668\") )
				( member ( pinPairRef "@baseboard_fab2_lib.baseboard_fab2(sch_1):\PP677\") )
				( objectStatus "MG_DQ-DQS_NEAR_DIMM_NG_M_D_BYTE0" )
			)
			( matchGroup "@baseboard_fab2_lib.baseboard_fab2(sch_1):\MG_DQ_NEAR_DIMM_NG_M_D_BYTE0\"
				( memberType ( signal ) )
				( member ( pinPairRef "@baseboard_fab2_lib.baseboard_fab2(sch_1):\PP4685\") )
				( member ( pinPairRef "@baseboard_fab2_lib.baseboard_fab2(sch_1):\PP4688\") )
				( member ( pinPairRef "@baseboard_fab2_lib.baseboard_fab2(sch_1):\PP4691\") )
				( member ( pinPairRef "@baseboard_fab2_lib.baseboard_fab2(sch_1):\PP4694\") )
				( member ( pinPairRef "@baseboard_fab2_lib.baseboard_fab2(sch_1):\PP4697\") )
				( member ( pinPairRef "@baseboard_fab2_lib.baseboard_fab2(sch_1):\PP4700\") )
				( member ( pinPairRef "@baseboard_fab2_lib.baseboard_fab2(sch_1):\PP4703\") )
				( member ( pinPairRef "@baseboard_fab2_lib.baseboard_fab2(sch_1):\PP4706\") )
				( objectStatus "MG_DQ_NEAR_DIMM_NG_M_D_BYTE0" )
			)
			( matchGroup "@baseboard_fab2_lib.baseboard_fab2(sch_1):\MG_DQ-DQS_FAR_DIMM_NG_M_D_BYTE1\"
				( memberType ( signal ) )
				( member ( pinPairRef "@baseboard_fab2_lib.baseboard_fab2(sch_1):\PP4659\") )
				( member ( pinPairRef "@baseboard_fab2_lib.baseboard_fab2(sch_1):\PP4662\") )
				( member ( pinPairRef "@baseboard_fab2_lib.baseboard_fab2(sch_1):\PP4665\") )
				( member ( pinPairRef "@baseboard_fab2_lib.baseboard_fab2(sch_1):\PP4668\") )
				( member ( pinPairRef "@baseboard_fab2_lib.baseboard_fab2(sch_1):\PP4671\") )
				( member ( pinPairRef "@baseboard_fab2_lib.baseboard_fab2(sch_1):\PP4674\") )
				( member ( pinPairRef "@baseboard_fab2_lib.baseboard_fab2(sch_1):\PP4677\") )
				( member ( pinPairRef "@baseboard_fab2_lib.baseboard_fab2(sch_1):\PP4680\") )
				( member ( pinPairRef "@baseboard_fab2_lib.baseboard_fab2(sch_1):\PP682\") )
				( member ( pinPairRef "@baseboard_fab2_lib.baseboard_fab2(sch_1):\PP685\") )
				( member ( pinPairRef "@baseboard_fab2_lib.baseboard_fab2(sch_1):\PP679\") )
				( member ( pinPairRef "@baseboard_fab2_lib.baseboard_fab2(sch_1):\PP688\") )
				( objectStatus "MG_DQ-DQS_FAR_DIMM_NG_M_D_BYTE1" )
			)
			( matchGroup "@baseboard_fab2_lib.baseboard_fab2(sch_1):\MG_DQ_FAR_DIMM_NG_M_D_BYTE1\"
				( memberType ( signal ) )
				( member ( pinPairRef "@baseboard_fab2_lib.baseboard_fab2(sch_1):\PP4659\") )
				( member ( pinPairRef "@baseboard_fab2_lib.baseboard_fab2(sch_1):\PP4662\") )
				( member ( pinPairRef "@baseboard_fab2_lib.baseboard_fab2(sch_1):\PP4665\") )
				( member ( pinPairRef "@baseboard_fab2_lib.baseboard_fab2(sch_1):\PP4668\") )
				( member ( pinPairRef "@baseboard_fab2_lib.baseboard_fab2(sch_1):\PP4671\") )
				( member ( pinPairRef "@baseboard_fab2_lib.baseboard_fab2(sch_1):\PP4674\") )
				( member ( pinPairRef "@baseboard_fab2_lib.baseboard_fab2(sch_1):\PP4677\") )
				( member ( pinPairRef "@baseboard_fab2_lib.baseboard_fab2(sch_1):\PP4680\") )
				( objectStatus "MG_DQ_FAR_DIMM_NG_M_D_BYTE1" )
			)
			( matchGroup "@baseboard_fab2_lib.baseboard_fab2(sch_1):\MG_DQ-DQS_NEAR_DIMM_NG_M_D_BYTE1\"
				( memberType ( signal ) )
				( member ( pinPairRef "@baseboard_fab2_lib.baseboard_fab2(sch_1):\PP4661\") )
				( member ( pinPairRef "@baseboard_fab2_lib.baseboard_fab2(sch_1):\PP4664\") )
				( member ( pinPairRef "@baseboard_fab2_lib.baseboard_fab2(sch_1):\PP4667\") )
				( member ( pinPairRef "@baseboard_fab2_lib.baseboard_fab2(sch_1):\PP4670\") )
				( member ( pinPairRef "@baseboard_fab2_lib.baseboard_fab2(sch_1):\PP4673\") )
				( member ( pinPairRef "@baseboard_fab2_lib.baseboard_fab2(sch_1):\PP4676\") )
				( member ( pinPairRef "@baseboard_fab2_lib.baseboard_fab2(sch_1):\PP4679\") )
				( member ( pinPairRef "@baseboard_fab2_lib.baseboard_fab2(sch_1):\PP4682\") )
				( member ( pinPairRef "@baseboard_fab2_lib.baseboard_fab2(sch_1):\PP683\") )
				( member ( pinPairRef "@baseboard_fab2_lib.baseboard_fab2(sch_1):\PP686\") )
				( member ( pinPairRef "@baseboard_fab2_lib.baseboard_fab2(sch_1):\PP680\") )
				( member ( pinPairRef "@baseboard_fab2_lib.baseboard_fab2(sch_1):\PP689\") )
				( objectStatus "MG_DQ-DQS_NEAR_DIMM_NG_M_D_BYTE1" )
			)
			( matchGroup "@baseboard_fab2_lib.baseboard_fab2(sch_1):\MG_DQ_NEAR_DIMM_NG_M_D_BYTE1\"
				( memberType ( signal ) )
				( member ( pinPairRef "@baseboard_fab2_lib.baseboard_fab2(sch_1):\PP4661\") )
				( member ( pinPairRef "@baseboard_fab2_lib.baseboard_fab2(sch_1):\PP4664\") )
				( member ( pinPairRef "@baseboard_fab2_lib.baseboard_fab2(sch_1):\PP4667\") )
				( member ( pinPairRef "@baseboard_fab2_lib.baseboard_fab2(sch_1):\PP4670\") )
				( member ( pinPairRef "@baseboard_fab2_lib.baseboard_fab2(sch_1):\PP4673\") )
				( member ( pinPairRef "@baseboard_fab2_lib.baseboard_fab2(sch_1):\PP4676\") )
				( member ( pinPairRef "@baseboard_fab2_lib.baseboard_fab2(sch_1):\PP4679\") )
				( member ( pinPairRef "@baseboard_fab2_lib.baseboard_fab2(sch_1):\PP4682\") )
				( objectStatus "MG_DQ_NEAR_DIMM_NG_M_D_BYTE1" )
			)
			( matchGroup "@baseboard_fab2_lib.baseboard_fab2(sch_1):\MG_DQ-DQS_FAR_DIMM_NG_M_D_BYTE2\"
				( memberType ( signal ) )
				( member ( pinPairRef "@baseboard_fab2_lib.baseboard_fab2(sch_1):\PP4635\") )
				( member ( pinPairRef "@baseboard_fab2_lib.baseboard_fab2(sch_1):\PP4638\") )
				( member ( pinPairRef "@baseboard_fab2_lib.baseboard_fab2(sch_1):\PP4641\") )
				( member ( pinPairRef "@baseboard_fab2_lib.baseboard_fab2(sch_1):\PP4644\") )
				( member ( pinPairRef "@baseboard_fab2_lib.baseboard_fab2(sch_1):\PP4647\") )
				( member ( pinPairRef "@baseboard_fab2_lib.baseboard_fab2(sch_1):\PP4650\") )
				( member ( pinPairRef "@baseboard_fab2_lib.baseboard_fab2(sch_1):\PP4653\") )
				( member ( pinPairRef "@baseboard_fab2_lib.baseboard_fab2(sch_1):\PP4656\") )
				( member ( pinPairRef "@baseboard_fab2_lib.baseboard_fab2(sch_1):\PP694\") )
				( member ( pinPairRef "@baseboard_fab2_lib.baseboard_fab2(sch_1):\PP697\") )
				( member ( pinPairRef "@baseboard_fab2_lib.baseboard_fab2(sch_1):\PP691\") )
				( member ( pinPairRef "@baseboard_fab2_lib.baseboard_fab2(sch_1):\PP700\") )
				( objectStatus "MG_DQ-DQS_FAR_DIMM_NG_M_D_BYTE2" )
			)
			( matchGroup "@baseboard_fab2_lib.baseboard_fab2(sch_1):\MG_DQ_FAR_DIMM_NG_M_D_BYTE2\"
				( memberType ( signal ) )
				( member ( pinPairRef "@baseboard_fab2_lib.baseboard_fab2(sch_1):\PP4635\") )
				( member ( pinPairRef "@baseboard_fab2_lib.baseboard_fab2(sch_1):\PP4638\") )
				( member ( pinPairRef "@baseboard_fab2_lib.baseboard_fab2(sch_1):\PP4641\") )
				( member ( pinPairRef "@baseboard_fab2_lib.baseboard_fab2(sch_1):\PP4644\") )
				( member ( pinPairRef "@baseboard_fab2_lib.baseboard_fab2(sch_1):\PP4647\") )
				( member ( pinPairRef "@baseboard_fab2_lib.baseboard_fab2(sch_1):\PP4650\") )
				( member ( pinPairRef "@baseboard_fab2_lib.baseboard_fab2(sch_1):\PP4653\") )
				( member ( pinPairRef "@baseboard_fab2_lib.baseboard_fab2(sch_1):\PP4656\") )
				( objectStatus "MG_DQ_FAR_DIMM_NG_M_D_BYTE2" )
			)
			( matchGroup "@baseboard_fab2_lib.baseboard_fab2(sch_1):\MG_DQ-DQS_NEAR_DIMM_NG_M_D_BYTE2\"
				( memberType ( signal ) )
				( member ( pinPairRef "@baseboard_fab2_lib.baseboard_fab2(sch_1):\PP4637\") )
				( member ( pinPairRef "@baseboard_fab2_lib.baseboard_fab2(sch_1):\PP4640\") )
				( member ( pinPairRef "@baseboard_fab2_lib.baseboard_fab2(sch_1):\PP4643\") )
				( member ( pinPairRef "@baseboard_fab2_lib.baseboard_fab2(sch_1):\PP4646\") )
				( member ( pinPairRef "@baseboard_fab2_lib.baseboard_fab2(sch_1):\PP4649\") )
				( member ( pinPairRef "@baseboard_fab2_lib.baseboard_fab2(sch_1):\PP4652\") )
				( member ( pinPairRef "@baseboard_fab2_lib.baseboard_fab2(sch_1):\PP4655\") )
				( member ( pinPairRef "@baseboard_fab2_lib.baseboard_fab2(sch_1):\PP4658\") )
				( member ( pinPairRef "@baseboard_fab2_lib.baseboard_fab2(sch_1):\PP695\") )
				( member ( pinPairRef "@baseboard_fab2_lib.baseboard_fab2(sch_1):\PP698\") )
				( member ( pinPairRef "@baseboard_fab2_lib.baseboard_fab2(sch_1):\PP692\") )
				( member ( pinPairRef "@baseboard_fab2_lib.baseboard_fab2(sch_1):\PP701\") )
				( objectStatus "MG_DQ-DQS_NEAR_DIMM_NG_M_D_BYTE2" )
			)
			( matchGroup "@baseboard_fab2_lib.baseboard_fab2(sch_1):\MG_DQ_NEAR_DIMM_NG_M_D_BYTE2\"
				( memberType ( signal ) )
				( member ( pinPairRef "@baseboard_fab2_lib.baseboard_fab2(sch_1):\PP4637\") )
				( member ( pinPairRef "@baseboard_fab2_lib.baseboard_fab2(sch_1):\PP4640\") )
				( member ( pinPairRef "@baseboard_fab2_lib.baseboard_fab2(sch_1):\PP4643\") )
				( member ( pinPairRef "@baseboard_fab2_lib.baseboard_fab2(sch_1):\PP4646\") )
				( member ( pinPairRef "@baseboard_fab2_lib.baseboard_fab2(sch_1):\PP4649\") )
				( member ( pinPairRef "@baseboard_fab2_lib.baseboard_fab2(sch_1):\PP4652\") )
				( member ( pinPairRef "@baseboard_fab2_lib.baseboard_fab2(sch_1):\PP4655\") )
				( member ( pinPairRef "@baseboard_fab2_lib.baseboard_fab2(sch_1):\PP4658\") )
				( objectStatus "MG_DQ_NEAR_DIMM_NG_M_D_BYTE2" )
			)
			( matchGroup "@baseboard_fab2_lib.baseboard_fab2(sch_1):\MG_DQ-DQS_FAR_DIMM_NG_M_D_BYTE3\"
				( memberType ( signal ) )
				( member ( pinPairRef "@baseboard_fab2_lib.baseboard_fab2(sch_1):\PP4611\") )
				( member ( pinPairRef "@baseboard_fab2_lib.baseboard_fab2(sch_1):\PP4614\") )
				( member ( pinPairRef "@baseboard_fab2_lib.baseboard_fab2(sch_1):\PP4617\") )
				( member ( pinPairRef "@baseboard_fab2_lib.baseboard_fab2(sch_1):\PP4620\") )
				( member ( pinPairRef "@baseboard_fab2_lib.baseboard_fab2(sch_1):\PP4623\") )
				( member ( pinPairRef "@baseboard_fab2_lib.baseboard_fab2(sch_1):\PP4626\") )
				( member ( pinPairRef "@baseboard_fab2_lib.baseboard_fab2(sch_1):\PP4629\") )
				( member ( pinPairRef "@baseboard_fab2_lib.baseboard_fab2(sch_1):\PP4632\") )
				( member ( pinPairRef "@baseboard_fab2_lib.baseboard_fab2(sch_1):\PP706\") )
				( member ( pinPairRef "@baseboard_fab2_lib.baseboard_fab2(sch_1):\PP709\") )
				( member ( pinPairRef "@baseboard_fab2_lib.baseboard_fab2(sch_1):\PP703\") )
				( member ( pinPairRef "@baseboard_fab2_lib.baseboard_fab2(sch_1):\PP712\") )
				( objectStatus "MG_DQ-DQS_FAR_DIMM_NG_M_D_BYTE3" )
			)
			( matchGroup "@crescent_city_bb_fab1_lib.crescent_city_bb_fab1(sch_1):\MG_DQ_FAR_DIMM_NG_M_D_BYTE3\"
				( memberType ( signal ) )
				( member ( pinPairRef "@baseboard_fab2_lib.baseboard_fab2(sch_1):\PP4611\") )
				( member ( pinPairRef "@baseboard_fab2_lib.baseboard_fab2(sch_1):\PP4614\") )
				( member ( pinPairRef "@baseboard_fab2_lib.baseboard_fab2(sch_1):\PP4617\") )
				( member ( pinPairRef "@baseboard_fab2_lib.baseboard_fab2(sch_1):\PP4620\") )
				( member ( pinPairRef "@baseboard_fab2_lib.baseboard_fab2(sch_1):\PP4623\") )
				( member ( pinPairRef "@baseboard_fab2_lib.baseboard_fab2(sch_1):\PP4626\") )
				( member ( pinPairRef "@baseboard_fab2_lib.baseboard_fab2(sch_1):\PP4629\") )
				( member ( pinPairRef "@baseboard_fab2_lib.baseboard_fab2(sch_1):\PP4632\") )
				( objectStatus "MG_DQ_FAR_DIMM_NG_M_D_BYTE3" )
			)
			( matchGroup "@baseboard_fab2_lib.baseboard_fab2(sch_1):\MG_DQ-DQS_NEAR_DIMM_NG_M_D_BYTE3\"
				( memberType ( signal ) )
				( member ( pinPairRef "@baseboard_fab2_lib.baseboard_fab2(sch_1):\PP4613\") )
				( member ( pinPairRef "@baseboard_fab2_lib.baseboard_fab2(sch_1):\PP4616\") )
				( member ( pinPairRef "@baseboard_fab2_lib.baseboard_fab2(sch_1):\PP4619\") )
				( member ( pinPairRef "@baseboard_fab2_lib.baseboard_fab2(sch_1):\PP4622\") )
				( member ( pinPairRef "@baseboard_fab2_lib.baseboard_fab2(sch_1):\PP4625\") )
				( member ( pinPairRef "@baseboard_fab2_lib.baseboard_fab2(sch_1):\PP4628\") )
				( member ( pinPairRef "@baseboard_fab2_lib.baseboard_fab2(sch_1):\PP4631\") )
				( member ( pinPairRef "@baseboard_fab2_lib.baseboard_fab2(sch_1):\PP4634\") )
				( member ( pinPairRef "@baseboard_fab2_lib.baseboard_fab2(sch_1):\PP707\") )
				( member ( pinPairRef "@baseboard_fab2_lib.baseboard_fab2(sch_1):\PP710\") )
				( member ( pinPairRef "@baseboard_fab2_lib.baseboard_fab2(sch_1):\PP704\") )
				( member ( pinPairRef "@baseboard_fab2_lib.baseboard_fab2(sch_1):\PP713\") )
				( objectStatus "MG_DQ-DQS_NEAR_DIMM_NG_M_D_BYTE3" )
			)
			( matchGroup "@crescent_city_bb_fab1_lib.crescent_city_bb_fab1(sch_1):\MG_DQ_NEAR_DIMM_NG_M_D_BYTE3\"
				( memberType ( signal ) )
				( member ( pinPairRef "@baseboard_fab2_lib.baseboard_fab2(sch_1):\PP4613\") )
				( member ( pinPairRef "@baseboard_fab2_lib.baseboard_fab2(sch_1):\PP4616\") )
				( member ( pinPairRef "@baseboard_fab2_lib.baseboard_fab2(sch_1):\PP4619\") )
				( member ( pinPairRef "@baseboard_fab2_lib.baseboard_fab2(sch_1):\PP4622\") )
				( member ( pinPairRef "@baseboard_fab2_lib.baseboard_fab2(sch_1):\PP4625\") )
				( member ( pinPairRef "@baseboard_fab2_lib.baseboard_fab2(sch_1):\PP4628\") )
				( member ( pinPairRef "@baseboard_fab2_lib.baseboard_fab2(sch_1):\PP4631\") )
				( member ( pinPairRef "@baseboard_fab2_lib.baseboard_fab2(sch_1):\PP4634\") )
				( objectStatus "MG_DQ_NEAR_DIMM_NG_M_D_BYTE3" )
			)
			( matchGroup "@baseboard_fab2_lib.baseboard_fab2(sch_1):\MG_DQ-DQS_FAR_DIMM_NG_M_M_BYTE3\"
				( memberType ( signal ) )
				( member ( pinPairRef "@baseboard_fab2_lib.baseboard_fab2(sch_1):\PP1786\") )
				( member ( pinPairRef "@baseboard_fab2_lib.baseboard_fab2(sch_1):\PP1789\") )
				( member ( pinPairRef "@baseboard_fab2_lib.baseboard_fab2(sch_1):\PP1792\") )
				( member ( pinPairRef "@baseboard_fab2_lib.baseboard_fab2(sch_1):\PP1771\") )
				( member ( pinPairRef "@baseboard_fab2_lib.baseboard_fab2(sch_1):\PP1774\") )
				( member ( pinPairRef "@baseboard_fab2_lib.baseboard_fab2(sch_1):\PP1777\") )
				( member ( pinPairRef "@baseboard_fab2_lib.baseboard_fab2(sch_1):\PP1780\") )
				( member ( pinPairRef "@baseboard_fab2_lib.baseboard_fab2(sch_1):\PP1783\") )
				( member ( pinPairRef "@baseboard_fab2_lib.baseboard_fab2(sch_1):\PP1345\") )
				( member ( pinPairRef "@baseboard_fab2_lib.baseboard_fab2(sch_1):\PP1348\") )
				( member ( pinPairRef "@baseboard_fab2_lib.baseboard_fab2(sch_1):\PP1339\") )
				( member ( pinPairRef "@baseboard_fab2_lib.baseboard_fab2(sch_1):\PP1342\") )
				( objectStatus "MG_DQ-DQS_FAR_DIMM_NG_M_M_BYTE3" )
			)
			( matchGroup "@baseboard_fab2_lib.baseboard_fab2(sch_1):\MG_DQ_FAR_DIMM_NG_M_M_BYTE3\"
				( memberType ( signal ) )
				( member ( pinPairRef "@baseboard_fab2_lib.baseboard_fab2(sch_1):\PP1786\") )
				( member ( pinPairRef "@baseboard_fab2_lib.baseboard_fab2(sch_1):\PP1789\") )
				( member ( pinPairRef "@baseboard_fab2_lib.baseboard_fab2(sch_1):\PP1792\") )
				( member ( pinPairRef "@baseboard_fab2_lib.baseboard_fab2(sch_1):\PP1771\") )
				( member ( pinPairRef "@baseboard_fab2_lib.baseboard_fab2(sch_1):\PP1774\") )
				( member ( pinPairRef "@baseboard_fab2_lib.baseboard_fab2(sch_1):\PP1777\") )
				( member ( pinPairRef "@baseboard_fab2_lib.baseboard_fab2(sch_1):\PP1780\") )
				( member ( pinPairRef "@baseboard_fab2_lib.baseboard_fab2(sch_1):\PP1783\") )
				( objectStatus "MG_DQ_FAR_DIMM_NG_M_M_BYTE3" )
			)
			( matchGroup "@baseboard_fab2_lib.baseboard_fab2(sch_1):\MG_DQ-DQS_NEAR_DIMM_NG_M_M_BYTE3\"
				( memberType ( signal ) )
				( member ( pinPairRef "@baseboard_fab2_lib.baseboard_fab2(sch_1):\PP1787\") )
				( member ( pinPairRef "@baseboard_fab2_lib.baseboard_fab2(sch_1):\PP1790\") )
				( member ( pinPairRef "@baseboard_fab2_lib.baseboard_fab2(sch_1):\PP1793\") )
				( member ( pinPairRef "@baseboard_fab2_lib.baseboard_fab2(sch_1):\PP1772\") )
				( member ( pinPairRef "@baseboard_fab2_lib.baseboard_fab2(sch_1):\PP1775\") )
				( member ( pinPairRef "@baseboard_fab2_lib.baseboard_fab2(sch_1):\PP1778\") )
				( member ( pinPairRef "@baseboard_fab2_lib.baseboard_fab2(sch_1):\PP1781\") )
				( member ( pinPairRef "@baseboard_fab2_lib.baseboard_fab2(sch_1):\PP1784\") )
				( member ( pinPairRef "@baseboard_fab2_lib.baseboard_fab2(sch_1):\PP1346\") )
				( member ( pinPairRef "@baseboard_fab2_lib.baseboard_fab2(sch_1):\PP1349\") )
				( member ( pinPairRef "@baseboard_fab2_lib.baseboard_fab2(sch_1):\PP1340\") )
				( member ( pinPairRef "@baseboard_fab2_lib.baseboard_fab2(sch_1):\PP1343\") )
				( objectStatus "MG_DQ-DQS_NEAR_DIMM_NG_M_M_BYTE3" )
			)
			( matchGroup "@crescent_city_bb_fab1_lib.crescent_city_bb_fab1(sch_1):\MG_DQ_NEAR_DIMM_NG_M_M_BYTE3\"
				( memberType ( signal ) )
				( member ( pinPairRef "@baseboard_fab2_lib.baseboard_fab2(sch_1):\PP1787\") )
				( member ( pinPairRef "@baseboard_fab2_lib.baseboard_fab2(sch_1):\PP1790\") )
				( member ( pinPairRef "@baseboard_fab2_lib.baseboard_fab2(sch_1):\PP1793\") )
				( member ( pinPairRef "@baseboard_fab2_lib.baseboard_fab2(sch_1):\PP1772\") )
				( member ( pinPairRef "@baseboard_fab2_lib.baseboard_fab2(sch_1):\PP1775\") )
				( member ( pinPairRef "@baseboard_fab2_lib.baseboard_fab2(sch_1):\PP1778\") )
				( member ( pinPairRef "@baseboard_fab2_lib.baseboard_fab2(sch_1):\PP1781\") )
				( member ( pinPairRef "@baseboard_fab2_lib.baseboard_fab2(sch_1):\PP1784\") )
				( objectStatus "MG_DQ_NEAR_DIMM_NG_M_M_BYTE3" )
			)
			( matchGroup "@baseboard_fab2_lib.baseboard_fab2(sch_1):\MG_DQ-DQS_FAR_DIMM_NG_M_M_BYTE4\"
				( memberType ( signal ) )
				( member ( pinPairRef "@baseboard_fab2_lib.baseboard_fab2(sch_1):\PP1747\") )
				( member ( pinPairRef "@baseboard_fab2_lib.baseboard_fab2(sch_1):\PP1750\") )
				( member ( pinPairRef "@baseboard_fab2_lib.baseboard_fab2(sch_1):\PP1753\") )
				( member ( pinPairRef "@baseboard_fab2_lib.baseboard_fab2(sch_1):\PP1756\") )
				( member ( pinPairRef "@baseboard_fab2_lib.baseboard_fab2(sch_1):\PP1759\") )
				( member ( pinPairRef "@baseboard_fab2_lib.baseboard_fab2(sch_1):\PP1762\") )
				( member ( pinPairRef "@baseboard_fab2_lib.baseboard_fab2(sch_1):\PP1765\") )
				( member ( pinPairRef "@baseboard_fab2_lib.baseboard_fab2(sch_1):\PP1768\") )
				( member ( pinPairRef "@baseboard_fab2_lib.baseboard_fab2(sch_1):\PP1333\") )
				( member ( pinPairRef "@baseboard_fab2_lib.baseboard_fab2(sch_1):\PP1336\") )
				( member ( pinPairRef "@baseboard_fab2_lib.baseboard_fab2(sch_1):\PP1327\") )
				( member ( pinPairRef "@baseboard_fab2_lib.baseboard_fab2(sch_1):\PP1330\") )
				( objectStatus "MG_DQ-DQS_FAR_DIMM_NG_M_M_BYTE4" )
			)
			( matchGroup "@crescent_city_bb_fab1_lib.crescent_city_bb_fab1(sch_1):\MG_DQ_FAR_DIMM_NG_M_M_BYTE4\"
				( memberType ( signal ) )
				( member ( pinPairRef "@baseboard_fab2_lib.baseboard_fab2(sch_1):\PP1747\") )
				( member ( pinPairRef "@baseboard_fab2_lib.baseboard_fab2(sch_1):\PP1750\") )
				( member ( pinPairRef "@baseboard_fab2_lib.baseboard_fab2(sch_1):\PP1753\") )
				( member ( pinPairRef "@baseboard_fab2_lib.baseboard_fab2(sch_1):\PP1756\") )
				( member ( pinPairRef "@baseboard_fab2_lib.baseboard_fab2(sch_1):\PP1759\") )
				( member ( pinPairRef "@baseboard_fab2_lib.baseboard_fab2(sch_1):\PP1762\") )
				( member ( pinPairRef "@baseboard_fab2_lib.baseboard_fab2(sch_1):\PP1765\") )
				( member ( pinPairRef "@baseboard_fab2_lib.baseboard_fab2(sch_1):\PP1768\") )
				( objectStatus "MG_DQ_FAR_DIMM_NG_M_M_BYTE4" )
			)
			( matchGroup "@baseboard_fab2_lib.baseboard_fab2(sch_1):\MG_DQ-DQS_NEAR_DIMM_NG_M_M_BYTE4\"
				( memberType ( signal ) )
				( member ( pinPairRef "@baseboard_fab2_lib.baseboard_fab2(sch_1):\PP1749\") )
				( member ( pinPairRef "@baseboard_fab2_lib.baseboard_fab2(sch_1):\PP1752\") )
				( member ( pinPairRef "@baseboard_fab2_lib.baseboard_fab2(sch_1):\PP1755\") )
				( member ( pinPairRef "@baseboard_fab2_lib.baseboard_fab2(sch_1):\PP1758\") )
				( member ( pinPairRef "@baseboard_fab2_lib.baseboard_fab2(sch_1):\PP1761\") )
				( member ( pinPairRef "@baseboard_fab2_lib.baseboard_fab2(sch_1):\PP1764\") )
				( member ( pinPairRef "@baseboard_fab2_lib.baseboard_fab2(sch_1):\PP1767\") )
				( member ( pinPairRef "@baseboard_fab2_lib.baseboard_fab2(sch_1):\PP1770\") )
				( member ( pinPairRef "@baseboard_fab2_lib.baseboard_fab2(sch_1):\PP1335\") )
				( member ( pinPairRef "@baseboard_fab2_lib.baseboard_fab2(sch_1):\PP1338\") )
				( member ( pinPairRef "@baseboard_fab2_lib.baseboard_fab2(sch_1):\PP1329\") )
				( member ( pinPairRef "@baseboard_fab2_lib.baseboard_fab2(sch_1):\PP1332\") )
				( objectStatus "MG_DQ-DQS_NEAR_DIMM_NG_M_M_BYTE4" )
			)
			( matchGroup "@crescent_city_bb_fab1_lib.crescent_city_bb_fab1(sch_1):\MG_DQ_NEAR_DIMM_NG_M_M_BYTE4\"
				( memberType ( signal ) )
				( member ( pinPairRef "@baseboard_fab2_lib.baseboard_fab2(sch_1):\PP1749\") )
				( member ( pinPairRef "@baseboard_fab2_lib.baseboard_fab2(sch_1):\PP1752\") )
				( member ( pinPairRef "@baseboard_fab2_lib.baseboard_fab2(sch_1):\PP1755\") )
				( member ( pinPairRef "@baseboard_fab2_lib.baseboard_fab2(sch_1):\PP1758\") )
				( member ( pinPairRef "@baseboard_fab2_lib.baseboard_fab2(sch_1):\PP1761\") )
				( member ( pinPairRef "@baseboard_fab2_lib.baseboard_fab2(sch_1):\PP1764\") )
				( member ( pinPairRef "@baseboard_fab2_lib.baseboard_fab2(sch_1):\PP1767\") )
				( member ( pinPairRef "@baseboard_fab2_lib.baseboard_fab2(sch_1):\PP1770\") )
				( objectStatus "MG_DQ_NEAR_DIMM_NG_M_M_BYTE4" )
			)
			( matchGroup "@baseboard_fab2_lib.baseboard_fab2(sch_1):\MG_DQ-DQS_FAR_DIMM_NG_M_M_BYTE5\"
				( memberType ( signal ) )
				( member ( pinPairRef "@baseboard_fab2_lib.baseboard_fab2(sch_1):\PP1723\") )
				( member ( pinPairRef "@baseboard_fab2_lib.baseboard_fab2(sch_1):\PP1726\") )
				( member ( pinPairRef "@baseboard_fab2_lib.baseboard_fab2(sch_1):\PP1729\") )
				( member ( pinPairRef "@baseboard_fab2_lib.baseboard_fab2(sch_1):\PP1732\") )
				( member ( pinPairRef "@baseboard_fab2_lib.baseboard_fab2(sch_1):\PP1735\") )
				( member ( pinPairRef "@baseboard_fab2_lib.baseboard_fab2(sch_1):\PP1738\") )
				( member ( pinPairRef "@baseboard_fab2_lib.baseboard_fab2(sch_1):\PP1741\") )
				( member ( pinPairRef "@baseboard_fab2_lib.baseboard_fab2(sch_1):\PP1744\") )
				( member ( pinPairRef "@baseboard_fab2_lib.baseboard_fab2(sch_1):\PP1321\") )
				( member ( pinPairRef "@baseboard_fab2_lib.baseboard_fab2(sch_1):\PP1324\") )
				( member ( pinPairRef "@baseboard_fab2_lib.baseboard_fab2(sch_1):\PP1315\") )
				( member ( pinPairRef "@baseboard_fab2_lib.baseboard_fab2(sch_1):\PP1318\") )
				( objectStatus "MG_DQ-DQS_FAR_DIMM_NG_M_M_BYTE5" )
			)
			( matchGroup "@baseboard_fab2_lib.baseboard_fab2(sch_1):\MG_DQ_FAR_DIMM_NG_M_M_BYTE5\"
				( memberType ( signal ) )
				( member ( pinPairRef "@baseboard_fab2_lib.baseboard_fab2(sch_1):\PP1723\") )
				( member ( pinPairRef "@baseboard_fab2_lib.baseboard_fab2(sch_1):\PP1726\") )
				( member ( pinPairRef "@baseboard_fab2_lib.baseboard_fab2(sch_1):\PP1729\") )
				( member ( pinPairRef "@baseboard_fab2_lib.baseboard_fab2(sch_1):\PP1732\") )
				( member ( pinPairRef "@baseboard_fab2_lib.baseboard_fab2(sch_1):\PP1735\") )
				( member ( pinPairRef "@baseboard_fab2_lib.baseboard_fab2(sch_1):\PP1738\") )
				( member ( pinPairRef "@baseboard_fab2_lib.baseboard_fab2(sch_1):\PP1741\") )
				( member ( pinPairRef "@baseboard_fab2_lib.baseboard_fab2(sch_1):\PP1744\") )
				( objectStatus "MG_DQ_FAR_DIMM_NG_M_M_BYTE5" )
			)
			( matchGroup "@baseboard_fab2_lib.baseboard_fab2(sch_1):\MG_DQ-DQS_NEAR_DIMM_NG_M_M_BYTE5\"
				( memberType ( signal ) )
				( member ( pinPairRef "@baseboard_fab2_lib.baseboard_fab2(sch_1):\PP1725\") )
				( member ( pinPairRef "@baseboard_fab2_lib.baseboard_fab2(sch_1):\PP1728\") )
				( member ( pinPairRef "@baseboard_fab2_lib.baseboard_fab2(sch_1):\PP1731\") )
				( member ( pinPairRef "@baseboard_fab2_lib.baseboard_fab2(sch_1):\PP1734\") )
				( member ( pinPairRef "@baseboard_fab2_lib.baseboard_fab2(sch_1):\PP1737\") )
				( member ( pinPairRef "@baseboard_fab2_lib.baseboard_fab2(sch_1):\PP1740\") )
				( member ( pinPairRef "@baseboard_fab2_lib.baseboard_fab2(sch_1):\PP1743\") )
				( member ( pinPairRef "@baseboard_fab2_lib.baseboard_fab2(sch_1):\PP1746\") )
				( member ( pinPairRef "@baseboard_fab2_lib.baseboard_fab2(sch_1):\PP1323\") )
				( member ( pinPairRef "@baseboard_fab2_lib.baseboard_fab2(sch_1):\PP1326\") )
				( member ( pinPairRef "@baseboard_fab2_lib.baseboard_fab2(sch_1):\PP1317\") )
				( member ( pinPairRef "@baseboard_fab2_lib.baseboard_fab2(sch_1):\PP1320\") )
				( objectStatus "MG_DQ-DQS_NEAR_DIMM_NG_M_M_BYTE5" )
			)
			( matchGroup "@crescent_city_bb_fab1_lib.crescent_city_bb_fab1(sch_1):\MG_DQ_NEAR_DIMM_NG_M_M_BYTE5\"
				( memberType ( signal ) )
				( member ( pinPairRef "@baseboard_fab2_lib.baseboard_fab2(sch_1):\PP1725\") )
				( member ( pinPairRef "@baseboard_fab2_lib.baseboard_fab2(sch_1):\PP1728\") )
				( member ( pinPairRef "@baseboard_fab2_lib.baseboard_fab2(sch_1):\PP1731\") )
				( member ( pinPairRef "@baseboard_fab2_lib.baseboard_fab2(sch_1):\PP1734\") )
				( member ( pinPairRef "@baseboard_fab2_lib.baseboard_fab2(sch_1):\PP1737\") )
				( member ( pinPairRef "@baseboard_fab2_lib.baseboard_fab2(sch_1):\PP1740\") )
				( member ( pinPairRef "@baseboard_fab2_lib.baseboard_fab2(sch_1):\PP1743\") )
				( member ( pinPairRef "@baseboard_fab2_lib.baseboard_fab2(sch_1):\PP1746\") )
				( objectStatus "MG_DQ_NEAR_DIMM_NG_M_M_BYTE5" )
			)
			( matchGroup "@baseboard_fab2_lib.baseboard_fab2(sch_1):\MG_DQ-DQS_FAR_DIMM_NG_M_M_BYTE6\"
				( memberType ( signal ) )
				( member ( pinPairRef "@baseboard_fab2_lib.baseboard_fab2(sch_1):\PP1699\") )
				( member ( pinPairRef "@baseboard_fab2_lib.baseboard_fab2(sch_1):\PP1702\") )
				( member ( pinPairRef "@baseboard_fab2_lib.baseboard_fab2(sch_1):\PP1705\") )
				( member ( pinPairRef "@baseboard_fab2_lib.baseboard_fab2(sch_1):\PP1708\") )
				( member ( pinPairRef "@baseboard_fab2_lib.baseboard_fab2(sch_1):\PP1711\") )
				( member ( pinPairRef "@baseboard_fab2_lib.baseboard_fab2(sch_1):\PP1714\") )
				( member ( pinPairRef "@baseboard_fab2_lib.baseboard_fab2(sch_1):\PP1717\") )
				( member ( pinPairRef "@baseboard_fab2_lib.baseboard_fab2(sch_1):\PP1720\") )
				( member ( pinPairRef "@baseboard_fab2_lib.baseboard_fab2(sch_1):\PP1309\") )
				( member ( pinPairRef "@baseboard_fab2_lib.baseboard_fab2(sch_1):\PP1312\") )
				( member ( pinPairRef "@baseboard_fab2_lib.baseboard_fab2(sch_1):\PP1303\") )
				( member ( pinPairRef "@baseboard_fab2_lib.baseboard_fab2(sch_1):\PP1306\") )
				( objectStatus "MG_DQ-DQS_FAR_DIMM_NG_M_M_BYTE6" )
			)
			( matchGroup "@baseboard_fab2_lib.baseboard_fab2(sch_1):\MG_DQ_FAR_DIMM_NG_M_M_BYTE6\"
				( memberType ( signal ) )
				( member ( pinPairRef "@baseboard_fab2_lib.baseboard_fab2(sch_1):\PP1699\") )
				( member ( pinPairRef "@baseboard_fab2_lib.baseboard_fab2(sch_1):\PP1702\") )
				( member ( pinPairRef "@baseboard_fab2_lib.baseboard_fab2(sch_1):\PP1705\") )
				( member ( pinPairRef "@baseboard_fab2_lib.baseboard_fab2(sch_1):\PP1708\") )
				( member ( pinPairRef "@baseboard_fab2_lib.baseboard_fab2(sch_1):\PP1711\") )
				( member ( pinPairRef "@baseboard_fab2_lib.baseboard_fab2(sch_1):\PP1714\") )
				( member ( pinPairRef "@baseboard_fab2_lib.baseboard_fab2(sch_1):\PP1717\") )
				( member ( pinPairRef "@baseboard_fab2_lib.baseboard_fab2(sch_1):\PP1720\") )
				( objectStatus "MG_DQ_FAR_DIMM_NG_M_M_BYTE6" )
			)
			( matchGroup "@baseboard_fab2_lib.baseboard_fab2(sch_1):\MG_DQ-DQS_NEAR_DIMM_NG_M_M_BYTE6\"
				( memberType ( signal ) )
				( member ( pinPairRef "@baseboard_fab2_lib.baseboard_fab2(sch_1):\PP1701\") )
				( member ( pinPairRef "@baseboard_fab2_lib.baseboard_fab2(sch_1):\PP1704\") )
				( member ( pinPairRef "@baseboard_fab2_lib.baseboard_fab2(sch_1):\PP1707\") )
				( member ( pinPairRef "@baseboard_fab2_lib.baseboard_fab2(sch_1):\PP1710\") )
				( member ( pinPairRef "@baseboard_fab2_lib.baseboard_fab2(sch_1):\PP1713\") )
				( member ( pinPairRef "@baseboard_fab2_lib.baseboard_fab2(sch_1):\PP1716\") )
				( member ( pinPairRef "@baseboard_fab2_lib.baseboard_fab2(sch_1):\PP1719\") )
				( member ( pinPairRef "@baseboard_fab2_lib.baseboard_fab2(sch_1):\PP1722\") )
				( member ( pinPairRef "@baseboard_fab2_lib.baseboard_fab2(sch_1):\PP1311\") )
				( member ( pinPairRef "@baseboard_fab2_lib.baseboard_fab2(sch_1):\PP1314\") )
				( member ( pinPairRef "@baseboard_fab2_lib.baseboard_fab2(sch_1):\PP1305\") )
				( member ( pinPairRef "@baseboard_fab2_lib.baseboard_fab2(sch_1):\PP1308\") )
				( objectStatus "MG_DQ-DQS_NEAR_DIMM_NG_M_M_BYTE6" )
			)
			( matchGroup "@crescent_city_bb_fab1_lib.crescent_city_bb_fab1(sch_1):\MG_DQ_NEAR_DIMM_NG_M_M_BYTE6\"
				( memberType ( signal ) )
				( member ( pinPairRef "@baseboard_fab2_lib.baseboard_fab2(sch_1):\PP1701\") )
				( member ( pinPairRef "@baseboard_fab2_lib.baseboard_fab2(sch_1):\PP1704\") )
				( member ( pinPairRef "@baseboard_fab2_lib.baseboard_fab2(sch_1):\PP1707\") )
				( member ( pinPairRef "@baseboard_fab2_lib.baseboard_fab2(sch_1):\PP1710\") )
				( member ( pinPairRef "@baseboard_fab2_lib.baseboard_fab2(sch_1):\PP1713\") )
				( member ( pinPairRef "@baseboard_fab2_lib.baseboard_fab2(sch_1):\PP1716\") )
				( member ( pinPairRef "@baseboard_fab2_lib.baseboard_fab2(sch_1):\PP1719\") )
				( member ( pinPairRef "@baseboard_fab2_lib.baseboard_fab2(sch_1):\PP1722\") )
				( objectStatus "MG_DQ_NEAR_DIMM_NG_M_M_BYTE6" )
			)
			( matchGroup "@baseboard_fab2_lib.baseboard_fab2(sch_1):\MG_DQ-DQS_FAR_DIMM_NG_M_M_BYTE7\"
				( memberType ( signal ) )
				( member ( pinPairRef "@baseboard_fab2_lib.baseboard_fab2(sch_1):\PP1675\") )
				( member ( pinPairRef "@baseboard_fab2_lib.baseboard_fab2(sch_1):\PP1678\") )
				( member ( pinPairRef "@baseboard_fab2_lib.baseboard_fab2(sch_1):\PP1681\") )
				( member ( pinPairRef "@baseboard_fab2_lib.baseboard_fab2(sch_1):\PP1684\") )
				( member ( pinPairRef "@baseboard_fab2_lib.baseboard_fab2(sch_1):\PP1687\") )
				( member ( pinPairRef "@baseboard_fab2_lib.baseboard_fab2(sch_1):\PP1690\") )
				( member ( pinPairRef "@baseboard_fab2_lib.baseboard_fab2(sch_1):\PP1693\") )
				( member ( pinPairRef "@baseboard_fab2_lib.baseboard_fab2(sch_1):\PP1696\") )
				( member ( pinPairRef "@baseboard_fab2_lib.baseboard_fab2(sch_1):\PP1297\") )
				( member ( pinPairRef "@baseboard_fab2_lib.baseboard_fab2(sch_1):\PP1300\") )
				( member ( pinPairRef "@baseboard_fab2_lib.baseboard_fab2(sch_1):\PP1291\") )
				( member ( pinPairRef "@baseboard_fab2_lib.baseboard_fab2(sch_1):\PP1294\") )
				( objectStatus "MG_DQ-DQS_FAR_DIMM_NG_M_M_BYTE7" )
			)
			( matchGroup "@crescent_city_bb_fab1_lib.crescent_city_bb_fab1(sch_1):\MG_DQ_FAR_DIMM_NG_M_M_BYTE7\"
				( memberType ( signal ) )
				( member ( pinPairRef "@baseboard_fab2_lib.baseboard_fab2(sch_1):\PP1675\") )
				( member ( pinPairRef "@baseboard_fab2_lib.baseboard_fab2(sch_1):\PP1678\") )
				( member ( pinPairRef "@baseboard_fab2_lib.baseboard_fab2(sch_1):\PP1681\") )
				( member ( pinPairRef "@baseboard_fab2_lib.baseboard_fab2(sch_1):\PP1684\") )
				( member ( pinPairRef "@baseboard_fab2_lib.baseboard_fab2(sch_1):\PP1687\") )
				( member ( pinPairRef "@baseboard_fab2_lib.baseboard_fab2(sch_1):\PP1690\") )
				( member ( pinPairRef "@baseboard_fab2_lib.baseboard_fab2(sch_1):\PP1693\") )
				( member ( pinPairRef "@baseboard_fab2_lib.baseboard_fab2(sch_1):\PP1696\") )
				( objectStatus "MG_DQ_FAR_DIMM_NG_M_M_BYTE7" )
			)
			( matchGroup "@baseboard_fab2_lib.baseboard_fab2(sch_1):\MG_DQ-DQS_NEAR_DIMM_NG_M_M_BYTE7\"
				( memberType ( signal ) )
				( member ( pinPairRef "@baseboard_fab2_lib.baseboard_fab2(sch_1):\PP1677\") )
				( member ( pinPairRef "@baseboard_fab2_lib.baseboard_fab2(sch_1):\PP1680\") )
				( member ( pinPairRef "@baseboard_fab2_lib.baseboard_fab2(sch_1):\PP1683\") )
				( member ( pinPairRef "@baseboard_fab2_lib.baseboard_fab2(sch_1):\PP1686\") )
				( member ( pinPairRef "@baseboard_fab2_lib.baseboard_fab2(sch_1):\PP1689\") )
				( member ( pinPairRef "@baseboard_fab2_lib.baseboard_fab2(sch_1):\PP1692\") )
				( member ( pinPairRef "@baseboard_fab2_lib.baseboard_fab2(sch_1):\PP1694\") )
				( member ( pinPairRef "@baseboard_fab2_lib.baseboard_fab2(sch_1):\PP1698\") )
				( member ( pinPairRef "@baseboard_fab2_lib.baseboard_fab2(sch_1):\PP1299\") )
				( member ( pinPairRef "@baseboard_fab2_lib.baseboard_fab2(sch_1):\PP1302\") )
				( member ( pinPairRef "@baseboard_fab2_lib.baseboard_fab2(sch_1):\PP1293\") )
				( member ( pinPairRef "@baseboard_fab2_lib.baseboard_fab2(sch_1):\PP1296\") )
				( objectStatus "MG_DQ-DQS_NEAR_DIMM_NG_M_M_BYTE7" )
			)
			( matchGroup "@crescent_city_bb_fab1_lib.crescent_city_bb_fab1(sch_1):\MG_DQ_NEAR_DIMM_NG_M_M_BYTE7\"
				( memberType ( signal ) )
				( member ( pinPairRef "@baseboard_fab2_lib.baseboard_fab2(sch_1):\PP1677\") )
				( member ( pinPairRef "@baseboard_fab2_lib.baseboard_fab2(sch_1):\PP1680\") )
				( member ( pinPairRef "@baseboard_fab2_lib.baseboard_fab2(sch_1):\PP1683\") )
				( member ( pinPairRef "@baseboard_fab2_lib.baseboard_fab2(sch_1):\PP1686\") )
				( member ( pinPairRef "@baseboard_fab2_lib.baseboard_fab2(sch_1):\PP1689\") )
				( member ( pinPairRef "@baseboard_fab2_lib.baseboard_fab2(sch_1):\PP1692\") )
				( member ( pinPairRef "@baseboard_fab2_lib.baseboard_fab2(sch_1):\PP1694\") )
				( member ( pinPairRef "@baseboard_fab2_lib.baseboard_fab2(sch_1):\PP1698\") )
				( objectStatus "MG_DQ_NEAR_DIMM_NG_M_M_BYTE7" )
			)
			( matchGroup "@baseboard_fab2_lib.baseboard_fab2(sch_1):\MG_DQ-DQS_FAR_DIMM_NG_M_B_BYTE0\"
				( memberType ( signal ) )
				( member ( pinPairRef "@baseboard_fab2_lib.baseboard_fab2(sch_1):\PP5091\") )
				( member ( pinPairRef "@baseboard_fab2_lib.baseboard_fab2(sch_1):\PP5094\") )
				( member ( pinPairRef "@baseboard_fab2_lib.baseboard_fab2(sch_1):\PP5097\") )
				( member ( pinPairRef "@baseboard_fab2_lib.baseboard_fab2(sch_1):\PP5100\") )
				( member ( pinPairRef "@baseboard_fab2_lib.baseboard_fab2(sch_1):\PP5103\") )
				( member ( pinPairRef "@baseboard_fab2_lib.baseboard_fab2(sch_1):\PP5106\") )
				( member ( pinPairRef "@baseboard_fab2_lib.baseboard_fab2(sch_1):\PP5109\") )
				( member ( pinPairRef "@baseboard_fab2_lib.baseboard_fab2(sch_1):\PP5112\") )
				( member ( pinPairRef "@baseboard_fab2_lib.baseboard_fab2(sch_1):\PP568\") )
				( member ( pinPairRef "@baseboard_fab2_lib.baseboard_fab2(sch_1):\PP562\") )
				( member ( pinPairRef "@baseboard_fab2_lib.baseboard_fab2(sch_1):\PP565\") )
				( member ( pinPairRef "@baseboard_fab2_lib.baseboard_fab2(sch_1):\PP559\") )
				( objectStatus "MG_DQ-DQS_FAR_DIMM_NG_M_B_BYTE0" )
			)
			( matchGroup "@baseboard_fab2_lib.baseboard_fab2(sch_1):\MG_DQ_FAR_DIMM_NG_M_B_BYTE0\"
				( memberType ( signal ) )
				( member ( pinPairRef "@baseboard_fab2_lib.baseboard_fab2(sch_1):\PP5091\") )
				( member ( pinPairRef "@baseboard_fab2_lib.baseboard_fab2(sch_1):\PP5094\") )
				( member ( pinPairRef "@baseboard_fab2_lib.baseboard_fab2(sch_1):\PP5097\") )
				( member ( pinPairRef "@baseboard_fab2_lib.baseboard_fab2(sch_1):\PP5100\") )
				( member ( pinPairRef "@baseboard_fab2_lib.baseboard_fab2(sch_1):\PP5103\") )
				( member ( pinPairRef "@baseboard_fab2_lib.baseboard_fab2(sch_1):\PP5106\") )
				( member ( pinPairRef "@baseboard_fab2_lib.baseboard_fab2(sch_1):\PP5109\") )
				( member ( pinPairRef "@baseboard_fab2_lib.baseboard_fab2(sch_1):\PP5112\") )
				( objectStatus "MG_DQ_FAR_DIMM_NG_M_B_BYTE0" )
			)
			( matchGroup "@baseboard_fab2_lib.baseboard_fab2(sch_1):\MG_DQ-DQS_NEAR_DIMM_NG_M_B_BYTE0\"
				( memberType ( signal ) )
				( member ( pinPairRef "@baseboard_fab2_lib.baseboard_fab2(sch_1):\PP5093\") )
				( member ( pinPairRef "@baseboard_fab2_lib.baseboard_fab2(sch_1):\PP5096\") )
				( member ( pinPairRef "@baseboard_fab2_lib.baseboard_fab2(sch_1):\PP5099\") )
				( member ( pinPairRef "@baseboard_fab2_lib.baseboard_fab2(sch_1):\PP5102\") )
				( member ( pinPairRef "@baseboard_fab2_lib.baseboard_fab2(sch_1):\PP5105\") )
				( member ( pinPairRef "@baseboard_fab2_lib.baseboard_fab2(sch_1):\PP5108\") )
				( member ( pinPairRef "@baseboard_fab2_lib.baseboard_fab2(sch_1):\PP5111\") )
				( member ( pinPairRef "@baseboard_fab2_lib.baseboard_fab2(sch_1):\PP5114\") )
				( member ( pinPairRef "@baseboard_fab2_lib.baseboard_fab2(sch_1):\PP569\") )
				( member ( pinPairRef "@baseboard_fab2_lib.baseboard_fab2(sch_1):\PP563\") )
				( member ( pinPairRef "@baseboard_fab2_lib.baseboard_fab2(sch_1):\PP566\") )
				( member ( pinPairRef "@baseboard_fab2_lib.baseboard_fab2(sch_1):\PP560\") )
				( objectStatus "MG_DQ-DQS_NEAR_DIMM_NG_M_B_BYTE0" )
			)
			( matchGroup "@baseboard_fab2_lib.baseboard_fab2(sch_1):\MG_DQ_NEAR_DIMM_NG_M_B_BYTE0\"
				( memberType ( signal ) )
				( member ( pinPairRef "@baseboard_fab2_lib.baseboard_fab2(sch_1):\PP5093\") )
				( member ( pinPairRef "@baseboard_fab2_lib.baseboard_fab2(sch_1):\PP5096\") )
				( member ( pinPairRef "@baseboard_fab2_lib.baseboard_fab2(sch_1):\PP5099\") )
				( member ( pinPairRef "@baseboard_fab2_lib.baseboard_fab2(sch_1):\PP5102\") )
				( member ( pinPairRef "@baseboard_fab2_lib.baseboard_fab2(sch_1):\PP5105\") )
				( member ( pinPairRef "@baseboard_fab2_lib.baseboard_fab2(sch_1):\PP5108\") )
				( member ( pinPairRef "@baseboard_fab2_lib.baseboard_fab2(sch_1):\PP5111\") )
				( member ( pinPairRef "@baseboard_fab2_lib.baseboard_fab2(sch_1):\PP5114\") )
				( objectStatus "MG_DQ_NEAR_DIMM_NG_M_B_BYTE0" )
			)
			( matchGroup "@baseboard_fab2_lib.baseboard_fab2(sch_1):\MG_DQ-DQS_FAR_DIMM_NG_M_B_BYTE1\"
				( memberType ( signal ) )
				( member ( pinPairRef "@baseboard_fab2_lib.baseboard_fab2(sch_1):\PP5067\") )
				( member ( pinPairRef "@baseboard_fab2_lib.baseboard_fab2(sch_1):\PP5070\") )
				( member ( pinPairRef "@baseboard_fab2_lib.baseboard_fab2(sch_1):\PP5073\") )
				( member ( pinPairRef "@baseboard_fab2_lib.baseboard_fab2(sch_1):\PP5076\") )
				( member ( pinPairRef "@baseboard_fab2_lib.baseboard_fab2(sch_1):\PP5079\") )
				( member ( pinPairRef "@baseboard_fab2_lib.baseboard_fab2(sch_1):\PP5082\") )
				( member ( pinPairRef "@baseboard_fab2_lib.baseboard_fab2(sch_1):\PP5085\") )
				( member ( pinPairRef "@baseboard_fab2_lib.baseboard_fab2(sch_1):\PP5088\") )
				( member ( pinPairRef "@baseboard_fab2_lib.baseboard_fab2(sch_1):\PP556\") )
				( member ( pinPairRef "@baseboard_fab2_lib.baseboard_fab2(sch_1):\PP550\") )
				( member ( pinPairRef "@baseboard_fab2_lib.baseboard_fab2(sch_1):\PP553\") )
				( member ( pinPairRef "@baseboard_fab2_lib.baseboard_fab2(sch_1):\PP547\") )
				( objectStatus "MG_DQ-DQS_FAR_DIMM_NG_M_B_BYTE1" )
			)
			( matchGroup "@baseboard_fab2_lib.baseboard_fab2(sch_1):\MG_DQ_FAR_DIMM_NG_M_B_BYTE1\"
				( memberType ( signal ) )
				( member ( pinPairRef "@baseboard_fab2_lib.baseboard_fab2(sch_1):\PP5067\") )
				( member ( pinPairRef "@baseboard_fab2_lib.baseboard_fab2(sch_1):\PP5070\") )
				( member ( pinPairRef "@baseboard_fab2_lib.baseboard_fab2(sch_1):\PP5073\") )
				( member ( pinPairRef "@baseboard_fab2_lib.baseboard_fab2(sch_1):\PP5076\") )
				( member ( pinPairRef "@baseboard_fab2_lib.baseboard_fab2(sch_1):\PP5079\") )
				( member ( pinPairRef "@baseboard_fab2_lib.baseboard_fab2(sch_1):\PP5082\") )
				( member ( pinPairRef "@baseboard_fab2_lib.baseboard_fab2(sch_1):\PP5085\") )
				( member ( pinPairRef "@baseboard_fab2_lib.baseboard_fab2(sch_1):\PP5088\") )
				( objectStatus "MG_DQ_FAR_DIMM_NG_M_B_BYTE1" )
			)
			( matchGroup "@baseboard_fab2_lib.baseboard_fab2(sch_1):\MG_DQ-DQS_NEAR_DIMM_NG_M_B_BYTE1\"
				( memberType ( signal ) )
				( member ( pinPairRef "@baseboard_fab2_lib.baseboard_fab2(sch_1):\PP5069\") )
				( member ( pinPairRef "@baseboard_fab2_lib.baseboard_fab2(sch_1):\PP5072\") )
				( member ( pinPairRef "@baseboard_fab2_lib.baseboard_fab2(sch_1):\PP5075\") )
				( member ( pinPairRef "@baseboard_fab2_lib.baseboard_fab2(sch_1):\PP5078\") )
				( member ( pinPairRef "@baseboard_fab2_lib.baseboard_fab2(sch_1):\PP5081\") )
				( member ( pinPairRef "@baseboard_fab2_lib.baseboard_fab2(sch_1):\PP5084\") )
				( member ( pinPairRef "@baseboard_fab2_lib.baseboard_fab2(sch_1):\PP5087\") )
				( member ( pinPairRef "@baseboard_fab2_lib.baseboard_fab2(sch_1):\PP5090\") )
				( member ( pinPairRef "@baseboard_fab2_lib.baseboard_fab2(sch_1):\PP557\") )
				( member ( pinPairRef "@baseboard_fab2_lib.baseboard_fab2(sch_1):\PP551\") )
				( member ( pinPairRef "@baseboard_fab2_lib.baseboard_fab2(sch_1):\PP554\") )
				( member ( pinPairRef "@baseboard_fab2_lib.baseboard_fab2(sch_1):\PP548\") )
				( objectStatus "MG_DQ-DQS_NEAR_DIMM_NG_M_B_BYTE1" )
			)
			( matchGroup "@baseboard_fab2_lib.baseboard_fab2(sch_1):\MG_DQ_NEAR_DIMM_NG_M_B_BYTE1\"
				( memberType ( signal ) )
				( member ( pinPairRef "@baseboard_fab2_lib.baseboard_fab2(sch_1):\PP5069\") )
				( member ( pinPairRef "@baseboard_fab2_lib.baseboard_fab2(sch_1):\PP5072\") )
				( member ( pinPairRef "@baseboard_fab2_lib.baseboard_fab2(sch_1):\PP5075\") )
				( member ( pinPairRef "@baseboard_fab2_lib.baseboard_fab2(sch_1):\PP5078\") )
				( member ( pinPairRef "@baseboard_fab2_lib.baseboard_fab2(sch_1):\PP5081\") )
				( member ( pinPairRef "@baseboard_fab2_lib.baseboard_fab2(sch_1):\PP5084\") )
				( member ( pinPairRef "@baseboard_fab2_lib.baseboard_fab2(sch_1):\PP5087\") )
				( member ( pinPairRef "@baseboard_fab2_lib.baseboard_fab2(sch_1):\PP5090\") )
				( objectStatus "MG_DQ_NEAR_DIMM_NG_M_B_BYTE1" )
			)
			( matchGroup "@baseboard_fab2_lib.baseboard_fab2(sch_1):\MG_DQ-DQS_FAR_DIMM_NG_M_B_BYTE2\"
				( memberType ( signal ) )
				( member ( pinPairRef "@baseboard_fab2_lib.baseboard_fab2(sch_1):\PP5043\") )
				( member ( pinPairRef "@baseboard_fab2_lib.baseboard_fab2(sch_1):\PP5046\") )
				( member ( pinPairRef "@baseboard_fab2_lib.baseboard_fab2(sch_1):\PP5049\") )
				( member ( pinPairRef "@baseboard_fab2_lib.baseboard_fab2(sch_1):\PP5052\") )
				( member ( pinPairRef "@baseboard_fab2_lib.baseboard_fab2(sch_1):\PP5055\") )
				( member ( pinPairRef "@baseboard_fab2_lib.baseboard_fab2(sch_1):\PP5058\") )
				( member ( pinPairRef "@baseboard_fab2_lib.baseboard_fab2(sch_1):\PP5061\") )
				( member ( pinPairRef "@baseboard_fab2_lib.baseboard_fab2(sch_1):\PP5064\") )
				( member ( pinPairRef "@baseboard_fab2_lib.baseboard_fab2(sch_1):\PP544\") )
				( member ( pinPairRef "@baseboard_fab2_lib.baseboard_fab2(sch_1):\PP538\") )
				( member ( pinPairRef "@baseboard_fab2_lib.baseboard_fab2(sch_1):\PP541\") )
				( member ( pinPairRef "@baseboard_fab2_lib.baseboard_fab2(sch_1):\PP535\") )
				( objectStatus "MG_DQ-DQS_FAR_DIMM_NG_M_B_BYTE2" )
			)
			( matchGroup "@baseboard_fab2_lib.baseboard_fab2(sch_1):\MG_DQ_FAR_DIMM_NG_M_B_BYTE2\"
				( memberType ( signal ) )
				( member ( pinPairRef "@baseboard_fab2_lib.baseboard_fab2(sch_1):\PP5043\") )
				( member ( pinPairRef "@baseboard_fab2_lib.baseboard_fab2(sch_1):\PP5046\") )
				( member ( pinPairRef "@baseboard_fab2_lib.baseboard_fab2(sch_1):\PP5049\") )
				( member ( pinPairRef "@baseboard_fab2_lib.baseboard_fab2(sch_1):\PP5052\") )
				( member ( pinPairRef "@baseboard_fab2_lib.baseboard_fab2(sch_1):\PP5055\") )
				( member ( pinPairRef "@baseboard_fab2_lib.baseboard_fab2(sch_1):\PP5058\") )
				( member ( pinPairRef "@baseboard_fab2_lib.baseboard_fab2(sch_1):\PP5061\") )
				( member ( pinPairRef "@baseboard_fab2_lib.baseboard_fab2(sch_1):\PP5064\") )
				( objectStatus "MG_DQ_FAR_DIMM_NG_M_B_BYTE2" )
			)
			( matchGroup "@baseboard_fab2_lib.baseboard_fab2(sch_1):\MG_DQ-DQS_NEAR_DIMM_NG_M_B_BYTE2\"
				( memberType ( signal ) )
				( member ( pinPairRef "@baseboard_fab2_lib.baseboard_fab2(sch_1):\PP5045\") )
				( member ( pinPairRef "@baseboard_fab2_lib.baseboard_fab2(sch_1):\PP5048\") )
				( member ( pinPairRef "@baseboard_fab2_lib.baseboard_fab2(sch_1):\PP5051\") )
				( member ( pinPairRef "@baseboard_fab2_lib.baseboard_fab2(sch_1):\PP5054\") )
				( member ( pinPairRef "@baseboard_fab2_lib.baseboard_fab2(sch_1):\PP5057\") )
				( member ( pinPairRef "@baseboard_fab2_lib.baseboard_fab2(sch_1):\PP5060\") )
				( member ( pinPairRef "@baseboard_fab2_lib.baseboard_fab2(sch_1):\PP5063\") )
				( member ( pinPairRef "@baseboard_fab2_lib.baseboard_fab2(sch_1):\PP5066\") )
				( member ( pinPairRef "@baseboard_fab2_lib.baseboard_fab2(sch_1):\PP545\") )
				( member ( pinPairRef "@baseboard_fab2_lib.baseboard_fab2(sch_1):\PP539\") )
				( member ( pinPairRef "@baseboard_fab2_lib.baseboard_fab2(sch_1):\PP542\") )
				( member ( pinPairRef "@baseboard_fab2_lib.baseboard_fab2(sch_1):\PP536\") )
				( objectStatus "MG_DQ-DQS_NEAR_DIMM_NG_M_B_BYTE2" )
			)
			( matchGroup "@baseboard_fab2_lib.baseboard_fab2(sch_1):\MG_DQ_NEAR_DIMM_NG_M_B_BYTE2\"
				( memberType ( signal ) )
				( member ( pinPairRef "@baseboard_fab2_lib.baseboard_fab2(sch_1):\PP5045\") )
				( member ( pinPairRef "@baseboard_fab2_lib.baseboard_fab2(sch_1):\PP5048\") )
				( member ( pinPairRef "@baseboard_fab2_lib.baseboard_fab2(sch_1):\PP5051\") )
				( member ( pinPairRef "@baseboard_fab2_lib.baseboard_fab2(sch_1):\PP5054\") )
				( member ( pinPairRef "@baseboard_fab2_lib.baseboard_fab2(sch_1):\PP5057\") )
				( member ( pinPairRef "@baseboard_fab2_lib.baseboard_fab2(sch_1):\PP5060\") )
				( member ( pinPairRef "@baseboard_fab2_lib.baseboard_fab2(sch_1):\PP5063\") )
				( member ( pinPairRef "@baseboard_fab2_lib.baseboard_fab2(sch_1):\PP5066\") )
				( objectStatus "MG_DQ_NEAR_DIMM_NG_M_B_BYTE2" )
			)
			( matchGroup "@baseboard_fab2_lib.baseboard_fab2(sch_1):\MG_DQ-DQS_FAR_DIMM_NG_M_B_BYTE3\"
				( memberType ( signal ) )
				( member ( pinPairRef "@baseboard_fab2_lib.baseboard_fab2(sch_1):\PP5019\") )
				( member ( pinPairRef "@baseboard_fab2_lib.baseboard_fab2(sch_1):\PP5022\") )
				( member ( pinPairRef "@baseboard_fab2_lib.baseboard_fab2(sch_1):\PP5025\") )
				( member ( pinPairRef "@baseboard_fab2_lib.baseboard_fab2(sch_1):\PP5028\") )
				( member ( pinPairRef "@baseboard_fab2_lib.baseboard_fab2(sch_1):\PP5031\") )
				( member ( pinPairRef "@baseboard_fab2_lib.baseboard_fab2(sch_1):\PP5034\") )
				( member ( pinPairRef "@baseboard_fab2_lib.baseboard_fab2(sch_1):\PP5037\") )
				( member ( pinPairRef "@baseboard_fab2_lib.baseboard_fab2(sch_1):\PP5040\") )
				( member ( pinPairRef "@baseboard_fab2_lib.baseboard_fab2(sch_1):\PP532\") )
				( member ( pinPairRef "@baseboard_fab2_lib.baseboard_fab2(sch_1):\PP526\") )
				( member ( pinPairRef "@baseboard_fab2_lib.baseboard_fab2(sch_1):\PP529\") )
				( member ( pinPairRef "@baseboard_fab2_lib.baseboard_fab2(sch_1):\PP523\") )
				( objectStatus "MG_DQ-DQS_FAR_DIMM_NG_M_B_BYTE3" )
			)
			( matchGroup "@crescent_city_bb_fab1_lib.crescent_city_bb_fab1(sch_1):\MG_DQ_FAR_DIMM_NG_M_B_BYTE3\"
				( memberType ( signal ) )
				( member ( pinPairRef "@baseboard_fab2_lib.baseboard_fab2(sch_1):\PP5019\") )
				( member ( pinPairRef "@baseboard_fab2_lib.baseboard_fab2(sch_1):\PP5022\") )
				( member ( pinPairRef "@baseboard_fab2_lib.baseboard_fab2(sch_1):\PP5025\") )
				( member ( pinPairRef "@baseboard_fab2_lib.baseboard_fab2(sch_1):\PP5028\") )
				( member ( pinPairRef "@baseboard_fab2_lib.baseboard_fab2(sch_1):\PP5031\") )
				( member ( pinPairRef "@baseboard_fab2_lib.baseboard_fab2(sch_1):\PP5034\") )
				( member ( pinPairRef "@baseboard_fab2_lib.baseboard_fab2(sch_1):\PP5037\") )
				( member ( pinPairRef "@baseboard_fab2_lib.baseboard_fab2(sch_1):\PP5040\") )
				( objectStatus "MG_DQ_FAR_DIMM_NG_M_B_BYTE3" )
			)
			( matchGroup "@baseboard_fab2_lib.baseboard_fab2(sch_1):\MG_DQ-DQS_NEAR_DIMM_NG_M_B_BYTE3\"
				( memberType ( signal ) )
				( member ( pinPairRef "@baseboard_fab2_lib.baseboard_fab2(sch_1):\PP5021\") )
				( member ( pinPairRef "@baseboard_fab2_lib.baseboard_fab2(sch_1):\PP5024\") )
				( member ( pinPairRef "@baseboard_fab2_lib.baseboard_fab2(sch_1):\PP5027\") )
				( member ( pinPairRef "@baseboard_fab2_lib.baseboard_fab2(sch_1):\PP5030\") )
				( member ( pinPairRef "@baseboard_fab2_lib.baseboard_fab2(sch_1):\PP5033\") )
				( member ( pinPairRef "@baseboard_fab2_lib.baseboard_fab2(sch_1):\PP5036\") )
				( member ( pinPairRef "@baseboard_fab2_lib.baseboard_fab2(sch_1):\PP5039\") )
				( member ( pinPairRef "@baseboard_fab2_lib.baseboard_fab2(sch_1):\PP5042\") )
				( member ( pinPairRef "@baseboard_fab2_lib.baseboard_fab2(sch_1):\PP533\") )
				( member ( pinPairRef "@baseboard_fab2_lib.baseboard_fab2(sch_1):\PP527\") )
				( member ( pinPairRef "@baseboard_fab2_lib.baseboard_fab2(sch_1):\PP530\") )
				( member ( pinPairRef "@baseboard_fab2_lib.baseboard_fab2(sch_1):\PP524\") )
				( objectStatus "MG_DQ-DQS_NEAR_DIMM_NG_M_B_BYTE3" )
			)
			( matchGroup "@crescent_city_bb_fab1_lib.crescent_city_bb_fab1(sch_1):\MG_DQ_NEAR_DIMM_NG_M_B_BYTE3\"
				( memberType ( signal ) )
				( member ( pinPairRef "@baseboard_fab2_lib.baseboard_fab2(sch_1):\PP5021\") )
				( member ( pinPairRef "@baseboard_fab2_lib.baseboard_fab2(sch_1):\PP5024\") )
				( member ( pinPairRef "@baseboard_fab2_lib.baseboard_fab2(sch_1):\PP5027\") )
				( member ( pinPairRef "@baseboard_fab2_lib.baseboard_fab2(sch_1):\PP5030\") )
				( member ( pinPairRef "@baseboard_fab2_lib.baseboard_fab2(sch_1):\PP5033\") )
				( member ( pinPairRef "@baseboard_fab2_lib.baseboard_fab2(sch_1):\PP5036\") )
				( member ( pinPairRef "@baseboard_fab2_lib.baseboard_fab2(sch_1):\PP5039\") )
				( member ( pinPairRef "@baseboard_fab2_lib.baseboard_fab2(sch_1):\PP5042\") )
				( objectStatus "MG_DQ_NEAR_DIMM_NG_M_B_BYTE3" )
			)
			( matchGroup "@baseboard_fab2_lib.baseboard_fab2(sch_1):\MG_DQ-DQS_FAR_DIMM_NG_M_B_BYTE4\"
				( memberType ( signal ) )
				( member ( pinPairRef "@baseboard_fab2_lib.baseboard_fab2(sch_1):\PP4995\") )
				( member ( pinPairRef "@baseboard_fab2_lib.baseboard_fab2(sch_1):\PP4998\") )
				( member ( pinPairRef "@baseboard_fab2_lib.baseboard_fab2(sch_1):\PP5001\") )
				( member ( pinPairRef "@baseboard_fab2_lib.baseboard_fab2(sch_1):\PP5004\") )
				( member ( pinPairRef "@baseboard_fab2_lib.baseboard_fab2(sch_1):\PP5007\") )
				( member ( pinPairRef "@baseboard_fab2_lib.baseboard_fab2(sch_1):\PP5010\") )
				( member ( pinPairRef "@baseboard_fab2_lib.baseboard_fab2(sch_1):\PP5013\") )
				( member ( pinPairRef "@baseboard_fab2_lib.baseboard_fab2(sch_1):\PP5016\") )
				( member ( pinPairRef "@baseboard_fab2_lib.baseboard_fab2(sch_1):\PP520\") )
				( member ( pinPairRef "@baseboard_fab2_lib.baseboard_fab2(sch_1):\PP514\") )
				( member ( pinPairRef "@baseboard_fab2_lib.baseboard_fab2(sch_1):\PP517\") )
				( member ( pinPairRef "@baseboard_fab2_lib.baseboard_fab2(sch_1):\PP511\") )
				( objectStatus "MG_DQ-DQS_FAR_DIMM_NG_M_B_BYTE4" )
			)
			( matchGroup "@crescent_city_bb_fab1_lib.crescent_city_bb_fab1(sch_1):\MG_DQ_FAR_DIMM_NG_M_B_BYTE4\"
				( memberType ( signal ) )
				( member ( pinPairRef "@baseboard_fab2_lib.baseboard_fab2(sch_1):\PP4995\") )
				( member ( pinPairRef "@baseboard_fab2_lib.baseboard_fab2(sch_1):\PP4998\") )
				( member ( pinPairRef "@baseboard_fab2_lib.baseboard_fab2(sch_1):\PP5001\") )
				( member ( pinPairRef "@baseboard_fab2_lib.baseboard_fab2(sch_1):\PP5004\") )
				( member ( pinPairRef "@baseboard_fab2_lib.baseboard_fab2(sch_1):\PP5007\") )
				( member ( pinPairRef "@baseboard_fab2_lib.baseboard_fab2(sch_1):\PP5010\") )
				( member ( pinPairRef "@baseboard_fab2_lib.baseboard_fab2(sch_1):\PP5013\") )
				( member ( pinPairRef "@baseboard_fab2_lib.baseboard_fab2(sch_1):\PP5016\") )
				( objectStatus "MG_DQ_FAR_DIMM_NG_M_B_BYTE4" )
			)
			( matchGroup "@baseboard_fab2_lib.baseboard_fab2(sch_1):\MG_DQ-DQS_NEAR_DIMM_NG_M_B_BYTE4\"
				( memberType ( signal ) )
				( member ( pinPairRef "@baseboard_fab2_lib.baseboard_fab2(sch_1):\PP4997\") )
				( member ( pinPairRef "@baseboard_fab2_lib.baseboard_fab2(sch_1):\PP5000\") )
				( member ( pinPairRef "@baseboard_fab2_lib.baseboard_fab2(sch_1):\PP5003\") )
				( member ( pinPairRef "@baseboard_fab2_lib.baseboard_fab2(sch_1):\PP5006\") )
				( member ( pinPairRef "@baseboard_fab2_lib.baseboard_fab2(sch_1):\PP5009\") )
				( member ( pinPairRef "@baseboard_fab2_lib.baseboard_fab2(sch_1):\PP5012\") )
				( member ( pinPairRef "@baseboard_fab2_lib.baseboard_fab2(sch_1):\PP5015\") )
				( member ( pinPairRef "@baseboard_fab2_lib.baseboard_fab2(sch_1):\PP5018\") )
				( member ( pinPairRef "@baseboard_fab2_lib.baseboard_fab2(sch_1):\PP522\") )
				( member ( pinPairRef "@baseboard_fab2_lib.baseboard_fab2(sch_1):\PP516\") )
				( member ( pinPairRef "@baseboard_fab2_lib.baseboard_fab2(sch_1):\PP519\") )
				( member ( pinPairRef "@baseboard_fab2_lib.baseboard_fab2(sch_1):\PP513\") )
				( objectStatus "MG_DQ-DQS_NEAR_DIMM_NG_M_B_BYTE4" )
			)
			( matchGroup "@crescent_city_bb_fab1_lib.crescent_city_bb_fab1(sch_1):\MG_DQ_NEAR_DIMM_NG_M_B_BYTE4\"
				( memberType ( signal ) )
				( member ( pinPairRef "@baseboard_fab2_lib.baseboard_fab2(sch_1):\PP4997\") )
				( member ( pinPairRef "@baseboard_fab2_lib.baseboard_fab2(sch_1):\PP5000\") )
				( member ( pinPairRef "@baseboard_fab2_lib.baseboard_fab2(sch_1):\PP5003\") )
				( member ( pinPairRef "@baseboard_fab2_lib.baseboard_fab2(sch_1):\PP5006\") )
				( member ( pinPairRef "@baseboard_fab2_lib.baseboard_fab2(sch_1):\PP5009\") )
				( member ( pinPairRef "@baseboard_fab2_lib.baseboard_fab2(sch_1):\PP5012\") )
				( member ( pinPairRef "@baseboard_fab2_lib.baseboard_fab2(sch_1):\PP5015\") )
				( member ( pinPairRef "@baseboard_fab2_lib.baseboard_fab2(sch_1):\PP5018\") )
				( objectStatus "MG_DQ_NEAR_DIMM_NG_M_B_BYTE4" )
			)
			( matchGroup "@baseboard_fab2_lib.baseboard_fab2(sch_1):\MG_DQ-DQS_FAR_DIMM_NG_M_B_BYTE5\"
				( memberType ( signal ) )
				( member ( pinPairRef "@baseboard_fab2_lib.baseboard_fab2(sch_1):\PP4971\") )
				( member ( pinPairRef "@baseboard_fab2_lib.baseboard_fab2(sch_1):\PP4974\") )
				( member ( pinPairRef "@baseboard_fab2_lib.baseboard_fab2(sch_1):\PP4977\") )
				( member ( pinPairRef "@baseboard_fab2_lib.baseboard_fab2(sch_1):\PP4980\") )
				( member ( pinPairRef "@baseboard_fab2_lib.baseboard_fab2(sch_1):\PP4983\") )
				( member ( pinPairRef "@baseboard_fab2_lib.baseboard_fab2(sch_1):\PP4986\") )
				( member ( pinPairRef "@baseboard_fab2_lib.baseboard_fab2(sch_1):\PP4989\") )
				( member ( pinPairRef "@baseboard_fab2_lib.baseboard_fab2(sch_1):\PP4992\") )
				( member ( pinPairRef "@baseboard_fab2_lib.baseboard_fab2(sch_1):\PP508\") )
				( member ( pinPairRef "@baseboard_fab2_lib.baseboard_fab2(sch_1):\PP502\") )
				( member ( pinPairRef "@baseboard_fab2_lib.baseboard_fab2(sch_1):\PP505\") )
				( member ( pinPairRef "@baseboard_fab2_lib.baseboard_fab2(sch_1):\PP499\") )
				( objectStatus "MG_DQ-DQS_FAR_DIMM_NG_M_B_BYTE5" )
			)
			( matchGroup "@baseboard_fab2_lib.baseboard_fab2(sch_1):\MG_DQ_FAR_DIMM_NG_M_B_BYTE5\"
				( memberType ( signal ) )
				( member ( pinPairRef "@baseboard_fab2_lib.baseboard_fab2(sch_1):\PP4971\") )
				( member ( pinPairRef "@baseboard_fab2_lib.baseboard_fab2(sch_1):\PP4974\") )
				( member ( pinPairRef "@baseboard_fab2_lib.baseboard_fab2(sch_1):\PP4977\") )
				( member ( pinPairRef "@baseboard_fab2_lib.baseboard_fab2(sch_1):\PP4980\") )
				( member ( pinPairRef "@baseboard_fab2_lib.baseboard_fab2(sch_1):\PP4983\") )
				( member ( pinPairRef "@baseboard_fab2_lib.baseboard_fab2(sch_1):\PP4986\") )
				( member ( pinPairRef "@baseboard_fab2_lib.baseboard_fab2(sch_1):\PP4989\") )
				( member ( pinPairRef "@baseboard_fab2_lib.baseboard_fab2(sch_1):\PP4992\") )
				( objectStatus "MG_DQ_FAR_DIMM_NG_M_B_BYTE5" )
			)
			( matchGroup "@baseboard_fab2_lib.baseboard_fab2(sch_1):\MG_DQ-DQS_NEAR_DIMM_NG_M_B_BYTE5\"
				( memberType ( signal ) )
				( member ( pinPairRef "@baseboard_fab2_lib.baseboard_fab2(sch_1):\PP4973\") )
				( member ( pinPairRef "@baseboard_fab2_lib.baseboard_fab2(sch_1):\PP4976\") )
				( member ( pinPairRef "@baseboard_fab2_lib.baseboard_fab2(sch_1):\PP4979\") )
				( member ( pinPairRef "@baseboard_fab2_lib.baseboard_fab2(sch_1):\PP4982\") )
				( member ( pinPairRef "@baseboard_fab2_lib.baseboard_fab2(sch_1):\PP4985\") )
				( member ( pinPairRef "@baseboard_fab2_lib.baseboard_fab2(sch_1):\PP4988\") )
				( member ( pinPairRef "@baseboard_fab2_lib.baseboard_fab2(sch_1):\PP4991\") )
				( member ( pinPairRef "@baseboard_fab2_lib.baseboard_fab2(sch_1):\PP4994\") )
				( member ( pinPairRef "@baseboard_fab2_lib.baseboard_fab2(sch_1):\PP509\") )
				( member ( pinPairRef "@baseboard_fab2_lib.baseboard_fab2(sch_1):\PP503\") )
				( member ( pinPairRef "@baseboard_fab2_lib.baseboard_fab2(sch_1):\PP506\") )
				( member ( pinPairRef "@baseboard_fab2_lib.baseboard_fab2(sch_1):\PP500\") )
				( objectStatus "MG_DQ-DQS_NEAR_DIMM_NG_M_B_BYTE5" )
			)
			( matchGroup "@baseboard_fab2_lib.baseboard_fab2(sch_1):\MG_DQ_NEAR_DIMM_NG_M_B_BYTE5\"
				( memberType ( signal ) )
				( member ( pinPairRef "@baseboard_fab2_lib.baseboard_fab2(sch_1):\PP4973\") )
				( member ( pinPairRef "@baseboard_fab2_lib.baseboard_fab2(sch_1):\PP4976\") )
				( member ( pinPairRef "@baseboard_fab2_lib.baseboard_fab2(sch_1):\PP4979\") )
				( member ( pinPairRef "@baseboard_fab2_lib.baseboard_fab2(sch_1):\PP4982\") )
				( member ( pinPairRef "@baseboard_fab2_lib.baseboard_fab2(sch_1):\PP4985\") )
				( member ( pinPairRef "@baseboard_fab2_lib.baseboard_fab2(sch_1):\PP4988\") )
				( member ( pinPairRef "@baseboard_fab2_lib.baseboard_fab2(sch_1):\PP4991\") )
				( member ( pinPairRef "@baseboard_fab2_lib.baseboard_fab2(sch_1):\PP4994\") )
				( objectStatus "MG_DQ_NEAR_DIMM_NG_M_B_BYTE5" )
			)
			( matchGroup "@baseboard_fab2_lib.baseboard_fab2(sch_1):\MG_DQ-DQS_FAR_DIMM_NG_M_B_BYTE6\"
				( memberType ( signal ) )
				( member ( pinPairRef "@baseboard_fab2_lib.baseboard_fab2(sch_1):\PP4947\") )
				( member ( pinPairRef "@baseboard_fab2_lib.baseboard_fab2(sch_1):\PP4950\") )
				( member ( pinPairRef "@baseboard_fab2_lib.baseboard_fab2(sch_1):\PP4953\") )
				( member ( pinPairRef "@baseboard_fab2_lib.baseboard_fab2(sch_1):\PP4956\") )
				( member ( pinPairRef "@baseboard_fab2_lib.baseboard_fab2(sch_1):\PP4959\") )
				( member ( pinPairRef "@baseboard_fab2_lib.baseboard_fab2(sch_1):\PP4962\") )
				( member ( pinPairRef "@baseboard_fab2_lib.baseboard_fab2(sch_1):\PP4965\") )
				( member ( pinPairRef "@baseboard_fab2_lib.baseboard_fab2(sch_1):\PP4968\") )
				( member ( pinPairRef "@baseboard_fab2_lib.baseboard_fab2(sch_1):\PP496\") )
				( member ( pinPairRef "@baseboard_fab2_lib.baseboard_fab2(sch_1):\PP490\") )
				( member ( pinPairRef "@baseboard_fab2_lib.baseboard_fab2(sch_1):\PP493\") )
				( member ( pinPairRef "@baseboard_fab2_lib.baseboard_fab2(sch_1):\PP487\") )
				( objectStatus "MG_DQ-DQS_FAR_DIMM_NG_M_B_BYTE6" )
			)
			( matchGroup "@baseboard_fab2_lib.baseboard_fab2(sch_1):\MG_DQ_FAR_DIMM_NG_M_B_BYTE6\"
				( memberType ( signal ) )
				( member ( pinPairRef "@baseboard_fab2_lib.baseboard_fab2(sch_1):\PP4947\") )
				( member ( pinPairRef "@baseboard_fab2_lib.baseboard_fab2(sch_1):\PP4950\") )
				( member ( pinPairRef "@baseboard_fab2_lib.baseboard_fab2(sch_1):\PP4953\") )
				( member ( pinPairRef "@baseboard_fab2_lib.baseboard_fab2(sch_1):\PP4956\") )
				( member ( pinPairRef "@baseboard_fab2_lib.baseboard_fab2(sch_1):\PP4959\") )
				( member ( pinPairRef "@baseboard_fab2_lib.baseboard_fab2(sch_1):\PP4962\") )
				( member ( pinPairRef "@baseboard_fab2_lib.baseboard_fab2(sch_1):\PP4965\") )
				( member ( pinPairRef "@baseboard_fab2_lib.baseboard_fab2(sch_1):\PP4968\") )
				( objectStatus "MG_DQ_FAR_DIMM_NG_M_B_BYTE6" )
			)
			( matchGroup "@baseboard_fab2_lib.baseboard_fab2(sch_1):\MG_DQ-DQS_NEAR_DIMM_NG_M_B_BYTE6\"
				( memberType ( signal ) )
				( member ( pinPairRef "@baseboard_fab2_lib.baseboard_fab2(sch_1):\PP4949\") )
				( member ( pinPairRef "@baseboard_fab2_lib.baseboard_fab2(sch_1):\PP4952\") )
				( member ( pinPairRef "@baseboard_fab2_lib.baseboard_fab2(sch_1):\PP4955\") )
				( member ( pinPairRef "@baseboard_fab2_lib.baseboard_fab2(sch_1):\PP4958\") )
				( member ( pinPairRef "@baseboard_fab2_lib.baseboard_fab2(sch_1):\PP4961\") )
				( member ( pinPairRef "@baseboard_fab2_lib.baseboard_fab2(sch_1):\PP4964\") )
				( member ( pinPairRef "@baseboard_fab2_lib.baseboard_fab2(sch_1):\PP4967\") )
				( member ( pinPairRef "@baseboard_fab2_lib.baseboard_fab2(sch_1):\PP4970\") )
				( member ( pinPairRef "@baseboard_fab2_lib.baseboard_fab2(sch_1):\PP497\") )
				( member ( pinPairRef "@baseboard_fab2_lib.baseboard_fab2(sch_1):\PP491\") )
				( member ( pinPairRef "@baseboard_fab2_lib.baseboard_fab2(sch_1):\PP494\") )
				( member ( pinPairRef "@baseboard_fab2_lib.baseboard_fab2(sch_1):\PP488\") )
				( objectStatus "MG_DQ-DQS_NEAR_DIMM_NG_M_B_BYTE6" )
			)
			( matchGroup "@baseboard_fab2_lib.baseboard_fab2(sch_1):\MG_DQ_NEAR_DIMM_NG_M_B_BYTE6\"
				( memberType ( signal ) )
				( member ( pinPairRef "@baseboard_fab2_lib.baseboard_fab2(sch_1):\PP4949\") )
				( member ( pinPairRef "@baseboard_fab2_lib.baseboard_fab2(sch_1):\PP4952\") )
				( member ( pinPairRef "@baseboard_fab2_lib.baseboard_fab2(sch_1):\PP4955\") )
				( member ( pinPairRef "@baseboard_fab2_lib.baseboard_fab2(sch_1):\PP4958\") )
				( member ( pinPairRef "@baseboard_fab2_lib.baseboard_fab2(sch_1):\PP4961\") )
				( member ( pinPairRef "@baseboard_fab2_lib.baseboard_fab2(sch_1):\PP4964\") )
				( member ( pinPairRef "@baseboard_fab2_lib.baseboard_fab2(sch_1):\PP4967\") )
				( member ( pinPairRef "@baseboard_fab2_lib.baseboard_fab2(sch_1):\PP4970\") )
				( objectStatus "MG_DQ_NEAR_DIMM_NG_M_B_BYTE6" )
			)
			( matchGroup "@baseboard_fab2_lib.baseboard_fab2(sch_1):\MG_DQ-DQS_FAR_DIMM_NG_M_B_BYTE7\"
				( memberType ( signal ) )
				( member ( pinPairRef "@baseboard_fab2_lib.baseboard_fab2(sch_1):\PP4923\") )
				( member ( pinPairRef "@baseboard_fab2_lib.baseboard_fab2(sch_1):\PP4926\") )
				( member ( pinPairRef "@baseboard_fab2_lib.baseboard_fab2(sch_1):\PP4929\") )
				( member ( pinPairRef "@baseboard_fab2_lib.baseboard_fab2(sch_1):\PP4932\") )
				( member ( pinPairRef "@baseboard_fab2_lib.baseboard_fab2(sch_1):\PP4935\") )
				( member ( pinPairRef "@baseboard_fab2_lib.baseboard_fab2(sch_1):\PP4938\") )
				( member ( pinPairRef "@baseboard_fab2_lib.baseboard_fab2(sch_1):\PP4941\") )
				( member ( pinPairRef "@baseboard_fab2_lib.baseboard_fab2(sch_1):\PP4944\") )
				( member ( pinPairRef "@baseboard_fab2_lib.baseboard_fab2(sch_1):\PP475\") )
				( member ( pinPairRef "@baseboard_fab2_lib.baseboard_fab2(sch_1):\PP484\") )
				( member ( pinPairRef "@baseboard_fab2_lib.baseboard_fab2(sch_1):\PP478\") )
				( member ( pinPairRef "@baseboard_fab2_lib.baseboard_fab2(sch_1):\PP481\") )
				( objectStatus "MG_DQ-DQS_FAR_DIMM_NG_M_B_BYTE7" )
			)
			( matchGroup "@baseboard_fab2_lib.baseboard_fab2(sch_1):\MG_DQ_FAR_DIMM_NG_M_B_BYTE7\"
				( memberType ( signal ) )
				( member ( pinPairRef "@baseboard_fab2_lib.baseboard_fab2(sch_1):\PP4923\") )
				( member ( pinPairRef "@baseboard_fab2_lib.baseboard_fab2(sch_1):\PP4926\") )
				( member ( pinPairRef "@baseboard_fab2_lib.baseboard_fab2(sch_1):\PP4929\") )
				( member ( pinPairRef "@baseboard_fab2_lib.baseboard_fab2(sch_1):\PP4932\") )
				( member ( pinPairRef "@baseboard_fab2_lib.baseboard_fab2(sch_1):\PP4935\") )
				( member ( pinPairRef "@baseboard_fab2_lib.baseboard_fab2(sch_1):\PP4938\") )
				( member ( pinPairRef "@baseboard_fab2_lib.baseboard_fab2(sch_1):\PP4941\") )
				( member ( pinPairRef "@baseboard_fab2_lib.baseboard_fab2(sch_1):\PP4944\") )
				( objectStatus "MG_DQ_FAR_DIMM_NG_M_B_BYTE7" )
			)
			( matchGroup "@baseboard_fab2_lib.baseboard_fab2(sch_1):\MG_DQ-DQS_NEAR_DIMM_NG_M_B_BYTE7\"
				( memberType ( signal ) )
				( member ( pinPairRef "@baseboard_fab2_lib.baseboard_fab2(sch_1):\PP4925\") )
				( member ( pinPairRef "@baseboard_fab2_lib.baseboard_fab2(sch_1):\PP4928\") )
				( member ( pinPairRef "@baseboard_fab2_lib.baseboard_fab2(sch_1):\PP4931\") )
				( member ( pinPairRef "@baseboard_fab2_lib.baseboard_fab2(sch_1):\PP4934\") )
				( member ( pinPairRef "@baseboard_fab2_lib.baseboard_fab2(sch_1):\PP4937\") )
				( member ( pinPairRef "@baseboard_fab2_lib.baseboard_fab2(sch_1):\PP4940\") )
				( member ( pinPairRef "@baseboard_fab2_lib.baseboard_fab2(sch_1):\PP4943\") )
				( member ( pinPairRef "@baseboard_fab2_lib.baseboard_fab2(sch_1):\PP4946\") )
				( member ( pinPairRef "@baseboard_fab2_lib.baseboard_fab2(sch_1):\PP477\") )
				( member ( pinPairRef "@baseboard_fab2_lib.baseboard_fab2(sch_1):\PP486\") )
				( member ( pinPairRef "@baseboard_fab2_lib.baseboard_fab2(sch_1):\PP480\") )
				( member ( pinPairRef "@baseboard_fab2_lib.baseboard_fab2(sch_1):\PP483\") )
				( objectStatus "MG_DQ-DQS_NEAR_DIMM_NG_M_B_BYTE7" )
			)
			( matchGroup "@baseboard_fab2_lib.baseboard_fab2(sch_1):\MG_DQ_NEAR_DIMM_NG_M_B_BYTE7\"
				( memberType ( signal ) )
				( member ( pinPairRef "@baseboard_fab2_lib.baseboard_fab2(sch_1):\PP4925\") )
				( member ( pinPairRef "@baseboard_fab2_lib.baseboard_fab2(sch_1):\PP4928\") )
				( member ( pinPairRef "@baseboard_fab2_lib.baseboard_fab2(sch_1):\PP4931\") )
				( member ( pinPairRef "@baseboard_fab2_lib.baseboard_fab2(sch_1):\PP4934\") )
				( member ( pinPairRef "@baseboard_fab2_lib.baseboard_fab2(sch_1):\PP4937\") )
				( member ( pinPairRef "@baseboard_fab2_lib.baseboard_fab2(sch_1):\PP4940\") )
				( member ( pinPairRef "@baseboard_fab2_lib.baseboard_fab2(sch_1):\PP4943\") )
				( member ( pinPairRef "@baseboard_fab2_lib.baseboard_fab2(sch_1):\PP4946\") )
				( objectStatus "MG_DQ_NEAR_DIMM_NG_M_B_BYTE7" )
			)
			( matchGroup "@baseboard_fab2_lib.baseboard_fab2(sch_1):\MG_DQ-DQS_FAR_DIMM_NG_M_K_BYTE7\"
				( memberType ( signal ) )
				( member ( pinPairRef "@baseboard_fab2_lib.baseboard_fab2(sch_1):\PP2110\") )
				( member ( pinPairRef "@baseboard_fab2_lib.baseboard_fab2(sch_1):\PP2113\") )
				( member ( pinPairRef "@baseboard_fab2_lib.baseboard_fab2(sch_1):\PP2116\") )
				( member ( pinPairRef "@baseboard_fab2_lib.baseboard_fab2(sch_1):\PP2119\") )
				( member ( pinPairRef "@baseboard_fab2_lib.baseboard_fab2(sch_1):\PP2122\") )
				( member ( pinPairRef "@baseboard_fab2_lib.baseboard_fab2(sch_1):\PP2125\") )
				( member ( pinPairRef "@baseboard_fab2_lib.baseboard_fab2(sch_1):\PP2128\") )
				( member ( pinPairRef "@baseboard_fab2_lib.baseboard_fab2(sch_1):\PP2107\") )
				( member ( pinPairRef "@baseboard_fab2_lib.baseboard_fab2(sch_1):\PP1489\") )
				( member ( pinPairRef "@baseboard_fab2_lib.baseboard_fab2(sch_1):\PP1492\") )
				( member ( pinPairRef "@baseboard_fab2_lib.baseboard_fab2(sch_1):\PP1483\") )
				( member ( pinPairRef "@baseboard_fab2_lib.baseboard_fab2(sch_1):\PP1486\") )
				( objectStatus "MG_DQ-DQS_FAR_DIMM_NG_M_K_BYTE7" )
			)
			( matchGroup "@crescent_city_bb_fab1_lib.crescent_city_bb_fab1(sch_1):\MG_DQ_FAR_DIMM_NG_M_K_BYTE7\"
				( memberType ( signal ) )
				( member ( pinPairRef "@baseboard_fab2_lib.baseboard_fab2(sch_1):\PP2110\") )
				( member ( pinPairRef "@baseboard_fab2_lib.baseboard_fab2(sch_1):\PP2113\") )
				( member ( pinPairRef "@baseboard_fab2_lib.baseboard_fab2(sch_1):\PP2116\") )
				( member ( pinPairRef "@baseboard_fab2_lib.baseboard_fab2(sch_1):\PP2119\") )
				( member ( pinPairRef "@baseboard_fab2_lib.baseboard_fab2(sch_1):\PP2122\") )
				( member ( pinPairRef "@baseboard_fab2_lib.baseboard_fab2(sch_1):\PP2125\") )
				( member ( pinPairRef "@baseboard_fab2_lib.baseboard_fab2(sch_1):\PP2128\") )
				( member ( pinPairRef "@baseboard_fab2_lib.baseboard_fab2(sch_1):\PP2107\") )
				( objectStatus "MG_DQ_FAR_DIMM_NG_M_K_BYTE7" )
			)
			( matchGroup "@baseboard_fab2_lib.baseboard_fab2(sch_1):\MG_DQ-DQS_NEAR_DIMM_NG_M_K_BYTE7\"
				( memberType ( signal ) )
				( member ( pinPairRef "@baseboard_fab2_lib.baseboard_fab2(sch_1):\PP2112\") )
				( member ( pinPairRef "@baseboard_fab2_lib.baseboard_fab2(sch_1):\PP2115\") )
				( member ( pinPairRef "@baseboard_fab2_lib.baseboard_fab2(sch_1):\PP2118\") )
				( member ( pinPairRef "@baseboard_fab2_lib.baseboard_fab2(sch_1):\PP2121\") )
				( member ( pinPairRef "@baseboard_fab2_lib.baseboard_fab2(sch_1):\PP2124\") )
				( member ( pinPairRef "@baseboard_fab2_lib.baseboard_fab2(sch_1):\PP2127\") )
				( member ( pinPairRef "@baseboard_fab2_lib.baseboard_fab2(sch_1):\PP2130\") )
				( member ( pinPairRef "@baseboard_fab2_lib.baseboard_fab2(sch_1):\PP2109\") )
				( member ( pinPairRef "@baseboard_fab2_lib.baseboard_fab2(sch_1):\PP1491\") )
				( member ( pinPairRef "@baseboard_fab2_lib.baseboard_fab2(sch_1):\PP1494\") )
				( member ( pinPairRef "@baseboard_fab2_lib.baseboard_fab2(sch_1):\PP1485\") )
				( member ( pinPairRef "@baseboard_fab2_lib.baseboard_fab2(sch_1):\PP1488\") )
				( objectStatus "MG_DQ-DQS_NEAR_DIMM_NG_M_K_BYTE7" )
			)
			( matchGroup "@crescent_city_bb_fab1_lib.crescent_city_bb_fab1(sch_1):\MG_DQ_NEAR_DIMM_NG_M_K_BYTE7\"
				( memberType ( signal ) )
				( member ( pinPairRef "@baseboard_fab2_lib.baseboard_fab2(sch_1):\PP2112\") )
				( member ( pinPairRef "@baseboard_fab2_lib.baseboard_fab2(sch_1):\PP2115\") )
				( member ( pinPairRef "@baseboard_fab2_lib.baseboard_fab2(sch_1):\PP2118\") )
				( member ( pinPairRef "@baseboard_fab2_lib.baseboard_fab2(sch_1):\PP2121\") )
				( member ( pinPairRef "@baseboard_fab2_lib.baseboard_fab2(sch_1):\PP2124\") )
				( member ( pinPairRef "@baseboard_fab2_lib.baseboard_fab2(sch_1):\PP2127\") )
				( member ( pinPairRef "@baseboard_fab2_lib.baseboard_fab2(sch_1):\PP2130\") )
				( member ( pinPairRef "@baseboard_fab2_lib.baseboard_fab2(sch_1):\PP2109\") )
				( objectStatus "MG_DQ_NEAR_DIMM_NG_M_K_BYTE7" )
			)
			( matchGroup "@baseboard_fab2_lib.baseboard_fab2(sch_1):\MG_DQ-DQS_FAR_DIMM_NG_M_L_BYTE0\"
				( memberType ( signal ) )
				( member ( pinPairRef "@baseboard_fab2_lib.baseboard_fab2(sch_1):\PP2059\") )
				( member ( pinPairRef "@baseboard_fab2_lib.baseboard_fab2(sch_1):\PP2062\") )
				( member ( pinPairRef "@baseboard_fab2_lib.baseboard_fab2(sch_1):\PP2065\") )
				( member ( pinPairRef "@baseboard_fab2_lib.baseboard_fab2(sch_1):\PP2068\") )
				( member ( pinPairRef "@baseboard_fab2_lib.baseboard_fab2(sch_1):\PP2071\") )
				( member ( pinPairRef "@baseboard_fab2_lib.baseboard_fab2(sch_1):\PP2074\") )
				( member ( pinPairRef "@baseboard_fab2_lib.baseboard_fab2(sch_1):\PP2077\") )
				( member ( pinPairRef "@baseboard_fab2_lib.baseboard_fab2(sch_1):\PP2080\") )
				( member ( pinPairRef "@baseboard_fab2_lib.baseboard_fab2(sch_1):\PP1477\") )
				( member ( pinPairRef "@baseboard_fab2_lib.baseboard_fab2(sch_1):\PP1480\") )
				( member ( pinPairRef "@baseboard_fab2_lib.baseboard_fab2(sch_1):\PP1471\") )
				( member ( pinPairRef "@baseboard_fab2_lib.baseboard_fab2(sch_1):\PP1474\") )
				( objectStatus "MG_DQ-DQS_FAR_DIMM_NG_M_L_BYTE0" )
			)
			( matchGroup "@baseboard_fab2_lib.baseboard_fab2(sch_1):\MG_DQ_FAR_DIMM_NG_M_L_BYTE0\"
				( memberType ( signal ) )
				( member ( pinPairRef "@baseboard_fab2_lib.baseboard_fab2(sch_1):\PP2059\") )
				( member ( pinPairRef "@baseboard_fab2_lib.baseboard_fab2(sch_1):\PP2062\") )
				( member ( pinPairRef "@baseboard_fab2_lib.baseboard_fab2(sch_1):\PP2065\") )
				( member ( pinPairRef "@baseboard_fab2_lib.baseboard_fab2(sch_1):\PP2068\") )
				( member ( pinPairRef "@baseboard_fab2_lib.baseboard_fab2(sch_1):\PP2071\") )
				( member ( pinPairRef "@baseboard_fab2_lib.baseboard_fab2(sch_1):\PP2074\") )
				( member ( pinPairRef "@baseboard_fab2_lib.baseboard_fab2(sch_1):\PP2077\") )
				( member ( pinPairRef "@baseboard_fab2_lib.baseboard_fab2(sch_1):\PP2080\") )
				( objectStatus "MG_DQ_FAR_DIMM_NG_M_L_BYTE0" )
			)
			( matchGroup "@baseboard_fab2_lib.baseboard_fab2(sch_1):\MG_DQ-DQS_NEAR_DIMM_NG_M_L_BYTE0\"
				( memberType ( signal ) )
				( member ( pinPairRef "@baseboard_fab2_lib.baseboard_fab2(sch_1):\PP2060\") )
				( member ( pinPairRef "@baseboard_fab2_lib.baseboard_fab2(sch_1):\PP2063\") )
				( member ( pinPairRef "@baseboard_fab2_lib.baseboard_fab2(sch_1):\PP2066\") )
				( member ( pinPairRef "@baseboard_fab2_lib.baseboard_fab2(sch_1):\PP2069\") )
				( member ( pinPairRef "@baseboard_fab2_lib.baseboard_fab2(sch_1):\PP2072\") )
				( member ( pinPairRef "@baseboard_fab2_lib.baseboard_fab2(sch_1):\PP2075\") )
				( member ( pinPairRef "@baseboard_fab2_lib.baseboard_fab2(sch_1):\PP2078\") )
				( member ( pinPairRef "@baseboard_fab2_lib.baseboard_fab2(sch_1):\PP2081\") )
				( member ( pinPairRef "@baseboard_fab2_lib.baseboard_fab2(sch_1):\PP1478\") )
				( member ( pinPairRef "@baseboard_fab2_lib.baseboard_fab2(sch_1):\PP1481\") )
				( member ( pinPairRef "@baseboard_fab2_lib.baseboard_fab2(sch_1):\PP1472\") )
				( member ( pinPairRef "@baseboard_fab2_lib.baseboard_fab2(sch_1):\PP1475\") )
				( objectStatus "MG_DQ-DQS_NEAR_DIMM_NG_M_L_BYTE0" )
			)
			( matchGroup "@baseboard_fab2_lib.baseboard_fab2(sch_1):\MG_DQ_NEAR_DIMM_NG_M_L_BYTE0\"
				( memberType ( signal ) )
				( member ( pinPairRef "@baseboard_fab2_lib.baseboard_fab2(sch_1):\PP2060\") )
				( member ( pinPairRef "@baseboard_fab2_lib.baseboard_fab2(sch_1):\PP2063\") )
				( member ( pinPairRef "@baseboard_fab2_lib.baseboard_fab2(sch_1):\PP2066\") )
				( member ( pinPairRef "@baseboard_fab2_lib.baseboard_fab2(sch_1):\PP2069\") )
				( member ( pinPairRef "@baseboard_fab2_lib.baseboard_fab2(sch_1):\PP2072\") )
				( member ( pinPairRef "@baseboard_fab2_lib.baseboard_fab2(sch_1):\PP2075\") )
				( member ( pinPairRef "@baseboard_fab2_lib.baseboard_fab2(sch_1):\PP2078\") )
				( member ( pinPairRef "@baseboard_fab2_lib.baseboard_fab2(sch_1):\PP2081\") )
				( objectStatus "MG_DQ_NEAR_DIMM_NG_M_L_BYTE0" )
			)
			( matchGroup "@baseboard_fab2_lib.baseboard_fab2(sch_1):\MG_DQ-DQS_FAR_DIMM_NG_M_L_BYTE1\"
				( memberType ( signal ) )
				( member ( pinPairRef "@baseboard_fab2_lib.baseboard_fab2(sch_1):\PP2035\") )
				( member ( pinPairRef "@baseboard_fab2_lib.baseboard_fab2(sch_1):\PP2038\") )
				( member ( pinPairRef "@baseboard_fab2_lib.baseboard_fab2(sch_1):\PP2041\") )
				( member ( pinPairRef "@baseboard_fab2_lib.baseboard_fab2(sch_1):\PP2044\") )
				( member ( pinPairRef "@baseboard_fab2_lib.baseboard_fab2(sch_1):\PP2047\") )
				( member ( pinPairRef "@baseboard_fab2_lib.baseboard_fab2(sch_1):\PP2050\") )
				( member ( pinPairRef "@baseboard_fab2_lib.baseboard_fab2(sch_1):\PP2053\") )
				( member ( pinPairRef "@baseboard_fab2_lib.baseboard_fab2(sch_1):\PP2056\") )
				( member ( pinPairRef "@baseboard_fab2_lib.baseboard_fab2(sch_1):\PP1465\") )
				( member ( pinPairRef "@baseboard_fab2_lib.baseboard_fab2(sch_1):\PP1468\") )
				( member ( pinPairRef "@baseboard_fab2_lib.baseboard_fab2(sch_1):\PP1459\") )
				( member ( pinPairRef "@baseboard_fab2_lib.baseboard_fab2(sch_1):\PP1462\") )
				( objectStatus "MG_DQ-DQS_FAR_DIMM_NG_M_L_BYTE1" )
			)
			( matchGroup "@baseboard_fab2_lib.baseboard_fab2(sch_1):\MG_DQ_FAR_DIMM_NG_M_L_BYTE1\"
				( memberType ( signal ) )
				( member ( pinPairRef "@baseboard_fab2_lib.baseboard_fab2(sch_1):\PP2035\") )
				( member ( pinPairRef "@baseboard_fab2_lib.baseboard_fab2(sch_1):\PP2038\") )
				( member ( pinPairRef "@baseboard_fab2_lib.baseboard_fab2(sch_1):\PP2041\") )
				( member ( pinPairRef "@baseboard_fab2_lib.baseboard_fab2(sch_1):\PP2044\") )
				( member ( pinPairRef "@baseboard_fab2_lib.baseboard_fab2(sch_1):\PP2047\") )
				( member ( pinPairRef "@baseboard_fab2_lib.baseboard_fab2(sch_1):\PP2050\") )
				( member ( pinPairRef "@baseboard_fab2_lib.baseboard_fab2(sch_1):\PP2053\") )
				( member ( pinPairRef "@baseboard_fab2_lib.baseboard_fab2(sch_1):\PP2056\") )
				( objectStatus "MG_DQ_FAR_DIMM_NG_M_L_BYTE1" )
			)
			( matchGroup "@baseboard_fab2_lib.baseboard_fab2(sch_1):\MG_DQ-DQS_NEAR_DIMM_NG_M_L_BYTE1\"
				( memberType ( signal ) )
				( member ( pinPairRef "@baseboard_fab2_lib.baseboard_fab2(sch_1):\PP2036\") )
				( member ( pinPairRef "@baseboard_fab2_lib.baseboard_fab2(sch_1):\PP2039\") )
				( member ( pinPairRef "@baseboard_fab2_lib.baseboard_fab2(sch_1):\PP2042\") )
				( member ( pinPairRef "@baseboard_fab2_lib.baseboard_fab2(sch_1):\PP2045\") )
				( member ( pinPairRef "@baseboard_fab2_lib.baseboard_fab2(sch_1):\PP2048\") )
				( member ( pinPairRef "@baseboard_fab2_lib.baseboard_fab2(sch_1):\PP2051\") )
				( member ( pinPairRef "@baseboard_fab2_lib.baseboard_fab2(sch_1):\PP2054\") )
				( member ( pinPairRef "@baseboard_fab2_lib.baseboard_fab2(sch_1):\PP2057\") )
				( member ( pinPairRef "@baseboard_fab2_lib.baseboard_fab2(sch_1):\PP1466\") )
				( member ( pinPairRef "@baseboard_fab2_lib.baseboard_fab2(sch_1):\PP1469\") )
				( member ( pinPairRef "@baseboard_fab2_lib.baseboard_fab2(sch_1):\PP1460\") )
				( member ( pinPairRef "@baseboard_fab2_lib.baseboard_fab2(sch_1):\PP1463\") )
				( objectStatus "MG_DQ-DQS_NEAR_DIMM_NG_M_L_BYTE1" )
			)
			( matchGroup "@baseboard_fab2_lib.baseboard_fab2(sch_1):\MG_DQ_NEAR_DIMM_NG_M_L_BYTE1\"
				( memberType ( signal ) )
				( member ( pinPairRef "@baseboard_fab2_lib.baseboard_fab2(sch_1):\PP2036\") )
				( member ( pinPairRef "@baseboard_fab2_lib.baseboard_fab2(sch_1):\PP2039\") )
				( member ( pinPairRef "@baseboard_fab2_lib.baseboard_fab2(sch_1):\PP2042\") )
				( member ( pinPairRef "@baseboard_fab2_lib.baseboard_fab2(sch_1):\PP2045\") )
				( member ( pinPairRef "@baseboard_fab2_lib.baseboard_fab2(sch_1):\PP2048\") )
				( member ( pinPairRef "@baseboard_fab2_lib.baseboard_fab2(sch_1):\PP2051\") )
				( member ( pinPairRef "@baseboard_fab2_lib.baseboard_fab2(sch_1):\PP2054\") )
				( member ( pinPairRef "@baseboard_fab2_lib.baseboard_fab2(sch_1):\PP2057\") )
				( objectStatus "MG_DQ_NEAR_DIMM_NG_M_L_BYTE1" )
			)
			( matchGroup "@baseboard_fab2_lib.baseboard_fab2(sch_1):\MG_DQ-DQS_FAR_DIMM_NG_M_L_BYTE2\"
				( memberType ( signal ) )
				( member ( pinPairRef "@baseboard_fab2_lib.baseboard_fab2(sch_1):\PP2011\") )
				( member ( pinPairRef "@baseboard_fab2_lib.baseboard_fab2(sch_1):\PP2014\") )
				( member ( pinPairRef "@baseboard_fab2_lib.baseboard_fab2(sch_1):\PP2017\") )
				( member ( pinPairRef "@baseboard_fab2_lib.baseboard_fab2(sch_1):\PP2020\") )
				( member ( pinPairRef "@baseboard_fab2_lib.baseboard_fab2(sch_1):\PP2023\") )
				( member ( pinPairRef "@baseboard_fab2_lib.baseboard_fab2(sch_1):\PP2026\") )
				( member ( pinPairRef "@baseboard_fab2_lib.baseboard_fab2(sch_1):\PP2029\") )
				( member ( pinPairRef "@baseboard_fab2_lib.baseboard_fab2(sch_1):\PP2032\") )
				( member ( pinPairRef "@baseboard_fab2_lib.baseboard_fab2(sch_1):\PP1453\") )
				( member ( pinPairRef "@baseboard_fab2_lib.baseboard_fab2(sch_1):\PP1456\") )
				( member ( pinPairRef "@baseboard_fab2_lib.baseboard_fab2(sch_1):\PP1447\") )
				( member ( pinPairRef "@baseboard_fab2_lib.baseboard_fab2(sch_1):\PP1450\") )
				( objectStatus "MG_DQ-DQS_FAR_DIMM_NG_M_L_BYTE2" )
			)
			( matchGroup "@crescent_city_bb_fab1_lib.crescent_city_bb_fab1(sch_1):\MG_DQ_FAR_DIMM_NG_M_L_BYTE2\"
				( memberType ( signal ) )
				( member ( pinPairRef "@baseboard_fab2_lib.baseboard_fab2(sch_1):\PP2011\") )
				( member ( pinPairRef "@baseboard_fab2_lib.baseboard_fab2(sch_1):\PP2014\") )
				( member ( pinPairRef "@baseboard_fab2_lib.baseboard_fab2(sch_1):\PP2017\") )
				( member ( pinPairRef "@baseboard_fab2_lib.baseboard_fab2(sch_1):\PP2020\") )
				( member ( pinPairRef "@baseboard_fab2_lib.baseboard_fab2(sch_1):\PP2023\") )
				( member ( pinPairRef "@baseboard_fab2_lib.baseboard_fab2(sch_1):\PP2026\") )
				( member ( pinPairRef "@baseboard_fab2_lib.baseboard_fab2(sch_1):\PP2029\") )
				( member ( pinPairRef "@baseboard_fab2_lib.baseboard_fab2(sch_1):\PP2032\") )
				( objectStatus "MG_DQ_FAR_DIMM_NG_M_L_BYTE2" )
			)
			( matchGroup "@baseboard_fab2_lib.baseboard_fab2(sch_1):\MG_DQ-DQS_NEAR_DIMM_NG_M_L_BYTE2\"
				( memberType ( signal ) )
				( member ( pinPairRef "@baseboard_fab2_lib.baseboard_fab2(sch_1):\PP2012\") )
				( member ( pinPairRef "@baseboard_fab2_lib.baseboard_fab2(sch_1):\PP2015\") )
				( member ( pinPairRef "@baseboard_fab2_lib.baseboard_fab2(sch_1):\PP2018\") )
				( member ( pinPairRef "@baseboard_fab2_lib.baseboard_fab2(sch_1):\PP2021\") )
				( member ( pinPairRef "@baseboard_fab2_lib.baseboard_fab2(sch_1):\PP2024\") )
				( member ( pinPairRef "@baseboard_fab2_lib.baseboard_fab2(sch_1):\PP2027\") )
				( member ( pinPairRef "@baseboard_fab2_lib.baseboard_fab2(sch_1):\PP2030\") )
				( member ( pinPairRef "@baseboard_fab2_lib.baseboard_fab2(sch_1):\PP2033\") )
				( member ( pinPairRef "@baseboard_fab2_lib.baseboard_fab2(sch_1):\PP1454\") )
				( member ( pinPairRef "@baseboard_fab2_lib.baseboard_fab2(sch_1):\PP1457\") )
				( member ( pinPairRef "@baseboard_fab2_lib.baseboard_fab2(sch_1):\PP1448\") )
				( member ( pinPairRef "@baseboard_fab2_lib.baseboard_fab2(sch_1):\PP1451\") )
				( objectStatus "MG_DQ-DQS_NEAR_DIMM_NG_M_L_BYTE2" )
			)
			( matchGroup "@crescent_city_bb_fab1_lib.crescent_city_bb_fab1(sch_1):\MG_DQ_NEAR_DIMM_NG_M_L_BYTE2\"
				( memberType ( signal ) )
				( member ( pinPairRef "@baseboard_fab2_lib.baseboard_fab2(sch_1):\PP2012\") )
				( member ( pinPairRef "@baseboard_fab2_lib.baseboard_fab2(sch_1):\PP2015\") )
				( member ( pinPairRef "@baseboard_fab2_lib.baseboard_fab2(sch_1):\PP2018\") )
				( member ( pinPairRef "@baseboard_fab2_lib.baseboard_fab2(sch_1):\PP2021\") )
				( member ( pinPairRef "@baseboard_fab2_lib.baseboard_fab2(sch_1):\PP2024\") )
				( member ( pinPairRef "@baseboard_fab2_lib.baseboard_fab2(sch_1):\PP2027\") )
				( member ( pinPairRef "@baseboard_fab2_lib.baseboard_fab2(sch_1):\PP2030\") )
				( member ( pinPairRef "@baseboard_fab2_lib.baseboard_fab2(sch_1):\PP2033\") )
				( objectStatus "MG_DQ_NEAR_DIMM_NG_M_L_BYTE2" )
			)
			( matchGroup "@baseboard_fab2_lib.baseboard_fab2(sch_1):\MG_DQ-DQS_FAR_DIMM_NG_M_L_BYTE3\"
				( memberType ( signal ) )
				( member ( pinPairRef "@baseboard_fab2_lib.baseboard_fab2(sch_1):\PP1987\") )
				( member ( pinPairRef "@baseboard_fab2_lib.baseboard_fab2(sch_1):\PP1990\") )
				( member ( pinPairRef "@baseboard_fab2_lib.baseboard_fab2(sch_1):\PP1993\") )
				( member ( pinPairRef "@baseboard_fab2_lib.baseboard_fab2(sch_1):\PP1996\") )
				( member ( pinPairRef "@baseboard_fab2_lib.baseboard_fab2(sch_1):\PP1999\") )
				( member ( pinPairRef "@baseboard_fab2_lib.baseboard_fab2(sch_1):\PP2002\") )
				( member ( pinPairRef "@baseboard_fab2_lib.baseboard_fab2(sch_1):\PP2005\") )
				( member ( pinPairRef "@baseboard_fab2_lib.baseboard_fab2(sch_1):\PP2008\") )
				( member ( pinPairRef "@baseboard_fab2_lib.baseboard_fab2(sch_1):\PP1441\") )
				( member ( pinPairRef "@baseboard_fab2_lib.baseboard_fab2(sch_1):\PP1444\") )
				( member ( pinPairRef "@baseboard_fab2_lib.baseboard_fab2(sch_1):\PP1435\") )
				( member ( pinPairRef "@baseboard_fab2_lib.baseboard_fab2(sch_1):\PP1438\") )
				( objectStatus "MG_DQ-DQS_FAR_DIMM_NG_M_L_BYTE3" )
			)
			( matchGroup "@crescent_city_bb_fab1_lib.crescent_city_bb_fab1(sch_1):\MG_DQ_FAR_DIMM_NG_M_L_BYTE3\"
				( memberType ( signal ) )
				( member ( pinPairRef "@baseboard_fab2_lib.baseboard_fab2(sch_1):\PP1987\") )
				( member ( pinPairRef "@baseboard_fab2_lib.baseboard_fab2(sch_1):\PP1990\") )
				( member ( pinPairRef "@baseboard_fab2_lib.baseboard_fab2(sch_1):\PP1993\") )
				( member ( pinPairRef "@baseboard_fab2_lib.baseboard_fab2(sch_1):\PP1996\") )
				( member ( pinPairRef "@baseboard_fab2_lib.baseboard_fab2(sch_1):\PP1999\") )
				( member ( pinPairRef "@baseboard_fab2_lib.baseboard_fab2(sch_1):\PP2002\") )
				( member ( pinPairRef "@baseboard_fab2_lib.baseboard_fab2(sch_1):\PP2005\") )
				( member ( pinPairRef "@baseboard_fab2_lib.baseboard_fab2(sch_1):\PP2008\") )
				( objectStatus "MG_DQ_FAR_DIMM_NG_M_L_BYTE3" )
			)
			( matchGroup "@baseboard_fab2_lib.baseboard_fab2(sch_1):\MG_DQ-DQS_NEAR_DIMM_NG_M_L_BYTE3\"
				( memberType ( signal ) )
				( member ( pinPairRef "@baseboard_fab2_lib.baseboard_fab2(sch_1):\PP1988\") )
				( member ( pinPairRef "@baseboard_fab2_lib.baseboard_fab2(sch_1):\PP1991\") )
				( member ( pinPairRef "@baseboard_fab2_lib.baseboard_fab2(sch_1):\PP1994\") )
				( member ( pinPairRef "@baseboard_fab2_lib.baseboard_fab2(sch_1):\PP1997\") )
				( member ( pinPairRef "@baseboard_fab2_lib.baseboard_fab2(sch_1):\PP2000\") )
				( member ( pinPairRef "@baseboard_fab2_lib.baseboard_fab2(sch_1):\PP2003\") )
				( member ( pinPairRef "@baseboard_fab2_lib.baseboard_fab2(sch_1):\PP2006\") )
				( member ( pinPairRef "@baseboard_fab2_lib.baseboard_fab2(sch_1):\PP2009\") )
				( member ( pinPairRef "@baseboard_fab2_lib.baseboard_fab2(sch_1):\PP1442\") )
				( member ( pinPairRef "@baseboard_fab2_lib.baseboard_fab2(sch_1):\PP1445\") )
				( member ( pinPairRef "@baseboard_fab2_lib.baseboard_fab2(sch_1):\PP1436\") )
				( member ( pinPairRef "@baseboard_fab2_lib.baseboard_fab2(sch_1):\PP1439\") )
				( objectStatus "MG_DQ-DQS_NEAR_DIMM_NG_M_L_BYTE3" )
			)
			( matchGroup "@crescent_city_bb_fab1_lib.crescent_city_bb_fab1(sch_1):\MG_DQ_NEAR_DIMM_NG_M_L_BYTE3\"
				( memberType ( signal ) )
				( member ( pinPairRef "@baseboard_fab2_lib.baseboard_fab2(sch_1):\PP1988\") )
				( member ( pinPairRef "@baseboard_fab2_lib.baseboard_fab2(sch_1):\PP1991\") )
				( member ( pinPairRef "@baseboard_fab2_lib.baseboard_fab2(sch_1):\PP1994\") )
				( member ( pinPairRef "@baseboard_fab2_lib.baseboard_fab2(sch_1):\PP1997\") )
				( member ( pinPairRef "@baseboard_fab2_lib.baseboard_fab2(sch_1):\PP2000\") )
				( member ( pinPairRef "@baseboard_fab2_lib.baseboard_fab2(sch_1):\PP2003\") )
				( member ( pinPairRef "@baseboard_fab2_lib.baseboard_fab2(sch_1):\PP2006\") )
				( member ( pinPairRef "@baseboard_fab2_lib.baseboard_fab2(sch_1):\PP2009\") )
				( objectStatus "MG_DQ_NEAR_DIMM_NG_M_L_BYTE3" )
			)
			( matchGroup "@baseboard_fab2_lib.baseboard_fab2(sch_1):\MG_DQ-DQS_FAR_DIMM_NG_M_L_BYTE4\"
				( memberType ( signal ) )
				( member ( pinPairRef "@baseboard_fab2_lib.baseboard_fab2(sch_1):\PP1963\") )
				( member ( pinPairRef "@baseboard_fab2_lib.baseboard_fab2(sch_1):\PP1966\") )
				( member ( pinPairRef "@baseboard_fab2_lib.baseboard_fab2(sch_1):\PP1969\") )
				( member ( pinPairRef "@baseboard_fab2_lib.baseboard_fab2(sch_1):\PP1972\") )
				( member ( pinPairRef "@baseboard_fab2_lib.baseboard_fab2(sch_1):\PP1975\") )
				( member ( pinPairRef "@baseboard_fab2_lib.baseboard_fab2(sch_1):\PP1978\") )
				( member ( pinPairRef "@baseboard_fab2_lib.baseboard_fab2(sch_1):\PP1981\") )
				( member ( pinPairRef "@baseboard_fab2_lib.baseboard_fab2(sch_1):\PP1984\") )
				( member ( pinPairRef "@baseboard_fab2_lib.baseboard_fab2(sch_1):\PP1429\") )
				( member ( pinPairRef "@baseboard_fab2_lib.baseboard_fab2(sch_1):\PP1432\") )
				( member ( pinPairRef "@baseboard_fab2_lib.baseboard_fab2(sch_1):\PP1423\") )
				( member ( pinPairRef "@baseboard_fab2_lib.baseboard_fab2(sch_1):\PP1426\") )
				( objectStatus "MG_DQ-DQS_FAR_DIMM_NG_M_L_BYTE4" )
			)
			( matchGroup "@crescent_city_bb_fab1_lib.crescent_city_bb_fab1(sch_1):\MG_DQ_FAR_DIMM_NG_M_L_BYTE4\"
				( memberType ( signal ) )
				( member ( pinPairRef "@baseboard_fab2_lib.baseboard_fab2(sch_1):\PP1963\") )
				( member ( pinPairRef "@baseboard_fab2_lib.baseboard_fab2(sch_1):\PP1966\") )
				( member ( pinPairRef "@baseboard_fab2_lib.baseboard_fab2(sch_1):\PP1969\") )
				( member ( pinPairRef "@baseboard_fab2_lib.baseboard_fab2(sch_1):\PP1972\") )
				( member ( pinPairRef "@baseboard_fab2_lib.baseboard_fab2(sch_1):\PP1975\") )
				( member ( pinPairRef "@baseboard_fab2_lib.baseboard_fab2(sch_1):\PP1978\") )
				( member ( pinPairRef "@baseboard_fab2_lib.baseboard_fab2(sch_1):\PP1981\") )
				( member ( pinPairRef "@baseboard_fab2_lib.baseboard_fab2(sch_1):\PP1984\") )
				( objectStatus "MG_DQ_FAR_DIMM_NG_M_L_BYTE4" )
			)
			( matchGroup "@baseboard_fab2_lib.baseboard_fab2(sch_1):\MG_DQ-DQS_NEAR_DIMM_NG_M_L_BYTE4\"
				( memberType ( signal ) )
				( member ( pinPairRef "@baseboard_fab2_lib.baseboard_fab2(sch_1):\PP1965\") )
				( member ( pinPairRef "@baseboard_fab2_lib.baseboard_fab2(sch_1):\PP1968\") )
				( member ( pinPairRef "@baseboard_fab2_lib.baseboard_fab2(sch_1):\PP1971\") )
				( member ( pinPairRef "@baseboard_fab2_lib.baseboard_fab2(sch_1):\PP1974\") )
				( member ( pinPairRef "@baseboard_fab2_lib.baseboard_fab2(sch_1):\PP1977\") )
				( member ( pinPairRef "@baseboard_fab2_lib.baseboard_fab2(sch_1):\PP1980\") )
				( member ( pinPairRef "@baseboard_fab2_lib.baseboard_fab2(sch_1):\PP1983\") )
				( member ( pinPairRef "@baseboard_fab2_lib.baseboard_fab2(sch_1):\PP1986\") )
				( member ( pinPairRef "@baseboard_fab2_lib.baseboard_fab2(sch_1):\PP1431\") )
				( member ( pinPairRef "@baseboard_fab2_lib.baseboard_fab2(sch_1):\PP1434\") )
				( member ( pinPairRef "@baseboard_fab2_lib.baseboard_fab2(sch_1):\PP1425\") )
				( member ( pinPairRef "@baseboard_fab2_lib.baseboard_fab2(sch_1):\PP1428\") )
				( objectStatus "MG_DQ-DQS_NEAR_DIMM_NG_M_L_BYTE4" )
			)
			( matchGroup "@crescent_city_bb_fab1_lib.crescent_city_bb_fab1(sch_1):\MG_DQ_NEAR_DIMM_NG_M_L_BYTE4\"
				( memberType ( signal ) )
				( member ( pinPairRef "@baseboard_fab2_lib.baseboard_fab2(sch_1):\PP1965\") )
				( member ( pinPairRef "@baseboard_fab2_lib.baseboard_fab2(sch_1):\PP1968\") )
				( member ( pinPairRef "@baseboard_fab2_lib.baseboard_fab2(sch_1):\PP1971\") )
				( member ( pinPairRef "@baseboard_fab2_lib.baseboard_fab2(sch_1):\PP1974\") )
				( member ( pinPairRef "@baseboard_fab2_lib.baseboard_fab2(sch_1):\PP1977\") )
				( member ( pinPairRef "@baseboard_fab2_lib.baseboard_fab2(sch_1):\PP1980\") )
				( member ( pinPairRef "@baseboard_fab2_lib.baseboard_fab2(sch_1):\PP1983\") )
				( member ( pinPairRef "@baseboard_fab2_lib.baseboard_fab2(sch_1):\PP1986\") )
				( objectStatus "MG_DQ_NEAR_DIMM_NG_M_L_BYTE4" )
			)
			( matchGroup "@baseboard_fab2_lib.baseboard_fab2(sch_1):\MG_DQ-DQS_FAR_DIMM_NG_M_L_BYTE5\"
				( memberType ( signal ) )
				( member ( pinPairRef "@baseboard_fab2_lib.baseboard_fab2(sch_1):\PP1939\") )
				( member ( pinPairRef "@baseboard_fab2_lib.baseboard_fab2(sch_1):\PP1942\") )
				( member ( pinPairRef "@baseboard_fab2_lib.baseboard_fab2(sch_1):\PP1945\") )
				( member ( pinPairRef "@baseboard_fab2_lib.baseboard_fab2(sch_1):\PP1948\") )
				( member ( pinPairRef "@baseboard_fab2_lib.baseboard_fab2(sch_1):\PP1951\") )
				( member ( pinPairRef "@baseboard_fab2_lib.baseboard_fab2(sch_1):\PP1954\") )
				( member ( pinPairRef "@baseboard_fab2_lib.baseboard_fab2(sch_1):\PP1957\") )
				( member ( pinPairRef "@baseboard_fab2_lib.baseboard_fab2(sch_1):\PP1960\") )
				( member ( pinPairRef "@baseboard_fab2_lib.baseboard_fab2(sch_1):\PP1417\") )
				( member ( pinPairRef "@baseboard_fab2_lib.baseboard_fab2(sch_1):\PP1420\") )
				( member ( pinPairRef "@baseboard_fab2_lib.baseboard_fab2(sch_1):\PP1411\") )
				( member ( pinPairRef "@baseboard_fab2_lib.baseboard_fab2(sch_1):\PP1414\") )
				( objectStatus "MG_DQ-DQS_FAR_DIMM_NG_M_L_BYTE5" )
			)
			( matchGroup "@baseboard_fab2_lib.baseboard_fab2(sch_1):\MG_DQ_FAR_DIMM_NG_M_L_BYTE5\"
				( memberType ( signal ) )
				( member ( pinPairRef "@baseboard_fab2_lib.baseboard_fab2(sch_1):\PP1939\") )
				( member ( pinPairRef "@baseboard_fab2_lib.baseboard_fab2(sch_1):\PP1942\") )
				( member ( pinPairRef "@baseboard_fab2_lib.baseboard_fab2(sch_1):\PP1945\") )
				( member ( pinPairRef "@baseboard_fab2_lib.baseboard_fab2(sch_1):\PP1948\") )
				( member ( pinPairRef "@baseboard_fab2_lib.baseboard_fab2(sch_1):\PP1951\") )
				( member ( pinPairRef "@baseboard_fab2_lib.baseboard_fab2(sch_1):\PP1954\") )
				( member ( pinPairRef "@baseboard_fab2_lib.baseboard_fab2(sch_1):\PP1957\") )
				( member ( pinPairRef "@baseboard_fab2_lib.baseboard_fab2(sch_1):\PP1960\") )
				( objectStatus "MG_DQ_FAR_DIMM_NG_M_L_BYTE5" )
			)
			( matchGroup "@baseboard_fab2_lib.baseboard_fab2(sch_1):\MG_DQ-DQS_NEAR_DIMM_NG_M_L_BYTE5\"
				( memberType ( signal ) )
				( member ( pinPairRef "@baseboard_fab2_lib.baseboard_fab2(sch_1):\PP1941\") )
				( member ( pinPairRef "@baseboard_fab2_lib.baseboard_fab2(sch_1):\PP1944\") )
				( member ( pinPairRef "@baseboard_fab2_lib.baseboard_fab2(sch_1):\PP1947\") )
				( member ( pinPairRef "@baseboard_fab2_lib.baseboard_fab2(sch_1):\PP1950\") )
				( member ( pinPairRef "@baseboard_fab2_lib.baseboard_fab2(sch_1):\PP1953\") )
				( member ( pinPairRef "@baseboard_fab2_lib.baseboard_fab2(sch_1):\PP1956\") )
				( member ( pinPairRef "@baseboard_fab2_lib.baseboard_fab2(sch_1):\PP1959\") )
				( member ( pinPairRef "@baseboard_fab2_lib.baseboard_fab2(sch_1):\PP1962\") )
				( member ( pinPairRef "@baseboard_fab2_lib.baseboard_fab2(sch_1):\PP1419\") )
				( member ( pinPairRef "@baseboard_fab2_lib.baseboard_fab2(sch_1):\PP1422\") )
				( member ( pinPairRef "@baseboard_fab2_lib.baseboard_fab2(sch_1):\PP1413\") )
				( member ( pinPairRef "@baseboard_fab2_lib.baseboard_fab2(sch_1):\PP1416\") )
				( objectStatus "MG_DQ-DQS_NEAR_DIMM_NG_M_L_BYTE5" )
			)
			( matchGroup "@baseboard_fab2_lib.baseboard_fab2(sch_1):\MG_DQ_NEAR_DIMM_NG_M_L_BYTE5\"
				( memberType ( signal ) )
				( member ( pinPairRef "@baseboard_fab2_lib.baseboard_fab2(sch_1):\PP1941\") )
				( member ( pinPairRef "@baseboard_fab2_lib.baseboard_fab2(sch_1):\PP1944\") )
				( member ( pinPairRef "@baseboard_fab2_lib.baseboard_fab2(sch_1):\PP1947\") )
				( member ( pinPairRef "@baseboard_fab2_lib.baseboard_fab2(sch_1):\PP1950\") )
				( member ( pinPairRef "@baseboard_fab2_lib.baseboard_fab2(sch_1):\PP1953\") )
				( member ( pinPairRef "@baseboard_fab2_lib.baseboard_fab2(sch_1):\PP1956\") )
				( member ( pinPairRef "@baseboard_fab2_lib.baseboard_fab2(sch_1):\PP1959\") )
				( member ( pinPairRef "@baseboard_fab2_lib.baseboard_fab2(sch_1):\PP1962\") )
				( objectStatus "MG_DQ_NEAR_DIMM_NG_M_L_BYTE5" )
			)
			( matchGroup "@baseboard_fab2_lib.baseboard_fab2(sch_1):\MG_DQ-DQS_FAR_DIMM_NG_M_L_BYTE6\"
				( memberType ( signal ) )
				( member ( pinPairRef "@baseboard_fab2_lib.baseboard_fab2(sch_1):\PP1915\") )
				( member ( pinPairRef "@baseboard_fab2_lib.baseboard_fab2(sch_1):\PP1918\") )
				( member ( pinPairRef "@baseboard_fab2_lib.baseboard_fab2(sch_1):\PP1921\") )
				( member ( pinPairRef "@baseboard_fab2_lib.baseboard_fab2(sch_1):\PP1924\") )
				( member ( pinPairRef "@baseboard_fab2_lib.baseboard_fab2(sch_1):\PP1927\") )
				( member ( pinPairRef "@baseboard_fab2_lib.baseboard_fab2(sch_1):\PP1930\") )
				( member ( pinPairRef "@baseboard_fab2_lib.baseboard_fab2(sch_1):\PP1933\") )
				( member ( pinPairRef "@baseboard_fab2_lib.baseboard_fab2(sch_1):\PP1936\") )
				( member ( pinPairRef "@baseboard_fab2_lib.baseboard_fab2(sch_1):\PP1405\") )
				( member ( pinPairRef "@baseboard_fab2_lib.baseboard_fab2(sch_1):\PP1408\") )
				( member ( pinPairRef "@baseboard_fab2_lib.baseboard_fab2(sch_1):\PP1399\") )
				( member ( pinPairRef "@baseboard_fab2_lib.baseboard_fab2(sch_1):\PP1402\") )
				( objectStatus "MG_DQ-DQS_FAR_DIMM_NG_M_L_BYTE6" )
			)
			( matchGroup "@baseboard_fab2_lib.baseboard_fab2(sch_1):\MG_DQ_FAR_DIMM_NG_M_L_BYTE6\"
				( memberType ( signal ) )
				( member ( pinPairRef "@baseboard_fab2_lib.baseboard_fab2(sch_1):\PP1915\") )
				( member ( pinPairRef "@baseboard_fab2_lib.baseboard_fab2(sch_1):\PP1918\") )
				( member ( pinPairRef "@baseboard_fab2_lib.baseboard_fab2(sch_1):\PP1921\") )
				( member ( pinPairRef "@baseboard_fab2_lib.baseboard_fab2(sch_1):\PP1924\") )
				( member ( pinPairRef "@baseboard_fab2_lib.baseboard_fab2(sch_1):\PP1927\") )
				( member ( pinPairRef "@baseboard_fab2_lib.baseboard_fab2(sch_1):\PP1930\") )
				( member ( pinPairRef "@baseboard_fab2_lib.baseboard_fab2(sch_1):\PP1933\") )
				( member ( pinPairRef "@baseboard_fab2_lib.baseboard_fab2(sch_1):\PP1936\") )
				( objectStatus "MG_DQ_FAR_DIMM_NG_M_L_BYTE6" )
			)
			( matchGroup "@baseboard_fab2_lib.baseboard_fab2(sch_1):\MG_DQ-DQS_NEAR_DIMM_NG_M_L_BYTE6\"
				( memberType ( signal ) )
				( member ( pinPairRef "@baseboard_fab2_lib.baseboard_fab2(sch_1):\PP1917\") )
				( member ( pinPairRef "@baseboard_fab2_lib.baseboard_fab2(sch_1):\PP1920\") )
				( member ( pinPairRef "@baseboard_fab2_lib.baseboard_fab2(sch_1):\PP1923\") )
				( member ( pinPairRef "@baseboard_fab2_lib.baseboard_fab2(sch_1):\PP1926\") )
				( member ( pinPairRef "@baseboard_fab2_lib.baseboard_fab2(sch_1):\PP1929\") )
				( member ( pinPairRef "@baseboard_fab2_lib.baseboard_fab2(sch_1):\PP1932\") )
				( member ( pinPairRef "@baseboard_fab2_lib.baseboard_fab2(sch_1):\PP1935\") )
				( member ( pinPairRef "@baseboard_fab2_lib.baseboard_fab2(sch_1):\PP1938\") )
				( member ( pinPairRef "@baseboard_fab2_lib.baseboard_fab2(sch_1):\PP1407\") )
				( member ( pinPairRef "@baseboard_fab2_lib.baseboard_fab2(sch_1):\PP1410\") )
				( member ( pinPairRef "@baseboard_fab2_lib.baseboard_fab2(sch_1):\PP1401\") )
				( member ( pinPairRef "@baseboard_fab2_lib.baseboard_fab2(sch_1):\PP1404\") )
				( objectStatus "MG_DQ-DQS_NEAR_DIMM_NG_M_L_BYTE6" )
			)
			( matchGroup "@baseboard_fab2_lib.baseboard_fab2(sch_1):\MG_DQ_NEAR_DIMM_NG_M_L_BYTE6\"
				( memberType ( signal ) )
				( member ( pinPairRef "@baseboard_fab2_lib.baseboard_fab2(sch_1):\PP1917\") )
				( member ( pinPairRef "@baseboard_fab2_lib.baseboard_fab2(sch_1):\PP1920\") )
				( member ( pinPairRef "@baseboard_fab2_lib.baseboard_fab2(sch_1):\PP1923\") )
				( member ( pinPairRef "@baseboard_fab2_lib.baseboard_fab2(sch_1):\PP1926\") )
				( member ( pinPairRef "@baseboard_fab2_lib.baseboard_fab2(sch_1):\PP1929\") )
				( member ( pinPairRef "@baseboard_fab2_lib.baseboard_fab2(sch_1):\PP1932\") )
				( member ( pinPairRef "@baseboard_fab2_lib.baseboard_fab2(sch_1):\PP1935\") )
				( member ( pinPairRef "@baseboard_fab2_lib.baseboard_fab2(sch_1):\PP1938\") )
				( objectStatus "MG_DQ_NEAR_DIMM_NG_M_L_BYTE6" )
			)
			( matchGroup "@baseboard_fab2_lib.baseboard_fab2(sch_1):\MG_DQ-DQS_FAR_DIMM_NG_M_L_BYTE7\"
				( memberType ( signal ) )
				( member ( pinPairRef "@baseboard_fab2_lib.baseboard_fab2(sch_1):\PP1891\") )
				( member ( pinPairRef "@baseboard_fab2_lib.baseboard_fab2(sch_1):\PP1894\") )
				( member ( pinPairRef "@baseboard_fab2_lib.baseboard_fab2(sch_1):\PP1897\") )
				( member ( pinPairRef "@baseboard_fab2_lib.baseboard_fab2(sch_1):\PP1900\") )
				( member ( pinPairRef "@baseboard_fab2_lib.baseboard_fab2(sch_1):\PP1903\") )
				( member ( pinPairRef "@baseboard_fab2_lib.baseboard_fab2(sch_1):\PP1906\") )
				( member ( pinPairRef "@baseboard_fab2_lib.baseboard_fab2(sch_1):\PP1909\") )
				( member ( pinPairRef "@baseboard_fab2_lib.baseboard_fab2(sch_1):\PP1912\") )
				( member ( pinPairRef "@baseboard_fab2_lib.baseboard_fab2(sch_1):\PP1393\") )
				( member ( pinPairRef "@baseboard_fab2_lib.baseboard_fab2(sch_1):\PP1396\") )
				( member ( pinPairRef "@baseboard_fab2_lib.baseboard_fab2(sch_1):\PP1387\") )
				( member ( pinPairRef "@baseboard_fab2_lib.baseboard_fab2(sch_1):\PP1390\") )
				( objectStatus "MG_DQ-DQS_FAR_DIMM_NG_M_L_BYTE7" )
			)
			( matchGroup "@baseboard_fab2_lib.baseboard_fab2(sch_1):\MG_DQ_FAR_DIMM_NG_M_L_BYTE7\"
				( memberType ( signal ) )
				( member ( pinPairRef "@baseboard_fab2_lib.baseboard_fab2(sch_1):\PP1891\") )
				( member ( pinPairRef "@baseboard_fab2_lib.baseboard_fab2(sch_1):\PP1894\") )
				( member ( pinPairRef "@baseboard_fab2_lib.baseboard_fab2(sch_1):\PP1897\") )
				( member ( pinPairRef "@baseboard_fab2_lib.baseboard_fab2(sch_1):\PP1900\") )
				( member ( pinPairRef "@baseboard_fab2_lib.baseboard_fab2(sch_1):\PP1903\") )
				( member ( pinPairRef "@baseboard_fab2_lib.baseboard_fab2(sch_1):\PP1906\") )
				( member ( pinPairRef "@baseboard_fab2_lib.baseboard_fab2(sch_1):\PP1909\") )
				( member ( pinPairRef "@baseboard_fab2_lib.baseboard_fab2(sch_1):\PP1912\") )
				( objectStatus "MG_DQ_FAR_DIMM_NG_M_L_BYTE7" )
			)
			( matchGroup "@baseboard_fab2_lib.baseboard_fab2(sch_1):\MG_DQ-DQS_NEAR_DIMM_NG_M_L_BYTE7\"
				( memberType ( signal ) )
				( member ( pinPairRef "@baseboard_fab2_lib.baseboard_fab2(sch_1):\PP1893\") )
				( member ( pinPairRef "@baseboard_fab2_lib.baseboard_fab2(sch_1):\PP1896\") )
				( member ( pinPairRef "@baseboard_fab2_lib.baseboard_fab2(sch_1):\PP1899\") )
				( member ( pinPairRef "@baseboard_fab2_lib.baseboard_fab2(sch_1):\PP1902\") )
				( member ( pinPairRef "@baseboard_fab2_lib.baseboard_fab2(sch_1):\PP1905\") )
				( member ( pinPairRef "@baseboard_fab2_lib.baseboard_fab2(sch_1):\PP1908\") )
				( member ( pinPairRef "@baseboard_fab2_lib.baseboard_fab2(sch_1):\PP1911\") )
				( member ( pinPairRef "@baseboard_fab2_lib.baseboard_fab2(sch_1):\PP1914\") )
				( member ( pinPairRef "@baseboard_fab2_lib.baseboard_fab2(sch_1):\PP1395\") )
				( member ( pinPairRef "@baseboard_fab2_lib.baseboard_fab2(sch_1):\PP1398\") )
				( member ( pinPairRef "@baseboard_fab2_lib.baseboard_fab2(sch_1):\PP1389\") )
				( member ( pinPairRef "@baseboard_fab2_lib.baseboard_fab2(sch_1):\PP1392\") )
				( objectStatus "MG_DQ-DQS_NEAR_DIMM_NG_M_L_BYTE7" )
			)
			( matchGroup "@baseboard_fab2_lib.baseboard_fab2(sch_1):\MG_DQ_NEAR_DIMM_NG_M_L_BYTE7\"
				( memberType ( signal ) )
				( member ( pinPairRef "@baseboard_fab2_lib.baseboard_fab2(sch_1):\PP1893\") )
				( member ( pinPairRef "@baseboard_fab2_lib.baseboard_fab2(sch_1):\PP1896\") )
				( member ( pinPairRef "@baseboard_fab2_lib.baseboard_fab2(sch_1):\PP1899\") )
				( member ( pinPairRef "@baseboard_fab2_lib.baseboard_fab2(sch_1):\PP1902\") )
				( member ( pinPairRef "@baseboard_fab2_lib.baseboard_fab2(sch_1):\PP1905\") )
				( member ( pinPairRef "@baseboard_fab2_lib.baseboard_fab2(sch_1):\PP1908\") )
				( member ( pinPairRef "@baseboard_fab2_lib.baseboard_fab2(sch_1):\PP1911\") )
				( member ( pinPairRef "@baseboard_fab2_lib.baseboard_fab2(sch_1):\PP1914\") )
				( objectStatus "MG_DQ_NEAR_DIMM_NG_M_L_BYTE7" )
			)
			( matchGroup "@baseboard_fab2_lib.baseboard_fab2(sch_1):\MG_DQ-DQS_FAR_DIMM_NG_M_M_BYTE0\"
				( memberType ( signal ) )
				( member ( pinPairRef "@baseboard_fab2_lib.baseboard_fab2(sch_1):\PP1843\") )
				( member ( pinPairRef "@baseboard_fab2_lib.baseboard_fab2(sch_1):\PP1846\") )
				( member ( pinPairRef "@baseboard_fab2_lib.baseboard_fab2(sch_1):\PP1849\") )
				( member ( pinPairRef "@baseboard_fab2_lib.baseboard_fab2(sch_1):\PP1852\") )
				( member ( pinPairRef "@baseboard_fab2_lib.baseboard_fab2(sch_1):\PP1855\") )
				( member ( pinPairRef "@baseboard_fab2_lib.baseboard_fab2(sch_1):\PP1858\") )
				( member ( pinPairRef "@baseboard_fab2_lib.baseboard_fab2(sch_1):\PP1861\") )
				( member ( pinPairRef "@baseboard_fab2_lib.baseboard_fab2(sch_1):\PP1864\") )
				( member ( pinPairRef "@baseboard_fab2_lib.baseboard_fab2(sch_1):\PP1381\") )
				( member ( pinPairRef "@baseboard_fab2_lib.baseboard_fab2(sch_1):\PP1384\") )
				( member ( pinPairRef "@baseboard_fab2_lib.baseboard_fab2(sch_1):\PP1375\") )
				( member ( pinPairRef "@baseboard_fab2_lib.baseboard_fab2(sch_1):\PP1378\") )
				( objectStatus "MG_DQ-DQS_FAR_DIMM_NG_M_M_BYTE0" )
			)
			( matchGroup "@baseboard_fab2_lib.baseboard_fab2(sch_1):\MG_DQ_FAR_DIMM_NG_M_M_BYTE0\"
				( memberType ( signal ) )
				( member ( pinPairRef "@baseboard_fab2_lib.baseboard_fab2(sch_1):\PP1843\") )
				( member ( pinPairRef "@baseboard_fab2_lib.baseboard_fab2(sch_1):\PP1846\") )
				( member ( pinPairRef "@baseboard_fab2_lib.baseboard_fab2(sch_1):\PP1849\") )
				( member ( pinPairRef "@baseboard_fab2_lib.baseboard_fab2(sch_1):\PP1852\") )
				( member ( pinPairRef "@baseboard_fab2_lib.baseboard_fab2(sch_1):\PP1855\") )
				( member ( pinPairRef "@baseboard_fab2_lib.baseboard_fab2(sch_1):\PP1858\") )
				( member ( pinPairRef "@baseboard_fab2_lib.baseboard_fab2(sch_1):\PP1861\") )
				( member ( pinPairRef "@baseboard_fab2_lib.baseboard_fab2(sch_1):\PP1864\") )
				( objectStatus "MG_DQ_FAR_DIMM_NG_M_M_BYTE0" )
			)
			( matchGroup "@baseboard_fab2_lib.baseboard_fab2(sch_1):\MG_DQ-DQS_NEAR_DIMM_NG_M_M_BYTE0\"
				( memberType ( signal ) )
				( member ( pinPairRef "@baseboard_fab2_lib.baseboard_fab2(sch_1):\PP1844\") )
				( member ( pinPairRef "@baseboard_fab2_lib.baseboard_fab2(sch_1):\PP1847\") )
				( member ( pinPairRef "@baseboard_fab2_lib.baseboard_fab2(sch_1):\PP1850\") )
				( member ( pinPairRef "@baseboard_fab2_lib.baseboard_fab2(sch_1):\PP1853\") )
				( member ( pinPairRef "@baseboard_fab2_lib.baseboard_fab2(sch_1):\PP1856\") )
				( member ( pinPairRef "@baseboard_fab2_lib.baseboard_fab2(sch_1):\PP1859\") )
				( member ( pinPairRef "@baseboard_fab2_lib.baseboard_fab2(sch_1):\PP1862\") )
				( member ( pinPairRef "@baseboard_fab2_lib.baseboard_fab2(sch_1):\PP1865\") )
				( member ( pinPairRef "@baseboard_fab2_lib.baseboard_fab2(sch_1):\PP1382\") )
				( member ( pinPairRef "@baseboard_fab2_lib.baseboard_fab2(sch_1):\PP1385\") )
				( member ( pinPairRef "@baseboard_fab2_lib.baseboard_fab2(sch_1):\PP1376\") )
				( member ( pinPairRef "@baseboard_fab2_lib.baseboard_fab2(sch_1):\PP1379\") )
				( objectStatus "MG_DQ-DQS_NEAR_DIMM_NG_M_M_BYTE0" )
			)
			( matchGroup "@baseboard_fab2_lib.baseboard_fab2(sch_1):\MG_DQ_NEAR_DIMM_NG_M_M_BYTE0\"
				( memberType ( signal ) )
				( member ( pinPairRef "@baseboard_fab2_lib.baseboard_fab2(sch_1):\PP1844\") )
				( member ( pinPairRef "@baseboard_fab2_lib.baseboard_fab2(sch_1):\PP1847\") )
				( member ( pinPairRef "@baseboard_fab2_lib.baseboard_fab2(sch_1):\PP1850\") )
				( member ( pinPairRef "@baseboard_fab2_lib.baseboard_fab2(sch_1):\PP1853\") )
				( member ( pinPairRef "@baseboard_fab2_lib.baseboard_fab2(sch_1):\PP1856\") )
				( member ( pinPairRef "@baseboard_fab2_lib.baseboard_fab2(sch_1):\PP1859\") )
				( member ( pinPairRef "@baseboard_fab2_lib.baseboard_fab2(sch_1):\PP1862\") )
				( member ( pinPairRef "@baseboard_fab2_lib.baseboard_fab2(sch_1):\PP1865\") )
				( objectStatus "MG_DQ_NEAR_DIMM_NG_M_M_BYTE0" )
			)
			( matchGroup "@baseboard_fab2_lib.baseboard_fab2(sch_1):\MG_DQ-DQS_FAR_DIMM_NG_M_M_BYTE1\"
				( memberType ( signal ) )
				( member ( pinPairRef "@baseboard_fab2_lib.baseboard_fab2(sch_1):\PP1819\") )
				( member ( pinPairRef "@baseboard_fab2_lib.baseboard_fab2(sch_1):\PP1822\") )
				( member ( pinPairRef "@baseboard_fab2_lib.baseboard_fab2(sch_1):\PP1825\") )
				( member ( pinPairRef "@baseboard_fab2_lib.baseboard_fab2(sch_1):\PP1828\") )
				( member ( pinPairRef "@baseboard_fab2_lib.baseboard_fab2(sch_1):\PP1831\") )
				( member ( pinPairRef "@baseboard_fab2_lib.baseboard_fab2(sch_1):\PP1834\") )
				( member ( pinPairRef "@baseboard_fab2_lib.baseboard_fab2(sch_1):\PP1837\") )
				( member ( pinPairRef "@baseboard_fab2_lib.baseboard_fab2(sch_1):\PP1840\") )
				( member ( pinPairRef "@baseboard_fab2_lib.baseboard_fab2(sch_1):\PP1369\") )
				( member ( pinPairRef "@baseboard_fab2_lib.baseboard_fab2(sch_1):\PP1372\") )
				( member ( pinPairRef "@baseboard_fab2_lib.baseboard_fab2(sch_1):\PP1363\") )
				( member ( pinPairRef "@baseboard_fab2_lib.baseboard_fab2(sch_1):\PP1366\") )
				( objectStatus "MG_DQ-DQS_FAR_DIMM_NG_M_M_BYTE1" )
			)
			( matchGroup "@baseboard_fab2_lib.baseboard_fab2(sch_1):\MG_DQ_FAR_DIMM_NG_M_M_BYTE1\"
				( memberType ( signal ) )
				( member ( pinPairRef "@baseboard_fab2_lib.baseboard_fab2(sch_1):\PP1819\") )
				( member ( pinPairRef "@baseboard_fab2_lib.baseboard_fab2(sch_1):\PP1822\") )
				( member ( pinPairRef "@baseboard_fab2_lib.baseboard_fab2(sch_1):\PP1825\") )
				( member ( pinPairRef "@baseboard_fab2_lib.baseboard_fab2(sch_1):\PP1828\") )
				( member ( pinPairRef "@baseboard_fab2_lib.baseboard_fab2(sch_1):\PP1831\") )
				( member ( pinPairRef "@baseboard_fab2_lib.baseboard_fab2(sch_1):\PP1834\") )
				( member ( pinPairRef "@baseboard_fab2_lib.baseboard_fab2(sch_1):\PP1837\") )
				( member ( pinPairRef "@baseboard_fab2_lib.baseboard_fab2(sch_1):\PP1840\") )
				( objectStatus "MG_DQ_FAR_DIMM_NG_M_M_BYTE1" )
			)
			( matchGroup "@baseboard_fab2_lib.baseboard_fab2(sch_1):\MG_DQ-DQS_NEAR_DIMM_NG_M_M_BYTE1\"
				( memberType ( signal ) )
				( member ( pinPairRef "@baseboard_fab2_lib.baseboard_fab2(sch_1):\PP1820\") )
				( member ( pinPairRef "@baseboard_fab2_lib.baseboard_fab2(sch_1):\PP1823\") )
				( member ( pinPairRef "@baseboard_fab2_lib.baseboard_fab2(sch_1):\PP1826\") )
				( member ( pinPairRef "@baseboard_fab2_lib.baseboard_fab2(sch_1):\PP1829\") )
				( member ( pinPairRef "@baseboard_fab2_lib.baseboard_fab2(sch_1):\PP1832\") )
				( member ( pinPairRef "@baseboard_fab2_lib.baseboard_fab2(sch_1):\PP1835\") )
				( member ( pinPairRef "@baseboard_fab2_lib.baseboard_fab2(sch_1):\PP1838\") )
				( member ( pinPairRef "@baseboard_fab2_lib.baseboard_fab2(sch_1):\PP1841\") )
				( member ( pinPairRef "@baseboard_fab2_lib.baseboard_fab2(sch_1):\PP1370\") )
				( member ( pinPairRef "@baseboard_fab2_lib.baseboard_fab2(sch_1):\PP1373\") )
				( member ( pinPairRef "@baseboard_fab2_lib.baseboard_fab2(sch_1):\PP1364\") )
				( member ( pinPairRef "@baseboard_fab2_lib.baseboard_fab2(sch_1):\PP1367\") )
				( objectStatus "MG_DQ-DQS_NEAR_DIMM_NG_M_M_BYTE1" )
			)
			( matchGroup "@baseboard_fab2_lib.baseboard_fab2(sch_1):\MG_DQ_NEAR_DIMM_NG_M_M_BYTE1\"
				( memberType ( signal ) )
				( member ( pinPairRef "@baseboard_fab2_lib.baseboard_fab2(sch_1):\PP1820\") )
				( member ( pinPairRef "@baseboard_fab2_lib.baseboard_fab2(sch_1):\PP1823\") )
				( member ( pinPairRef "@baseboard_fab2_lib.baseboard_fab2(sch_1):\PP1826\") )
				( member ( pinPairRef "@baseboard_fab2_lib.baseboard_fab2(sch_1):\PP1829\") )
				( member ( pinPairRef "@baseboard_fab2_lib.baseboard_fab2(sch_1):\PP1832\") )
				( member ( pinPairRef "@baseboard_fab2_lib.baseboard_fab2(sch_1):\PP1835\") )
				( member ( pinPairRef "@baseboard_fab2_lib.baseboard_fab2(sch_1):\PP1838\") )
				( member ( pinPairRef "@baseboard_fab2_lib.baseboard_fab2(sch_1):\PP1841\") )
				( objectStatus "MG_DQ_NEAR_DIMM_NG_M_M_BYTE1" )
			)
			( matchGroup "@baseboard_fab2_lib.baseboard_fab2(sch_1):\MG_DQ-DQS_FAR_DIMM_NG_M_M_BYTE2\"
				( memberType ( signal ) )
				( member ( pinPairRef "@baseboard_fab2_lib.baseboard_fab2(sch_1):\PP1795\") )
				( member ( pinPairRef "@baseboard_fab2_lib.baseboard_fab2(sch_1):\PP1798\") )
				( member ( pinPairRef "@baseboard_fab2_lib.baseboard_fab2(sch_1):\PP1801\") )
				( member ( pinPairRef "@baseboard_fab2_lib.baseboard_fab2(sch_1):\PP1804\") )
				( member ( pinPairRef "@baseboard_fab2_lib.baseboard_fab2(sch_1):\PP1807\") )
				( member ( pinPairRef "@baseboard_fab2_lib.baseboard_fab2(sch_1):\PP1810\") )
				( member ( pinPairRef "@baseboard_fab2_lib.baseboard_fab2(sch_1):\PP1813\") )
				( member ( pinPairRef "@baseboard_fab2_lib.baseboard_fab2(sch_1):\PP1816\") )
				( member ( pinPairRef "@baseboard_fab2_lib.baseboard_fab2(sch_1):\PP1357\") )
				( member ( pinPairRef "@baseboard_fab2_lib.baseboard_fab2(sch_1):\PP1360\") )
				( member ( pinPairRef "@baseboard_fab2_lib.baseboard_fab2(sch_1):\PP1351\") )
				( member ( pinPairRef "@baseboard_fab2_lib.baseboard_fab2(sch_1):\PP1354\") )
				( objectStatus "MG_DQ-DQS_FAR_DIMM_NG_M_M_BYTE2" )
			)
			( matchGroup "@baseboard_fab2_lib.baseboard_fab2(sch_1):\MG_DQ_FAR_DIMM_NG_M_M_BYTE2\"
				( memberType ( signal ) )
				( member ( pinPairRef "@baseboard_fab2_lib.baseboard_fab2(sch_1):\PP1795\") )
				( member ( pinPairRef "@baseboard_fab2_lib.baseboard_fab2(sch_1):\PP1798\") )
				( member ( pinPairRef "@baseboard_fab2_lib.baseboard_fab2(sch_1):\PP1801\") )
				( member ( pinPairRef "@baseboard_fab2_lib.baseboard_fab2(sch_1):\PP1804\") )
				( member ( pinPairRef "@baseboard_fab2_lib.baseboard_fab2(sch_1):\PP1807\") )
				( member ( pinPairRef "@baseboard_fab2_lib.baseboard_fab2(sch_1):\PP1810\") )
				( member ( pinPairRef "@baseboard_fab2_lib.baseboard_fab2(sch_1):\PP1813\") )
				( member ( pinPairRef "@baseboard_fab2_lib.baseboard_fab2(sch_1):\PP1816\") )
				( objectStatus "MG_DQ_FAR_DIMM_NG_M_M_BYTE2" )
			)
			( matchGroup "@baseboard_fab2_lib.baseboard_fab2(sch_1):\MG_DQ-DQS_NEAR_DIMM_NG_M_M_BYTE2\"
				( memberType ( signal ) )
				( member ( pinPairRef "@baseboard_fab2_lib.baseboard_fab2(sch_1):\PP1796\") )
				( member ( pinPairRef "@baseboard_fab2_lib.baseboard_fab2(sch_1):\PP1799\") )
				( member ( pinPairRef "@baseboard_fab2_lib.baseboard_fab2(sch_1):\PP1802\") )
				( member ( pinPairRef "@baseboard_fab2_lib.baseboard_fab2(sch_1):\PP1805\") )
				( member ( pinPairRef "@baseboard_fab2_lib.baseboard_fab2(sch_1):\PP1808\") )
				( member ( pinPairRef "@baseboard_fab2_lib.baseboard_fab2(sch_1):\PP1811\") )
				( member ( pinPairRef "@baseboard_fab2_lib.baseboard_fab2(sch_1):\PP1814\") )
				( member ( pinPairRef "@baseboard_fab2_lib.baseboard_fab2(sch_1):\PP1817\") )
				( member ( pinPairRef "@baseboard_fab2_lib.baseboard_fab2(sch_1):\PP1358\") )
				( member ( pinPairRef "@baseboard_fab2_lib.baseboard_fab2(sch_1):\PP1361\") )
				( member ( pinPairRef "@baseboard_fab2_lib.baseboard_fab2(sch_1):\PP1352\") )
				( member ( pinPairRef "@baseboard_fab2_lib.baseboard_fab2(sch_1):\PP1355\") )
				( objectStatus "MG_DQ-DQS_NEAR_DIMM_NG_M_M_BYTE2" )
			)
			( matchGroup "@baseboard_fab2_lib.baseboard_fab2(sch_1):\MG_DQ_NEAR_DIMM_NG_M_M_BYTE2\"
				( memberType ( signal ) )
				( member ( pinPairRef "@baseboard_fab2_lib.baseboard_fab2(sch_1):\PP1796\") )
				( member ( pinPairRef "@baseboard_fab2_lib.baseboard_fab2(sch_1):\PP1799\") )
				( member ( pinPairRef "@baseboard_fab2_lib.baseboard_fab2(sch_1):\PP1802\") )
				( member ( pinPairRef "@baseboard_fab2_lib.baseboard_fab2(sch_1):\PP1805\") )
				( member ( pinPairRef "@baseboard_fab2_lib.baseboard_fab2(sch_1):\PP1808\") )
				( member ( pinPairRef "@baseboard_fab2_lib.baseboard_fab2(sch_1):\PP1811\") )
				( member ( pinPairRef "@baseboard_fab2_lib.baseboard_fab2(sch_1):\PP1814\") )
				( member ( pinPairRef "@baseboard_fab2_lib.baseboard_fab2(sch_1):\PP1817\") )
				( objectStatus "MG_DQ_NEAR_DIMM_NG_M_M_BYTE2" )
			)
			( matchGroup "@baseboard_fab2_lib.baseboard_fab2(sch_1):\MG_DQ-DQS_FAR_DIMM_NG_M_J_BYTE2\"
				( memberType ( signal ) )
				( member ( pinPairRef "@baseboard_fab2_lib.baseboard_fab2(sch_1):\PP2458\") )
				( member ( pinPairRef "@baseboard_fab2_lib.baseboard_fab2(sch_1):\PP2461\") )
				( member ( pinPairRef "@baseboard_fab2_lib.baseboard_fab2(sch_1):\PP2464\") )
				( member ( pinPairRef "@baseboard_fab2_lib.baseboard_fab2(sch_1):\PP2443\") )
				( member ( pinPairRef "@baseboard_fab2_lib.baseboard_fab2(sch_1):\PP2446\") )
				( member ( pinPairRef "@baseboard_fab2_lib.baseboard_fab2(sch_1):\PP2449\") )
				( member ( pinPairRef "@baseboard_fab2_lib.baseboard_fab2(sch_1):\PP2452\") )
				( member ( pinPairRef "@baseboard_fab2_lib.baseboard_fab2(sch_1):\PP2455\") )
				( member ( pinPairRef "@baseboard_fab2_lib.baseboard_fab2(sch_1):\PP1645\") )
				( member ( pinPairRef "@baseboard_fab2_lib.baseboard_fab2(sch_1):\PP1648\") )
				( member ( pinPairRef "@baseboard_fab2_lib.baseboard_fab2(sch_1):\PP1639\") )
				( member ( pinPairRef "@baseboard_fab2_lib.baseboard_fab2(sch_1):\PP1642\") )
				( objectStatus "MG_DQ-DQS_FAR_DIMM_NG_M_J_BYTE2" )
			)
			( matchGroup "@baseboard_fab2_lib.baseboard_fab2(sch_1):\MG_DQ_FAR_DIMM_NG_M_J_BYTE2\"
				( memberType ( signal ) )
				( member ( pinPairRef "@baseboard_fab2_lib.baseboard_fab2(sch_1):\PP2458\") )
				( member ( pinPairRef "@baseboard_fab2_lib.baseboard_fab2(sch_1):\PP2461\") )
				( member ( pinPairRef "@baseboard_fab2_lib.baseboard_fab2(sch_1):\PP2464\") )
				( member ( pinPairRef "@baseboard_fab2_lib.baseboard_fab2(sch_1):\PP2443\") )
				( member ( pinPairRef "@baseboard_fab2_lib.baseboard_fab2(sch_1):\PP2446\") )
				( member ( pinPairRef "@baseboard_fab2_lib.baseboard_fab2(sch_1):\PP2449\") )
				( member ( pinPairRef "@baseboard_fab2_lib.baseboard_fab2(sch_1):\PP2452\") )
				( member ( pinPairRef "@baseboard_fab2_lib.baseboard_fab2(sch_1):\PP2455\") )
				( objectStatus "MG_DQ_FAR_DIMM_NG_M_J_BYTE2" )
			)
			( matchGroup "@baseboard_fab2_lib.baseboard_fab2(sch_1):\MG_DQ-DQS_NEAR_DIMM_NG_M_J_BYTE2\"
				( memberType ( signal ) )
				( member ( pinPairRef "@baseboard_fab2_lib.baseboard_fab2(sch_1):\PP2459\") )
				( member ( pinPairRef "@baseboard_fab2_lib.baseboard_fab2(sch_1):\PP2462\") )
				( member ( pinPairRef "@baseboard_fab2_lib.baseboard_fab2(sch_1):\PP2465\") )
				( member ( pinPairRef "@baseboard_fab2_lib.baseboard_fab2(sch_1):\PP2444\") )
				( member ( pinPairRef "@baseboard_fab2_lib.baseboard_fab2(sch_1):\PP2447\") )
				( member ( pinPairRef "@baseboard_fab2_lib.baseboard_fab2(sch_1):\PP2450\") )
				( member ( pinPairRef "@baseboard_fab2_lib.baseboard_fab2(sch_1):\PP2453\") )
				( member ( pinPairRef "@baseboard_fab2_lib.baseboard_fab2(sch_1):\PP2456\") )
				( member ( pinPairRef "@baseboard_fab2_lib.baseboard_fab2(sch_1):\PP1646\") )
				( member ( pinPairRef "@baseboard_fab2_lib.baseboard_fab2(sch_1):\PP1649\") )
				( member ( pinPairRef "@baseboard_fab2_lib.baseboard_fab2(sch_1):\PP1640\") )
				( member ( pinPairRef "@baseboard_fab2_lib.baseboard_fab2(sch_1):\PP1643\") )
				( objectStatus "MG_DQ-DQS_NEAR_DIMM_NG_M_J_BYTE2" )
			)
			( matchGroup "@baseboard_fab2_lib.baseboard_fab2(sch_1):\MG_DQ_NEAR_DIMM_NG_M_J_BYTE2\"
				( memberType ( signal ) )
				( member ( pinPairRef "@baseboard_fab2_lib.baseboard_fab2(sch_1):\PP2459\") )
				( member ( pinPairRef "@baseboard_fab2_lib.baseboard_fab2(sch_1):\PP2462\") )
				( member ( pinPairRef "@baseboard_fab2_lib.baseboard_fab2(sch_1):\PP2465\") )
				( member ( pinPairRef "@baseboard_fab2_lib.baseboard_fab2(sch_1):\PP2444\") )
				( member ( pinPairRef "@baseboard_fab2_lib.baseboard_fab2(sch_1):\PP2447\") )
				( member ( pinPairRef "@baseboard_fab2_lib.baseboard_fab2(sch_1):\PP2450\") )
				( member ( pinPairRef "@baseboard_fab2_lib.baseboard_fab2(sch_1):\PP2453\") )
				( member ( pinPairRef "@baseboard_fab2_lib.baseboard_fab2(sch_1):\PP2456\") )
				( objectStatus "MG_DQ_NEAR_DIMM_NG_M_J_BYTE2" )
			)
			( matchGroup "@baseboard_fab2_lib.baseboard_fab2(sch_1):\MG_DQ-DQS_FAR_DIMM_NG_M_J_BYTE3\"
				( memberType ( signal ) )
				( member ( pinPairRef "@baseboard_fab2_lib.baseboard_fab2(sch_1):\PP2419\") )
				( member ( pinPairRef "@baseboard_fab2_lib.baseboard_fab2(sch_1):\PP2422\") )
				( member ( pinPairRef "@baseboard_fab2_lib.baseboard_fab2(sch_1):\PP2425\") )
				( member ( pinPairRef "@baseboard_fab2_lib.baseboard_fab2(sch_1):\PP2428\") )
				( member ( pinPairRef "@baseboard_fab2_lib.baseboard_fab2(sch_1):\PP2431\") )
				( member ( pinPairRef "@baseboard_fab2_lib.baseboard_fab2(sch_1):\PP2434\") )
				( member ( pinPairRef "@baseboard_fab2_lib.baseboard_fab2(sch_1):\PP2437\") )
				( member ( pinPairRef "@baseboard_fab2_lib.baseboard_fab2(sch_1):\PP2440\") )
				( member ( pinPairRef "@baseboard_fab2_lib.baseboard_fab2(sch_1):\PP1633\") )
				( member ( pinPairRef "@baseboard_fab2_lib.baseboard_fab2(sch_1):\PP1636\") )
				( member ( pinPairRef "@baseboard_fab2_lib.baseboard_fab2(sch_1):\PP1627\") )
				( member ( pinPairRef "@baseboard_fab2_lib.baseboard_fab2(sch_1):\PP1630\") )
				( objectStatus "MG_DQ-DQS_FAR_DIMM_NG_M_J_BYTE3" )
			)
			( matchGroup "@baseboard_fab2_lib.baseboard_fab2(sch_1):\MG_DQ_FAR_DIMM_NG_M_J_BYTE3\"
				( memberType ( signal ) )
				( member ( pinPairRef "@baseboard_fab2_lib.baseboard_fab2(sch_1):\PP2419\") )
				( member ( pinPairRef "@baseboard_fab2_lib.baseboard_fab2(sch_1):\PP2422\") )
				( member ( pinPairRef "@baseboard_fab2_lib.baseboard_fab2(sch_1):\PP2425\") )
				( member ( pinPairRef "@baseboard_fab2_lib.baseboard_fab2(sch_1):\PP2428\") )
				( member ( pinPairRef "@baseboard_fab2_lib.baseboard_fab2(sch_1):\PP2431\") )
				( member ( pinPairRef "@baseboard_fab2_lib.baseboard_fab2(sch_1):\PP2434\") )
				( member ( pinPairRef "@baseboard_fab2_lib.baseboard_fab2(sch_1):\PP2437\") )
				( member ( pinPairRef "@baseboard_fab2_lib.baseboard_fab2(sch_1):\PP2440\") )
				( objectStatus "MG_DQ_FAR_DIMM_NG_M_J_BYTE3" )
			)
			( matchGroup "@baseboard_fab2_lib.baseboard_fab2(sch_1):\MG_DQ-DQS_NEAR_DIMM_NG_M_J_BYTE3\"
				( memberType ( signal ) )
				( member ( pinPairRef "@baseboard_fab2_lib.baseboard_fab2(sch_1):\PP2420\") )
				( member ( pinPairRef "@baseboard_fab2_lib.baseboard_fab2(sch_1):\PP2423\") )
				( member ( pinPairRef "@baseboard_fab2_lib.baseboard_fab2(sch_1):\PP2426\") )
				( member ( pinPairRef "@baseboard_fab2_lib.baseboard_fab2(sch_1):\PP2429\") )
				( member ( pinPairRef "@baseboard_fab2_lib.baseboard_fab2(sch_1):\PP2432\") )
				( member ( pinPairRef "@baseboard_fab2_lib.baseboard_fab2(sch_1):\PP2435\") )
				( member ( pinPairRef "@baseboard_fab2_lib.baseboard_fab2(sch_1):\PP2438\") )
				( member ( pinPairRef "@baseboard_fab2_lib.baseboard_fab2(sch_1):\PP2441\") )
				( member ( pinPairRef "@baseboard_fab2_lib.baseboard_fab2(sch_1):\PP1634\") )
				( member ( pinPairRef "@baseboard_fab2_lib.baseboard_fab2(sch_1):\PP1637\") )
				( member ( pinPairRef "@baseboard_fab2_lib.baseboard_fab2(sch_1):\PP1628\") )
				( member ( pinPairRef "@baseboard_fab2_lib.baseboard_fab2(sch_1):\PP1631\") )
				( objectStatus "MG_DQ-DQS_NEAR_DIMM_NG_M_J_BYTE3" )
			)
			( matchGroup "@baseboard_fab2_lib.baseboard_fab2(sch_1):\MG_DQ_NEAR_DIMM_NG_M_J_BYTE3\"
				( memberType ( signal ) )
				( member ( pinPairRef "@baseboard_fab2_lib.baseboard_fab2(sch_1):\PP2420\") )
				( member ( pinPairRef "@baseboard_fab2_lib.baseboard_fab2(sch_1):\PP2423\") )
				( member ( pinPairRef "@baseboard_fab2_lib.baseboard_fab2(sch_1):\PP2426\") )
				( member ( pinPairRef "@baseboard_fab2_lib.baseboard_fab2(sch_1):\PP2429\") )
				( member ( pinPairRef "@baseboard_fab2_lib.baseboard_fab2(sch_1):\PP2432\") )
				( member ( pinPairRef "@baseboard_fab2_lib.baseboard_fab2(sch_1):\PP2435\") )
				( member ( pinPairRef "@baseboard_fab2_lib.baseboard_fab2(sch_1):\PP2438\") )
				( member ( pinPairRef "@baseboard_fab2_lib.baseboard_fab2(sch_1):\PP2441\") )
				( objectStatus "MG_DQ_NEAR_DIMM_NG_M_J_BYTE3" )
			)
			( matchGroup "@baseboard_fab2_lib.baseboard_fab2(sch_1):\MG_DQ-DQS_FAR_DIMM_NG_M_J_BYTE4\"
				( memberType ( signal ) )
				( member ( pinPairRef "@baseboard_fab2_lib.baseboard_fab2(sch_1):\PP2395\") )
				( member ( pinPairRef "@baseboard_fab2_lib.baseboard_fab2(sch_1):\PP2398\") )
				( member ( pinPairRef "@baseboard_fab2_lib.baseboard_fab2(sch_1):\PP2401\") )
				( member ( pinPairRef "@baseboard_fab2_lib.baseboard_fab2(sch_1):\PP2404\") )
				( member ( pinPairRef "@baseboard_fab2_lib.baseboard_fab2(sch_1):\PP2407\") )
				( member ( pinPairRef "@baseboard_fab2_lib.baseboard_fab2(sch_1):\PP2410\") )
				( member ( pinPairRef "@baseboard_fab2_lib.baseboard_fab2(sch_1):\PP2413\") )
				( member ( pinPairRef "@baseboard_fab2_lib.baseboard_fab2(sch_1):\PP2416\") )
				( member ( pinPairRef "@baseboard_fab2_lib.baseboard_fab2(sch_1):\PP1621\") )
				( member ( pinPairRef "@baseboard_fab2_lib.baseboard_fab2(sch_1):\PP1624\") )
				( member ( pinPairRef "@baseboard_fab2_lib.baseboard_fab2(sch_1):\PP1615\") )
				( member ( pinPairRef "@baseboard_fab2_lib.baseboard_fab2(sch_1):\PP1618\") )
				( objectStatus "MG_DQ-DQS_FAR_DIMM_NG_M_J_BYTE4" )
			)
			( matchGroup "@baseboard_fab2_lib.baseboard_fab2(sch_1):\MG_DQ_FAR_DIMM_NG_M_J_BYTE4\"
				( memberType ( signal ) )
				( member ( pinPairRef "@baseboard_fab2_lib.baseboard_fab2(sch_1):\PP2395\") )
				( member ( pinPairRef "@baseboard_fab2_lib.baseboard_fab2(sch_1):\PP2398\") )
				( member ( pinPairRef "@baseboard_fab2_lib.baseboard_fab2(sch_1):\PP2401\") )
				( member ( pinPairRef "@baseboard_fab2_lib.baseboard_fab2(sch_1):\PP2404\") )
				( member ( pinPairRef "@baseboard_fab2_lib.baseboard_fab2(sch_1):\PP2407\") )
				( member ( pinPairRef "@baseboard_fab2_lib.baseboard_fab2(sch_1):\PP2410\") )
				( member ( pinPairRef "@baseboard_fab2_lib.baseboard_fab2(sch_1):\PP2413\") )
				( member ( pinPairRef "@baseboard_fab2_lib.baseboard_fab2(sch_1):\PP2416\") )
				( objectStatus "MG_DQ_FAR_DIMM_NG_M_J_BYTE4" )
			)
			( matchGroup "@baseboard_fab2_lib.baseboard_fab2(sch_1):\MG_DQ-DQS_NEAR_DIMM_NG_M_J_BYTE4\"
				( memberType ( signal ) )
				( member ( pinPairRef "@baseboard_fab2_lib.baseboard_fab2(sch_1):\PP2397\") )
				( member ( pinPairRef "@baseboard_fab2_lib.baseboard_fab2(sch_1):\PP2400\") )
				( member ( pinPairRef "@baseboard_fab2_lib.baseboard_fab2(sch_1):\PP2403\") )
				( member ( pinPairRef "@baseboard_fab2_lib.baseboard_fab2(sch_1):\PP2406\") )
				( member ( pinPairRef "@baseboard_fab2_lib.baseboard_fab2(sch_1):\PP2409\") )
				( member ( pinPairRef "@baseboard_fab2_lib.baseboard_fab2(sch_1):\PP2412\") )
				( member ( pinPairRef "@baseboard_fab2_lib.baseboard_fab2(sch_1):\PP2415\") )
				( member ( pinPairRef "@baseboard_fab2_lib.baseboard_fab2(sch_1):\PP2418\") )
				( member ( pinPairRef "@baseboard_fab2_lib.baseboard_fab2(sch_1):\PP1623\") )
				( member ( pinPairRef "@baseboard_fab2_lib.baseboard_fab2(sch_1):\PP1626\") )
				( member ( pinPairRef "@baseboard_fab2_lib.baseboard_fab2(sch_1):\PP1617\") )
				( member ( pinPairRef "@baseboard_fab2_lib.baseboard_fab2(sch_1):\PP1620\") )
				( objectStatus "MG_DQ-DQS_NEAR_DIMM_NG_M_J_BYTE4" )
			)
			( matchGroup "@baseboard_fab2_lib.baseboard_fab2(sch_1):\MG_DQ_NEAR_DIMM_NG_M_J_BYTE4\"
				( memberType ( signal ) )
				( member ( pinPairRef "@baseboard_fab2_lib.baseboard_fab2(sch_1):\PP2397\") )
				( member ( pinPairRef "@baseboard_fab2_lib.baseboard_fab2(sch_1):\PP2400\") )
				( member ( pinPairRef "@baseboard_fab2_lib.baseboard_fab2(sch_1):\PP2403\") )
				( member ( pinPairRef "@baseboard_fab2_lib.baseboard_fab2(sch_1):\PP2406\") )
				( member ( pinPairRef "@baseboard_fab2_lib.baseboard_fab2(sch_1):\PP2409\") )
				( member ( pinPairRef "@baseboard_fab2_lib.baseboard_fab2(sch_1):\PP2412\") )
				( member ( pinPairRef "@baseboard_fab2_lib.baseboard_fab2(sch_1):\PP2415\") )
				( member ( pinPairRef "@baseboard_fab2_lib.baseboard_fab2(sch_1):\PP2418\") )
				( objectStatus "MG_DQ_NEAR_DIMM_NG_M_J_BYTE4" )
			)
			( matchGroup "@baseboard_fab2_lib.baseboard_fab2(sch_1):\MG_DQ-DQS_FAR_DIMM_NG_M_J_BYTE5\"
				( memberType ( signal ) )
				( member ( pinPairRef "@baseboard_fab2_lib.baseboard_fab2(sch_1):\PP2371\") )
				( member ( pinPairRef "@baseboard_fab2_lib.baseboard_fab2(sch_1):\PP2374\") )
				( member ( pinPairRef "@baseboard_fab2_lib.baseboard_fab2(sch_1):\PP2377\") )
				( member ( pinPairRef "@baseboard_fab2_lib.baseboard_fab2(sch_1):\PP2380\") )
				( member ( pinPairRef "@baseboard_fab2_lib.baseboard_fab2(sch_1):\PP2383\") )
				( member ( pinPairRef "@baseboard_fab2_lib.baseboard_fab2(sch_1):\PP2386\") )
				( member ( pinPairRef "@baseboard_fab2_lib.baseboard_fab2(sch_1):\PP2389\") )
				( member ( pinPairRef "@baseboard_fab2_lib.baseboard_fab2(sch_1):\PP2392\") )
				( member ( pinPairRef "@baseboard_fab2_lib.baseboard_fab2(sch_1):\PP1609\") )
				( member ( pinPairRef "@baseboard_fab2_lib.baseboard_fab2(sch_1):\PP1612\") )
				( member ( pinPairRef "@baseboard_fab2_lib.baseboard_fab2(sch_1):\PP1603\") )
				( member ( pinPairRef "@baseboard_fab2_lib.baseboard_fab2(sch_1):\PP1606\") )
				( objectStatus "MG_DQ-DQS_FAR_DIMM_NG_M_J_BYTE5" )
			)
			( matchGroup "@baseboard_fab2_lib.baseboard_fab2(sch_1):\MG_DQ_FAR_DIMM_NG_M_J_BYTE5\"
				( memberType ( signal ) )
				( member ( pinPairRef "@baseboard_fab2_lib.baseboard_fab2(sch_1):\PP2371\") )
				( member ( pinPairRef "@baseboard_fab2_lib.baseboard_fab2(sch_1):\PP2374\") )
				( member ( pinPairRef "@baseboard_fab2_lib.baseboard_fab2(sch_1):\PP2377\") )
				( member ( pinPairRef "@baseboard_fab2_lib.baseboard_fab2(sch_1):\PP2380\") )
				( member ( pinPairRef "@baseboard_fab2_lib.baseboard_fab2(sch_1):\PP2383\") )
				( member ( pinPairRef "@baseboard_fab2_lib.baseboard_fab2(sch_1):\PP2386\") )
				( member ( pinPairRef "@baseboard_fab2_lib.baseboard_fab2(sch_1):\PP2389\") )
				( member ( pinPairRef "@baseboard_fab2_lib.baseboard_fab2(sch_1):\PP2392\") )
				( objectStatus "MG_DQ_FAR_DIMM_NG_M_J_BYTE5" )
			)
			( matchGroup "@baseboard_fab2_lib.baseboard_fab2(sch_1):\MG_DQ-DQS_NEAR_DIMM_NG_M_J_BYTE5\"
				( memberType ( signal ) )
				( member ( pinPairRef "@baseboard_fab2_lib.baseboard_fab2(sch_1):\PP2373\") )
				( member ( pinPairRef "@baseboard_fab2_lib.baseboard_fab2(sch_1):\PP2376\") )
				( member ( pinPairRef "@baseboard_fab2_lib.baseboard_fab2(sch_1):\PP2379\") )
				( member ( pinPairRef "@baseboard_fab2_lib.baseboard_fab2(sch_1):\PP2382\") )
				( member ( pinPairRef "@baseboard_fab2_lib.baseboard_fab2(sch_1):\PP2385\") )
				( member ( pinPairRef "@baseboard_fab2_lib.baseboard_fab2(sch_1):\PP2388\") )
				( member ( pinPairRef "@baseboard_fab2_lib.baseboard_fab2(sch_1):\PP2391\") )
				( member ( pinPairRef "@baseboard_fab2_lib.baseboard_fab2(sch_1):\PP2394\") )
				( member ( pinPairRef "@baseboard_fab2_lib.baseboard_fab2(sch_1):\PP1611\") )
				( member ( pinPairRef "@baseboard_fab2_lib.baseboard_fab2(sch_1):\PP1614\") )
				( member ( pinPairRef "@baseboard_fab2_lib.baseboard_fab2(sch_1):\PP1605\") )
				( member ( pinPairRef "@baseboard_fab2_lib.baseboard_fab2(sch_1):\PP1608\") )
				( objectStatus "MG_DQ-DQS_NEAR_DIMM_NG_M_J_BYTE5" )
			)
			( matchGroup "@baseboard_fab2_lib.baseboard_fab2(sch_1):\MG_DQ_NEAR_DIMM_NG_M_J_BYTE5\"
				( memberType ( signal ) )
				( member ( pinPairRef "@baseboard_fab2_lib.baseboard_fab2(sch_1):\PP2373\") )
				( member ( pinPairRef "@baseboard_fab2_lib.baseboard_fab2(sch_1):\PP2376\") )
				( member ( pinPairRef "@baseboard_fab2_lib.baseboard_fab2(sch_1):\PP2379\") )
				( member ( pinPairRef "@baseboard_fab2_lib.baseboard_fab2(sch_1):\PP2382\") )
				( member ( pinPairRef "@baseboard_fab2_lib.baseboard_fab2(sch_1):\PP2385\") )
				( member ( pinPairRef "@baseboard_fab2_lib.baseboard_fab2(sch_1):\PP2388\") )
				( member ( pinPairRef "@baseboard_fab2_lib.baseboard_fab2(sch_1):\PP2391\") )
				( member ( pinPairRef "@baseboard_fab2_lib.baseboard_fab2(sch_1):\PP2394\") )
				( objectStatus "MG_DQ_NEAR_DIMM_NG_M_J_BYTE5" )
			)
			( matchGroup "@baseboard_fab2_lib.baseboard_fab2(sch_1):\MG_DQ-DQS_FAR_DIMM_NG_M_J_BYTE6\"
				( memberType ( signal ) )
				( member ( pinPairRef "@baseboard_fab2_lib.baseboard_fab2(sch_1):\PP2347\") )
				( member ( pinPairRef "@baseboard_fab2_lib.baseboard_fab2(sch_1):\PP2350\") )
				( member ( pinPairRef "@baseboard_fab2_lib.baseboard_fab2(sch_1):\PP2353\") )
				( member ( pinPairRef "@baseboard_fab2_lib.baseboard_fab2(sch_1):\PP2356\") )
				( member ( pinPairRef "@baseboard_fab2_lib.baseboard_fab2(sch_1):\PP2359\") )
				( member ( pinPairRef "@baseboard_fab2_lib.baseboard_fab2(sch_1):\PP2362\") )
				( member ( pinPairRef "@baseboard_fab2_lib.baseboard_fab2(sch_1):\PP2365\") )
				( member ( pinPairRef "@baseboard_fab2_lib.baseboard_fab2(sch_1):\PP2368\") )
				( member ( pinPairRef "@baseboard_fab2_lib.baseboard_fab2(sch_1):\PP1597\") )
				( member ( pinPairRef "@baseboard_fab2_lib.baseboard_fab2(sch_1):\PP1600\") )
				( member ( pinPairRef "@baseboard_fab2_lib.baseboard_fab2(sch_1):\PP1591\") )
				( member ( pinPairRef "@baseboard_fab2_lib.baseboard_fab2(sch_1):\PP1594\") )
				( objectStatus "MG_DQ-DQS_FAR_DIMM_NG_M_J_BYTE6" )
			)
			( matchGroup "@crescent_city_bb_fab1_lib.crescent_city_bb_fab1(sch_1):\MG_DQ_FAR_DIMM_NG_M_J_BYTE6\"
				( memberType ( signal ) )
				( member ( pinPairRef "@baseboard_fab2_lib.baseboard_fab2(sch_1):\PP2347\") )
				( member ( pinPairRef "@baseboard_fab2_lib.baseboard_fab2(sch_1):\PP2350\") )
				( member ( pinPairRef "@baseboard_fab2_lib.baseboard_fab2(sch_1):\PP2353\") )
				( member ( pinPairRef "@baseboard_fab2_lib.baseboard_fab2(sch_1):\PP2356\") )
				( member ( pinPairRef "@baseboard_fab2_lib.baseboard_fab2(sch_1):\PP2359\") )
				( member ( pinPairRef "@baseboard_fab2_lib.baseboard_fab2(sch_1):\PP2362\") )
				( member ( pinPairRef "@baseboard_fab2_lib.baseboard_fab2(sch_1):\PP2365\") )
				( member ( pinPairRef "@baseboard_fab2_lib.baseboard_fab2(sch_1):\PP2368\") )
				( objectStatus "MG_DQ_FAR_DIMM_NG_M_J_BYTE6" )
			)
			( matchGroup "@baseboard_fab2_lib.baseboard_fab2(sch_1):\MG_DQ-DQS_NEAR_DIMM_NG_M_J_BYTE6\"
				( memberType ( signal ) )
				( member ( pinPairRef "@baseboard_fab2_lib.baseboard_fab2(sch_1):\PP2349\") )
				( member ( pinPairRef "@baseboard_fab2_lib.baseboard_fab2(sch_1):\PP2352\") )
				( member ( pinPairRef "@baseboard_fab2_lib.baseboard_fab2(sch_1):\PP2355\") )
				( member ( pinPairRef "@baseboard_fab2_lib.baseboard_fab2(sch_1):\PP2358\") )
				( member ( pinPairRef "@baseboard_fab2_lib.baseboard_fab2(sch_1):\PP2361\") )
				( member ( pinPairRef "@baseboard_fab2_lib.baseboard_fab2(sch_1):\PP2364\") )
				( member ( pinPairRef "@baseboard_fab2_lib.baseboard_fab2(sch_1):\PP2367\") )
				( member ( pinPairRef "@baseboard_fab2_lib.baseboard_fab2(sch_1):\PP2370\") )
				( member ( pinPairRef "@baseboard_fab2_lib.baseboard_fab2(sch_1):\PP1599\") )
				( member ( pinPairRef "@baseboard_fab2_lib.baseboard_fab2(sch_1):\PP1602\") )
				( member ( pinPairRef "@baseboard_fab2_lib.baseboard_fab2(sch_1):\PP1593\") )
				( member ( pinPairRef "@baseboard_fab2_lib.baseboard_fab2(sch_1):\PP1596\") )
				( objectStatus "MG_DQ-DQS_NEAR_DIMM_NG_M_J_BYTE6" )
			)
			( matchGroup "@crescent_city_bb_fab1_lib.crescent_city_bb_fab1(sch_1):\MG_DQ_NEAR_DIMM_NG_M_J_BYTE6\"
				( memberType ( signal ) )
				( member ( pinPairRef "@baseboard_fab2_lib.baseboard_fab2(sch_1):\PP2349\") )
				( member ( pinPairRef "@baseboard_fab2_lib.baseboard_fab2(sch_1):\PP2352\") )
				( member ( pinPairRef "@baseboard_fab2_lib.baseboard_fab2(sch_1):\PP2355\") )
				( member ( pinPairRef "@baseboard_fab2_lib.baseboard_fab2(sch_1):\PP2358\") )
				( member ( pinPairRef "@baseboard_fab2_lib.baseboard_fab2(sch_1):\PP2361\") )
				( member ( pinPairRef "@baseboard_fab2_lib.baseboard_fab2(sch_1):\PP2364\") )
				( member ( pinPairRef "@baseboard_fab2_lib.baseboard_fab2(sch_1):\PP2367\") )
				( member ( pinPairRef "@baseboard_fab2_lib.baseboard_fab2(sch_1):\PP2370\") )
				( objectStatus "MG_DQ_NEAR_DIMM_NG_M_J_BYTE6" )
			)
			( matchGroup "@baseboard_fab2_lib.baseboard_fab2(sch_1):\MG_DQ-DQS_FAR_DIMM_NG_M_J_BYTE7\"
				( memberType ( signal ) )
				( member ( pinPairRef "@baseboard_fab2_lib.baseboard_fab2(sch_1):\PP2323\") )
				( member ( pinPairRef "@baseboard_fab2_lib.baseboard_fab2(sch_1):\PP2326\") )
				( member ( pinPairRef "@baseboard_fab2_lib.baseboard_fab2(sch_1):\PP2329\") )
				( member ( pinPairRef "@baseboard_fab2_lib.baseboard_fab2(sch_1):\PP2332\") )
				( member ( pinPairRef "@baseboard_fab2_lib.baseboard_fab2(sch_1):\PP2335\") )
				( member ( pinPairRef "@baseboard_fab2_lib.baseboard_fab2(sch_1):\PP2338\") )
				( member ( pinPairRef "@baseboard_fab2_lib.baseboard_fab2(sch_1):\PP2341\") )
				( member ( pinPairRef "@baseboard_fab2_lib.baseboard_fab2(sch_1):\PP2344\") )
				( member ( pinPairRef "@baseboard_fab2_lib.baseboard_fab2(sch_1):\PP1585\") )
				( member ( pinPairRef "@baseboard_fab2_lib.baseboard_fab2(sch_1):\PP1588\") )
				( member ( pinPairRef "@baseboard_fab2_lib.baseboard_fab2(sch_1):\PP1579\") )
				( member ( pinPairRef "@baseboard_fab2_lib.baseboard_fab2(sch_1):\PP1582\") )
				( objectStatus "MG_DQ-DQS_FAR_DIMM_NG_M_J_BYTE7" )
			)
			( matchGroup "@baseboard_fab2_lib.baseboard_fab2(sch_1):\MG_DQ_FAR_DIMM_NG_M_J_BYTE7\"
				( memberType ( signal ) )
				( member ( pinPairRef "@baseboard_fab2_lib.baseboard_fab2(sch_1):\PP2323\") )
				( member ( pinPairRef "@baseboard_fab2_lib.baseboard_fab2(sch_1):\PP2326\") )
				( member ( pinPairRef "@baseboard_fab2_lib.baseboard_fab2(sch_1):\PP2329\") )
				( member ( pinPairRef "@baseboard_fab2_lib.baseboard_fab2(sch_1):\PP2332\") )
				( member ( pinPairRef "@baseboard_fab2_lib.baseboard_fab2(sch_1):\PP2335\") )
				( member ( pinPairRef "@baseboard_fab2_lib.baseboard_fab2(sch_1):\PP2338\") )
				( member ( pinPairRef "@baseboard_fab2_lib.baseboard_fab2(sch_1):\PP2341\") )
				( member ( pinPairRef "@baseboard_fab2_lib.baseboard_fab2(sch_1):\PP2344\") )
				( objectStatus "MG_DQ_FAR_DIMM_NG_M_J_BYTE7" )
			)
			( matchGroup "@baseboard_fab2_lib.baseboard_fab2(sch_1):\MG_DQ-DQS_NEAR_DIMM_NG_M_J_BYTE7\"
				( memberType ( signal ) )
				( member ( pinPairRef "@baseboard_fab2_lib.baseboard_fab2(sch_1):\PP2325\") )
				( member ( pinPairRef "@baseboard_fab2_lib.baseboard_fab2(sch_1):\PP2328\") )
				( member ( pinPairRef "@baseboard_fab2_lib.baseboard_fab2(sch_1):\PP2331\") )
				( member ( pinPairRef "@baseboard_fab2_lib.baseboard_fab2(sch_1):\PP2334\") )
				( member ( pinPairRef "@baseboard_fab2_lib.baseboard_fab2(sch_1):\PP2337\") )
				( member ( pinPairRef "@baseboard_fab2_lib.baseboard_fab2(sch_1):\PP2340\") )
				( member ( pinPairRef "@baseboard_fab2_lib.baseboard_fab2(sch_1):\PP2343\") )
				( member ( pinPairRef "@baseboard_fab2_lib.baseboard_fab2(sch_1):\PP2346\") )
				( member ( pinPairRef "@baseboard_fab2_lib.baseboard_fab2(sch_1):\PP1587\") )
				( member ( pinPairRef "@baseboard_fab2_lib.baseboard_fab2(sch_1):\PP1590\") )
				( member ( pinPairRef "@baseboard_fab2_lib.baseboard_fab2(sch_1):\PP1581\") )
				( member ( pinPairRef "@baseboard_fab2_lib.baseboard_fab2(sch_1):\PP1584\") )
				( objectStatus "MG_DQ-DQS_NEAR_DIMM_NG_M_J_BYTE7" )
			)
			( matchGroup "@baseboard_fab2_lib.baseboard_fab2(sch_1):\MG_DQ_NEAR_DIMM_NG_M_J_BYTE7\"
				( memberType ( signal ) )
				( member ( pinPairRef "@baseboard_fab2_lib.baseboard_fab2(sch_1):\PP2325\") )
				( member ( pinPairRef "@baseboard_fab2_lib.baseboard_fab2(sch_1):\PP2328\") )
				( member ( pinPairRef "@baseboard_fab2_lib.baseboard_fab2(sch_1):\PP2331\") )
				( member ( pinPairRef "@baseboard_fab2_lib.baseboard_fab2(sch_1):\PP2334\") )
				( member ( pinPairRef "@baseboard_fab2_lib.baseboard_fab2(sch_1):\PP2337\") )
				( member ( pinPairRef "@baseboard_fab2_lib.baseboard_fab2(sch_1):\PP2340\") )
				( member ( pinPairRef "@baseboard_fab2_lib.baseboard_fab2(sch_1):\PP2343\") )
				( member ( pinPairRef "@baseboard_fab2_lib.baseboard_fab2(sch_1):\PP2346\") )
				( objectStatus "MG_DQ_NEAR_DIMM_NG_M_J_BYTE7" )
			)
			( matchGroup "@baseboard_fab2_lib.baseboard_fab2(sch_1):\MG_DQ-DQS_FAR_DIMM_NG_M_K_BYTE0\"
				( memberType ( signal ) )
				( member ( pinPairRef "@baseboard_fab2_lib.baseboard_fab2(sch_1):\PP2275\") )
				( member ( pinPairRef "@baseboard_fab2_lib.baseboard_fab2(sch_1):\PP2278\") )
				( member ( pinPairRef "@baseboard_fab2_lib.baseboard_fab2(sch_1):\PP2281\") )
				( member ( pinPairRef "@baseboard_fab2_lib.baseboard_fab2(sch_1):\PP2284\") )
				( member ( pinPairRef "@baseboard_fab2_lib.baseboard_fab2(sch_1):\PP2287\") )
				( member ( pinPairRef "@baseboard_fab2_lib.baseboard_fab2(sch_1):\PP2290\") )
				( member ( pinPairRef "@baseboard_fab2_lib.baseboard_fab2(sch_1):\PP2293\") )
				( member ( pinPairRef "@baseboard_fab2_lib.baseboard_fab2(sch_1):\PP2296\") )
				( member ( pinPairRef "@baseboard_fab2_lib.baseboard_fab2(sch_1):\PP1573\") )
				( member ( pinPairRef "@baseboard_fab2_lib.baseboard_fab2(sch_1):\PP1576\") )
				( member ( pinPairRef "@baseboard_fab2_lib.baseboard_fab2(sch_1):\PP1567\") )
				( member ( pinPairRef "@baseboard_fab2_lib.baseboard_fab2(sch_1):\PP1570\") )
				( objectStatus "MG_DQ-DQS_FAR_DIMM_NG_M_K_BYTE0" )
			)
			( matchGroup "@baseboard_fab2_lib.baseboard_fab2(sch_1):\MG_DQ_FAR_DIMM_NG_M_K_BYTE0\"
				( memberType ( signal ) )
				( member ( pinPairRef "@baseboard_fab2_lib.baseboard_fab2(sch_1):\PP2275\") )
				( member ( pinPairRef "@baseboard_fab2_lib.baseboard_fab2(sch_1):\PP2278\") )
				( member ( pinPairRef "@baseboard_fab2_lib.baseboard_fab2(sch_1):\PP2281\") )
				( member ( pinPairRef "@baseboard_fab2_lib.baseboard_fab2(sch_1):\PP2284\") )
				( member ( pinPairRef "@baseboard_fab2_lib.baseboard_fab2(sch_1):\PP2287\") )
				( member ( pinPairRef "@baseboard_fab2_lib.baseboard_fab2(sch_1):\PP2290\") )
				( member ( pinPairRef "@baseboard_fab2_lib.baseboard_fab2(sch_1):\PP2293\") )
				( member ( pinPairRef "@baseboard_fab2_lib.baseboard_fab2(sch_1):\PP2296\") )
				( objectStatus "MG_DQ_FAR_DIMM_NG_M_K_BYTE0" )
			)
			( matchGroup "@baseboard_fab2_lib.baseboard_fab2(sch_1):\MG_DQ-DQS_NEAR_DIMM_NG_M_K_BYTE0\"
				( memberType ( signal ) )
				( member ( pinPairRef "@baseboard_fab2_lib.baseboard_fab2(sch_1):\PP2276\") )
				( member ( pinPairRef "@baseboard_fab2_lib.baseboard_fab2(sch_1):\PP2279\") )
				( member ( pinPairRef "@baseboard_fab2_lib.baseboard_fab2(sch_1):\PP2282\") )
				( member ( pinPairRef "@baseboard_fab2_lib.baseboard_fab2(sch_1):\PP2285\") )
				( member ( pinPairRef "@baseboard_fab2_lib.baseboard_fab2(sch_1):\PP2288\") )
				( member ( pinPairRef "@baseboard_fab2_lib.baseboard_fab2(sch_1):\PP2291\") )
				( member ( pinPairRef "@baseboard_fab2_lib.baseboard_fab2(sch_1):\PP2294\") )
				( member ( pinPairRef "@baseboard_fab2_lib.baseboard_fab2(sch_1):\PP2297\") )
				( member ( pinPairRef "@baseboard_fab2_lib.baseboard_fab2(sch_1):\PP1574\") )
				( member ( pinPairRef "@baseboard_fab2_lib.baseboard_fab2(sch_1):\PP1577\") )
				( member ( pinPairRef "@baseboard_fab2_lib.baseboard_fab2(sch_1):\PP1568\") )
				( member ( pinPairRef "@baseboard_fab2_lib.baseboard_fab2(sch_1):\PP1571\") )
				( objectStatus "MG_DQ-DQS_NEAR_DIMM_NG_M_K_BYTE0" )
			)
			( matchGroup "@baseboard_fab2_lib.baseboard_fab2(sch_1):\MG_DQ_NEAR_DIMM_NG_M_K_BYTE0\"
				( memberType ( signal ) )
				( member ( pinPairRef "@baseboard_fab2_lib.baseboard_fab2(sch_1):\PP2276\") )
				( member ( pinPairRef "@baseboard_fab2_lib.baseboard_fab2(sch_1):\PP2279\") )
				( member ( pinPairRef "@baseboard_fab2_lib.baseboard_fab2(sch_1):\PP2282\") )
				( member ( pinPairRef "@baseboard_fab2_lib.baseboard_fab2(sch_1):\PP2285\") )
				( member ( pinPairRef "@baseboard_fab2_lib.baseboard_fab2(sch_1):\PP2288\") )
				( member ( pinPairRef "@baseboard_fab2_lib.baseboard_fab2(sch_1):\PP2291\") )
				( member ( pinPairRef "@baseboard_fab2_lib.baseboard_fab2(sch_1):\PP2294\") )
				( member ( pinPairRef "@baseboard_fab2_lib.baseboard_fab2(sch_1):\PP2297\") )
				( objectStatus "MG_DQ_NEAR_DIMM_NG_M_K_BYTE0" )
			)
			( matchGroup "@baseboard_fab2_lib.baseboard_fab2(sch_1):\MG_DQ-DQS_FAR_DIMM_NG_M_K_BYTE1\"
				( memberType ( signal ) )
				( member ( pinPairRef "@baseboard_fab2_lib.baseboard_fab2(sch_1):\PP2251\") )
				( member ( pinPairRef "@baseboard_fab2_lib.baseboard_fab2(sch_1):\PP2254\") )
				( member ( pinPairRef "@baseboard_fab2_lib.baseboard_fab2(sch_1):\PP2257\") )
				( member ( pinPairRef "@baseboard_fab2_lib.baseboard_fab2(sch_1):\PP2260\") )
				( member ( pinPairRef "@baseboard_fab2_lib.baseboard_fab2(sch_1):\PP2263\") )
				( member ( pinPairRef "@baseboard_fab2_lib.baseboard_fab2(sch_1):\PP2266\") )
				( member ( pinPairRef "@baseboard_fab2_lib.baseboard_fab2(sch_1):\PP2269\") )
				( member ( pinPairRef "@baseboard_fab2_lib.baseboard_fab2(sch_1):\PP2272\") )
				( member ( pinPairRef "@baseboard_fab2_lib.baseboard_fab2(sch_1):\PP1561\") )
				( member ( pinPairRef "@baseboard_fab2_lib.baseboard_fab2(sch_1):\PP1564\") )
				( member ( pinPairRef "@baseboard_fab2_lib.baseboard_fab2(sch_1):\PP1555\") )
				( member ( pinPairRef "@baseboard_fab2_lib.baseboard_fab2(sch_1):\PP1558\") )
				( objectStatus "MG_DQ-DQS_FAR_DIMM_NG_M_K_BYTE1" )
			)
			( matchGroup "@baseboard_fab2_lib.baseboard_fab2(sch_1):\MG_DQ_FAR_DIMM_NG_M_K_BYTE1\"
				( memberType ( signal ) )
				( member ( pinPairRef "@baseboard_fab2_lib.baseboard_fab2(sch_1):\PP2251\") )
				( member ( pinPairRef "@baseboard_fab2_lib.baseboard_fab2(sch_1):\PP2254\") )
				( member ( pinPairRef "@baseboard_fab2_lib.baseboard_fab2(sch_1):\PP2257\") )
				( member ( pinPairRef "@baseboard_fab2_lib.baseboard_fab2(sch_1):\PP2260\") )
				( member ( pinPairRef "@baseboard_fab2_lib.baseboard_fab2(sch_1):\PP2263\") )
				( member ( pinPairRef "@baseboard_fab2_lib.baseboard_fab2(sch_1):\PP2266\") )
				( member ( pinPairRef "@baseboard_fab2_lib.baseboard_fab2(sch_1):\PP2269\") )
				( member ( pinPairRef "@baseboard_fab2_lib.baseboard_fab2(sch_1):\PP2272\") )
				( objectStatus "MG_DQ_FAR_DIMM_NG_M_K_BYTE1" )
			)
			( matchGroup "@baseboard_fab2_lib.baseboard_fab2(sch_1):\MG_DQ-DQS_NEAR_DIMM_NG_M_K_BYTE1\"
				( memberType ( signal ) )
				( member ( pinPairRef "@baseboard_fab2_lib.baseboard_fab2(sch_1):\PP2252\") )
				( member ( pinPairRef "@baseboard_fab2_lib.baseboard_fab2(sch_1):\PP2255\") )
				( member ( pinPairRef "@baseboard_fab2_lib.baseboard_fab2(sch_1):\PP2258\") )
				( member ( pinPairRef "@baseboard_fab2_lib.baseboard_fab2(sch_1):\PP2261\") )
				( member ( pinPairRef "@baseboard_fab2_lib.baseboard_fab2(sch_1):\PP2264\") )
				( member ( pinPairRef "@baseboard_fab2_lib.baseboard_fab2(sch_1):\PP2267\") )
				( member ( pinPairRef "@baseboard_fab2_lib.baseboard_fab2(sch_1):\PP2270\") )
				( member ( pinPairRef "@baseboard_fab2_lib.baseboard_fab2(sch_1):\PP2273\") )
				( member ( pinPairRef "@baseboard_fab2_lib.baseboard_fab2(sch_1):\PP1562\") )
				( member ( pinPairRef "@baseboard_fab2_lib.baseboard_fab2(sch_1):\PP1565\") )
				( member ( pinPairRef "@baseboard_fab2_lib.baseboard_fab2(sch_1):\PP1556\") )
				( member ( pinPairRef "@baseboard_fab2_lib.baseboard_fab2(sch_1):\PP1559\") )
				( objectStatus "MG_DQ-DQS_NEAR_DIMM_NG_M_K_BYTE1" )
			)
			( matchGroup "@baseboard_fab2_lib.baseboard_fab2(sch_1):\MG_DQ_NEAR_DIMM_NG_M_K_BYTE1\"
				( memberType ( signal ) )
				( member ( pinPairRef "@baseboard_fab2_lib.baseboard_fab2(sch_1):\PP2252\") )
				( member ( pinPairRef "@baseboard_fab2_lib.baseboard_fab2(sch_1):\PP2255\") )
				( member ( pinPairRef "@baseboard_fab2_lib.baseboard_fab2(sch_1):\PP2258\") )
				( member ( pinPairRef "@baseboard_fab2_lib.baseboard_fab2(sch_1):\PP2261\") )
				( member ( pinPairRef "@baseboard_fab2_lib.baseboard_fab2(sch_1):\PP2264\") )
				( member ( pinPairRef "@baseboard_fab2_lib.baseboard_fab2(sch_1):\PP2267\") )
				( member ( pinPairRef "@baseboard_fab2_lib.baseboard_fab2(sch_1):\PP2270\") )
				( member ( pinPairRef "@baseboard_fab2_lib.baseboard_fab2(sch_1):\PP2273\") )
				( objectStatus "MG_DQ_NEAR_DIMM_NG_M_K_BYTE1" )
			)
			( matchGroup "@baseboard_fab2_lib.baseboard_fab2(sch_1):\MG_DQ-DQS_FAR_DIMM_NG_M_K_BYTE2\"
				( memberType ( signal ) )
				( member ( pinPairRef "@baseboard_fab2_lib.baseboard_fab2(sch_1):\PP2227\") )
				( member ( pinPairRef "@baseboard_fab2_lib.baseboard_fab2(sch_1):\PP2230\") )
				( member ( pinPairRef "@baseboard_fab2_lib.baseboard_fab2(sch_1):\PP2233\") )
				( member ( pinPairRef "@baseboard_fab2_lib.baseboard_fab2(sch_1):\PP2236\") )
				( member ( pinPairRef "@baseboard_fab2_lib.baseboard_fab2(sch_1):\PP2239\") )
				( member ( pinPairRef "@baseboard_fab2_lib.baseboard_fab2(sch_1):\PP2242\") )
				( member ( pinPairRef "@baseboard_fab2_lib.baseboard_fab2(sch_1):\PP2245\") )
				( member ( pinPairRef "@baseboard_fab2_lib.baseboard_fab2(sch_1):\PP2248\") )
				( member ( pinPairRef "@baseboard_fab2_lib.baseboard_fab2(sch_1):\PP1549\") )
				( member ( pinPairRef "@baseboard_fab2_lib.baseboard_fab2(sch_1):\PP1552\") )
				( member ( pinPairRef "@baseboard_fab2_lib.baseboard_fab2(sch_1):\PP1543\") )
				( member ( pinPairRef "@baseboard_fab2_lib.baseboard_fab2(sch_1):\PP1546\") )
				( objectStatus "MG_DQ-DQS_FAR_DIMM_NG_M_K_BYTE2" )
			)
			( matchGroup "@baseboard_fab2_lib.baseboard_fab2(sch_1):\MG_DQ_FAR_DIMM_NG_M_K_BYTE2\"
				( memberType ( signal ) )
				( member ( pinPairRef "@baseboard_fab2_lib.baseboard_fab2(sch_1):\PP2227\") )
				( member ( pinPairRef "@baseboard_fab2_lib.baseboard_fab2(sch_1):\PP2230\") )
				( member ( pinPairRef "@baseboard_fab2_lib.baseboard_fab2(sch_1):\PP2233\") )
				( member ( pinPairRef "@baseboard_fab2_lib.baseboard_fab2(sch_1):\PP2236\") )
				( member ( pinPairRef "@baseboard_fab2_lib.baseboard_fab2(sch_1):\PP2239\") )
				( member ( pinPairRef "@baseboard_fab2_lib.baseboard_fab2(sch_1):\PP2242\") )
				( member ( pinPairRef "@baseboard_fab2_lib.baseboard_fab2(sch_1):\PP2245\") )
				( member ( pinPairRef "@baseboard_fab2_lib.baseboard_fab2(sch_1):\PP2248\") )
				( objectStatus "MG_DQ_FAR_DIMM_NG_M_K_BYTE2" )
			)
			( matchGroup "@baseboard_fab2_lib.baseboard_fab2(sch_1):\MG_DQ-DQS_NEAR_DIMM_NG_M_K_BYTE2\"
				( memberType ( signal ) )
				( member ( pinPairRef "@baseboard_fab2_lib.baseboard_fab2(sch_1):\PP2228\") )
				( member ( pinPairRef "@baseboard_fab2_lib.baseboard_fab2(sch_1):\PP2231\") )
				( member ( pinPairRef "@baseboard_fab2_lib.baseboard_fab2(sch_1):\PP2234\") )
				( member ( pinPairRef "@baseboard_fab2_lib.baseboard_fab2(sch_1):\PP2237\") )
				( member ( pinPairRef "@baseboard_fab2_lib.baseboard_fab2(sch_1):\PP2240\") )
				( member ( pinPairRef "@baseboard_fab2_lib.baseboard_fab2(sch_1):\PP2243\") )
				( member ( pinPairRef "@baseboard_fab2_lib.baseboard_fab2(sch_1):\PP2246\") )
				( member ( pinPairRef "@baseboard_fab2_lib.baseboard_fab2(sch_1):\PP2249\") )
				( member ( pinPairRef "@baseboard_fab2_lib.baseboard_fab2(sch_1):\PP1550\") )
				( member ( pinPairRef "@baseboard_fab2_lib.baseboard_fab2(sch_1):\PP1553\") )
				( member ( pinPairRef "@baseboard_fab2_lib.baseboard_fab2(sch_1):\PP1544\") )
				( member ( pinPairRef "@baseboard_fab2_lib.baseboard_fab2(sch_1):\PP1547\") )
				( objectStatus "MG_DQ-DQS_NEAR_DIMM_NG_M_K_BYTE2" )
			)
			( matchGroup "@baseboard_fab2_lib.baseboard_fab2(sch_1):\MG_DQ_NEAR_DIMM_NG_M_K_BYTE2\"
				( memberType ( signal ) )
				( member ( pinPairRef "@baseboard_fab2_lib.baseboard_fab2(sch_1):\PP2228\") )
				( member ( pinPairRef "@baseboard_fab2_lib.baseboard_fab2(sch_1):\PP2231\") )
				( member ( pinPairRef "@baseboard_fab2_lib.baseboard_fab2(sch_1):\PP2234\") )
				( member ( pinPairRef "@baseboard_fab2_lib.baseboard_fab2(sch_1):\PP2237\") )
				( member ( pinPairRef "@baseboard_fab2_lib.baseboard_fab2(sch_1):\PP2240\") )
				( member ( pinPairRef "@baseboard_fab2_lib.baseboard_fab2(sch_1):\PP2243\") )
				( member ( pinPairRef "@baseboard_fab2_lib.baseboard_fab2(sch_1):\PP2246\") )
				( member ( pinPairRef "@baseboard_fab2_lib.baseboard_fab2(sch_1):\PP2249\") )
				( objectStatus "MG_DQ_NEAR_DIMM_NG_M_K_BYTE2" )
			)
			( matchGroup "@baseboard_fab2_lib.baseboard_fab2(sch_1):\MG_DQ-DQS_FAR_DIMM_NG_M_K_BYTE3\"
				( memberType ( signal ) )
				( member ( pinPairRef "@baseboard_fab2_lib.baseboard_fab2(sch_1):\PP2203\") )
				( member ( pinPairRef "@baseboard_fab2_lib.baseboard_fab2(sch_1):\PP2206\") )
				( member ( pinPairRef "@baseboard_fab2_lib.baseboard_fab2(sch_1):\PP2209\") )
				( member ( pinPairRef "@baseboard_fab2_lib.baseboard_fab2(sch_1):\PP2212\") )
				( member ( pinPairRef "@baseboard_fab2_lib.baseboard_fab2(sch_1):\PP2215\") )
				( member ( pinPairRef "@baseboard_fab2_lib.baseboard_fab2(sch_1):\PP2218\") )
				( member ( pinPairRef "@baseboard_fab2_lib.baseboard_fab2(sch_1):\PP2221\") )
				( member ( pinPairRef "@baseboard_fab2_lib.baseboard_fab2(sch_1):\PP2224\") )
				( member ( pinPairRef "@baseboard_fab2_lib.baseboard_fab2(sch_1):\PP1537\") )
				( member ( pinPairRef "@baseboard_fab2_lib.baseboard_fab2(sch_1):\PP1540\") )
				( member ( pinPairRef "@baseboard_fab2_lib.baseboard_fab2(sch_1):\PP1531\") )
				( member ( pinPairRef "@baseboard_fab2_lib.baseboard_fab2(sch_1):\PP1534\") )
				( objectStatus "MG_DQ-DQS_FAR_DIMM_NG_M_K_BYTE3" )
			)
			( matchGroup "@crescent_city_bb_fab1_lib.crescent_city_bb_fab1(sch_1):\MG_DQ_FAR_DIMM_NG_M_K_BYTE3\"
				( memberType ( signal ) )
				( member ( pinPairRef "@baseboard_fab2_lib.baseboard_fab2(sch_1):\PP2203\") )
				( member ( pinPairRef "@baseboard_fab2_lib.baseboard_fab2(sch_1):\PP2206\") )
				( member ( pinPairRef "@baseboard_fab2_lib.baseboard_fab2(sch_1):\PP2209\") )
				( member ( pinPairRef "@baseboard_fab2_lib.baseboard_fab2(sch_1):\PP2212\") )
				( member ( pinPairRef "@baseboard_fab2_lib.baseboard_fab2(sch_1):\PP2215\") )
				( member ( pinPairRef "@baseboard_fab2_lib.baseboard_fab2(sch_1):\PP2218\") )
				( member ( pinPairRef "@baseboard_fab2_lib.baseboard_fab2(sch_1):\PP2221\") )
				( member ( pinPairRef "@baseboard_fab2_lib.baseboard_fab2(sch_1):\PP2224\") )
				( objectStatus "MG_DQ_FAR_DIMM_NG_M_K_BYTE3" )
			)
			( matchGroup "@baseboard_fab2_lib.baseboard_fab2(sch_1):\MG_DQ-DQS_NEAR_DIMM_NG_M_K_BYTE3\"
				( memberType ( signal ) )
				( member ( pinPairRef "@baseboard_fab2_lib.baseboard_fab2(sch_1):\PP2204\") )
				( member ( pinPairRef "@baseboard_fab2_lib.baseboard_fab2(sch_1):\PP2207\") )
				( member ( pinPairRef "@baseboard_fab2_lib.baseboard_fab2(sch_1):\PP2210\") )
				( member ( pinPairRef "@baseboard_fab2_lib.baseboard_fab2(sch_1):\PP2213\") )
				( member ( pinPairRef "@baseboard_fab2_lib.baseboard_fab2(sch_1):\PP2216\") )
				( member ( pinPairRef "@baseboard_fab2_lib.baseboard_fab2(sch_1):\PP2219\") )
				( member ( pinPairRef "@baseboard_fab2_lib.baseboard_fab2(sch_1):\PP2222\") )
				( member ( pinPairRef "@baseboard_fab2_lib.baseboard_fab2(sch_1):\PP2225\") )
				( member ( pinPairRef "@baseboard_fab2_lib.baseboard_fab2(sch_1):\PP1538\") )
				( member ( pinPairRef "@baseboard_fab2_lib.baseboard_fab2(sch_1):\PP1541\") )
				( member ( pinPairRef "@baseboard_fab2_lib.baseboard_fab2(sch_1):\PP1532\") )
				( member ( pinPairRef "@baseboard_fab2_lib.baseboard_fab2(sch_1):\PP1535\") )
				( objectStatus "MG_DQ-DQS_NEAR_DIMM_NG_M_K_BYTE3" )
			)
			( matchGroup "@crescent_city_bb_fab1_lib.crescent_city_bb_fab1(sch_1):\MG_DQ_NEAR_DIMM_NG_M_K_BYTE3\"
				( memberType ( signal ) )
				( member ( pinPairRef "@baseboard_fab2_lib.baseboard_fab2(sch_1):\PP2204\") )
				( member ( pinPairRef "@baseboard_fab2_lib.baseboard_fab2(sch_1):\PP2207\") )
				( member ( pinPairRef "@baseboard_fab2_lib.baseboard_fab2(sch_1):\PP2210\") )
				( member ( pinPairRef "@baseboard_fab2_lib.baseboard_fab2(sch_1):\PP2213\") )
				( member ( pinPairRef "@baseboard_fab2_lib.baseboard_fab2(sch_1):\PP2216\") )
				( member ( pinPairRef "@baseboard_fab2_lib.baseboard_fab2(sch_1):\PP2219\") )
				( member ( pinPairRef "@baseboard_fab2_lib.baseboard_fab2(sch_1):\PP2222\") )
				( member ( pinPairRef "@baseboard_fab2_lib.baseboard_fab2(sch_1):\PP2225\") )
				( objectStatus "MG_DQ_NEAR_DIMM_NG_M_K_BYTE3" )
			)
			( matchGroup "@baseboard_fab2_lib.baseboard_fab2(sch_1):\MG_DQ-DQS_FAR_DIMM_NG_M_K_BYTE4\"
				( memberType ( signal ) )
				( member ( pinPairRef "@baseboard_fab2_lib.baseboard_fab2(sch_1):\PP2179\") )
				( member ( pinPairRef "@baseboard_fab2_lib.baseboard_fab2(sch_1):\PP2182\") )
				( member ( pinPairRef "@baseboard_fab2_lib.baseboard_fab2(sch_1):\PP2185\") )
				( member ( pinPairRef "@baseboard_fab2_lib.baseboard_fab2(sch_1):\PP2188\") )
				( member ( pinPairRef "@baseboard_fab2_lib.baseboard_fab2(sch_1):\PP2191\") )
				( member ( pinPairRef "@baseboard_fab2_lib.baseboard_fab2(sch_1):\PP2194\") )
				( member ( pinPairRef "@baseboard_fab2_lib.baseboard_fab2(sch_1):\PP2197\") )
				( member ( pinPairRef "@baseboard_fab2_lib.baseboard_fab2(sch_1):\PP2200\") )
				( member ( pinPairRef "@baseboard_fab2_lib.baseboard_fab2(sch_1):\PP1525\") )
				( member ( pinPairRef "@baseboard_fab2_lib.baseboard_fab2(sch_1):\PP1528\") )
				( member ( pinPairRef "@baseboard_fab2_lib.baseboard_fab2(sch_1):\PP1519\") )
				( member ( pinPairRef "@baseboard_fab2_lib.baseboard_fab2(sch_1):\PP1522\") )
				( objectStatus "MG_DQ-DQS_FAR_DIMM_NG_M_K_BYTE4" )
			)
			( matchGroup "@baseboard_fab2_lib.baseboard_fab2(sch_1):\MG_DQ_FAR_DIMM_NG_M_K_BYTE4\"
				( memberType ( signal ) )
				( member ( pinPairRef "@baseboard_fab2_lib.baseboard_fab2(sch_1):\PP2179\") )
				( member ( pinPairRef "@baseboard_fab2_lib.baseboard_fab2(sch_1):\PP2182\") )
				( member ( pinPairRef "@baseboard_fab2_lib.baseboard_fab2(sch_1):\PP2185\") )
				( member ( pinPairRef "@baseboard_fab2_lib.baseboard_fab2(sch_1):\PP2188\") )
				( member ( pinPairRef "@baseboard_fab2_lib.baseboard_fab2(sch_1):\PP2191\") )
				( member ( pinPairRef "@baseboard_fab2_lib.baseboard_fab2(sch_1):\PP2194\") )
				( member ( pinPairRef "@baseboard_fab2_lib.baseboard_fab2(sch_1):\PP2197\") )
				( member ( pinPairRef "@baseboard_fab2_lib.baseboard_fab2(sch_1):\PP2200\") )
				( objectStatus "MG_DQ_FAR_DIMM_NG_M_K_BYTE4" )
			)
			( matchGroup "@baseboard_fab2_lib.baseboard_fab2(sch_1):\MG_DQ-DQS_NEAR_DIMM_NG_M_K_BYTE4\"
				( memberType ( signal ) )
				( member ( pinPairRef "@baseboard_fab2_lib.baseboard_fab2(sch_1):\PP2181\") )
				( member ( pinPairRef "@baseboard_fab2_lib.baseboard_fab2(sch_1):\PP2184\") )
				( member ( pinPairRef "@baseboard_fab2_lib.baseboard_fab2(sch_1):\PP2187\") )
				( member ( pinPairRef "@baseboard_fab2_lib.baseboard_fab2(sch_1):\PP2190\") )
				( member ( pinPairRef "@baseboard_fab2_lib.baseboard_fab2(sch_1):\PP2193\") )
				( member ( pinPairRef "@baseboard_fab2_lib.baseboard_fab2(sch_1):\PP2196\") )
				( member ( pinPairRef "@baseboard_fab2_lib.baseboard_fab2(sch_1):\PP2199\") )
				( member ( pinPairRef "@baseboard_fab2_lib.baseboard_fab2(sch_1):\PP2202\") )
				( member ( pinPairRef "@baseboard_fab2_lib.baseboard_fab2(sch_1):\PP1527\") )
				( member ( pinPairRef "@baseboard_fab2_lib.baseboard_fab2(sch_1):\PP1530\") )
				( member ( pinPairRef "@baseboard_fab2_lib.baseboard_fab2(sch_1):\PP1521\") )
				( member ( pinPairRef "@baseboard_fab2_lib.baseboard_fab2(sch_1):\PP1524\") )
				( objectStatus "MG_DQ-DQS_NEAR_DIMM_NG_M_K_BYTE4" )
			)
			( matchGroup "@crescent_city_bb_fab1_lib.crescent_city_bb_fab1(sch_1):\MG_DQ_NEAR_DIMM_NG_M_K_BYTE4\"
				( memberType ( signal ) )
				( member ( pinPairRef "@baseboard_fab2_lib.baseboard_fab2(sch_1):\PP2181\") )
				( member ( pinPairRef "@baseboard_fab2_lib.baseboard_fab2(sch_1):\PP2184\") )
				( member ( pinPairRef "@baseboard_fab2_lib.baseboard_fab2(sch_1):\PP2187\") )
				( member ( pinPairRef "@baseboard_fab2_lib.baseboard_fab2(sch_1):\PP2190\") )
				( member ( pinPairRef "@baseboard_fab2_lib.baseboard_fab2(sch_1):\PP2193\") )
				( member ( pinPairRef "@baseboard_fab2_lib.baseboard_fab2(sch_1):\PP2196\") )
				( member ( pinPairRef "@baseboard_fab2_lib.baseboard_fab2(sch_1):\PP2199\") )
				( member ( pinPairRef "@baseboard_fab2_lib.baseboard_fab2(sch_1):\PP2202\") )
				( objectStatus "MG_DQ_NEAR_DIMM_NG_M_K_BYTE4" )
			)
			( matchGroup "@baseboard_fab2_lib.baseboard_fab2(sch_1):\MG_DQ-DQS_FAR_DIMM_NG_M_K_BYTE5\"
				( memberType ( signal ) )
				( member ( pinPairRef "@baseboard_fab2_lib.baseboard_fab2(sch_1):\PP2155\") )
				( member ( pinPairRef "@baseboard_fab2_lib.baseboard_fab2(sch_1):\PP2158\") )
				( member ( pinPairRef "@baseboard_fab2_lib.baseboard_fab2(sch_1):\PP2161\") )
				( member ( pinPairRef "@baseboard_fab2_lib.baseboard_fab2(sch_1):\PP2164\") )
				( member ( pinPairRef "@baseboard_fab2_lib.baseboard_fab2(sch_1):\PP2167\") )
				( member ( pinPairRef "@baseboard_fab2_lib.baseboard_fab2(sch_1):\PP2170\") )
				( member ( pinPairRef "@baseboard_fab2_lib.baseboard_fab2(sch_1):\PP2173\") )
				( member ( pinPairRef "@baseboard_fab2_lib.baseboard_fab2(sch_1):\PP2176\") )
				( member ( pinPairRef "@baseboard_fab2_lib.baseboard_fab2(sch_1):\PP1513\") )
				( member ( pinPairRef "@baseboard_fab2_lib.baseboard_fab2(sch_1):\PP1516\") )
				( member ( pinPairRef "@baseboard_fab2_lib.baseboard_fab2(sch_1):\PP1507\") )
				( member ( pinPairRef "@baseboard_fab2_lib.baseboard_fab2(sch_1):\PP1510\") )
				( objectStatus "MG_DQ-DQS_FAR_DIMM_NG_M_K_BYTE5" )
			)
			( matchGroup "@crescent_city_bb_fab1_lib.crescent_city_bb_fab1(sch_1):\MG_DQ_FAR_DIMM_NG_M_K_BYTE5\"
				( memberType ( signal ) )
				( member ( pinPairRef "@baseboard_fab2_lib.baseboard_fab2(sch_1):\PP2155\") )
				( member ( pinPairRef "@baseboard_fab2_lib.baseboard_fab2(sch_1):\PP2158\") )
				( member ( pinPairRef "@baseboard_fab2_lib.baseboard_fab2(sch_1):\PP2161\") )
				( member ( pinPairRef "@baseboard_fab2_lib.baseboard_fab2(sch_1):\PP2164\") )
				( member ( pinPairRef "@baseboard_fab2_lib.baseboard_fab2(sch_1):\PP2167\") )
				( member ( pinPairRef "@baseboard_fab2_lib.baseboard_fab2(sch_1):\PP2170\") )
				( member ( pinPairRef "@baseboard_fab2_lib.baseboard_fab2(sch_1):\PP2173\") )
				( member ( pinPairRef "@baseboard_fab2_lib.baseboard_fab2(sch_1):\PP2176\") )
				( objectStatus "MG_DQ_FAR_DIMM_NG_M_K_BYTE5" )
			)
			( matchGroup "@baseboard_fab2_lib.baseboard_fab2(sch_1):\MG_DQ-DQS_NEAR_DIMM_NG_M_K_BYTE5\"
				( memberType ( signal ) )
				( member ( pinPairRef "@baseboard_fab2_lib.baseboard_fab2(sch_1):\PP2157\") )
				( member ( pinPairRef "@baseboard_fab2_lib.baseboard_fab2(sch_1):\PP2160\") )
				( member ( pinPairRef "@baseboard_fab2_lib.baseboard_fab2(sch_1):\PP2163\") )
				( member ( pinPairRef "@baseboard_fab2_lib.baseboard_fab2(sch_1):\PP2166\") )
				( member ( pinPairRef "@baseboard_fab2_lib.baseboard_fab2(sch_1):\PP2169\") )
				( member ( pinPairRef "@baseboard_fab2_lib.baseboard_fab2(sch_1):\PP2172\") )
				( member ( pinPairRef "@baseboard_fab2_lib.baseboard_fab2(sch_1):\PP2175\") )
				( member ( pinPairRef "@baseboard_fab2_lib.baseboard_fab2(sch_1):\PP2178\") )
				( member ( pinPairRef "@baseboard_fab2_lib.baseboard_fab2(sch_1):\PP1515\") )
				( member ( pinPairRef "@baseboard_fab2_lib.baseboard_fab2(sch_1):\PP1518\") )
				( member ( pinPairRef "@baseboard_fab2_lib.baseboard_fab2(sch_1):\PP1509\") )
				( member ( pinPairRef "@baseboard_fab2_lib.baseboard_fab2(sch_1):\PP1512\") )
				( objectStatus "MG_DQ-DQS_NEAR_DIMM_NG_M_K_BYTE5" )
			)
			( matchGroup "@crescent_city_bb_fab1_lib.crescent_city_bb_fab1(sch_1):\MG_DQ_NEAR_DIMM_NG_M_K_BYTE5\"
				( memberType ( signal ) )
				( member ( pinPairRef "@baseboard_fab2_lib.baseboard_fab2(sch_1):\PP2157\") )
				( member ( pinPairRef "@baseboard_fab2_lib.baseboard_fab2(sch_1):\PP2160\") )
				( member ( pinPairRef "@baseboard_fab2_lib.baseboard_fab2(sch_1):\PP2163\") )
				( member ( pinPairRef "@baseboard_fab2_lib.baseboard_fab2(sch_1):\PP2166\") )
				( member ( pinPairRef "@baseboard_fab2_lib.baseboard_fab2(sch_1):\PP2169\") )
				( member ( pinPairRef "@baseboard_fab2_lib.baseboard_fab2(sch_1):\PP2172\") )
				( member ( pinPairRef "@baseboard_fab2_lib.baseboard_fab2(sch_1):\PP2175\") )
				( member ( pinPairRef "@baseboard_fab2_lib.baseboard_fab2(sch_1):\PP2178\") )
				( objectStatus "MG_DQ_NEAR_DIMM_NG_M_K_BYTE5" )
			)
			( matchGroup "@baseboard_fab2_lib.baseboard_fab2(sch_1):\MG_DQ-DQS_FAR_DIMM_NG_M_K_BYTE6\"
				( memberType ( signal ) )
				( member ( pinPairRef "@baseboard_fab2_lib.baseboard_fab2(sch_1):\PP2131\") )
				( member ( pinPairRef "@baseboard_fab2_lib.baseboard_fab2(sch_1):\PP2134\") )
				( member ( pinPairRef "@baseboard_fab2_lib.baseboard_fab2(sch_1):\PP2137\") )
				( member ( pinPairRef "@baseboard_fab2_lib.baseboard_fab2(sch_1):\PP2140\") )
				( member ( pinPairRef "@baseboard_fab2_lib.baseboard_fab2(sch_1):\PP2143\") )
				( member ( pinPairRef "@baseboard_fab2_lib.baseboard_fab2(sch_1):\PP2146\") )
				( member ( pinPairRef "@baseboard_fab2_lib.baseboard_fab2(sch_1):\PP2149\") )
				( member ( pinPairRef "@baseboard_fab2_lib.baseboard_fab2(sch_1):\PP2152\") )
				( member ( pinPairRef "@baseboard_fab2_lib.baseboard_fab2(sch_1):\PP1501\") )
				( member ( pinPairRef "@baseboard_fab2_lib.baseboard_fab2(sch_1):\PP1504\") )
				( member ( pinPairRef "@baseboard_fab2_lib.baseboard_fab2(sch_1):\PP1495\") )
				( member ( pinPairRef "@baseboard_fab2_lib.baseboard_fab2(sch_1):\PP1498\") )
				( objectStatus "MG_DQ-DQS_FAR_DIMM_NG_M_K_BYTE6" )
			)
			( matchGroup "@baseboard_fab2_lib.baseboard_fab2(sch_1):\MG_DQ_FAR_DIMM_NG_M_K_BYTE6\"
				( memberType ( signal ) )
				( member ( pinPairRef "@baseboard_fab2_lib.baseboard_fab2(sch_1):\PP2131\") )
				( member ( pinPairRef "@baseboard_fab2_lib.baseboard_fab2(sch_1):\PP2134\") )
				( member ( pinPairRef "@baseboard_fab2_lib.baseboard_fab2(sch_1):\PP2137\") )
				( member ( pinPairRef "@baseboard_fab2_lib.baseboard_fab2(sch_1):\PP2140\") )
				( member ( pinPairRef "@baseboard_fab2_lib.baseboard_fab2(sch_1):\PP2143\") )
				( member ( pinPairRef "@baseboard_fab2_lib.baseboard_fab2(sch_1):\PP2146\") )
				( member ( pinPairRef "@baseboard_fab2_lib.baseboard_fab2(sch_1):\PP2149\") )
				( member ( pinPairRef "@baseboard_fab2_lib.baseboard_fab2(sch_1):\PP2152\") )
				( objectStatus "MG_DQ_FAR_DIMM_NG_M_K_BYTE6" )
			)
			( matchGroup "@baseboard_fab2_lib.baseboard_fab2(sch_1):\MG_DQ-DQS_NEAR_DIMM_NG_M_K_BYTE6\"
				( memberType ( signal ) )
				( member ( pinPairRef "@baseboard_fab2_lib.baseboard_fab2(sch_1):\PP2133\") )
				( member ( pinPairRef "@baseboard_fab2_lib.baseboard_fab2(sch_1):\PP2136\") )
				( member ( pinPairRef "@baseboard_fab2_lib.baseboard_fab2(sch_1):\PP2139\") )
				( member ( pinPairRef "@baseboard_fab2_lib.baseboard_fab2(sch_1):\PP2142\") )
				( member ( pinPairRef "@baseboard_fab2_lib.baseboard_fab2(sch_1):\PP2145\") )
				( member ( pinPairRef "@baseboard_fab2_lib.baseboard_fab2(sch_1):\PP2148\") )
				( member ( pinPairRef "@baseboard_fab2_lib.baseboard_fab2(sch_1):\PP2151\") )
				( member ( pinPairRef "@baseboard_fab2_lib.baseboard_fab2(sch_1):\PP2154\") )
				( member ( pinPairRef "@baseboard_fab2_lib.baseboard_fab2(sch_1):\PP1503\") )
				( member ( pinPairRef "@baseboard_fab2_lib.baseboard_fab2(sch_1):\PP1506\") )
				( member ( pinPairRef "@baseboard_fab2_lib.baseboard_fab2(sch_1):\PP1497\") )
				( member ( pinPairRef "@baseboard_fab2_lib.baseboard_fab2(sch_1):\PP1500\") )
				( objectStatus "MG_DQ-DQS_NEAR_DIMM_NG_M_K_BYTE6" )
			)
			( matchGroup "@crescent_city_bb_fab1_lib.crescent_city_bb_fab1(sch_1):\MG_DQ_NEAR_DIMM_NG_M_K_BYTE6\"
				( memberType ( signal ) )
				( member ( pinPairRef "@baseboard_fab2_lib.baseboard_fab2(sch_1):\PP2133\") )
				( member ( pinPairRef "@baseboard_fab2_lib.baseboard_fab2(sch_1):\PP2136\") )
				( member ( pinPairRef "@baseboard_fab2_lib.baseboard_fab2(sch_1):\PP2139\") )
				( member ( pinPairRef "@baseboard_fab2_lib.baseboard_fab2(sch_1):\PP2142\") )
				( member ( pinPairRef "@baseboard_fab2_lib.baseboard_fab2(sch_1):\PP2145\") )
				( member ( pinPairRef "@baseboard_fab2_lib.baseboard_fab2(sch_1):\PP2148\") )
				( member ( pinPairRef "@baseboard_fab2_lib.baseboard_fab2(sch_1):\PP2151\") )
				( member ( pinPairRef "@baseboard_fab2_lib.baseboard_fab2(sch_1):\PP2154\") )
				( objectStatus "MG_DQ_NEAR_DIMM_NG_M_K_BYTE6" )
			)
			( matchGroup "@baseboard_fab2_lib.baseboard_fab2(sch_1):\MG_DQ-DQS_FAR_DIMM_NG_M_G_BYTE5\"
				( memberType ( signal ) )
				( member ( pinPairRef "@baseboard_fab2_lib.baseboard_fab2(sch_1):\PP2818\") )
				( member ( pinPairRef "@baseboard_fab2_lib.baseboard_fab2(sch_1):\PP2821\") )
				( member ( pinPairRef "@baseboard_fab2_lib.baseboard_fab2(sch_1):\PP2824\") )
				( member ( pinPairRef "@baseboard_fab2_lib.baseboard_fab2(sch_1):\PP2803\") )
				( member ( pinPairRef "@baseboard_fab2_lib.baseboard_fab2(sch_1):\PP2806\") )
				( member ( pinPairRef "@baseboard_fab2_lib.baseboard_fab2(sch_1):\PP2809\") )
				( member ( pinPairRef "@baseboard_fab2_lib.baseboard_fab2(sch_1):\PP2812\") )
				( member ( pinPairRef "@baseboard_fab2_lib.baseboard_fab2(sch_1):\PP2815\") )
				( member ( pinPairRef "@baseboard_fab2_lib.baseboard_fab2(sch_1):\PP913\") )
				( member ( pinPairRef "@baseboard_fab2_lib.baseboard_fab2(sch_1):\PP916\") )
				( member ( pinPairRef "@baseboard_fab2_lib.baseboard_fab2(sch_1):\PP907\") )
				( member ( pinPairRef "@baseboard_fab2_lib.baseboard_fab2(sch_1):\PP910\") )
				( objectStatus "MG_DQ-DQS_FAR_DIMM_NG_M_G_BYTE5" )
			)
			( matchGroup "@crescent_city_bb_fab1_lib.crescent_city_bb_fab1(sch_1):\MG_DQ_FAR_DIMM_NG_M_G_BYTE5\"
				( memberType ( signal ) )
				( member ( pinPairRef "@baseboard_fab2_lib.baseboard_fab2(sch_1):\PP2818\") )
				( member ( pinPairRef "@baseboard_fab2_lib.baseboard_fab2(sch_1):\PP2821\") )
				( member ( pinPairRef "@baseboard_fab2_lib.baseboard_fab2(sch_1):\PP2824\") )
				( member ( pinPairRef "@baseboard_fab2_lib.baseboard_fab2(sch_1):\PP2803\") )
				( member ( pinPairRef "@baseboard_fab2_lib.baseboard_fab2(sch_1):\PP2806\") )
				( member ( pinPairRef "@baseboard_fab2_lib.baseboard_fab2(sch_1):\PP2809\") )
				( member ( pinPairRef "@baseboard_fab2_lib.baseboard_fab2(sch_1):\PP2812\") )
				( member ( pinPairRef "@baseboard_fab2_lib.baseboard_fab2(sch_1):\PP2815\") )
				( objectStatus "MG_DQ_FAR_DIMM_NG_M_G_BYTE5" )
			)
			( matchGroup "@baseboard_fab2_lib.baseboard_fab2(sch_1):\MG_DQ-DQS_NEAR_DIMM_NG_M_G_BYTE5\"
				( memberType ( signal ) )
				( member ( pinPairRef "@baseboard_fab2_lib.baseboard_fab2(sch_1):\PP2820\") )
				( member ( pinPairRef "@baseboard_fab2_lib.baseboard_fab2(sch_1):\PP2823\") )
				( member ( pinPairRef "@baseboard_fab2_lib.baseboard_fab2(sch_1):\PP2826\") )
				( member ( pinPairRef "@baseboard_fab2_lib.baseboard_fab2(sch_1):\PP2805\") )
				( member ( pinPairRef "@baseboard_fab2_lib.baseboard_fab2(sch_1):\PP2808\") )
				( member ( pinPairRef "@baseboard_fab2_lib.baseboard_fab2(sch_1):\PP2811\") )
				( member ( pinPairRef "@baseboard_fab2_lib.baseboard_fab2(sch_1):\PP2814\") )
				( member ( pinPairRef "@baseboard_fab2_lib.baseboard_fab2(sch_1):\PP2817\") )
				( member ( pinPairRef "@baseboard_fab2_lib.baseboard_fab2(sch_1):\PP915\") )
				( member ( pinPairRef "@baseboard_fab2_lib.baseboard_fab2(sch_1):\PP918\") )
				( member ( pinPairRef "@baseboard_fab2_lib.baseboard_fab2(sch_1):\PP909\") )
				( member ( pinPairRef "@baseboard_fab2_lib.baseboard_fab2(sch_1):\PP912\") )
				( objectStatus "MG_DQ-DQS_NEAR_DIMM_NG_M_G_BYTE5" )
			)
			( matchGroup "@crescent_city_bb_fab1_lib.crescent_city_bb_fab1(sch_1):\MG_DQ_NEAR_DIMM_NG_M_G_BYTE5\"
				( memberType ( signal ) )
				( member ( pinPairRef "@baseboard_fab2_lib.baseboard_fab2(sch_1):\PP2820\") )
				( member ( pinPairRef "@baseboard_fab2_lib.baseboard_fab2(sch_1):\PP2823\") )
				( member ( pinPairRef "@baseboard_fab2_lib.baseboard_fab2(sch_1):\PP2826\") )
				( member ( pinPairRef "@baseboard_fab2_lib.baseboard_fab2(sch_1):\PP2805\") )
				( member ( pinPairRef "@baseboard_fab2_lib.baseboard_fab2(sch_1):\PP2808\") )
				( member ( pinPairRef "@baseboard_fab2_lib.baseboard_fab2(sch_1):\PP2811\") )
				( member ( pinPairRef "@baseboard_fab2_lib.baseboard_fab2(sch_1):\PP2814\") )
				( member ( pinPairRef "@baseboard_fab2_lib.baseboard_fab2(sch_1):\PP2817\") )
				( objectStatus "MG_DQ_NEAR_DIMM_NG_M_G_BYTE5" )
			)
			( matchGroup "@baseboard_fab2_lib.baseboard_fab2(sch_1):\MG_DQ-DQS_FAR_DIMM_NG_M_G_BYTE6\"
				( memberType ( signal ) )
				( member ( pinPairRef "@baseboard_fab2_lib.baseboard_fab2(sch_1):\PP2779\") )
				( member ( pinPairRef "@baseboard_fab2_lib.baseboard_fab2(sch_1):\PP2782\") )
				( member ( pinPairRef "@baseboard_fab2_lib.baseboard_fab2(sch_1):\PP2785\") )
				( member ( pinPairRef "@baseboard_fab2_lib.baseboard_fab2(sch_1):\PP2788\") )
				( member ( pinPairRef "@baseboard_fab2_lib.baseboard_fab2(sch_1):\PP2791\") )
				( member ( pinPairRef "@baseboard_fab2_lib.baseboard_fab2(sch_1):\PP2794\") )
				( member ( pinPairRef "@baseboard_fab2_lib.baseboard_fab2(sch_1):\PP2797\") )
				( member ( pinPairRef "@baseboard_fab2_lib.baseboard_fab2(sch_1):\PP2800\") )
				( member ( pinPairRef "@baseboard_fab2_lib.baseboard_fab2(sch_1):\PP901\") )
				( member ( pinPairRef "@baseboard_fab2_lib.baseboard_fab2(sch_1):\PP904\") )
				( member ( pinPairRef "@baseboard_fab2_lib.baseboard_fab2(sch_1):\PP895\") )
				( member ( pinPairRef "@baseboard_fab2_lib.baseboard_fab2(sch_1):\PP898\") )
				( objectStatus "MG_DQ-DQS_FAR_DIMM_NG_M_G_BYTE6" )
			)
			( matchGroup "@baseboard_fab2_lib.baseboard_fab2(sch_1):\MG_DQ_FAR_DIMM_NG_M_G_BYTE6\"
				( memberType ( signal ) )
				( member ( pinPairRef "@baseboard_fab2_lib.baseboard_fab2(sch_1):\PP2779\") )
				( member ( pinPairRef "@baseboard_fab2_lib.baseboard_fab2(sch_1):\PP2782\") )
				( member ( pinPairRef "@baseboard_fab2_lib.baseboard_fab2(sch_1):\PP2785\") )
				( member ( pinPairRef "@baseboard_fab2_lib.baseboard_fab2(sch_1):\PP2788\") )
				( member ( pinPairRef "@baseboard_fab2_lib.baseboard_fab2(sch_1):\PP2791\") )
				( member ( pinPairRef "@baseboard_fab2_lib.baseboard_fab2(sch_1):\PP2794\") )
				( member ( pinPairRef "@baseboard_fab2_lib.baseboard_fab2(sch_1):\PP2797\") )
				( member ( pinPairRef "@baseboard_fab2_lib.baseboard_fab2(sch_1):\PP2800\") )
				( objectStatus "MG_DQ_FAR_DIMM_NG_M_G_BYTE6" )
			)
			( matchGroup "@baseboard_fab2_lib.baseboard_fab2(sch_1):\MG_DQ-DQS_NEAR_DIMM_NG_M_G_BYTE6\"
				( memberType ( signal ) )
				( member ( pinPairRef "@baseboard_fab2_lib.baseboard_fab2(sch_1):\PP2781\") )
				( member ( pinPairRef "@baseboard_fab2_lib.baseboard_fab2(sch_1):\PP2784\") )
				( member ( pinPairRef "@baseboard_fab2_lib.baseboard_fab2(sch_1):\PP2787\") )
				( member ( pinPairRef "@baseboard_fab2_lib.baseboard_fab2(sch_1):\PP2790\") )
				( member ( pinPairRef "@baseboard_fab2_lib.baseboard_fab2(sch_1):\PP2793\") )
				( member ( pinPairRef "@baseboard_fab2_lib.baseboard_fab2(sch_1):\PP2796\") )
				( member ( pinPairRef "@baseboard_fab2_lib.baseboard_fab2(sch_1):\PP2799\") )
				( member ( pinPairRef "@baseboard_fab2_lib.baseboard_fab2(sch_1):\PP2802\") )
				( member ( pinPairRef "@baseboard_fab2_lib.baseboard_fab2(sch_1):\PP903\") )
				( member ( pinPairRef "@baseboard_fab2_lib.baseboard_fab2(sch_1):\PP906\") )
				( member ( pinPairRef "@baseboard_fab2_lib.baseboard_fab2(sch_1):\PP897\") )
				( member ( pinPairRef "@baseboard_fab2_lib.baseboard_fab2(sch_1):\PP900\") )
				( objectStatus "MG_DQ-DQS_NEAR_DIMM_NG_M_G_BYTE6" )
			)
			( matchGroup "@baseboard_fab2_lib.baseboard_fab2(sch_1):\MG_DQ_NEAR_DIMM_NG_M_G_BYTE6\"
				( memberType ( signal ) )
				( member ( pinPairRef "@baseboard_fab2_lib.baseboard_fab2(sch_1):\PP2781\") )
				( member ( pinPairRef "@baseboard_fab2_lib.baseboard_fab2(sch_1):\PP2784\") )
				( member ( pinPairRef "@baseboard_fab2_lib.baseboard_fab2(sch_1):\PP2787\") )
				( member ( pinPairRef "@baseboard_fab2_lib.baseboard_fab2(sch_1):\PP2790\") )
				( member ( pinPairRef "@baseboard_fab2_lib.baseboard_fab2(sch_1):\PP2793\") )
				( member ( pinPairRef "@baseboard_fab2_lib.baseboard_fab2(sch_1):\PP2796\") )
				( member ( pinPairRef "@baseboard_fab2_lib.baseboard_fab2(sch_1):\PP2799\") )
				( member ( pinPairRef "@baseboard_fab2_lib.baseboard_fab2(sch_1):\PP2802\") )
				( objectStatus "MG_DQ_NEAR_DIMM_NG_M_G_BYTE6" )
			)
			( matchGroup "@baseboard_fab2_lib.baseboard_fab2(sch_1):\MG_DQ-DQS_FAR_DIMM_NG_M_G_BYTE7\"
				( memberType ( signal ) )
				( member ( pinPairRef "@baseboard_fab2_lib.baseboard_fab2(sch_1):\PP2755\") )
				( member ( pinPairRef "@baseboard_fab2_lib.baseboard_fab2(sch_1):\PP2758\") )
				( member ( pinPairRef "@baseboard_fab2_lib.baseboard_fab2(sch_1):\PP2761\") )
				( member ( pinPairRef "@baseboard_fab2_lib.baseboard_fab2(sch_1):\PP2764\") )
				( member ( pinPairRef "@baseboard_fab2_lib.baseboard_fab2(sch_1):\PP2767\") )
				( member ( pinPairRef "@baseboard_fab2_lib.baseboard_fab2(sch_1):\PP2770\") )
				( member ( pinPairRef "@baseboard_fab2_lib.baseboard_fab2(sch_1):\PP2773\") )
				( member ( pinPairRef "@baseboard_fab2_lib.baseboard_fab2(sch_1):\PP2776\") )
				( member ( pinPairRef "@baseboard_fab2_lib.baseboard_fab2(sch_1):\PP889\") )
				( member ( pinPairRef "@baseboard_fab2_lib.baseboard_fab2(sch_1):\PP892\") )
				( member ( pinPairRef "@baseboard_fab2_lib.baseboard_fab2(sch_1):\PP883\") )
				( member ( pinPairRef "@baseboard_fab2_lib.baseboard_fab2(sch_1):\PP886\") )
				( objectStatus "MG_DQ-DQS_FAR_DIMM_NG_M_G_BYTE7" )
			)
			( matchGroup "@baseboard_fab2_lib.baseboard_fab2(sch_1):\MG_DQ_FAR_DIMM_NG_M_G_BYTE7\"
				( memberType ( signal ) )
				( member ( pinPairRef "@baseboard_fab2_lib.baseboard_fab2(sch_1):\PP2755\") )
				( member ( pinPairRef "@baseboard_fab2_lib.baseboard_fab2(sch_1):\PP2758\") )
				( member ( pinPairRef "@baseboard_fab2_lib.baseboard_fab2(sch_1):\PP2761\") )
				( member ( pinPairRef "@baseboard_fab2_lib.baseboard_fab2(sch_1):\PP2764\") )
				( member ( pinPairRef "@baseboard_fab2_lib.baseboard_fab2(sch_1):\PP2767\") )
				( member ( pinPairRef "@baseboard_fab2_lib.baseboard_fab2(sch_1):\PP2770\") )
				( member ( pinPairRef "@baseboard_fab2_lib.baseboard_fab2(sch_1):\PP2773\") )
				( member ( pinPairRef "@baseboard_fab2_lib.baseboard_fab2(sch_1):\PP2776\") )
				( objectStatus "MG_DQ_FAR_DIMM_NG_M_G_BYTE7" )
			)
			( matchGroup "@baseboard_fab2_lib.baseboard_fab2(sch_1):\MG_DQ-DQS_NEAR_DIMM_NG_M_G_BYTE7\"
				( memberType ( signal ) )
				( member ( pinPairRef "@baseboard_fab2_lib.baseboard_fab2(sch_1):\PP2757\") )
				( member ( pinPairRef "@baseboard_fab2_lib.baseboard_fab2(sch_1):\PP2760\") )
				( member ( pinPairRef "@baseboard_fab2_lib.baseboard_fab2(sch_1):\PP2763\") )
				( member ( pinPairRef "@baseboard_fab2_lib.baseboard_fab2(sch_1):\PP2766\") )
				( member ( pinPairRef "@baseboard_fab2_lib.baseboard_fab2(sch_1):\PP2769\") )
				( member ( pinPairRef "@baseboard_fab2_lib.baseboard_fab2(sch_1):\PP2772\") )
				( member ( pinPairRef "@baseboard_fab2_lib.baseboard_fab2(sch_1):\PP2775\") )
				( member ( pinPairRef "@baseboard_fab2_lib.baseboard_fab2(sch_1):\PP2778\") )
				( member ( pinPairRef "@baseboard_fab2_lib.baseboard_fab2(sch_1):\PP891\") )
				( member ( pinPairRef "@baseboard_fab2_lib.baseboard_fab2(sch_1):\PP894\") )
				( member ( pinPairRef "@baseboard_fab2_lib.baseboard_fab2(sch_1):\PP885\") )
				( member ( pinPairRef "@baseboard_fab2_lib.baseboard_fab2(sch_1):\PP888\") )
				( objectStatus "MG_DQ-DQS_NEAR_DIMM_NG_M_G_BYTE7" )
			)
			( matchGroup "@baseboard_fab2_lib.baseboard_fab2(sch_1):\MG_DQ_NEAR_DIMM_NG_M_G_BYTE7\"
				( memberType ( signal ) )
				( member ( pinPairRef "@baseboard_fab2_lib.baseboard_fab2(sch_1):\PP2757\") )
				( member ( pinPairRef "@baseboard_fab2_lib.baseboard_fab2(sch_1):\PP2760\") )
				( member ( pinPairRef "@baseboard_fab2_lib.baseboard_fab2(sch_1):\PP2763\") )
				( member ( pinPairRef "@baseboard_fab2_lib.baseboard_fab2(sch_1):\PP2766\") )
				( member ( pinPairRef "@baseboard_fab2_lib.baseboard_fab2(sch_1):\PP2769\") )
				( member ( pinPairRef "@baseboard_fab2_lib.baseboard_fab2(sch_1):\PP2772\") )
				( member ( pinPairRef "@baseboard_fab2_lib.baseboard_fab2(sch_1):\PP2775\") )
				( member ( pinPairRef "@baseboard_fab2_lib.baseboard_fab2(sch_1):\PP2778\") )
				( objectStatus "MG_DQ_NEAR_DIMM_NG_M_G_BYTE7" )
			)
			( matchGroup "@baseboard_fab2_lib.baseboard_fab2(sch_1):\MG_DQ-DQS_FAR_DIMM_NG_M_H_BYTE0\"
				( memberType ( signal ) )
				( member ( pinPairRef "@baseboard_fab2_lib.baseboard_fab2(sch_1):\PP2707\") )
				( member ( pinPairRef "@baseboard_fab2_lib.baseboard_fab2(sch_1):\PP2710\") )
				( member ( pinPairRef "@baseboard_fab2_lib.baseboard_fab2(sch_1):\PP2713\") )
				( member ( pinPairRef "@baseboard_fab2_lib.baseboard_fab2(sch_1):\PP2716\") )
				( member ( pinPairRef "@baseboard_fab2_lib.baseboard_fab2(sch_1):\PP2719\") )
				( member ( pinPairRef "@baseboard_fab2_lib.baseboard_fab2(sch_1):\PP2722\") )
				( member ( pinPairRef "@baseboard_fab2_lib.baseboard_fab2(sch_1):\PP2725\") )
				( member ( pinPairRef "@baseboard_fab2_lib.baseboard_fab2(sch_1):\PP2728\") )
				( member ( pinPairRef "@baseboard_fab2_lib.baseboard_fab2(sch_1):\PP859\") )
				( member ( pinPairRef "@baseboard_fab2_lib.baseboard_fab2(sch_1):\PP862\") )
				( member ( pinPairRef "@baseboard_fab2_lib.baseboard_fab2(sch_1):\PP865\") )
				( member ( pinPairRef "@baseboard_fab2_lib.baseboard_fab2(sch_1):\PP868\") )
				( objectStatus "MG_DQ-DQS_FAR_DIMM_NG_M_H_BYTE0" )
			)
			( matchGroup "@baseboard_fab2_lib.baseboard_fab2(sch_1):\MG_DQ_FAR_DIMM_NG_M_H_BYTE0\"
				( memberType ( signal ) )
				( member ( pinPairRef "@baseboard_fab2_lib.baseboard_fab2(sch_1):\PP2707\") )
				( member ( pinPairRef "@baseboard_fab2_lib.baseboard_fab2(sch_1):\PP2710\") )
				( member ( pinPairRef "@baseboard_fab2_lib.baseboard_fab2(sch_1):\PP2713\") )
				( member ( pinPairRef "@baseboard_fab2_lib.baseboard_fab2(sch_1):\PP2716\") )
				( member ( pinPairRef "@baseboard_fab2_lib.baseboard_fab2(sch_1):\PP2719\") )
				( member ( pinPairRef "@baseboard_fab2_lib.baseboard_fab2(sch_1):\PP2722\") )
				( member ( pinPairRef "@baseboard_fab2_lib.baseboard_fab2(sch_1):\PP2725\") )
				( member ( pinPairRef "@baseboard_fab2_lib.baseboard_fab2(sch_1):\PP2728\") )
				( objectStatus "MG_DQ_FAR_DIMM_NG_M_H_BYTE0" )
			)
			( matchGroup "@baseboard_fab2_lib.baseboard_fab2(sch_1):\MG_DQ-DQS_NEAR_DIMM_NG_M_H_BYTE0\"
				( memberType ( signal ) )
				( member ( pinPairRef "@baseboard_fab2_lib.baseboard_fab2(sch_1):\PP2708\") )
				( member ( pinPairRef "@baseboard_fab2_lib.baseboard_fab2(sch_1):\PP2711\") )
				( member ( pinPairRef "@baseboard_fab2_lib.baseboard_fab2(sch_1):\PP2714\") )
				( member ( pinPairRef "@baseboard_fab2_lib.baseboard_fab2(sch_1):\PP2717\") )
				( member ( pinPairRef "@baseboard_fab2_lib.baseboard_fab2(sch_1):\PP2720\") )
				( member ( pinPairRef "@baseboard_fab2_lib.baseboard_fab2(sch_1):\PP2723\") )
				( member ( pinPairRef "@baseboard_fab2_lib.baseboard_fab2(sch_1):\PP2726\") )
				( member ( pinPairRef "@baseboard_fab2_lib.baseboard_fab2(sch_1):\PP2729\") )
				( member ( pinPairRef "@baseboard_fab2_lib.baseboard_fab2(sch_1):\PP860\") )
				( member ( pinPairRef "@baseboard_fab2_lib.baseboard_fab2(sch_1):\PP863\") )
				( member ( pinPairRef "@baseboard_fab2_lib.baseboard_fab2(sch_1):\PP866\") )
				( member ( pinPairRef "@baseboard_fab2_lib.baseboard_fab2(sch_1):\PP869\") )
				( objectStatus "MG_DQ-DQS_NEAR_DIMM_NG_M_H_BYTE0" )
			)
			( matchGroup "@baseboard_fab2_lib.baseboard_fab2(sch_1):\MG_DQ_NEAR_DIMM_NG_M_H_BYTE0\"
				( memberType ( signal ) )
				( member ( pinPairRef "@baseboard_fab2_lib.baseboard_fab2(sch_1):\PP2708\") )
				( member ( pinPairRef "@baseboard_fab2_lib.baseboard_fab2(sch_1):\PP2711\") )
				( member ( pinPairRef "@baseboard_fab2_lib.baseboard_fab2(sch_1):\PP2714\") )
				( member ( pinPairRef "@baseboard_fab2_lib.baseboard_fab2(sch_1):\PP2717\") )
				( member ( pinPairRef "@baseboard_fab2_lib.baseboard_fab2(sch_1):\PP2720\") )
				( member ( pinPairRef "@baseboard_fab2_lib.baseboard_fab2(sch_1):\PP2723\") )
				( member ( pinPairRef "@baseboard_fab2_lib.baseboard_fab2(sch_1):\PP2726\") )
				( member ( pinPairRef "@baseboard_fab2_lib.baseboard_fab2(sch_1):\PP2729\") )
				( objectStatus "MG_DQ_NEAR_DIMM_NG_M_H_BYTE0" )
			)
			( matchGroup "@baseboard_fab2_lib.baseboard_fab2(sch_1):\MG_DQ-DQS_FAR_DIMM_NG_M_H_BYTE3\"
				( memberType ( signal ) )
				( member ( pinPairRef "@baseboard_fab2_lib.baseboard_fab2(sch_1):\PP2635\") )
				( member ( pinPairRef "@baseboard_fab2_lib.baseboard_fab2(sch_1):\PP2638\") )
				( member ( pinPairRef "@baseboard_fab2_lib.baseboard_fab2(sch_1):\PP2641\") )
				( member ( pinPairRef "@baseboard_fab2_lib.baseboard_fab2(sch_1):\PP2644\") )
				( member ( pinPairRef "@baseboard_fab2_lib.baseboard_fab2(sch_1):\PP2647\") )
				( member ( pinPairRef "@baseboard_fab2_lib.baseboard_fab2(sch_1):\PP2650\") )
				( member ( pinPairRef "@baseboard_fab2_lib.baseboard_fab2(sch_1):\PP2653\") )
				( member ( pinPairRef "@baseboard_fab2_lib.baseboard_fab2(sch_1):\PP2656\") )
				( member ( pinPairRef "@baseboard_fab2_lib.baseboard_fab2(sch_1):\PP829\") )
				( member ( pinPairRef "@baseboard_fab2_lib.baseboard_fab2(sch_1):\PP832\") )
				( member ( pinPairRef "@baseboard_fab2_lib.baseboard_fab2(sch_1):\PP823\") )
				( member ( pinPairRef "@baseboard_fab2_lib.baseboard_fab2(sch_1):\PP826\") )
				( objectStatus "MG_DQ-DQS_FAR_DIMM_NG_M_H_BYTE3" )
			)
			( matchGroup "@crescent_city_bb_fab1_lib.crescent_city_bb_fab1(sch_1):\MG_DQ_FAR_DIMM_NG_M_H_BYTE3\"
				( memberType ( signal ) )
				( member ( pinPairRef "@baseboard_fab2_lib.baseboard_fab2(sch_1):\PP2635\") )
				( member ( pinPairRef "@baseboard_fab2_lib.baseboard_fab2(sch_1):\PP2638\") )
				( member ( pinPairRef "@baseboard_fab2_lib.baseboard_fab2(sch_1):\PP2641\") )
				( member ( pinPairRef "@baseboard_fab2_lib.baseboard_fab2(sch_1):\PP2644\") )
				( member ( pinPairRef "@baseboard_fab2_lib.baseboard_fab2(sch_1):\PP2647\") )
				( member ( pinPairRef "@baseboard_fab2_lib.baseboard_fab2(sch_1):\PP2650\") )
				( member ( pinPairRef "@baseboard_fab2_lib.baseboard_fab2(sch_1):\PP2653\") )
				( member ( pinPairRef "@baseboard_fab2_lib.baseboard_fab2(sch_1):\PP2656\") )
				( objectStatus "MG_DQ_FAR_DIMM_NG_M_H_BYTE3" )
			)
			( matchGroup "@baseboard_fab2_lib.baseboard_fab2(sch_1):\MG_DQ-DQS_NEAR_DIMM_NG_M_H_BYTE3\"
				( memberType ( signal ) )
				( member ( pinPairRef "@baseboard_fab2_lib.baseboard_fab2(sch_1):\PP2636\") )
				( member ( pinPairRef "@baseboard_fab2_lib.baseboard_fab2(sch_1):\PP2639\") )
				( member ( pinPairRef "@baseboard_fab2_lib.baseboard_fab2(sch_1):\PP2642\") )
				( member ( pinPairRef "@baseboard_fab2_lib.baseboard_fab2(sch_1):\PP2645\") )
				( member ( pinPairRef "@baseboard_fab2_lib.baseboard_fab2(sch_1):\PP2648\") )
				( member ( pinPairRef "@baseboard_fab2_lib.baseboard_fab2(sch_1):\PP2651\") )
				( member ( pinPairRef "@baseboard_fab2_lib.baseboard_fab2(sch_1):\PP2654\") )
				( member ( pinPairRef "@baseboard_fab2_lib.baseboard_fab2(sch_1):\PP2657\") )
				( member ( pinPairRef "@baseboard_fab2_lib.baseboard_fab2(sch_1):\PP830\") )
				( member ( pinPairRef "@baseboard_fab2_lib.baseboard_fab2(sch_1):\PP833\") )
				( member ( pinPairRef "@baseboard_fab2_lib.baseboard_fab2(sch_1):\PP824\") )
				( member ( pinPairRef "@baseboard_fab2_lib.baseboard_fab2(sch_1):\PP827\") )
				( objectStatus "MG_DQ-DQS_NEAR_DIMM_NG_M_H_BYTE3" )
			)
			( matchGroup "@crescent_city_bb_fab1_lib.crescent_city_bb_fab1(sch_1):\MG_DQ_NEAR_DIMM_NG_M_H_BYTE3\"
				( memberType ( signal ) )
				( member ( pinPairRef "@baseboard_fab2_lib.baseboard_fab2(sch_1):\PP2636\") )
				( member ( pinPairRef "@baseboard_fab2_lib.baseboard_fab2(sch_1):\PP2639\") )
				( member ( pinPairRef "@baseboard_fab2_lib.baseboard_fab2(sch_1):\PP2642\") )
				( member ( pinPairRef "@baseboard_fab2_lib.baseboard_fab2(sch_1):\PP2645\") )
				( member ( pinPairRef "@baseboard_fab2_lib.baseboard_fab2(sch_1):\PP2648\") )
				( member ( pinPairRef "@baseboard_fab2_lib.baseboard_fab2(sch_1):\PP2651\") )
				( member ( pinPairRef "@baseboard_fab2_lib.baseboard_fab2(sch_1):\PP2654\") )
				( member ( pinPairRef "@baseboard_fab2_lib.baseboard_fab2(sch_1):\PP2657\") )
				( objectStatus "MG_DQ_NEAR_DIMM_NG_M_H_BYTE3" )
			)
			( matchGroup "@baseboard_fab2_lib.baseboard_fab2(sch_1):\MG_DQ-DQS_FAR_DIMM_NG_M_H_BYTE4\"
				( memberType ( signal ) )
				( member ( pinPairRef "@baseboard_fab2_lib.baseboard_fab2(sch_1):\PP2611\") )
				( member ( pinPairRef "@baseboard_fab2_lib.baseboard_fab2(sch_1):\PP2614\") )
				( member ( pinPairRef "@baseboard_fab2_lib.baseboard_fab2(sch_1):\PP2617\") )
				( member ( pinPairRef "@baseboard_fab2_lib.baseboard_fab2(sch_1):\PP2620\") )
				( member ( pinPairRef "@baseboard_fab2_lib.baseboard_fab2(sch_1):\PP2623\") )
				( member ( pinPairRef "@baseboard_fab2_lib.baseboard_fab2(sch_1):\PP2626\") )
				( member ( pinPairRef "@baseboard_fab2_lib.baseboard_fab2(sch_1):\PP2629\") )
				( member ( pinPairRef "@baseboard_fab2_lib.baseboard_fab2(sch_1):\PP2632\") )
				( member ( pinPairRef "@baseboard_fab2_lib.baseboard_fab2(sch_1):\PP817\") )
				( member ( pinPairRef "@baseboard_fab2_lib.baseboard_fab2(sch_1):\PP820\") )
				( member ( pinPairRef "@baseboard_fab2_lib.baseboard_fab2(sch_1):\PP811\") )
				( member ( pinPairRef "@baseboard_fab2_lib.baseboard_fab2(sch_1):\PP814\") )
				( objectStatus "MG_DQ-DQS_FAR_DIMM_NG_M_H_BYTE4" )
			)
			( matchGroup "@crescent_city_bb_fab1_lib.crescent_city_bb_fab1(sch_1):\MG_DQ_FAR_DIMM_NG_M_H_BYTE4\"
				( memberType ( signal ) )
				( member ( pinPairRef "@baseboard_fab2_lib.baseboard_fab2(sch_1):\PP2611\") )
				( member ( pinPairRef "@baseboard_fab2_lib.baseboard_fab2(sch_1):\PP2614\") )
				( member ( pinPairRef "@baseboard_fab2_lib.baseboard_fab2(sch_1):\PP2617\") )
				( member ( pinPairRef "@baseboard_fab2_lib.baseboard_fab2(sch_1):\PP2620\") )
				( member ( pinPairRef "@baseboard_fab2_lib.baseboard_fab2(sch_1):\PP2623\") )
				( member ( pinPairRef "@baseboard_fab2_lib.baseboard_fab2(sch_1):\PP2626\") )
				( member ( pinPairRef "@baseboard_fab2_lib.baseboard_fab2(sch_1):\PP2629\") )
				( member ( pinPairRef "@baseboard_fab2_lib.baseboard_fab2(sch_1):\PP2632\") )
				( objectStatus "MG_DQ_FAR_DIMM_NG_M_H_BYTE4" )
			)
			( matchGroup "@baseboard_fab2_lib.baseboard_fab2(sch_1):\MG_DQ-DQS_NEAR_DIMM_NG_M_H_BYTE4\"
				( memberType ( signal ) )
				( member ( pinPairRef "@baseboard_fab2_lib.baseboard_fab2(sch_1):\PP2613\") )
				( member ( pinPairRef "@baseboard_fab2_lib.baseboard_fab2(sch_1):\PP2616\") )
				( member ( pinPairRef "@baseboard_fab2_lib.baseboard_fab2(sch_1):\PP2619\") )
				( member ( pinPairRef "@baseboard_fab2_lib.baseboard_fab2(sch_1):\PP2622\") )
				( member ( pinPairRef "@baseboard_fab2_lib.baseboard_fab2(sch_1):\PP2625\") )
				( member ( pinPairRef "@baseboard_fab2_lib.baseboard_fab2(sch_1):\PP2628\") )
				( member ( pinPairRef "@baseboard_fab2_lib.baseboard_fab2(sch_1):\PP2631\") )
				( member ( pinPairRef "@baseboard_fab2_lib.baseboard_fab2(sch_1):\PP2634\") )
				( member ( pinPairRef "@baseboard_fab2_lib.baseboard_fab2(sch_1):\PP819\") )
				( member ( pinPairRef "@baseboard_fab2_lib.baseboard_fab2(sch_1):\PP822\") )
				( member ( pinPairRef "@baseboard_fab2_lib.baseboard_fab2(sch_1):\PP813\") )
				( member ( pinPairRef "@baseboard_fab2_lib.baseboard_fab2(sch_1):\PP816\") )
				( objectStatus "MG_DQ-DQS_NEAR_DIMM_NG_M_H_BYTE4" )
			)
			( matchGroup "@crescent_city_bb_fab1_lib.crescent_city_bb_fab1(sch_1):\MG_DQ_NEAR_DIMM_NG_M_H_BYTE4\"
				( memberType ( signal ) )
				( member ( pinPairRef "@baseboard_fab2_lib.baseboard_fab2(sch_1):\PP2613\") )
				( member ( pinPairRef "@baseboard_fab2_lib.baseboard_fab2(sch_1):\PP2616\") )
				( member ( pinPairRef "@baseboard_fab2_lib.baseboard_fab2(sch_1):\PP2619\") )
				( member ( pinPairRef "@baseboard_fab2_lib.baseboard_fab2(sch_1):\PP2622\") )
				( member ( pinPairRef "@baseboard_fab2_lib.baseboard_fab2(sch_1):\PP2625\") )
				( member ( pinPairRef "@baseboard_fab2_lib.baseboard_fab2(sch_1):\PP2628\") )
				( member ( pinPairRef "@baseboard_fab2_lib.baseboard_fab2(sch_1):\PP2631\") )
				( member ( pinPairRef "@baseboard_fab2_lib.baseboard_fab2(sch_1):\PP2634\") )
				( objectStatus "MG_DQ_NEAR_DIMM_NG_M_H_BYTE4" )
			)
			( matchGroup "@baseboard_fab2_lib.baseboard_fab2(sch_1):\MG_DQ-DQS_FAR_DIMM_NG_M_H_BYTE5\"
				( memberType ( signal ) )
				( member ( pinPairRef "@baseboard_fab2_lib.baseboard_fab2(sch_1):\PP2587\") )
				( member ( pinPairRef "@baseboard_fab2_lib.baseboard_fab2(sch_1):\PP2590\") )
				( member ( pinPairRef "@baseboard_fab2_lib.baseboard_fab2(sch_1):\PP2593\") )
				( member ( pinPairRef "@baseboard_fab2_lib.baseboard_fab2(sch_1):\PP2596\") )
				( member ( pinPairRef "@baseboard_fab2_lib.baseboard_fab2(sch_1):\PP2599\") )
				( member ( pinPairRef "@baseboard_fab2_lib.baseboard_fab2(sch_1):\PP2602\") )
				( member ( pinPairRef "@baseboard_fab2_lib.baseboard_fab2(sch_1):\PP2605\") )
				( member ( pinPairRef "@baseboard_fab2_lib.baseboard_fab2(sch_1):\PP2608\") )
				( member ( pinPairRef "@baseboard_fab2_lib.baseboard_fab2(sch_1):\PP805\") )
				( member ( pinPairRef "@baseboard_fab2_lib.baseboard_fab2(sch_1):\PP808\") )
				( member ( pinPairRef "@baseboard_fab2_lib.baseboard_fab2(sch_1):\PP799\") )
				( member ( pinPairRef "@baseboard_fab2_lib.baseboard_fab2(sch_1):\PP802\") )
				( objectStatus "MG_DQ-DQS_FAR_DIMM_NG_M_H_BYTE5" )
			)
			( matchGroup "@baseboard_fab2_lib.baseboard_fab2(sch_1):\MG_DQ_FAR_DIMM_NG_M_H_BYTE5\"
				( memberType ( signal ) )
				( member ( pinPairRef "@baseboard_fab2_lib.baseboard_fab2(sch_1):\PP2587\") )
				( member ( pinPairRef "@baseboard_fab2_lib.baseboard_fab2(sch_1):\PP2590\") )
				( member ( pinPairRef "@baseboard_fab2_lib.baseboard_fab2(sch_1):\PP2593\") )
				( member ( pinPairRef "@baseboard_fab2_lib.baseboard_fab2(sch_1):\PP2596\") )
				( member ( pinPairRef "@baseboard_fab2_lib.baseboard_fab2(sch_1):\PP2599\") )
				( member ( pinPairRef "@baseboard_fab2_lib.baseboard_fab2(sch_1):\PP2602\") )
				( member ( pinPairRef "@baseboard_fab2_lib.baseboard_fab2(sch_1):\PP2605\") )
				( member ( pinPairRef "@baseboard_fab2_lib.baseboard_fab2(sch_1):\PP2608\") )
				( objectStatus "MG_DQ_FAR_DIMM_NG_M_H_BYTE5" )
			)
			( matchGroup "@baseboard_fab2_lib.baseboard_fab2(sch_1):\MG_DQ-DQS_NEAR_DIMM_NG_M_H_BYTE5\"
				( memberType ( signal ) )
				( member ( pinPairRef "@baseboard_fab2_lib.baseboard_fab2(sch_1):\PP2589\") )
				( member ( pinPairRef "@baseboard_fab2_lib.baseboard_fab2(sch_1):\PP2592\") )
				( member ( pinPairRef "@baseboard_fab2_lib.baseboard_fab2(sch_1):\PP2595\") )
				( member ( pinPairRef "@baseboard_fab2_lib.baseboard_fab2(sch_1):\PP2598\") )
				( member ( pinPairRef "@baseboard_fab2_lib.baseboard_fab2(sch_1):\PP2601\") )
				( member ( pinPairRef "@baseboard_fab2_lib.baseboard_fab2(sch_1):\PP2604\") )
				( member ( pinPairRef "@baseboard_fab2_lib.baseboard_fab2(sch_1):\PP2607\") )
				( member ( pinPairRef "@baseboard_fab2_lib.baseboard_fab2(sch_1):\PP2610\") )
				( member ( pinPairRef "@baseboard_fab2_lib.baseboard_fab2(sch_1):\PP807\") )
				( member ( pinPairRef "@baseboard_fab2_lib.baseboard_fab2(sch_1):\PP810\") )
				( member ( pinPairRef "@baseboard_fab2_lib.baseboard_fab2(sch_1):\PP801\") )
				( member ( pinPairRef "@baseboard_fab2_lib.baseboard_fab2(sch_1):\PP804\") )
				( objectStatus "MG_DQ-DQS_NEAR_DIMM_NG_M_H_BYTE5" )
			)
			( matchGroup "@baseboard_fab2_lib.baseboard_fab2(sch_1):\MG_DQ_NEAR_DIMM_NG_M_H_BYTE5\"
				( memberType ( signal ) )
				( member ( pinPairRef "@baseboard_fab2_lib.baseboard_fab2(sch_1):\PP2589\") )
				( member ( pinPairRef "@baseboard_fab2_lib.baseboard_fab2(sch_1):\PP2592\") )
				( member ( pinPairRef "@baseboard_fab2_lib.baseboard_fab2(sch_1):\PP2595\") )
				( member ( pinPairRef "@baseboard_fab2_lib.baseboard_fab2(sch_1):\PP2598\") )
				( member ( pinPairRef "@baseboard_fab2_lib.baseboard_fab2(sch_1):\PP2601\") )
				( member ( pinPairRef "@baseboard_fab2_lib.baseboard_fab2(sch_1):\PP2604\") )
				( member ( pinPairRef "@baseboard_fab2_lib.baseboard_fab2(sch_1):\PP2607\") )
				( member ( pinPairRef "@baseboard_fab2_lib.baseboard_fab2(sch_1):\PP2610\") )
				( objectStatus "MG_DQ_NEAR_DIMM_NG_M_H_BYTE5" )
			)
			( matchGroup "@baseboard_fab2_lib.baseboard_fab2(sch_1):\MG_DQ-DQS_FAR_DIMM_NG_M_H_BYTE6\"
				( memberType ( signal ) )
				( member ( pinPairRef "@baseboard_fab2_lib.baseboard_fab2(sch_1):\PP2563\") )
				( member ( pinPairRef "@baseboard_fab2_lib.baseboard_fab2(sch_1):\PP2566\") )
				( member ( pinPairRef "@baseboard_fab2_lib.baseboard_fab2(sch_1):\PP2569\") )
				( member ( pinPairRef "@baseboard_fab2_lib.baseboard_fab2(sch_1):\PP2572\") )
				( member ( pinPairRef "@baseboard_fab2_lib.baseboard_fab2(sch_1):\PP2575\") )
				( member ( pinPairRef "@baseboard_fab2_lib.baseboard_fab2(sch_1):\PP2578\") )
				( member ( pinPairRef "@baseboard_fab2_lib.baseboard_fab2(sch_1):\PP2581\") )
				( member ( pinPairRef "@baseboard_fab2_lib.baseboard_fab2(sch_1):\PP2584\") )
				( member ( pinPairRef "@baseboard_fab2_lib.baseboard_fab2(sch_1):\PP793\") )
				( member ( pinPairRef "@baseboard_fab2_lib.baseboard_fab2(sch_1):\PP796\") )
				( member ( pinPairRef "@baseboard_fab2_lib.baseboard_fab2(sch_1):\PP787\") )
				( member ( pinPairRef "@baseboard_fab2_lib.baseboard_fab2(sch_1):\PP790\") )
				( objectStatus "MG_DQ-DQS_FAR_DIMM_NG_M_H_BYTE6" )
			)
			( matchGroup "@baseboard_fab2_lib.baseboard_fab2(sch_1):\MG_DQ_FAR_DIMM_NG_M_H_BYTE6\"
				( memberType ( signal ) )
				( member ( pinPairRef "@baseboard_fab2_lib.baseboard_fab2(sch_1):\PP2563\") )
				( member ( pinPairRef "@baseboard_fab2_lib.baseboard_fab2(sch_1):\PP2566\") )
				( member ( pinPairRef "@baseboard_fab2_lib.baseboard_fab2(sch_1):\PP2569\") )
				( member ( pinPairRef "@baseboard_fab2_lib.baseboard_fab2(sch_1):\PP2572\") )
				( member ( pinPairRef "@baseboard_fab2_lib.baseboard_fab2(sch_1):\PP2575\") )
				( member ( pinPairRef "@baseboard_fab2_lib.baseboard_fab2(sch_1):\PP2578\") )
				( member ( pinPairRef "@baseboard_fab2_lib.baseboard_fab2(sch_1):\PP2581\") )
				( member ( pinPairRef "@baseboard_fab2_lib.baseboard_fab2(sch_1):\PP2584\") )
				( objectStatus "MG_DQ_FAR_DIMM_NG_M_H_BYTE6" )
			)
			( matchGroup "@baseboard_fab2_lib.baseboard_fab2(sch_1):\MG_DQ-DQS_NEAR_DIMM_NG_M_H_BYTE6\"
				( memberType ( signal ) )
				( member ( pinPairRef "@baseboard_fab2_lib.baseboard_fab2(sch_1):\PP2565\") )
				( member ( pinPairRef "@baseboard_fab2_lib.baseboard_fab2(sch_1):\PP2568\") )
				( member ( pinPairRef "@baseboard_fab2_lib.baseboard_fab2(sch_1):\PP2571\") )
				( member ( pinPairRef "@baseboard_fab2_lib.baseboard_fab2(sch_1):\PP2574\") )
				( member ( pinPairRef "@baseboard_fab2_lib.baseboard_fab2(sch_1):\PP2577\") )
				( member ( pinPairRef "@baseboard_fab2_lib.baseboard_fab2(sch_1):\PP2580\") )
				( member ( pinPairRef "@baseboard_fab2_lib.baseboard_fab2(sch_1):\PP2583\") )
				( member ( pinPairRef "@baseboard_fab2_lib.baseboard_fab2(sch_1):\PP2586\") )
				( member ( pinPairRef "@baseboard_fab2_lib.baseboard_fab2(sch_1):\PP795\") )
				( member ( pinPairRef "@baseboard_fab2_lib.baseboard_fab2(sch_1):\PP798\") )
				( member ( pinPairRef "@baseboard_fab2_lib.baseboard_fab2(sch_1):\PP789\") )
				( member ( pinPairRef "@baseboard_fab2_lib.baseboard_fab2(sch_1):\PP792\") )
				( objectStatus "MG_DQ-DQS_NEAR_DIMM_NG_M_H_BYTE6" )
			)
			( matchGroup "@baseboard_fab2_lib.baseboard_fab2(sch_1):\MG_DQ_NEAR_DIMM_NG_M_H_BYTE6\"
				( memberType ( signal ) )
				( member ( pinPairRef "@baseboard_fab2_lib.baseboard_fab2(sch_1):\PP2565\") )
				( member ( pinPairRef "@baseboard_fab2_lib.baseboard_fab2(sch_1):\PP2568\") )
				( member ( pinPairRef "@baseboard_fab2_lib.baseboard_fab2(sch_1):\PP2571\") )
				( member ( pinPairRef "@baseboard_fab2_lib.baseboard_fab2(sch_1):\PP2574\") )
				( member ( pinPairRef "@baseboard_fab2_lib.baseboard_fab2(sch_1):\PP2577\") )
				( member ( pinPairRef "@baseboard_fab2_lib.baseboard_fab2(sch_1):\PP2580\") )
				( member ( pinPairRef "@baseboard_fab2_lib.baseboard_fab2(sch_1):\PP2583\") )
				( member ( pinPairRef "@baseboard_fab2_lib.baseboard_fab2(sch_1):\PP2586\") )
				( objectStatus "MG_DQ_NEAR_DIMM_NG_M_H_BYTE6" )
			)
			( matchGroup "@baseboard_fab2_lib.baseboard_fab2(sch_1):\MG_DQ-DQS_FAR_DIMM_NG_M_H_BYTE7\"
				( memberType ( signal ) )
				( member ( pinPairRef "@baseboard_fab2_lib.baseboard_fab2(sch_1):\PP2539\") )
				( member ( pinPairRef "@baseboard_fab2_lib.baseboard_fab2(sch_1):\PP2542\") )
				( member ( pinPairRef "@baseboard_fab2_lib.baseboard_fab2(sch_1):\PP2545\") )
				( member ( pinPairRef "@baseboard_fab2_lib.baseboard_fab2(sch_1):\PP2548\") )
				( member ( pinPairRef "@baseboard_fab2_lib.baseboard_fab2(sch_1):\PP2551\") )
				( member ( pinPairRef "@baseboard_fab2_lib.baseboard_fab2(sch_1):\PP2554\") )
				( member ( pinPairRef "@baseboard_fab2_lib.baseboard_fab2(sch_1):\PP2557\") )
				( member ( pinPairRef "@baseboard_fab2_lib.baseboard_fab2(sch_1):\PP2560\") )
				( member ( pinPairRef "@baseboard_fab2_lib.baseboard_fab2(sch_1):\PP781\") )
				( member ( pinPairRef "@baseboard_fab2_lib.baseboard_fab2(sch_1):\PP784\") )
				( member ( pinPairRef "@baseboard_fab2_lib.baseboard_fab2(sch_1):\PP775\") )
				( member ( pinPairRef "@baseboard_fab2_lib.baseboard_fab2(sch_1):\PP778\") )
				( objectStatus "MG_DQ-DQS_FAR_DIMM_NG_M_H_BYTE7" )
			)
			( matchGroup "@baseboard_fab2_lib.baseboard_fab2(sch_1):\MG_DQ_FAR_DIMM_NG_M_H_BYTE7\"
				( memberType ( signal ) )
				( member ( pinPairRef "@baseboard_fab2_lib.baseboard_fab2(sch_1):\PP2539\") )
				( member ( pinPairRef "@baseboard_fab2_lib.baseboard_fab2(sch_1):\PP2542\") )
				( member ( pinPairRef "@baseboard_fab2_lib.baseboard_fab2(sch_1):\PP2545\") )
				( member ( pinPairRef "@baseboard_fab2_lib.baseboard_fab2(sch_1):\PP2548\") )
				( member ( pinPairRef "@baseboard_fab2_lib.baseboard_fab2(sch_1):\PP2551\") )
				( member ( pinPairRef "@baseboard_fab2_lib.baseboard_fab2(sch_1):\PP2554\") )
				( member ( pinPairRef "@baseboard_fab2_lib.baseboard_fab2(sch_1):\PP2557\") )
				( member ( pinPairRef "@baseboard_fab2_lib.baseboard_fab2(sch_1):\PP2560\") )
				( objectStatus "MG_DQ_FAR_DIMM_NG_M_H_BYTE7" )
			)
			( matchGroup "@baseboard_fab2_lib.baseboard_fab2(sch_1):\MG_DQ-DQS_NEAR_DIMM_NG_M_H_BYTE7\"
				( memberType ( signal ) )
				( member ( pinPairRef "@baseboard_fab2_lib.baseboard_fab2(sch_1):\PP2541\") )
				( member ( pinPairRef "@baseboard_fab2_lib.baseboard_fab2(sch_1):\PP2544\") )
				( member ( pinPairRef "@baseboard_fab2_lib.baseboard_fab2(sch_1):\PP2547\") )
				( member ( pinPairRef "@baseboard_fab2_lib.baseboard_fab2(sch_1):\PP2550\") )
				( member ( pinPairRef "@baseboard_fab2_lib.baseboard_fab2(sch_1):\PP2553\") )
				( member ( pinPairRef "@baseboard_fab2_lib.baseboard_fab2(sch_1):\PP2556\") )
				( member ( pinPairRef "@baseboard_fab2_lib.baseboard_fab2(sch_1):\PP2559\") )
				( member ( pinPairRef "@baseboard_fab2_lib.baseboard_fab2(sch_1):\PP2562\") )
				( member ( pinPairRef "@baseboard_fab2_lib.baseboard_fab2(sch_1):\PP783\") )
				( member ( pinPairRef "@baseboard_fab2_lib.baseboard_fab2(sch_1):\PP786\") )
				( member ( pinPairRef "@baseboard_fab2_lib.baseboard_fab2(sch_1):\PP777\") )
				( member ( pinPairRef "@baseboard_fab2_lib.baseboard_fab2(sch_1):\PP780\") )
				( objectStatus "MG_DQ-DQS_NEAR_DIMM_NG_M_H_BYTE7" )
			)
			( matchGroup "@baseboard_fab2_lib.baseboard_fab2(sch_1):\MG_DQ_NEAR_DIMM_NG_M_H_BYTE7\"
				( memberType ( signal ) )
				( member ( pinPairRef "@baseboard_fab2_lib.baseboard_fab2(sch_1):\PP2541\") )
				( member ( pinPairRef "@baseboard_fab2_lib.baseboard_fab2(sch_1):\PP2544\") )
				( member ( pinPairRef "@baseboard_fab2_lib.baseboard_fab2(sch_1):\PP2547\") )
				( member ( pinPairRef "@baseboard_fab2_lib.baseboard_fab2(sch_1):\PP2550\") )
				( member ( pinPairRef "@baseboard_fab2_lib.baseboard_fab2(sch_1):\PP2553\") )
				( member ( pinPairRef "@baseboard_fab2_lib.baseboard_fab2(sch_1):\PP2556\") )
				( member ( pinPairRef "@baseboard_fab2_lib.baseboard_fab2(sch_1):\PP2559\") )
				( member ( pinPairRef "@baseboard_fab2_lib.baseboard_fab2(sch_1):\PP2562\") )
				( objectStatus "MG_DQ_NEAR_DIMM_NG_M_H_BYTE7" )
			)
			( matchGroup "@baseboard_fab2_lib.baseboard_fab2(sch_1):\MG_DQ-DQS_FAR_DIMM_NG_M_J_BYTE0\"
				( memberType ( signal ) )
				( member ( pinPairRef "@baseboard_fab2_lib.baseboard_fab2(sch_1):\PP2491\") )
				( member ( pinPairRef "@baseboard_fab2_lib.baseboard_fab2(sch_1):\PP2494\") )
				( member ( pinPairRef "@baseboard_fab2_lib.baseboard_fab2(sch_1):\PP2497\") )
				( member ( pinPairRef "@baseboard_fab2_lib.baseboard_fab2(sch_1):\PP2500\") )
				( member ( pinPairRef "@baseboard_fab2_lib.baseboard_fab2(sch_1):\PP2503\") )
				( member ( pinPairRef "@baseboard_fab2_lib.baseboard_fab2(sch_1):\PP2506\") )
				( member ( pinPairRef "@baseboard_fab2_lib.baseboard_fab2(sch_1):\PP2509\") )
				( member ( pinPairRef "@baseboard_fab2_lib.baseboard_fab2(sch_1):\PP2512\") )
				( member ( pinPairRef "@baseboard_fab2_lib.baseboard_fab2(sch_1):\PP1669\") )
				( member ( pinPairRef "@baseboard_fab2_lib.baseboard_fab2(sch_1):\PP1672\") )
				( member ( pinPairRef "@baseboard_fab2_lib.baseboard_fab2(sch_1):\PP1663\") )
				( member ( pinPairRef "@baseboard_fab2_lib.baseboard_fab2(sch_1):\PP1666\") )
				( objectStatus "MG_DQ-DQS_FAR_DIMM_NG_M_J_BYTE0" )
			)
			( matchGroup "@baseboard_fab2_lib.baseboard_fab2(sch_1):\MG_DQ_FAR_DIMM_NG_M_J_BYTE0\"
				( memberType ( signal ) )
				( member ( pinPairRef "@baseboard_fab2_lib.baseboard_fab2(sch_1):\PP2491\") )
				( member ( pinPairRef "@baseboard_fab2_lib.baseboard_fab2(sch_1):\PP2494\") )
				( member ( pinPairRef "@baseboard_fab2_lib.baseboard_fab2(sch_1):\PP2497\") )
				( member ( pinPairRef "@baseboard_fab2_lib.baseboard_fab2(sch_1):\PP2500\") )
				( member ( pinPairRef "@baseboard_fab2_lib.baseboard_fab2(sch_1):\PP2503\") )
				( member ( pinPairRef "@baseboard_fab2_lib.baseboard_fab2(sch_1):\PP2506\") )
				( member ( pinPairRef "@baseboard_fab2_lib.baseboard_fab2(sch_1):\PP2509\") )
				( member ( pinPairRef "@baseboard_fab2_lib.baseboard_fab2(sch_1):\PP2512\") )
				( objectStatus "MG_DQ_FAR_DIMM_NG_M_J_BYTE0" )
			)
			( matchGroup "@baseboard_fab2_lib.baseboard_fab2(sch_1):\MG_DQ-DQS_NEAR_DIMM_NG_M_J_BYTE0\"
				( memberType ( signal ) )
				( member ( pinPairRef "@baseboard_fab2_lib.baseboard_fab2(sch_1):\PP2492\") )
				( member ( pinPairRef "@baseboard_fab2_lib.baseboard_fab2(sch_1):\PP2495\") )
				( member ( pinPairRef "@baseboard_fab2_lib.baseboard_fab2(sch_1):\PP2498\") )
				( member ( pinPairRef "@baseboard_fab2_lib.baseboard_fab2(sch_1):\PP2501\") )
				( member ( pinPairRef "@baseboard_fab2_lib.baseboard_fab2(sch_1):\PP2504\") )
				( member ( pinPairRef "@baseboard_fab2_lib.baseboard_fab2(sch_1):\PP2507\") )
				( member ( pinPairRef "@baseboard_fab2_lib.baseboard_fab2(sch_1):\PP2510\") )
				( member ( pinPairRef "@baseboard_fab2_lib.baseboard_fab2(sch_1):\PP2513\") )
				( member ( pinPairRef "@baseboard_fab2_lib.baseboard_fab2(sch_1):\PP1670\") )
				( member ( pinPairRef "@baseboard_fab2_lib.baseboard_fab2(sch_1):\PP1673\") )
				( member ( pinPairRef "@baseboard_fab2_lib.baseboard_fab2(sch_1):\PP1664\") )
				( member ( pinPairRef "@baseboard_fab2_lib.baseboard_fab2(sch_1):\PP1667\") )
				( objectStatus "MG_DQ-DQS_NEAR_DIMM_NG_M_J_BYTE0" )
			)
			( matchGroup "@baseboard_fab2_lib.baseboard_fab2(sch_1):\MG_DQ_NEAR_DIMM_NG_M_J_BYTE0\"
				( memberType ( signal ) )
				( member ( pinPairRef "@baseboard_fab2_lib.baseboard_fab2(sch_1):\PP2492\") )
				( member ( pinPairRef "@baseboard_fab2_lib.baseboard_fab2(sch_1):\PP2495\") )
				( member ( pinPairRef "@baseboard_fab2_lib.baseboard_fab2(sch_1):\PP2498\") )
				( member ( pinPairRef "@baseboard_fab2_lib.baseboard_fab2(sch_1):\PP2501\") )
				( member ( pinPairRef "@baseboard_fab2_lib.baseboard_fab2(sch_1):\PP2504\") )
				( member ( pinPairRef "@baseboard_fab2_lib.baseboard_fab2(sch_1):\PP2507\") )
				( member ( pinPairRef "@baseboard_fab2_lib.baseboard_fab2(sch_1):\PP2510\") )
				( member ( pinPairRef "@baseboard_fab2_lib.baseboard_fab2(sch_1):\PP2513\") )
				( objectStatus "MG_DQ_NEAR_DIMM_NG_M_J_BYTE0" )
			)
			( matchGroup "@baseboard_fab2_lib.baseboard_fab2(sch_1):\MG_DQ-DQS_FAR_DIMM_NG_M_J_BYTE1\"
				( memberType ( signal ) )
				( member ( pinPairRef "@baseboard_fab2_lib.baseboard_fab2(sch_1):\PP2467\") )
				( member ( pinPairRef "@baseboard_fab2_lib.baseboard_fab2(sch_1):\PP2470\") )
				( member ( pinPairRef "@baseboard_fab2_lib.baseboard_fab2(sch_1):\PP2473\") )
				( member ( pinPairRef "@baseboard_fab2_lib.baseboard_fab2(sch_1):\PP2476\") )
				( member ( pinPairRef "@baseboard_fab2_lib.baseboard_fab2(sch_1):\PP2479\") )
				( member ( pinPairRef "@baseboard_fab2_lib.baseboard_fab2(sch_1):\PP2482\") )
				( member ( pinPairRef "@baseboard_fab2_lib.baseboard_fab2(sch_1):\PP2485\") )
				( member ( pinPairRef "@baseboard_fab2_lib.baseboard_fab2(sch_1):\PP2488\") )
				( member ( pinPairRef "@baseboard_fab2_lib.baseboard_fab2(sch_1):\PP1657\") )
				( member ( pinPairRef "@baseboard_fab2_lib.baseboard_fab2(sch_1):\PP1660\") )
				( member ( pinPairRef "@baseboard_fab2_lib.baseboard_fab2(sch_1):\PP1651\") )
				( member ( pinPairRef "@baseboard_fab2_lib.baseboard_fab2(sch_1):\PP1654\") )
				( objectStatus "MG_DQ-DQS_FAR_DIMM_NG_M_J_BYTE1" )
			)
			( matchGroup "@baseboard_fab2_lib.baseboard_fab2(sch_1):\MG_DQ_FAR_DIMM_NG_M_J_BYTE1\"
				( memberType ( signal ) )
				( member ( pinPairRef "@baseboard_fab2_lib.baseboard_fab2(sch_1):\PP2467\") )
				( member ( pinPairRef "@baseboard_fab2_lib.baseboard_fab2(sch_1):\PP2470\") )
				( member ( pinPairRef "@baseboard_fab2_lib.baseboard_fab2(sch_1):\PP2473\") )
				( member ( pinPairRef "@baseboard_fab2_lib.baseboard_fab2(sch_1):\PP2476\") )
				( member ( pinPairRef "@baseboard_fab2_lib.baseboard_fab2(sch_1):\PP2479\") )
				( member ( pinPairRef "@baseboard_fab2_lib.baseboard_fab2(sch_1):\PP2482\") )
				( member ( pinPairRef "@baseboard_fab2_lib.baseboard_fab2(sch_1):\PP2485\") )
				( member ( pinPairRef "@baseboard_fab2_lib.baseboard_fab2(sch_1):\PP2488\") )
				( objectStatus "MG_DQ_FAR_DIMM_NG_M_J_BYTE1" )
			)
			( matchGroup "@baseboard_fab2_lib.baseboard_fab2(sch_1):\MG_DQ-DQS_NEAR_DIMM_NG_M_J_BYTE1\"
				( memberType ( signal ) )
				( member ( pinPairRef "@baseboard_fab2_lib.baseboard_fab2(sch_1):\PP2468\") )
				( member ( pinPairRef "@baseboard_fab2_lib.baseboard_fab2(sch_1):\PP2471\") )
				( member ( pinPairRef "@baseboard_fab2_lib.baseboard_fab2(sch_1):\PP2474\") )
				( member ( pinPairRef "@baseboard_fab2_lib.baseboard_fab2(sch_1):\PP2477\") )
				( member ( pinPairRef "@baseboard_fab2_lib.baseboard_fab2(sch_1):\PP2480\") )
				( member ( pinPairRef "@baseboard_fab2_lib.baseboard_fab2(sch_1):\PP2483\") )
				( member ( pinPairRef "@baseboard_fab2_lib.baseboard_fab2(sch_1):\PP2486\") )
				( member ( pinPairRef "@baseboard_fab2_lib.baseboard_fab2(sch_1):\PP2489\") )
				( member ( pinPairRef "@baseboard_fab2_lib.baseboard_fab2(sch_1):\PP1658\") )
				( member ( pinPairRef "@baseboard_fab2_lib.baseboard_fab2(sch_1):\PP1661\") )
				( member ( pinPairRef "@baseboard_fab2_lib.baseboard_fab2(sch_1):\PP1652\") )
				( member ( pinPairRef "@baseboard_fab2_lib.baseboard_fab2(sch_1):\PP1655\") )
				( objectStatus "MG_DQ-DQS_NEAR_DIMM_NG_M_J_BYTE1" )
			)
			( matchGroup "@baseboard_fab2_lib.baseboard_fab2(sch_1):\MG_DQ_NEAR_DIMM_NG_M_J_BYTE1\"
				( memberType ( signal ) )
				( member ( pinPairRef "@baseboard_fab2_lib.baseboard_fab2(sch_1):\PP2468\") )
				( member ( pinPairRef "@baseboard_fab2_lib.baseboard_fab2(sch_1):\PP2471\") )
				( member ( pinPairRef "@baseboard_fab2_lib.baseboard_fab2(sch_1):\PP2474\") )
				( member ( pinPairRef "@baseboard_fab2_lib.baseboard_fab2(sch_1):\PP2477\") )
				( member ( pinPairRef "@baseboard_fab2_lib.baseboard_fab2(sch_1):\PP2480\") )
				( member ( pinPairRef "@baseboard_fab2_lib.baseboard_fab2(sch_1):\PP2483\") )
				( member ( pinPairRef "@baseboard_fab2_lib.baseboard_fab2(sch_1):\PP2486\") )
				( member ( pinPairRef "@baseboard_fab2_lib.baseboard_fab2(sch_1):\PP2489\") )
				( objectStatus "MG_DQ_NEAR_DIMM_NG_M_J_BYTE1" )
			)
			( matchGroup "@baseboard_fab2_lib.baseboard_fab2(sch_1):\MG_DQ-DQS_FAR_DIMM_NG_M_A_BYTE1\"
				( memberType ( signal ) )
				( member ( pinPairRef "@baseboard_fab2_lib.baseboard_fab2(sch_1):\PP5319\") )
				( member ( pinPairRef "@baseboard_fab2_lib.baseboard_fab2(sch_1):\PP5322\") )
				( member ( pinPairRef "@baseboard_fab2_lib.baseboard_fab2(sch_1):\PP5325\") )
				( member ( pinPairRef "@baseboard_fab2_lib.baseboard_fab2(sch_1):\PP5328\") )
				( member ( pinPairRef "@baseboard_fab2_lib.baseboard_fab2(sch_1):\PP5331\") )
				( member ( pinPairRef "@baseboard_fab2_lib.baseboard_fab2(sch_1):\PP5334\") )
				( member ( pinPairRef "@baseboard_fab2_lib.baseboard_fab2(sch_1):\PP5337\") )
				( member ( pinPairRef "@baseboard_fab2_lib.baseboard_fab2(sch_1):\PP5340\") )
				( member ( pinPairRef "@baseboard_fab2_lib.baseboard_fab2(sch_1):\PP457\") )
				( member ( pinPairRef "@baseboard_fab2_lib.baseboard_fab2(sch_1):\PP451\") )
				( member ( pinPairRef "@baseboard_fab2_lib.baseboard_fab2(sch_1):\PP460\") )
				( member ( pinPairRef "@baseboard_fab2_lib.baseboard_fab2(sch_1):\PP454\") )
				( objectStatus "MG_DQ-DQS_FAR_DIMM_NG_M_A_BYTE1" )
			)
			( matchGroup "@baseboard_fab2_lib.baseboard_fab2(sch_1):\MG_DQ_FAR_DIMM_NG_M_A_BYTE1\"
				( memberType ( signal ) )
				( member ( pinPairRef "@baseboard_fab2_lib.baseboard_fab2(sch_1):\PP5319\") )
				( member ( pinPairRef "@baseboard_fab2_lib.baseboard_fab2(sch_1):\PP5322\") )
				( member ( pinPairRef "@baseboard_fab2_lib.baseboard_fab2(sch_1):\PP5325\") )
				( member ( pinPairRef "@baseboard_fab2_lib.baseboard_fab2(sch_1):\PP5328\") )
				( member ( pinPairRef "@baseboard_fab2_lib.baseboard_fab2(sch_1):\PP5331\") )
				( member ( pinPairRef "@baseboard_fab2_lib.baseboard_fab2(sch_1):\PP5334\") )
				( member ( pinPairRef "@baseboard_fab2_lib.baseboard_fab2(sch_1):\PP5337\") )
				( member ( pinPairRef "@baseboard_fab2_lib.baseboard_fab2(sch_1):\PP5340\") )
				( objectStatus "MG_DQ_FAR_DIMM_NG_M_A_BYTE1" )
			)
			( matchGroup "@baseboard_fab2_lib.baseboard_fab2(sch_1):\MG_DQ-DQS_NEAR_DIMM_NG_M_A_BYTE1\"
				( memberType ( signal ) )
				( member ( pinPairRef "@baseboard_fab2_lib.baseboard_fab2(sch_1):\PP5321\") )
				( member ( pinPairRef "@baseboard_fab2_lib.baseboard_fab2(sch_1):\PP5324\") )
				( member ( pinPairRef "@baseboard_fab2_lib.baseboard_fab2(sch_1):\PP5327\") )
				( member ( pinPairRef "@baseboard_fab2_lib.baseboard_fab2(sch_1):\PP5330\") )
				( member ( pinPairRef "@baseboard_fab2_lib.baseboard_fab2(sch_1):\PP5333\") )
				( member ( pinPairRef "@baseboard_fab2_lib.baseboard_fab2(sch_1):\PP5336\") )
				( member ( pinPairRef "@baseboard_fab2_lib.baseboard_fab2(sch_1):\PP5339\") )
				( member ( pinPairRef "@baseboard_fab2_lib.baseboard_fab2(sch_1):\PP5342\") )
				( member ( pinPairRef "@baseboard_fab2_lib.baseboard_fab2(sch_1):\PP459\") )
				( member ( pinPairRef "@baseboard_fab2_lib.baseboard_fab2(sch_1):\PP453\") )
				( member ( pinPairRef "@baseboard_fab2_lib.baseboard_fab2(sch_1):\PP462\") )
				( member ( pinPairRef "@baseboard_fab2_lib.baseboard_fab2(sch_1):\PP456\") )
				( objectStatus "MG_DQ-DQS_NEAR_DIMM_NG_M_A_BYTE1" )
			)
			( matchGroup "@baseboard_fab2_lib.baseboard_fab2(sch_1):\MG_DQ_NEAR_DIMM_NG_M_A_BYTE1\"
				( memberType ( signal ) )
				( member ( pinPairRef "@baseboard_fab2_lib.baseboard_fab2(sch_1):\PP5321\") )
				( member ( pinPairRef "@baseboard_fab2_lib.baseboard_fab2(sch_1):\PP5324\") )
				( member ( pinPairRef "@baseboard_fab2_lib.baseboard_fab2(sch_1):\PP5327\") )
				( member ( pinPairRef "@baseboard_fab2_lib.baseboard_fab2(sch_1):\PP5330\") )
				( member ( pinPairRef "@baseboard_fab2_lib.baseboard_fab2(sch_1):\PP5333\") )
				( member ( pinPairRef "@baseboard_fab2_lib.baseboard_fab2(sch_1):\PP5336\") )
				( member ( pinPairRef "@baseboard_fab2_lib.baseboard_fab2(sch_1):\PP5339\") )
				( member ( pinPairRef "@baseboard_fab2_lib.baseboard_fab2(sch_1):\PP5342\") )
				( objectStatus "MG_DQ_NEAR_DIMM_NG_M_A_BYTE1" )
			)
			( matchGroup "@baseboard_fab2_lib.baseboard_fab2(sch_1):\MG_DQ-DQS_FAR_DIMM_NG_M_A_BYTE2\"
				( memberType ( signal ) )
				( member ( pinPairRef "@baseboard_fab2_lib.baseboard_fab2(sch_1):\PP5295\") )
				( member ( pinPairRef "@baseboard_fab2_lib.baseboard_fab2(sch_1):\PP5298\") )
				( member ( pinPairRef "@baseboard_fab2_lib.baseboard_fab2(sch_1):\PP5301\") )
				( member ( pinPairRef "@baseboard_fab2_lib.baseboard_fab2(sch_1):\PP5304\") )
				( member ( pinPairRef "@baseboard_fab2_lib.baseboard_fab2(sch_1):\PP5307\") )
				( member ( pinPairRef "@baseboard_fab2_lib.baseboard_fab2(sch_1):\PP5310\") )
				( member ( pinPairRef "@baseboard_fab2_lib.baseboard_fab2(sch_1):\PP5313\") )
				( member ( pinPairRef "@baseboard_fab2_lib.baseboard_fab2(sch_1):\PP5316\") )
				( member ( pinPairRef "@baseboard_fab2_lib.baseboard_fab2(sch_1):\PP445\") )
				( member ( pinPairRef "@baseboard_fab2_lib.baseboard_fab2(sch_1):\PP439\") )
				( member ( pinPairRef "@baseboard_fab2_lib.baseboard_fab2(sch_1):\PP448\") )
				( member ( pinPairRef "@baseboard_fab2_lib.baseboard_fab2(sch_1):\PP442\") )
				( objectStatus "MG_DQ-DQS_FAR_DIMM_NG_M_A_BYTE2" )
			)
			( matchGroup "@baseboard_fab2_lib.baseboard_fab2(sch_1):\MG_DQ_FAR_DIMM_NG_M_A_BYTE2\"
				( memberType ( signal ) )
				( member ( pinPairRef "@baseboard_fab2_lib.baseboard_fab2(sch_1):\PP5295\") )
				( member ( pinPairRef "@baseboard_fab2_lib.baseboard_fab2(sch_1):\PP5298\") )
				( member ( pinPairRef "@baseboard_fab2_lib.baseboard_fab2(sch_1):\PP5301\") )
				( member ( pinPairRef "@baseboard_fab2_lib.baseboard_fab2(sch_1):\PP5304\") )
				( member ( pinPairRef "@baseboard_fab2_lib.baseboard_fab2(sch_1):\PP5307\") )
				( member ( pinPairRef "@baseboard_fab2_lib.baseboard_fab2(sch_1):\PP5310\") )
				( member ( pinPairRef "@baseboard_fab2_lib.baseboard_fab2(sch_1):\PP5313\") )
				( member ( pinPairRef "@baseboard_fab2_lib.baseboard_fab2(sch_1):\PP5316\") )
				( objectStatus "MG_DQ_FAR_DIMM_NG_M_A_BYTE2" )
			)
			( matchGroup "@baseboard_fab2_lib.baseboard_fab2(sch_1):\MG_DQ-DQS_NEAR_DIMM_NG_M_A_BYTE2\"
				( memberType ( signal ) )
				( member ( pinPairRef "@baseboard_fab2_lib.baseboard_fab2(sch_1):\PP5297\") )
				( member ( pinPairRef "@baseboard_fab2_lib.baseboard_fab2(sch_1):\PP5300\") )
				( member ( pinPairRef "@baseboard_fab2_lib.baseboard_fab2(sch_1):\PP5303\") )
				( member ( pinPairRef "@baseboard_fab2_lib.baseboard_fab2(sch_1):\PP5306\") )
				( member ( pinPairRef "@baseboard_fab2_lib.baseboard_fab2(sch_1):\PP5309\") )
				( member ( pinPairRef "@baseboard_fab2_lib.baseboard_fab2(sch_1):\PP5312\") )
				( member ( pinPairRef "@baseboard_fab2_lib.baseboard_fab2(sch_1):\PP5315\") )
				( member ( pinPairRef "@baseboard_fab2_lib.baseboard_fab2(sch_1):\PP5318\") )
				( member ( pinPairRef "@baseboard_fab2_lib.baseboard_fab2(sch_1):\PP447\") )
				( member ( pinPairRef "@baseboard_fab2_lib.baseboard_fab2(sch_1):\PP441\") )
				( member ( pinPairRef "@baseboard_fab2_lib.baseboard_fab2(sch_1):\PP450\") )
				( member ( pinPairRef "@baseboard_fab2_lib.baseboard_fab2(sch_1):\PP444\") )
				( objectStatus "MG_DQ-DQS_NEAR_DIMM_NG_M_A_BYTE2" )
			)
			( matchGroup "@baseboard_fab2_lib.baseboard_fab2(sch_1):\MG_DQ_NEAR_DIMM_NG_M_A_BYTE2\"
				( memberType ( signal ) )
				( member ( pinPairRef "@baseboard_fab2_lib.baseboard_fab2(sch_1):\PP5297\") )
				( member ( pinPairRef "@baseboard_fab2_lib.baseboard_fab2(sch_1):\PP5300\") )
				( member ( pinPairRef "@baseboard_fab2_lib.baseboard_fab2(sch_1):\PP5303\") )
				( member ( pinPairRef "@baseboard_fab2_lib.baseboard_fab2(sch_1):\PP5306\") )
				( member ( pinPairRef "@baseboard_fab2_lib.baseboard_fab2(sch_1):\PP5309\") )
				( member ( pinPairRef "@baseboard_fab2_lib.baseboard_fab2(sch_1):\PP5312\") )
				( member ( pinPairRef "@baseboard_fab2_lib.baseboard_fab2(sch_1):\PP5315\") )
				( member ( pinPairRef "@baseboard_fab2_lib.baseboard_fab2(sch_1):\PP5318\") )
				( objectStatus "MG_DQ_NEAR_DIMM_NG_M_A_BYTE2" )
			)
			( matchGroup "@baseboard_fab2_lib.baseboard_fab2(sch_1):\MG_DQ-DQS_FAR_DIMM_NG_M_A_BYTE3\"
				( memberType ( signal ) )
				( member ( pinPairRef "@baseboard_fab2_lib.baseboard_fab2(sch_1):\PP5271\") )
				( member ( pinPairRef "@baseboard_fab2_lib.baseboard_fab2(sch_1):\PP5274\") )
				( member ( pinPairRef "@baseboard_fab2_lib.baseboard_fab2(sch_1):\PP5277\") )
				( member ( pinPairRef "@baseboard_fab2_lib.baseboard_fab2(sch_1):\PP5280\") )
				( member ( pinPairRef "@baseboard_fab2_lib.baseboard_fab2(sch_1):\PP5283\") )
				( member ( pinPairRef "@baseboard_fab2_lib.baseboard_fab2(sch_1):\PP5286\") )
				( member ( pinPairRef "@baseboard_fab2_lib.baseboard_fab2(sch_1):\PP5289\") )
				( member ( pinPairRef "@baseboard_fab2_lib.baseboard_fab2(sch_1):\PP5292\") )
				( member ( pinPairRef "@baseboard_fab2_lib.baseboard_fab2(sch_1):\PP433\") )
				( member ( pinPairRef "@baseboard_fab2_lib.baseboard_fab2(sch_1):\PP427\") )
				( member ( pinPairRef "@baseboard_fab2_lib.baseboard_fab2(sch_1):\PP436\") )
				( member ( pinPairRef "@baseboard_fab2_lib.baseboard_fab2(sch_1):\PP430\") )
				( objectStatus "MG_DQ-DQS_FAR_DIMM_NG_M_A_BYTE3" )
			)
			( matchGroup "@baseboard_fab2_lib.baseboard_fab2(sch_1):\MG_DQ_FAR_DIMM_NG_M_A_BYTE3\"
				( memberType ( signal ) )
				( member ( pinPairRef "@baseboard_fab2_lib.baseboard_fab2(sch_1):\PP5271\") )
				( member ( pinPairRef "@baseboard_fab2_lib.baseboard_fab2(sch_1):\PP5274\") )
				( member ( pinPairRef "@baseboard_fab2_lib.baseboard_fab2(sch_1):\PP5277\") )
				( member ( pinPairRef "@baseboard_fab2_lib.baseboard_fab2(sch_1):\PP5280\") )
				( member ( pinPairRef "@baseboard_fab2_lib.baseboard_fab2(sch_1):\PP5283\") )
				( member ( pinPairRef "@baseboard_fab2_lib.baseboard_fab2(sch_1):\PP5286\") )
				( member ( pinPairRef "@baseboard_fab2_lib.baseboard_fab2(sch_1):\PP5289\") )
				( member ( pinPairRef "@baseboard_fab2_lib.baseboard_fab2(sch_1):\PP5292\") )
				( objectStatus "MG_DQ_FAR_DIMM_NG_M_A_BYTE3" )
			)
			( matchGroup "@baseboard_fab2_lib.baseboard_fab2(sch_1):\MG_DQ-DQS_NEAR_DIMM_NG_M_A_BYTE3\"
				( memberType ( signal ) )
				( member ( pinPairRef "@baseboard_fab2_lib.baseboard_fab2(sch_1):\PP5273\") )
				( member ( pinPairRef "@baseboard_fab2_lib.baseboard_fab2(sch_1):\PP5276\") )
				( member ( pinPairRef "@baseboard_fab2_lib.baseboard_fab2(sch_1):\PP5279\") )
				( member ( pinPairRef "@baseboard_fab2_lib.baseboard_fab2(sch_1):\PP5282\") )
				( member ( pinPairRef "@baseboard_fab2_lib.baseboard_fab2(sch_1):\PP5285\") )
				( member ( pinPairRef "@baseboard_fab2_lib.baseboard_fab2(sch_1):\PP5288\") )
				( member ( pinPairRef "@baseboard_fab2_lib.baseboard_fab2(sch_1):\PP5291\") )
				( member ( pinPairRef "@baseboard_fab2_lib.baseboard_fab2(sch_1):\PP5294\") )
				( member ( pinPairRef "@baseboard_fab2_lib.baseboard_fab2(sch_1):\PP435\") )
				( member ( pinPairRef "@baseboard_fab2_lib.baseboard_fab2(sch_1):\PP429\") )
				( member ( pinPairRef "@baseboard_fab2_lib.baseboard_fab2(sch_1):\PP438\") )
				( member ( pinPairRef "@baseboard_fab2_lib.baseboard_fab2(sch_1):\PP432\") )
				( objectStatus "MG_DQ-DQS_NEAR_DIMM_NG_M_A_BYTE3" )
			)
			( matchGroup "@baseboard_fab2_lib.baseboard_fab2(sch_1):\MG_DQ_NEAR_DIMM_NG_M_A_BYTE3\"
				( memberType ( signal ) )
				( member ( pinPairRef "@baseboard_fab2_lib.baseboard_fab2(sch_1):\PP5273\") )
				( member ( pinPairRef "@baseboard_fab2_lib.baseboard_fab2(sch_1):\PP5276\") )
				( member ( pinPairRef "@baseboard_fab2_lib.baseboard_fab2(sch_1):\PP5279\") )
				( member ( pinPairRef "@baseboard_fab2_lib.baseboard_fab2(sch_1):\PP5282\") )
				( member ( pinPairRef "@baseboard_fab2_lib.baseboard_fab2(sch_1):\PP5285\") )
				( member ( pinPairRef "@baseboard_fab2_lib.baseboard_fab2(sch_1):\PP5288\") )
				( member ( pinPairRef "@baseboard_fab2_lib.baseboard_fab2(sch_1):\PP5291\") )
				( member ( pinPairRef "@baseboard_fab2_lib.baseboard_fab2(sch_1):\PP5294\") )
				( objectStatus "MG_DQ_NEAR_DIMM_NG_M_A_BYTE3" )
			)
			( matchGroup "@baseboard_fab2_lib.baseboard_fab2(sch_1):\MG_DQ-DQS_FAR_DIMM_NG_M_A_BYTE4\"
				( memberType ( signal ) )
				( member ( pinPairRef "@baseboard_fab2_lib.baseboard_fab2(sch_1):\PP5247\") )
				( member ( pinPairRef "@baseboard_fab2_lib.baseboard_fab2(sch_1):\PP5250\") )
				( member ( pinPairRef "@baseboard_fab2_lib.baseboard_fab2(sch_1):\PP5253\") )
				( member ( pinPairRef "@baseboard_fab2_lib.baseboard_fab2(sch_1):\PP5256\") )
				( member ( pinPairRef "@baseboard_fab2_lib.baseboard_fab2(sch_1):\PP5259\") )
				( member ( pinPairRef "@baseboard_fab2_lib.baseboard_fab2(sch_1):\PP5262\") )
				( member ( pinPairRef "@baseboard_fab2_lib.baseboard_fab2(sch_1):\PP5265\") )
				( member ( pinPairRef "@baseboard_fab2_lib.baseboard_fab2(sch_1):\PP5268\") )
				( member ( pinPairRef "@baseboard_fab2_lib.baseboard_fab2(sch_1):\PP421\") )
				( member ( pinPairRef "@baseboard_fab2_lib.baseboard_fab2(sch_1):\PP415\") )
				( member ( pinPairRef "@baseboard_fab2_lib.baseboard_fab2(sch_1):\PP424\") )
				( member ( pinPairRef "@baseboard_fab2_lib.baseboard_fab2(sch_1):\PP418\") )
				( objectStatus "MG_DQ-DQS_FAR_DIMM_NG_M_A_BYTE4" )
			)
			( matchGroup "@baseboard_fab2_lib.baseboard_fab2(sch_1):\MG_DQ_FAR_DIMM_NG_M_A_BYTE4\"
				( memberType ( signal ) )
				( member ( pinPairRef "@baseboard_fab2_lib.baseboard_fab2(sch_1):\PP5247\") )
				( member ( pinPairRef "@baseboard_fab2_lib.baseboard_fab2(sch_1):\PP5250\") )
				( member ( pinPairRef "@baseboard_fab2_lib.baseboard_fab2(sch_1):\PP5253\") )
				( member ( pinPairRef "@baseboard_fab2_lib.baseboard_fab2(sch_1):\PP5256\") )
				( member ( pinPairRef "@baseboard_fab2_lib.baseboard_fab2(sch_1):\PP5259\") )
				( member ( pinPairRef "@baseboard_fab2_lib.baseboard_fab2(sch_1):\PP5262\") )
				( member ( pinPairRef "@baseboard_fab2_lib.baseboard_fab2(sch_1):\PP5265\") )
				( member ( pinPairRef "@baseboard_fab2_lib.baseboard_fab2(sch_1):\PP5268\") )
				( objectStatus "MG_DQ_FAR_DIMM_NG_M_A_BYTE4" )
			)
			( matchGroup "@baseboard_fab2_lib.baseboard_fab2(sch_1):\MG_DQ-DQS_NEAR_DIMM_NG_M_A_BYTE4\"
				( memberType ( signal ) )
				( member ( pinPairRef "@baseboard_fab2_lib.baseboard_fab2(sch_1):\PP5249\") )
				( member ( pinPairRef "@baseboard_fab2_lib.baseboard_fab2(sch_1):\PP5252\") )
				( member ( pinPairRef "@baseboard_fab2_lib.baseboard_fab2(sch_1):\PP5255\") )
				( member ( pinPairRef "@baseboard_fab2_lib.baseboard_fab2(sch_1):\PP5258\") )
				( member ( pinPairRef "@baseboard_fab2_lib.baseboard_fab2(sch_1):\PP5261\") )
				( member ( pinPairRef "@baseboard_fab2_lib.baseboard_fab2(sch_1):\PP5264\") )
				( member ( pinPairRef "@baseboard_fab2_lib.baseboard_fab2(sch_1):\PP5267\") )
				( member ( pinPairRef "@baseboard_fab2_lib.baseboard_fab2(sch_1):\PP5270\") )
				( member ( pinPairRef "@baseboard_fab2_lib.baseboard_fab2(sch_1):\PP423\") )
				( member ( pinPairRef "@baseboard_fab2_lib.baseboard_fab2(sch_1):\PP417\") )
				( member ( pinPairRef "@baseboard_fab2_lib.baseboard_fab2(sch_1):\PP426\") )
				( member ( pinPairRef "@baseboard_fab2_lib.baseboard_fab2(sch_1):\PP420\") )
				( objectStatus "MG_DQ-DQS_NEAR_DIMM_NG_M_A_BYTE4" )
			)
			( matchGroup "@baseboard_fab2_lib.baseboard_fab2(sch_1):\MG_DQ_NEAR_DIMM_NG_M_A_BYTE4\"
				( memberType ( signal ) )
				( member ( pinPairRef "@baseboard_fab2_lib.baseboard_fab2(sch_1):\PP5249\") )
				( member ( pinPairRef "@baseboard_fab2_lib.baseboard_fab2(sch_1):\PP5252\") )
				( member ( pinPairRef "@baseboard_fab2_lib.baseboard_fab2(sch_1):\PP5255\") )
				( member ( pinPairRef "@baseboard_fab2_lib.baseboard_fab2(sch_1):\PP5258\") )
				( member ( pinPairRef "@baseboard_fab2_lib.baseboard_fab2(sch_1):\PP5261\") )
				( member ( pinPairRef "@baseboard_fab2_lib.baseboard_fab2(sch_1):\PP5264\") )
				( member ( pinPairRef "@baseboard_fab2_lib.baseboard_fab2(sch_1):\PP5267\") )
				( member ( pinPairRef "@baseboard_fab2_lib.baseboard_fab2(sch_1):\PP5270\") )
				( objectStatus "MG_DQ_NEAR_DIMM_NG_M_A_BYTE4" )
			)
			( matchGroup "@baseboard_fab2_lib.baseboard_fab2(sch_1):\MG_DQ-DQS_FAR_DIMM_NG_M_A_BYTE5\"
				( memberType ( signal ) )
				( member ( pinPairRef "@baseboard_fab2_lib.baseboard_fab2(sch_1):\PP5223\") )
				( member ( pinPairRef "@baseboard_fab2_lib.baseboard_fab2(sch_1):\PP5226\") )
				( member ( pinPairRef "@baseboard_fab2_lib.baseboard_fab2(sch_1):\PP5229\") )
				( member ( pinPairRef "@baseboard_fab2_lib.baseboard_fab2(sch_1):\PP5232\") )
				( member ( pinPairRef "@baseboard_fab2_lib.baseboard_fab2(sch_1):\PP5235\") )
				( member ( pinPairRef "@baseboard_fab2_lib.baseboard_fab2(sch_1):\PP5238\") )
				( member ( pinPairRef "@baseboard_fab2_lib.baseboard_fab2(sch_1):\PP5241\") )
				( member ( pinPairRef "@baseboard_fab2_lib.baseboard_fab2(sch_1):\PP5244\") )
				( member ( pinPairRef "@baseboard_fab2_lib.baseboard_fab2(sch_1):\PP409\") )
				( member ( pinPairRef "@baseboard_fab2_lib.baseboard_fab2(sch_1):\PP403\") )
				( member ( pinPairRef "@baseboard_fab2_lib.baseboard_fab2(sch_1):\PP412\") )
				( member ( pinPairRef "@baseboard_fab2_lib.baseboard_fab2(sch_1):\PP406\") )
				( objectStatus "MG_DQ-DQS_FAR_DIMM_NG_M_A_BYTE5" )
			)
			( matchGroup "@crescent_city_bb_fab1_lib.crescent_city_bb_fab1(sch_1):\MG_DQ_FAR_DIMM_NG_M_A_BYTE5\"
				( memberType ( signal ) )
				( member ( pinPairRef "@baseboard_fab2_lib.baseboard_fab2(sch_1):\PP5223\") )
				( member ( pinPairRef "@baseboard_fab2_lib.baseboard_fab2(sch_1):\PP5226\") )
				( member ( pinPairRef "@baseboard_fab2_lib.baseboard_fab2(sch_1):\PP5229\") )
				( member ( pinPairRef "@baseboard_fab2_lib.baseboard_fab2(sch_1):\PP5232\") )
				( member ( pinPairRef "@baseboard_fab2_lib.baseboard_fab2(sch_1):\PP5235\") )
				( member ( pinPairRef "@baseboard_fab2_lib.baseboard_fab2(sch_1):\PP5238\") )
				( member ( pinPairRef "@baseboard_fab2_lib.baseboard_fab2(sch_1):\PP5241\") )
				( member ( pinPairRef "@baseboard_fab2_lib.baseboard_fab2(sch_1):\PP5244\") )
				( objectStatus "MG_DQ_FAR_DIMM_NG_M_A_BYTE5" )
			)
			( matchGroup "@baseboard_fab2_lib.baseboard_fab2(sch_1):\MG_DQ-DQS_NEAR_DIMM_NG_M_A_BYTE5\"
				( memberType ( signal ) )
				( member ( pinPairRef "@baseboard_fab2_lib.baseboard_fab2(sch_1):\PP5225\") )
				( member ( pinPairRef "@baseboard_fab2_lib.baseboard_fab2(sch_1):\PP5228\") )
				( member ( pinPairRef "@baseboard_fab2_lib.baseboard_fab2(sch_1):\PP5231\") )
				( member ( pinPairRef "@baseboard_fab2_lib.baseboard_fab2(sch_1):\PP5234\") )
				( member ( pinPairRef "@baseboard_fab2_lib.baseboard_fab2(sch_1):\PP5237\") )
				( member ( pinPairRef "@baseboard_fab2_lib.baseboard_fab2(sch_1):\PP5240\") )
				( member ( pinPairRef "@baseboard_fab2_lib.baseboard_fab2(sch_1):\PP5243\") )
				( member ( pinPairRef "@baseboard_fab2_lib.baseboard_fab2(sch_1):\PP5246\") )
				( member ( pinPairRef "@baseboard_fab2_lib.baseboard_fab2(sch_1):\PP411\") )
				( member ( pinPairRef "@baseboard_fab2_lib.baseboard_fab2(sch_1):\PP405\") )
				( member ( pinPairRef "@baseboard_fab2_lib.baseboard_fab2(sch_1):\PP414\") )
				( member ( pinPairRef "@baseboard_fab2_lib.baseboard_fab2(sch_1):\PP408\") )
				( objectStatus "MG_DQ-DQS_NEAR_DIMM_NG_M_A_BYTE5" )
			)
			( matchGroup "@crescent_city_bb_fab1_lib.crescent_city_bb_fab1(sch_1):\MG_DQ_NEAR_DIMM_NG_M_A_BYTE5\"
				( memberType ( signal ) )
				( member ( pinPairRef "@baseboard_fab2_lib.baseboard_fab2(sch_1):\PP5225\") )
				( member ( pinPairRef "@baseboard_fab2_lib.baseboard_fab2(sch_1):\PP5228\") )
				( member ( pinPairRef "@baseboard_fab2_lib.baseboard_fab2(sch_1):\PP5231\") )
				( member ( pinPairRef "@baseboard_fab2_lib.baseboard_fab2(sch_1):\PP5234\") )
				( member ( pinPairRef "@baseboard_fab2_lib.baseboard_fab2(sch_1):\PP5237\") )
				( member ( pinPairRef "@baseboard_fab2_lib.baseboard_fab2(sch_1):\PP5240\") )
				( member ( pinPairRef "@baseboard_fab2_lib.baseboard_fab2(sch_1):\PP5243\") )
				( member ( pinPairRef "@baseboard_fab2_lib.baseboard_fab2(sch_1):\PP5246\") )
				( objectStatus "MG_DQ_NEAR_DIMM_NG_M_A_BYTE5" )
			)
			( matchGroup "@baseboard_fab2_lib.baseboard_fab2(sch_1):\MG_DQ-DQS_FAR_DIMM_NG_M_A_BYTE6\"
				( memberType ( signal ) )
				( member ( pinPairRef "@baseboard_fab2_lib.baseboard_fab2(sch_1):\PP5199\") )
				( member ( pinPairRef "@baseboard_fab2_lib.baseboard_fab2(sch_1):\PP5202\") )
				( member ( pinPairRef "@baseboard_fab2_lib.baseboard_fab2(sch_1):\PP5205\") )
				( member ( pinPairRef "@baseboard_fab2_lib.baseboard_fab2(sch_1):\PP5208\") )
				( member ( pinPairRef "@baseboard_fab2_lib.baseboard_fab2(sch_1):\PP5211\") )
				( member ( pinPairRef "@baseboard_fab2_lib.baseboard_fab2(sch_1):\PP5214\") )
				( member ( pinPairRef "@baseboard_fab2_lib.baseboard_fab2(sch_1):\PP5217\") )
				( member ( pinPairRef "@baseboard_fab2_lib.baseboard_fab2(sch_1):\PP5220\") )
				( member ( pinPairRef "@baseboard_fab2_lib.baseboard_fab2(sch_1):\PP397\") )
				( member ( pinPairRef "@baseboard_fab2_lib.baseboard_fab2(sch_1):\PP391\") )
				( member ( pinPairRef "@baseboard_fab2_lib.baseboard_fab2(sch_1):\PP400\") )
				( member ( pinPairRef "@baseboard_fab2_lib.baseboard_fab2(sch_1):\PP394\") )
				( objectStatus "MG_DQ-DQS_FAR_DIMM_NG_M_A_BYTE6" )
			)
			( matchGroup "@baseboard_fab2_lib.baseboard_fab2(sch_1):\MG_DQ_FAR_DIMM_NG_M_A_BYTE6\"
				( memberType ( signal ) )
				( member ( pinPairRef "@baseboard_fab2_lib.baseboard_fab2(sch_1):\PP5199\") )
				( member ( pinPairRef "@baseboard_fab2_lib.baseboard_fab2(sch_1):\PP5202\") )
				( member ( pinPairRef "@baseboard_fab2_lib.baseboard_fab2(sch_1):\PP5205\") )
				( member ( pinPairRef "@baseboard_fab2_lib.baseboard_fab2(sch_1):\PP5208\") )
				( member ( pinPairRef "@baseboard_fab2_lib.baseboard_fab2(sch_1):\PP5211\") )
				( member ( pinPairRef "@baseboard_fab2_lib.baseboard_fab2(sch_1):\PP5214\") )
				( member ( pinPairRef "@baseboard_fab2_lib.baseboard_fab2(sch_1):\PP5217\") )
				( member ( pinPairRef "@baseboard_fab2_lib.baseboard_fab2(sch_1):\PP5220\") )
				( objectStatus "MG_DQ_FAR_DIMM_NG_M_A_BYTE6" )
			)
			( matchGroup "@baseboard_fab2_lib.baseboard_fab2(sch_1):\MG_DQ-DQS_NEAR_DIMM_NG_M_A_BYTE6\"
				( memberType ( signal ) )
				( member ( pinPairRef "@baseboard_fab2_lib.baseboard_fab2(sch_1):\PP5201\") )
				( member ( pinPairRef "@baseboard_fab2_lib.baseboard_fab2(sch_1):\PP5204\") )
				( member ( pinPairRef "@baseboard_fab2_lib.baseboard_fab2(sch_1):\PP5207\") )
				( member ( pinPairRef "@baseboard_fab2_lib.baseboard_fab2(sch_1):\PP5210\") )
				( member ( pinPairRef "@baseboard_fab2_lib.baseboard_fab2(sch_1):\PP5213\") )
				( member ( pinPairRef "@baseboard_fab2_lib.baseboard_fab2(sch_1):\PP5216\") )
				( member ( pinPairRef "@baseboard_fab2_lib.baseboard_fab2(sch_1):\PP5219\") )
				( member ( pinPairRef "@baseboard_fab2_lib.baseboard_fab2(sch_1):\PP5222\") )
				( member ( pinPairRef "@baseboard_fab2_lib.baseboard_fab2(sch_1):\PP399\") )
				( member ( pinPairRef "@baseboard_fab2_lib.baseboard_fab2(sch_1):\PP393\") )
				( member ( pinPairRef "@baseboard_fab2_lib.baseboard_fab2(sch_1):\PP402\") )
				( member ( pinPairRef "@baseboard_fab2_lib.baseboard_fab2(sch_1):\PP396\") )
				( objectStatus "MG_DQ-DQS_NEAR_DIMM_NG_M_A_BYTE6" )
			)
			( matchGroup "@baseboard_fab2_lib.baseboard_fab2(sch_1):\MG_DQ_NEAR_DIMM_NG_M_A_BYTE6\"
				( memberType ( signal ) )
				( member ( pinPairRef "@baseboard_fab2_lib.baseboard_fab2(sch_1):\PP5201\") )
				( member ( pinPairRef "@baseboard_fab2_lib.baseboard_fab2(sch_1):\PP5204\") )
				( member ( pinPairRef "@baseboard_fab2_lib.baseboard_fab2(sch_1):\PP5207\") )
				( member ( pinPairRef "@baseboard_fab2_lib.baseboard_fab2(sch_1):\PP5210\") )
				( member ( pinPairRef "@baseboard_fab2_lib.baseboard_fab2(sch_1):\PP5213\") )
				( member ( pinPairRef "@baseboard_fab2_lib.baseboard_fab2(sch_1):\PP5216\") )
				( member ( pinPairRef "@baseboard_fab2_lib.baseboard_fab2(sch_1):\PP5219\") )
				( member ( pinPairRef "@baseboard_fab2_lib.baseboard_fab2(sch_1):\PP5222\") )
				( objectStatus "MG_DQ_NEAR_DIMM_NG_M_A_BYTE6" )
			)
			( matchGroup "@baseboard_fab2_lib.baseboard_fab2(sch_1):\MG_DQ-DQS_FAR_DIMM_NG_M_A_BYTE7\"
				( memberType ( signal ) )
				( member ( pinPairRef "@baseboard_fab2_lib.baseboard_fab2(sch_1):\PP5163\") )
				( member ( pinPairRef "@baseboard_fab2_lib.baseboard_fab2(sch_1):\PP5166\") )
				( member ( pinPairRef "@baseboard_fab2_lib.baseboard_fab2(sch_1):\PP5169\") )
				( member ( pinPairRef "@baseboard_fab2_lib.baseboard_fab2(sch_1):\PP5172\") )
				( member ( pinPairRef "@baseboard_fab2_lib.baseboard_fab2(sch_1):\PP5175\") )
				( member ( pinPairRef "@baseboard_fab2_lib.baseboard_fab2(sch_1):\PP5178\") )
				( member ( pinPairRef "@baseboard_fab2_lib.baseboard_fab2(sch_1):\PP5181\") )
				( member ( pinPairRef "@baseboard_fab2_lib.baseboard_fab2(sch_1):\PP5184\") )
				( member ( pinPairRef "@baseboard_fab2_lib.baseboard_fab2(sch_1):\PP5187\") )
				( member ( pinPairRef "@baseboard_fab2_lib.baseboard_fab2(sch_1):\PP5193\") )
				( member ( pinPairRef "@baseboard_fab2_lib.baseboard_fab2(sch_1):\PP5190\") )
				( member ( pinPairRef "@baseboard_fab2_lib.baseboard_fab2(sch_1):\PP5196\") )
				( objectStatus "MG_DQ-DQS_FAR_DIMM_NG_M_A_BYTE7" )
			)
			( matchGroup "@baseboard_fab2_lib.baseboard_fab2(sch_1):\MG_DQ_FAR_DIMM_NG_M_A_BYTE7\"
				( memberType ( signal ) )
				( member ( pinPairRef "@baseboard_fab2_lib.baseboard_fab2(sch_1):\PP5163\") )
				( member ( pinPairRef "@baseboard_fab2_lib.baseboard_fab2(sch_1):\PP5166\") )
				( member ( pinPairRef "@baseboard_fab2_lib.baseboard_fab2(sch_1):\PP5169\") )
				( member ( pinPairRef "@baseboard_fab2_lib.baseboard_fab2(sch_1):\PP5172\") )
				( member ( pinPairRef "@baseboard_fab2_lib.baseboard_fab2(sch_1):\PP5175\") )
				( member ( pinPairRef "@baseboard_fab2_lib.baseboard_fab2(sch_1):\PP5178\") )
				( member ( pinPairRef "@baseboard_fab2_lib.baseboard_fab2(sch_1):\PP5181\") )
				( member ( pinPairRef "@baseboard_fab2_lib.baseboard_fab2(sch_1):\PP5184\") )
				( objectStatus "MG_DQ_FAR_DIMM_NG_M_A_BYTE7" )
			)
			( matchGroup "@baseboard_fab2_lib.baseboard_fab2(sch_1):\MG_DQ-DQS_NEAR_DIMM_NG_M_A_BYTE7\"
				( memberType ( signal ) )
				( member ( pinPairRef "@baseboard_fab2_lib.baseboard_fab2(sch_1):\PP5165\") )
				( member ( pinPairRef "@baseboard_fab2_lib.baseboard_fab2(sch_1):\PP5168\") )
				( member ( pinPairRef "@baseboard_fab2_lib.baseboard_fab2(sch_1):\PP5171\") )
				( member ( pinPairRef "@baseboard_fab2_lib.baseboard_fab2(sch_1):\PP5174\") )
				( member ( pinPairRef "@baseboard_fab2_lib.baseboard_fab2(sch_1):\PP5177\") )
				( member ( pinPairRef "@baseboard_fab2_lib.baseboard_fab2(sch_1):\PP5180\") )
				( member ( pinPairRef "@baseboard_fab2_lib.baseboard_fab2(sch_1):\PP5183\") )
				( member ( pinPairRef "@baseboard_fab2_lib.baseboard_fab2(sch_1):\PP5186\") )
				( member ( pinPairRef "@baseboard_fab2_lib.baseboard_fab2(sch_1):\PP5189\") )
				( member ( pinPairRef "@baseboard_fab2_lib.baseboard_fab2(sch_1):\PP5195\") )
				( member ( pinPairRef "@baseboard_fab2_lib.baseboard_fab2(sch_1):\PP5192\") )
				( member ( pinPairRef "@baseboard_fab2_lib.baseboard_fab2(sch_1):\PP5198\") )
				( objectStatus "MG_DQ-DQS_NEAR_DIMM_NG_M_A_BYTE7" )
			)
			( matchGroup "@baseboard_fab2_lib.baseboard_fab2(sch_1):\MG_DQ_NEAR_DIMM_NG_M_A_BYTE7\"
				( memberType ( signal ) )
				( member ( pinPairRef "@baseboard_fab2_lib.baseboard_fab2(sch_1):\PP5165\") )
				( member ( pinPairRef "@baseboard_fab2_lib.baseboard_fab2(sch_1):\PP5168\") )
				( member ( pinPairRef "@baseboard_fab2_lib.baseboard_fab2(sch_1):\PP5171\") )
				( member ( pinPairRef "@baseboard_fab2_lib.baseboard_fab2(sch_1):\PP5174\") )
				( member ( pinPairRef "@baseboard_fab2_lib.baseboard_fab2(sch_1):\PP5177\") )
				( member ( pinPairRef "@baseboard_fab2_lib.baseboard_fab2(sch_1):\PP5180\") )
				( member ( pinPairRef "@baseboard_fab2_lib.baseboard_fab2(sch_1):\PP5183\") )
				( member ( pinPairRef "@baseboard_fab2_lib.baseboard_fab2(sch_1):\PP5186\") )
				( objectStatus "MG_DQ_NEAR_DIMM_NG_M_A_BYTE7" )
			)
			( matchGroup "@baseboard_fab2_lib.baseboard_fab2(sch_1):\MG_DQ-DQS_FAR_DIMM_NG_M_G_BYTE0\"
				( memberType ( signal ) )
				( member ( pinPairRef "@baseboard_fab2_lib.baseboard_fab2(sch_1):\PP2923\") )
				( member ( pinPairRef "@baseboard_fab2_lib.baseboard_fab2(sch_1):\PP2926\") )
				( member ( pinPairRef "@baseboard_fab2_lib.baseboard_fab2(sch_1):\PP2929\") )
				( member ( pinPairRef "@baseboard_fab2_lib.baseboard_fab2(sch_1):\PP2932\") )
				( member ( pinPairRef "@baseboard_fab2_lib.baseboard_fab2(sch_1):\PP2935\") )
				( member ( pinPairRef "@baseboard_fab2_lib.baseboard_fab2(sch_1):\PP2938\") )
				( member ( pinPairRef "@baseboard_fab2_lib.baseboard_fab2(sch_1):\PP2941\") )
				( member ( pinPairRef "@baseboard_fab2_lib.baseboard_fab2(sch_1):\PP2944\") )
				( member ( pinPairRef "@baseboard_fab2_lib.baseboard_fab2(sch_1):\PP973\") )
				( member ( pinPairRef "@baseboard_fab2_lib.baseboard_fab2(sch_1):\PP976\") )
				( member ( pinPairRef "@baseboard_fab2_lib.baseboard_fab2(sch_1):\PP967\") )
				( member ( pinPairRef "@baseboard_fab2_lib.baseboard_fab2(sch_1):\PP970\") )
				( objectStatus "MG_DQ-DQS_FAR_DIMM_NG_M_G_BYTE0" )
			)
			( matchGroup "@baseboard_fab2_lib.baseboard_fab2(sch_1):\MG_DQ_FAR_DIMM_NG_M_G_BYTE0\"
				( memberType ( signal ) )
				( member ( pinPairRef "@baseboard_fab2_lib.baseboard_fab2(sch_1):\PP2923\") )
				( member ( pinPairRef "@baseboard_fab2_lib.baseboard_fab2(sch_1):\PP2926\") )
				( member ( pinPairRef "@baseboard_fab2_lib.baseboard_fab2(sch_1):\PP2929\") )
				( member ( pinPairRef "@baseboard_fab2_lib.baseboard_fab2(sch_1):\PP2932\") )
				( member ( pinPairRef "@baseboard_fab2_lib.baseboard_fab2(sch_1):\PP2935\") )
				( member ( pinPairRef "@baseboard_fab2_lib.baseboard_fab2(sch_1):\PP2938\") )
				( member ( pinPairRef "@baseboard_fab2_lib.baseboard_fab2(sch_1):\PP2941\") )
				( member ( pinPairRef "@baseboard_fab2_lib.baseboard_fab2(sch_1):\PP2944\") )
				( objectStatus "MG_DQ_FAR_DIMM_NG_M_G_BYTE0" )
			)
			( matchGroup "@baseboard_fab2_lib.baseboard_fab2(sch_1):\MG_DQ-DQS_NEAR_DIMM_NG_M_G_BYTE0\"
				( memberType ( signal ) )
				( member ( pinPairRef "@baseboard_fab2_lib.baseboard_fab2(sch_1):\PP2924\") )
				( member ( pinPairRef "@baseboard_fab2_lib.baseboard_fab2(sch_1):\PP2927\") )
				( member ( pinPairRef "@baseboard_fab2_lib.baseboard_fab2(sch_1):\PP2930\") )
				( member ( pinPairRef "@baseboard_fab2_lib.baseboard_fab2(sch_1):\PP2933\") )
				( member ( pinPairRef "@baseboard_fab2_lib.baseboard_fab2(sch_1):\PP2936\") )
				( member ( pinPairRef "@baseboard_fab2_lib.baseboard_fab2(sch_1):\PP2939\") )
				( member ( pinPairRef "@baseboard_fab2_lib.baseboard_fab2(sch_1):\PP2942\") )
				( member ( pinPairRef "@baseboard_fab2_lib.baseboard_fab2(sch_1):\PP2945\") )
				( member ( pinPairRef "@baseboard_fab2_lib.baseboard_fab2(sch_1):\PP974\") )
				( member ( pinPairRef "@baseboard_fab2_lib.baseboard_fab2(sch_1):\PP977\") )
				( member ( pinPairRef "@baseboard_fab2_lib.baseboard_fab2(sch_1):\PP968\") )
				( member ( pinPairRef "@baseboard_fab2_lib.baseboard_fab2(sch_1):\PP971\") )
				( objectStatus "MG_DQ-DQS_NEAR_DIMM_NG_M_G_BYTE0" )
			)
			( matchGroup "@baseboard_fab2_lib.baseboard_fab2(sch_1):\MG_DQ_NEAR_DIMM_NG_M_G_BYTE0\"
				( memberType ( signal ) )
				( member ( pinPairRef "@baseboard_fab2_lib.baseboard_fab2(sch_1):\PP2924\") )
				( member ( pinPairRef "@baseboard_fab2_lib.baseboard_fab2(sch_1):\PP2927\") )
				( member ( pinPairRef "@baseboard_fab2_lib.baseboard_fab2(sch_1):\PP2930\") )
				( member ( pinPairRef "@baseboard_fab2_lib.baseboard_fab2(sch_1):\PP2933\") )
				( member ( pinPairRef "@baseboard_fab2_lib.baseboard_fab2(sch_1):\PP2936\") )
				( member ( pinPairRef "@baseboard_fab2_lib.baseboard_fab2(sch_1):\PP2939\") )
				( member ( pinPairRef "@baseboard_fab2_lib.baseboard_fab2(sch_1):\PP2942\") )
				( member ( pinPairRef "@baseboard_fab2_lib.baseboard_fab2(sch_1):\PP2945\") )
				( objectStatus "MG_DQ_NEAR_DIMM_NG_M_G_BYTE0" )
			)
			( matchGroup "@baseboard_fab2_lib.baseboard_fab2(sch_1):\MG_DQ-DQS_FAR_DIMM_NG_M_G_BYTE2\"
				( memberType ( signal ) )
				( member ( pinPairRef "@baseboard_fab2_lib.baseboard_fab2(sch_1):\PP2875\") )
				( member ( pinPairRef "@baseboard_fab2_lib.baseboard_fab2(sch_1):\PP2878\") )
				( member ( pinPairRef "@baseboard_fab2_lib.baseboard_fab2(sch_1):\PP2881\") )
				( member ( pinPairRef "@baseboard_fab2_lib.baseboard_fab2(sch_1):\PP2884\") )
				( member ( pinPairRef "@baseboard_fab2_lib.baseboard_fab2(sch_1):\PP2887\") )
				( member ( pinPairRef "@baseboard_fab2_lib.baseboard_fab2(sch_1):\PP2890\") )
				( member ( pinPairRef "@baseboard_fab2_lib.baseboard_fab2(sch_1):\PP2893\") )
				( member ( pinPairRef "@baseboard_fab2_lib.baseboard_fab2(sch_1):\PP2896\") )
				( member ( pinPairRef "@baseboard_fab2_lib.baseboard_fab2(sch_1):\PP949\") )
				( member ( pinPairRef "@baseboard_fab2_lib.baseboard_fab2(sch_1):\PP952\") )
				( member ( pinPairRef "@baseboard_fab2_lib.baseboard_fab2(sch_1):\PP943\") )
				( member ( pinPairRef "@baseboard_fab2_lib.baseboard_fab2(sch_1):\PP946\") )
				( objectStatus "MG_DQ-DQS_FAR_DIMM_NG_M_G_BYTE2" )
			)
			( matchGroup "@baseboard_fab2_lib.baseboard_fab2(sch_1):\MG_DQ_FAR_DIMM_NG_M_G_BYTE2\"
				( memberType ( signal ) )
				( member ( pinPairRef "@baseboard_fab2_lib.baseboard_fab2(sch_1):\PP2875\") )
				( member ( pinPairRef "@baseboard_fab2_lib.baseboard_fab2(sch_1):\PP2878\") )
				( member ( pinPairRef "@baseboard_fab2_lib.baseboard_fab2(sch_1):\PP2881\") )
				( member ( pinPairRef "@baseboard_fab2_lib.baseboard_fab2(sch_1):\PP2884\") )
				( member ( pinPairRef "@baseboard_fab2_lib.baseboard_fab2(sch_1):\PP2887\") )
				( member ( pinPairRef "@baseboard_fab2_lib.baseboard_fab2(sch_1):\PP2890\") )
				( member ( pinPairRef "@baseboard_fab2_lib.baseboard_fab2(sch_1):\PP2893\") )
				( member ( pinPairRef "@baseboard_fab2_lib.baseboard_fab2(sch_1):\PP2896\") )
				( objectStatus "MG_DQ_FAR_DIMM_NG_M_G_BYTE2" )
			)
			( matchGroup "@baseboard_fab2_lib.baseboard_fab2(sch_1):\MG_DQ-DQS_NEAR_DIMM_NG_M_G_BYTE2\"
				( memberType ( signal ) )
				( member ( pinPairRef "@baseboard_fab2_lib.baseboard_fab2(sch_1):\PP2876\") )
				( member ( pinPairRef "@baseboard_fab2_lib.baseboard_fab2(sch_1):\PP2879\") )
				( member ( pinPairRef "@baseboard_fab2_lib.baseboard_fab2(sch_1):\PP2882\") )
				( member ( pinPairRef "@baseboard_fab2_lib.baseboard_fab2(sch_1):\PP2885\") )
				( member ( pinPairRef "@baseboard_fab2_lib.baseboard_fab2(sch_1):\PP2888\") )
				( member ( pinPairRef "@baseboard_fab2_lib.baseboard_fab2(sch_1):\PP2891\") )
				( member ( pinPairRef "@baseboard_fab2_lib.baseboard_fab2(sch_1):\PP2894\") )
				( member ( pinPairRef "@baseboard_fab2_lib.baseboard_fab2(sch_1):\PP2897\") )
				( member ( pinPairRef "@baseboard_fab2_lib.baseboard_fab2(sch_1):\PP950\") )
				( member ( pinPairRef "@baseboard_fab2_lib.baseboard_fab2(sch_1):\PP953\") )
				( member ( pinPairRef "@baseboard_fab2_lib.baseboard_fab2(sch_1):\PP944\") )
				( member ( pinPairRef "@baseboard_fab2_lib.baseboard_fab2(sch_1):\PP947\") )
				( objectStatus "MG_DQ-DQS_NEAR_DIMM_NG_M_G_BYTE2" )
			)
			( matchGroup "@baseboard_fab2_lib.baseboard_fab2(sch_1):\MG_DQ_NEAR_DIMM_NG_M_G_BYTE2\"
				( memberType ( signal ) )
				( member ( pinPairRef "@baseboard_fab2_lib.baseboard_fab2(sch_1):\PP2876\") )
				( member ( pinPairRef "@baseboard_fab2_lib.baseboard_fab2(sch_1):\PP2879\") )
				( member ( pinPairRef "@baseboard_fab2_lib.baseboard_fab2(sch_1):\PP2882\") )
				( member ( pinPairRef "@baseboard_fab2_lib.baseboard_fab2(sch_1):\PP2885\") )
				( member ( pinPairRef "@baseboard_fab2_lib.baseboard_fab2(sch_1):\PP2888\") )
				( member ( pinPairRef "@baseboard_fab2_lib.baseboard_fab2(sch_1):\PP2891\") )
				( member ( pinPairRef "@baseboard_fab2_lib.baseboard_fab2(sch_1):\PP2894\") )
				( member ( pinPairRef "@baseboard_fab2_lib.baseboard_fab2(sch_1):\PP2897\") )
				( objectStatus "MG_DQ_NEAR_DIMM_NG_M_G_BYTE2" )
			)
			( matchGroup "@baseboard_fab2_lib.baseboard_fab2(sch_1):\MG_DQ-DQS_FAR_DIMM_NG_M_G_BYTE3\"
				( memberType ( signal ) )
				( member ( pinPairRef "@baseboard_fab2_lib.baseboard_fab2(sch_1):\PP2851\") )
				( member ( pinPairRef "@baseboard_fab2_lib.baseboard_fab2(sch_1):\PP2854\") )
				( member ( pinPairRef "@baseboard_fab2_lib.baseboard_fab2(sch_1):\PP2857\") )
				( member ( pinPairRef "@baseboard_fab2_lib.baseboard_fab2(sch_1):\PP2860\") )
				( member ( pinPairRef "@baseboard_fab2_lib.baseboard_fab2(sch_1):\PP2863\") )
				( member ( pinPairRef "@baseboard_fab2_lib.baseboard_fab2(sch_1):\PP2866\") )
				( member ( pinPairRef "@baseboard_fab2_lib.baseboard_fab2(sch_1):\PP2869\") )
				( member ( pinPairRef "@baseboard_fab2_lib.baseboard_fab2(sch_1):\PP2872\") )
				( member ( pinPairRef "@baseboard_fab2_lib.baseboard_fab2(sch_1):\PP937\") )
				( member ( pinPairRef "@baseboard_fab2_lib.baseboard_fab2(sch_1):\PP940\") )
				( member ( pinPairRef "@baseboard_fab2_lib.baseboard_fab2(sch_1):\PP931\") )
				( member ( pinPairRef "@baseboard_fab2_lib.baseboard_fab2(sch_1):\PP934\") )
				( objectStatus "MG_DQ-DQS_FAR_DIMM_NG_M_G_BYTE3" )
			)
			( matchGroup "@baseboard_fab2_lib.baseboard_fab2(sch_1):\MG_DQ_FAR_DIMM_NG_M_G_BYTE3\"
				( memberType ( signal ) )
				( member ( pinPairRef "@baseboard_fab2_lib.baseboard_fab2(sch_1):\PP2851\") )
				( member ( pinPairRef "@baseboard_fab2_lib.baseboard_fab2(sch_1):\PP2854\") )
				( member ( pinPairRef "@baseboard_fab2_lib.baseboard_fab2(sch_1):\PP2857\") )
				( member ( pinPairRef "@baseboard_fab2_lib.baseboard_fab2(sch_1):\PP2860\") )
				( member ( pinPairRef "@baseboard_fab2_lib.baseboard_fab2(sch_1):\PP2863\") )
				( member ( pinPairRef "@baseboard_fab2_lib.baseboard_fab2(sch_1):\PP2866\") )
				( member ( pinPairRef "@baseboard_fab2_lib.baseboard_fab2(sch_1):\PP2869\") )
				( member ( pinPairRef "@baseboard_fab2_lib.baseboard_fab2(sch_1):\PP2872\") )
				( objectStatus "MG_DQ_FAR_DIMM_NG_M_G_BYTE3" )
			)
			( matchGroup "@baseboard_fab2_lib.baseboard_fab2(sch_1):\MG_DQ-DQS_NEAR_DIMM_NG_M_G_BYTE3\"
				( memberType ( signal ) )
				( member ( pinPairRef "@baseboard_fab2_lib.baseboard_fab2(sch_1):\PP2852\") )
				( member ( pinPairRef "@baseboard_fab2_lib.baseboard_fab2(sch_1):\PP2855\") )
				( member ( pinPairRef "@baseboard_fab2_lib.baseboard_fab2(sch_1):\PP2858\") )
				( member ( pinPairRef "@baseboard_fab2_lib.baseboard_fab2(sch_1):\PP2861\") )
				( member ( pinPairRef "@baseboard_fab2_lib.baseboard_fab2(sch_1):\PP2864\") )
				( member ( pinPairRef "@baseboard_fab2_lib.baseboard_fab2(sch_1):\PP2867\") )
				( member ( pinPairRef "@baseboard_fab2_lib.baseboard_fab2(sch_1):\PP2870\") )
				( member ( pinPairRef "@baseboard_fab2_lib.baseboard_fab2(sch_1):\PP2873\") )
				( member ( pinPairRef "@baseboard_fab2_lib.baseboard_fab2(sch_1):\PP938\") )
				( member ( pinPairRef "@baseboard_fab2_lib.baseboard_fab2(sch_1):\PP941\") )
				( member ( pinPairRef "@baseboard_fab2_lib.baseboard_fab2(sch_1):\PP932\") )
				( member ( pinPairRef "@baseboard_fab2_lib.baseboard_fab2(sch_1):\PP935\") )
				( objectStatus "MG_DQ-DQS_NEAR_DIMM_NG_M_G_BYTE3" )
			)
			( matchGroup "@baseboard_fab2_lib.baseboard_fab2(sch_1):\MG_DQ_NEAR_DIMM_NG_M_G_BYTE3\"
				( memberType ( signal ) )
				( member ( pinPairRef "@baseboard_fab2_lib.baseboard_fab2(sch_1):\PP2852\") )
				( member ( pinPairRef "@baseboard_fab2_lib.baseboard_fab2(sch_1):\PP2855\") )
				( member ( pinPairRef "@baseboard_fab2_lib.baseboard_fab2(sch_1):\PP2858\") )
				( member ( pinPairRef "@baseboard_fab2_lib.baseboard_fab2(sch_1):\PP2861\") )
				( member ( pinPairRef "@baseboard_fab2_lib.baseboard_fab2(sch_1):\PP2864\") )
				( member ( pinPairRef "@baseboard_fab2_lib.baseboard_fab2(sch_1):\PP2867\") )
				( member ( pinPairRef "@baseboard_fab2_lib.baseboard_fab2(sch_1):\PP2870\") )
				( member ( pinPairRef "@baseboard_fab2_lib.baseboard_fab2(sch_1):\PP2873\") )
				( objectStatus "MG_DQ_NEAR_DIMM_NG_M_G_BYTE3" )
			)
			( matchGroup "@baseboard_fab2_lib.baseboard_fab2(sch_1):\MG_DQ-DQS_FAR_DIMM_NG_M_G_BYTE4\"
				( memberType ( signal ) )
				( member ( pinPairRef "@baseboard_fab2_lib.baseboard_fab2(sch_1):\PP2827\") )
				( member ( pinPairRef "@baseboard_fab2_lib.baseboard_fab2(sch_1):\PP2830\") )
				( member ( pinPairRef "@baseboard_fab2_lib.baseboard_fab2(sch_1):\PP2833\") )
				( member ( pinPairRef "@baseboard_fab2_lib.baseboard_fab2(sch_1):\PP2836\") )
				( member ( pinPairRef "@baseboard_fab2_lib.baseboard_fab2(sch_1):\PP2839\") )
				( member ( pinPairRef "@baseboard_fab2_lib.baseboard_fab2(sch_1):\PP2842\") )
				( member ( pinPairRef "@baseboard_fab2_lib.baseboard_fab2(sch_1):\PP2845\") )
				( member ( pinPairRef "@baseboard_fab2_lib.baseboard_fab2(sch_1):\PP2848\") )
				( member ( pinPairRef "@baseboard_fab2_lib.baseboard_fab2(sch_1):\PP925\") )
				( member ( pinPairRef "@baseboard_fab2_lib.baseboard_fab2(sch_1):\PP928\") )
				( member ( pinPairRef "@baseboard_fab2_lib.baseboard_fab2(sch_1):\PP919\") )
				( member ( pinPairRef "@baseboard_fab2_lib.baseboard_fab2(sch_1):\PP922\") )
				( objectStatus "MG_DQ-DQS_FAR_DIMM_NG_M_G_BYTE4" )
			)
			( matchGroup "@baseboard_fab2_lib.baseboard_fab2(sch_1):\MG_DQ_FAR_DIMM_NG_M_G_BYTE4\"
				( memberType ( signal ) )
				( member ( pinPairRef "@baseboard_fab2_lib.baseboard_fab2(sch_1):\PP2827\") )
				( member ( pinPairRef "@baseboard_fab2_lib.baseboard_fab2(sch_1):\PP2830\") )
				( member ( pinPairRef "@baseboard_fab2_lib.baseboard_fab2(sch_1):\PP2833\") )
				( member ( pinPairRef "@baseboard_fab2_lib.baseboard_fab2(sch_1):\PP2836\") )
				( member ( pinPairRef "@baseboard_fab2_lib.baseboard_fab2(sch_1):\PP2839\") )
				( member ( pinPairRef "@baseboard_fab2_lib.baseboard_fab2(sch_1):\PP2842\") )
				( member ( pinPairRef "@baseboard_fab2_lib.baseboard_fab2(sch_1):\PP2845\") )
				( member ( pinPairRef "@baseboard_fab2_lib.baseboard_fab2(sch_1):\PP2848\") )
				( objectStatus "MG_DQ_FAR_DIMM_NG_M_G_BYTE4" )
			)
			( matchGroup "@baseboard_fab2_lib.baseboard_fab2(sch_1):\MG_DQ-DQS_NEAR_DIMM_NG_M_G_BYTE4\"
				( memberType ( signal ) )
				( member ( pinPairRef "@baseboard_fab2_lib.baseboard_fab2(sch_1):\PP2829\") )
				( member ( pinPairRef "@baseboard_fab2_lib.baseboard_fab2(sch_1):\PP2832\") )
				( member ( pinPairRef "@baseboard_fab2_lib.baseboard_fab2(sch_1):\PP2835\") )
				( member ( pinPairRef "@baseboard_fab2_lib.baseboard_fab2(sch_1):\PP2838\") )
				( member ( pinPairRef "@baseboard_fab2_lib.baseboard_fab2(sch_1):\PP2841\") )
				( member ( pinPairRef "@baseboard_fab2_lib.baseboard_fab2(sch_1):\PP2844\") )
				( member ( pinPairRef "@baseboard_fab2_lib.baseboard_fab2(sch_1):\PP2847\") )
				( member ( pinPairRef "@baseboard_fab2_lib.baseboard_fab2(sch_1):\PP2850\") )
				( member ( pinPairRef "@baseboard_fab2_lib.baseboard_fab2(sch_1):\PP927\") )
				( member ( pinPairRef "@baseboard_fab2_lib.baseboard_fab2(sch_1):\PP930\") )
				( member ( pinPairRef "@baseboard_fab2_lib.baseboard_fab2(sch_1):\PP921\") )
				( member ( pinPairRef "@baseboard_fab2_lib.baseboard_fab2(sch_1):\PP924\") )
				( objectStatus "MG_DQ-DQS_NEAR_DIMM_NG_M_G_BYTE4" )
			)
			( matchGroup "@baseboard_fab2_lib.baseboard_fab2(sch_1):\MG_DQ_NEAR_DIMM_NG_M_G_BYTE4\"
				( memberType ( signal ) )
				( member ( pinPairRef "@baseboard_fab2_lib.baseboard_fab2(sch_1):\PP2829\") )
				( member ( pinPairRef "@baseboard_fab2_lib.baseboard_fab2(sch_1):\PP2832\") )
				( member ( pinPairRef "@baseboard_fab2_lib.baseboard_fab2(sch_1):\PP2835\") )
				( member ( pinPairRef "@baseboard_fab2_lib.baseboard_fab2(sch_1):\PP2838\") )
				( member ( pinPairRef "@baseboard_fab2_lib.baseboard_fab2(sch_1):\PP2841\") )
				( member ( pinPairRef "@baseboard_fab2_lib.baseboard_fab2(sch_1):\PP2844\") )
				( member ( pinPairRef "@baseboard_fab2_lib.baseboard_fab2(sch_1):\PP2847\") )
				( member ( pinPairRef "@baseboard_fab2_lib.baseboard_fab2(sch_1):\PP2850\") )
				( objectStatus "MG_DQ_NEAR_DIMM_NG_M_G_BYTE4" )
			)
			( matchGroup "@baseboard_fab2_lib.baseboard_fab2(sch_1):\MG_DQ-DQS_FAR_DIMM_NG_M_A_BYTE0\"
				( memberType ( signal ) )
				( member ( pinPairRef "@baseboard_fab2_lib.baseboard_fab2(sch_1):\PP5343\") )
				( member ( pinPairRef "@baseboard_fab2_lib.baseboard_fab2(sch_1):\PP5346\") )
				( member ( pinPairRef "@baseboard_fab2_lib.baseboard_fab2(sch_1):\PP5349\") )
				( member ( pinPairRef "@baseboard_fab2_lib.baseboard_fab2(sch_1):\PP5352\") )
				( member ( pinPairRef "@baseboard_fab2_lib.baseboard_fab2(sch_1):\PP5355\") )
				( member ( pinPairRef "@baseboard_fab2_lib.baseboard_fab2(sch_1):\PP5358\") )
				( member ( pinPairRef "@baseboard_fab2_lib.baseboard_fab2(sch_1):\PP5361\") )
				( member ( pinPairRef "@baseboard_fab2_lib.baseboard_fab2(sch_1):\PP5364\") )
				( member ( pinPairRef "@baseboard_fab2_lib.baseboard_fab2(sch_1):\PP469\") )
				( member ( pinPairRef "@baseboard_fab2_lib.baseboard_fab2(sch_1):\PP463\") )
				( member ( pinPairRef "@baseboard_fab2_lib.baseboard_fab2(sch_1):\PP472\") )
				( member ( pinPairRef "@baseboard_fab2_lib.baseboard_fab2(sch_1):\PP466\") )
				( objectStatus "MG_DQ-DQS_FAR_DIMM_NG_M_A_BYTE0" )
			)
			( matchGroup "@baseboard_fab2_lib.baseboard_fab2(sch_1):\MG_DQ_FAR_DIMM_NG_M_A_BYTE0\"
				( memberType ( signal ) )
				( member ( pinPairRef "@baseboard_fab2_lib.baseboard_fab2(sch_1):\PP5343\") )
				( member ( pinPairRef "@baseboard_fab2_lib.baseboard_fab2(sch_1):\PP5346\") )
				( member ( pinPairRef "@baseboard_fab2_lib.baseboard_fab2(sch_1):\PP5349\") )
				( member ( pinPairRef "@baseboard_fab2_lib.baseboard_fab2(sch_1):\PP5352\") )
				( member ( pinPairRef "@baseboard_fab2_lib.baseboard_fab2(sch_1):\PP5355\") )
				( member ( pinPairRef "@baseboard_fab2_lib.baseboard_fab2(sch_1):\PP5358\") )
				( member ( pinPairRef "@baseboard_fab2_lib.baseboard_fab2(sch_1):\PP5361\") )
				( member ( pinPairRef "@baseboard_fab2_lib.baseboard_fab2(sch_1):\PP5364\") )
				( objectStatus "MG_DQ_FAR_DIMM_NG_M_A_BYTE0" )
			)
			( matchGroup "@baseboard_fab2_lib.baseboard_fab2(sch_1):\MG_DQ-DQS_NEAR_DIMM_NG_M_A_BYTE0\"
				( memberType ( signal ) )
				( member ( pinPairRef "@baseboard_fab2_lib.baseboard_fab2(sch_1):\PP5345\") )
				( member ( pinPairRef "@baseboard_fab2_lib.baseboard_fab2(sch_1):\PP5348\") )
				( member ( pinPairRef "@baseboard_fab2_lib.baseboard_fab2(sch_1):\PP5351\") )
				( member ( pinPairRef "@baseboard_fab2_lib.baseboard_fab2(sch_1):\PP5354\") )
				( member ( pinPairRef "@baseboard_fab2_lib.baseboard_fab2(sch_1):\PP5357\") )
				( member ( pinPairRef "@baseboard_fab2_lib.baseboard_fab2(sch_1):\PP5360\") )
				( member ( pinPairRef "@baseboard_fab2_lib.baseboard_fab2(sch_1):\PP5363\") )
				( member ( pinPairRef "@baseboard_fab2_lib.baseboard_fab2(sch_1):\PP5366\") )
				( member ( pinPairRef "@baseboard_fab2_lib.baseboard_fab2(sch_1):\PP471\") )
				( member ( pinPairRef "@baseboard_fab2_lib.baseboard_fab2(sch_1):\PP465\") )
				( member ( pinPairRef "@baseboard_fab2_lib.baseboard_fab2(sch_1):\PP474\") )
				( member ( pinPairRef "@baseboard_fab2_lib.baseboard_fab2(sch_1):\PP468\") )
				( objectStatus "MG_DQ-DQS_NEAR_DIMM_NG_M_A_BYTE0" )
			)
			( matchGroup "@baseboard_fab2_lib.baseboard_fab2(sch_1):\MG_DQ_NEAR_DIMM_NG_M_A_BYTE0\"
				( memberType ( signal ) )
				( member ( pinPairRef "@baseboard_fab2_lib.baseboard_fab2(sch_1):\PP5345\") )
				( member ( pinPairRef "@baseboard_fab2_lib.baseboard_fab2(sch_1):\PP5348\") )
				( member ( pinPairRef "@baseboard_fab2_lib.baseboard_fab2(sch_1):\PP5351\") )
				( member ( pinPairRef "@baseboard_fab2_lib.baseboard_fab2(sch_1):\PP5354\") )
				( member ( pinPairRef "@baseboard_fab2_lib.baseboard_fab2(sch_1):\PP5357\") )
				( member ( pinPairRef "@baseboard_fab2_lib.baseboard_fab2(sch_1):\PP5360\") )
				( member ( pinPairRef "@baseboard_fab2_lib.baseboard_fab2(sch_1):\PP5363\") )
				( member ( pinPairRef "@baseboard_fab2_lib.baseboard_fab2(sch_1):\PP5366\") )
				( objectStatus "MG_DQ_NEAR_DIMM_NG_M_A_BYTE0" )
			)
			( matchGroup "@baseboard_fab2_lib.baseboard_fab2(sch_1):\MG_P3E_CPU0_PE3_OCP_RX0001\"
				( memberType ( signal ) )
				( member ( pinPairRef "@baseboard_fab2_lib.baseboard_fab2(sch_1):\PP3073\") )
				( member ( pinPairRef "@baseboard_fab2_lib.baseboard_fab2(sch_1):\PP3071\") )
				( member ( pinPairRef "@baseboard_fab2_lib.baseboard_fab2(sch_1):\PP3074\") )
				( member ( pinPairRef "@baseboard_fab2_lib.baseboard_fab2(sch_1):\PP3072\") )
				( objectStatus "MG_P3E_CPU0_PE3_OCP_RX0001" )
			)
			( matchGroup "@baseboard_fab2_lib.baseboard_fab2(sch_1):\MG_P3E_CPU0_PE3_OCP_RX0203\"
				( memberType ( signal ) )
				( member ( pinPairRef "@baseboard_fab2_lib.baseboard_fab2(sch_1):\PP3069\") )
				( member ( pinPairRef "@baseboard_fab2_lib.baseboard_fab2(sch_1):\PP3067\") )
				( member ( pinPairRef "@baseboard_fab2_lib.baseboard_fab2(sch_1):\PP3070\") )
				( member ( pinPairRef "@baseboard_fab2_lib.baseboard_fab2(sch_1):\PP3068\") )
				( objectStatus "MG_P3E_CPU0_PE3_OCP_RX0203" )
			)
			( matchGroup "@baseboard_fab2_lib.baseboard_fab2(sch_1):\MG_P3E_CPU0_PE3_OCP_RX0607\"
				( memberType ( signal ) )
				( member ( pinPairRef "@baseboard_fab2_lib.baseboard_fab2(sch_1):\PP3061\") )
				( member ( pinPairRef "@baseboard_fab2_lib.baseboard_fab2(sch_1):\PP3059\") )
				( member ( pinPairRef "@baseboard_fab2_lib.baseboard_fab2(sch_1):\PP3062\") )
				( member ( pinPairRef "@baseboard_fab2_lib.baseboard_fab2(sch_1):\PP3060\") )
				( objectStatus "MG_P3E_CPU0_PE3_OCP_RX0607" )
			)
			( matchGroup "@baseboard_fab2_lib.baseboard_fab2(sch_1):\MG_P3E_CPU0_PE3_OCP_RX0809\"
				( memberType ( signal ) )
				( member ( pinPairRef "@baseboard_fab2_lib.baseboard_fab2(sch_1):\PP3057\") )
				( member ( pinPairRef "@baseboard_fab2_lib.baseboard_fab2(sch_1):\PP3055\") )
				( member ( pinPairRef "@baseboard_fab2_lib.baseboard_fab2(sch_1):\PP3058\") )
				( member ( pinPairRef "@baseboard_fab2_lib.baseboard_fab2(sch_1):\PP3056\") )
				( objectStatus "MG_P3E_CPU0_PE3_OCP_RX0809" )
			)
			( matchGroup "@baseboard_fab2_lib.baseboard_fab2(sch_1):\MG_P3E_CPU0_PE3_OCP_RX1011\"
				( memberType ( signal ) )
				( member ( pinPairRef "@baseboard_fab2_lib.baseboard_fab2(sch_1):\PP3053\") )
				( member ( pinPairRef "@baseboard_fab2_lib.baseboard_fab2(sch_1):\PP3051\") )
				( member ( pinPairRef "@baseboard_fab2_lib.baseboard_fab2(sch_1):\PP3054\") )
				( member ( pinPairRef "@baseboard_fab2_lib.baseboard_fab2(sch_1):\PP3052\") )
				( objectStatus "MG_P3E_CPU0_PE3_OCP_RX1011" )
			)
			( matchGroup "@baseboard_fab2_lib.baseboard_fab2(sch_1):\MG_P3E_CPU0_PE3_OCP_RX1213\"
				( memberType ( signal ) )
				( member ( pinPairRef "@baseboard_fab2_lib.baseboard_fab2(sch_1):\PP3049\") )
				( member ( pinPairRef "@baseboard_fab2_lib.baseboard_fab2(sch_1):\PP3047\") )
				( member ( pinPairRef "@baseboard_fab2_lib.baseboard_fab2(sch_1):\PP3050\") )
				( member ( pinPairRef "@baseboard_fab2_lib.baseboard_fab2(sch_1):\PP3048\") )
				( objectStatus "MG_P3E_CPU0_PE3_OCP_RX1213" )
			)
			( matchGroup "@baseboard_fab2_lib.baseboard_fab2(sch_1):\MG_P3E_CPU0_PE3_OCP_RX1415\"
				( memberType ( signal ) )
				( member ( pinPairRef "@baseboard_fab2_lib.baseboard_fab2(sch_1):\PP3045\") )
				( member ( pinPairRef "@baseboard_fab2_lib.baseboard_fab2(sch_1):\PP3043\") )
				( member ( pinPairRef "@baseboard_fab2_lib.baseboard_fab2(sch_1):\PP3046\") )
				( member ( pinPairRef "@baseboard_fab2_lib.baseboard_fab2(sch_1):\PP3044\") )
				( objectStatus "MG_P3E_CPU0_PE3_OCP_RX1415" )
			)
			( matchGroup "@baseboard_fab2_lib.baseboard_fab2(sch_1):\MG_P3E_CPU1_PE3_MP_TX1011\"
				( memberType ( signal ) )
				( member ( pinPairRef "@baseboard_fab2_lib.baseboard_fab2(sch_1):\PP5832\") )
				( member ( pinPairRef "@baseboard_fab2_lib.baseboard_fab2(sch_1):\PP5828\") )
				( member ( pinPairRef "@baseboard_fab2_lib.baseboard_fab2(sch_1):\PP5974\") )
				( member ( pinPairRef "@baseboard_fab2_lib.baseboard_fab2(sch_1):\PP5972\") )
				( objectStatus "MG_P3E_CPU1_PE3_MP_TX1011" )
			)
			( matchGroup "@baseboard_fab2_lib.baseboard_fab2(sch_1):\MG_P3E_CPU0_PE3_OCP_RX0405\"
				( memberType ( signal ) )
				( member ( pinPairRef "@baseboard_fab2_lib.baseboard_fab2(sch_1):\PP3063\") )
				( member ( pinPairRef "@baseboard_fab2_lib.baseboard_fab2(sch_1):\PP3065\") )
				( member ( pinPairRef "@baseboard_fab2_lib.baseboard_fab2(sch_1):\PP3064\") )
				( member ( pinPairRef "@baseboard_fab2_lib.baseboard_fab2(sch_1):\PP3066\") )
				( objectStatus "MG_P3E_CPU0_PE3_OCP_RX0405" )
			)
			( matchGroup "@baseboard_fab2_lib.baseboard_fab2(sch_1):\MG_P3E_CPU0_PE1_PCH_PCIEUP_RX1011\"
				( memberType ( signal ) )
				( member ( pinPairRef "@baseboard_fab2_lib.baseboard_fab2(sch_1):\PP5838\") )
				( member ( pinPairRef "@baseboard_fab2_lib.baseboard_fab2(sch_1):\PP5839\") )
				( member ( pinPairRef "@baseboard_fab2_lib.baseboard_fab2(sch_1):\PP5840\") )
				( member ( pinPairRef "@baseboard_fab2_lib.baseboard_fab2(sch_1):\PP5833\") )
				( objectStatus "MG_P3E_CPU0_PE1_PCH_PCIEUP_RX1011" )
			)
			( matchGroup "@baseboard_fab2_lib.baseboard_fab2(sch_1):\MG_P3E_CPU0_PE1_PCH_PCIEUP_RX1213\"
				( memberType ( signal ) )
				( member ( pinPairRef "@baseboard_fab2_lib.baseboard_fab2(sch_1):\PP5834\") )
				( member ( pinPairRef "@baseboard_fab2_lib.baseboard_fab2(sch_1):\PP5844\") )
				( member ( pinPairRef "@baseboard_fab2_lib.baseboard_fab2(sch_1):\PP5843\") )
				( member ( pinPairRef "@baseboard_fab2_lib.baseboard_fab2(sch_1):\PP5845\") )
				( objectStatus "MG_P3E_CPU0_PE1_PCH_PCIEUP_RX1213" )
			)
			( matchGroup "@baseboard_fab2_lib.baseboard_fab2(sch_1):\MG_P3E_CPU0_PE1_PCH_PCIEUP_RX1415\"
				( memberType ( signal ) )
				( member ( pinPairRef "@baseboard_fab2_lib.baseboard_fab2(sch_1):\PP5846\") )
				( member ( pinPairRef "@baseboard_fab2_lib.baseboard_fab2(sch_1):\PP5847\") )
				( member ( pinPairRef "@baseboard_fab2_lib.baseboard_fab2(sch_1):\PP5848\") )
				( member ( pinPairRef "@baseboard_fab2_lib.baseboard_fab2(sch_1):\PP5841\") )
				( objectStatus "MG_P3E_CPU0_PE1_PCH_PCIEUP_RX1415" )
			)
			( matchGroup "@baseboard_fab2_lib.baseboard_fab2(sch_1):\MG_P3E_CPU1_PE3_MP_TX0809\"
				( memberType ( signal ) )
				( member ( pinPairRef "@baseboard_fab2_lib.baseboard_fab2(sch_1):\PP5830\") )
				( member ( pinPairRef "@baseboard_fab2_lib.baseboard_fab2(sch_1):\PP5831\") )
				( member ( pinPairRef "@baseboard_fab2_lib.baseboard_fab2(sch_1):\PP5983\") )
				( member ( pinPairRef "@baseboard_fab2_lib.baseboard_fab2(sch_1):\PP5982\") )
				( objectStatus "MG_P3E_CPU1_PE3_MP_TX0809" )
			)
			( matchGroup "@baseboard_fab2_lib.baseboard_fab2(sch_1):\MG_PCIE_L2\"
				( memberType ( signal ) )
				( member ( pinPairRef "@baseboard_fab2_lib.baseboard_fab2(sch_1):\PP5994\") )
				( member ( pinPairRef "@baseboard_fab2_lib.baseboard_fab2(sch_1):\PP5991\") )
				( member ( pinPairRef "@baseboard_fab2_lib.baseboard_fab2(sch_1):\PP5877\") )
				( member ( pinPairRef "@baseboard_fab2_lib.baseboard_fab2(sch_1):\PP5864\") )
				( member ( pinPairRef "@baseboard_fab2_lib.baseboard_fab2(sch_1):\PP5880\") )
				( member ( pinPairRef "@baseboard_fab2_lib.baseboard_fab2(sch_1):\PP5874\") )
				( member ( pinPairRef "@baseboard_fab2_lib.baseboard_fab2(sch_1):\PP5886\") )
				( member ( pinPairRef "@baseboard_fab2_lib.baseboard_fab2(sch_1):\PP5883\") )
				( member ( pinPairRef "@baseboard_fab2_lib.baseboard_fab2(sch_1):\PP5868\") )
				( member ( pinPairRef "@baseboard_fab2_lib.baseboard_fab2(sch_1):\PP5889\") )
				( member ( pinPairRef "@baseboard_fab2_lib.baseboard_fab2(sch_1):\PP5822\") )
				( member ( pinPairRef "@baseboard_fab2_lib.baseboard_fab2(sch_1):\PP5871\") )
				( member ( pinPairRef "@baseboard_fab2_lib.baseboard_fab2(sch_1):\PP5897\") )
				( member ( pinPairRef "@baseboard_fab2_lib.baseboard_fab2(sch_1):\PP5816\") )
				( member ( pinPairRef "@baseboard_fab2_lib.baseboard_fab2(sch_1):\PP5901\") )
				( member ( pinPairRef "@baseboard_fab2_lib.baseboard_fab2(sch_1):\PP5894\") )
				( member ( pinPairRef "@baseboard_fab2_lib.baseboard_fab2(sch_1):\PP5907\") )
				( member ( pinPairRef "@baseboard_fab2_lib.baseboard_fab2(sch_1):\PP5904\") )
				( member ( pinPairRef "@baseboard_fab2_lib.baseboard_fab2(sch_1):\PP6023\") )
				( member ( pinPairRef "@baseboard_fab2_lib.baseboard_fab2(sch_1):\PP6029\") )
				( member ( pinPairRef "@baseboard_fab2_lib.baseboard_fab2(sch_1):\PP6026\") )
				( member ( pinPairRef "@baseboard_fab2_lib.baseboard_fab2(sch_1):\PP6020\") )
				( member ( pinPairRef "@baseboard_fab2_lib.baseboard_fab2(sch_1):\PP6017\") )
				( member ( pinPairRef "@baseboard_fab2_lib.baseboard_fab2(sch_1):\PP6014\") )
				( member ( pinPairRef "@baseboard_fab2_lib.baseboard_fab2(sch_1):\PP6011\") )
				( member ( pinPairRef "@baseboard_fab2_lib.baseboard_fab2(sch_1):\PP5934\") )
				( member ( pinPairRef "@baseboard_fab2_lib.baseboard_fab2(sch_1):\PP5921\") )
				( member ( pinPairRef "@baseboard_fab2_lib.baseboard_fab2(sch_1):\PP5984\") )
				( member ( pinPairRef "@baseboard_fab2_lib.baseboard_fab2(sch_1):\PP6000\") )
				( member ( pinPairRef "@baseboard_fab2_lib.baseboard_fab2(sch_1):\PP6006\") )
				( member ( pinPairRef "@baseboard_fab2_lib.baseboard_fab2(sch_1):\PP6003\") )
				( member ( pinPairRef "@baseboard_fab2_lib.baseboard_fab2(sch_1):\PP5997\") )
				( objectStatus "MG_PCIE_L2" )
			)
			( matchGroup "@baseboard_fab2_lib.baseboard_fab2(sch_1):\MG_PCIE_ALL1\"
				( memberType ( signal ) )
				( member ( pinPairRef "@baseboard_fab2_lib.baseboard_fab2(sch_1):\PP5995\") )
				( member ( pinPairRef "@baseboard_fab2_lib.baseboard_fab2(sch_1):\PP5992\") )
				( member ( pinPairRef "@baseboard_fab2_lib.baseboard_fab2(sch_1):\PP5878\") )
				( member ( pinPairRef "@baseboard_fab2_lib.baseboard_fab2(sch_1):\PP5865\") )
				( member ( pinPairRef "@baseboard_fab2_lib.baseboard_fab2(sch_1):\PP5881\") )
				( member ( pinPairRef "@baseboard_fab2_lib.baseboard_fab2(sch_1):\PP5875\") )
				( member ( pinPairRef "@baseboard_fab2_lib.baseboard_fab2(sch_1):\PP5887\") )
				( member ( pinPairRef "@baseboard_fab2_lib.baseboard_fab2(sch_1):\PP5884\") )
				( member ( pinPairRef "@baseboard_fab2_lib.baseboard_fab2(sch_1):\PP5869\") )
				( member ( pinPairRef "@baseboard_fab2_lib.baseboard_fab2(sch_1):\PP5890\") )
				( member ( pinPairRef "@baseboard_fab2_lib.baseboard_fab2(sch_1):\PP5823\") )
				( member ( pinPairRef "@baseboard_fab2_lib.baseboard_fab2(sch_1):\PP5872\") )
				( member ( pinPairRef "@baseboard_fab2_lib.baseboard_fab2(sch_1):\PP5898\") )
				( member ( pinPairRef "@baseboard_fab2_lib.baseboard_fab2(sch_1):\PP5817\") )
				( member ( pinPairRef "@baseboard_fab2_lib.baseboard_fab2(sch_1):\PP5902\") )
				( member ( pinPairRef "@baseboard_fab2_lib.baseboard_fab2(sch_1):\PP5895\") )
				( member ( pinPairRef "@baseboard_fab2_lib.baseboard_fab2(sch_1):\PP5908\") )
				( member ( pinPairRef "@baseboard_fab2_lib.baseboard_fab2(sch_1):\PP5905\") )
				( member ( pinPairRef "@baseboard_fab2_lib.baseboard_fab2(sch_1):\PP6024\") )
				( member ( pinPairRef "@baseboard_fab2_lib.baseboard_fab2(sch_1):\PP6030\") )
				( member ( pinPairRef "@baseboard_fab2_lib.baseboard_fab2(sch_1):\PP6027\") )
				( member ( pinPairRef "@baseboard_fab2_lib.baseboard_fab2(sch_1):\PP6021\") )
				( member ( pinPairRef "@baseboard_fab2_lib.baseboard_fab2(sch_1):\PP6018\") )
				( member ( pinPairRef "@baseboard_fab2_lib.baseboard_fab2(sch_1):\PP6015\") )
				( member ( pinPairRef "@baseboard_fab2_lib.baseboard_fab2(sch_1):\PP6012\") )
				( member ( pinPairRef "@baseboard_fab2_lib.baseboard_fab2(sch_1):\PP5935\") )
				( member ( pinPairRef "@baseboard_fab2_lib.baseboard_fab2(sch_1):\PP5922\") )
				( member ( pinPairRef "@baseboard_fab2_lib.baseboard_fab2(sch_1):\PP5985\") )
				( member ( pinPairRef "@baseboard_fab2_lib.baseboard_fab2(sch_1):\PP6001\") )
				( member ( pinPairRef "@baseboard_fab2_lib.baseboard_fab2(sch_1):\PP6007\") )
				( member ( pinPairRef "@baseboard_fab2_lib.baseboard_fab2(sch_1):\PP6004\") )
				( member ( pinPairRef "@baseboard_fab2_lib.baseboard_fab2(sch_1):\PP5998\") )
				( objectStatus "MG_PCIE_ALL1" )
			)
			( matchGroup "@baseboard_fab2_lib.baseboard_fab2(sch_1):\MG_PCIE_ALL0\"
				( memberType ( signal ) )
				( member ( pinPairRef "@baseboard_fab2_lib.baseboard_fab2(sch_1):\PP5996\") )
				( member ( pinPairRef "@baseboard_fab2_lib.baseboard_fab2(sch_1):\PP5993\") )
				( member ( pinPairRef "@baseboard_fab2_lib.baseboard_fab2(sch_1):\PP5879\") )
				( member ( pinPairRef "@baseboard_fab2_lib.baseboard_fab2(sch_1):\PP5866\") )
				( member ( pinPairRef "@baseboard_fab2_lib.baseboard_fab2(sch_1):\PP5882\") )
				( member ( pinPairRef "@baseboard_fab2_lib.baseboard_fab2(sch_1):\PP5876\") )
				( member ( pinPairRef "@baseboard_fab2_lib.baseboard_fab2(sch_1):\PP5888\") )
				( member ( pinPairRef "@baseboard_fab2_lib.baseboard_fab2(sch_1):\PP5885\") )
				( member ( pinPairRef "@baseboard_fab2_lib.baseboard_fab2(sch_1):\PP5870\") )
				( member ( pinPairRef "@baseboard_fab2_lib.baseboard_fab2(sch_1):\PP5891\") )
				( member ( pinPairRef "@baseboard_fab2_lib.baseboard_fab2(sch_1):\PP5824\") )
				( member ( pinPairRef "@baseboard_fab2_lib.baseboard_fab2(sch_1):\PP5873\") )
				( member ( pinPairRef "@baseboard_fab2_lib.baseboard_fab2(sch_1):\PP5899\") )
				( member ( pinPairRef "@baseboard_fab2_lib.baseboard_fab2(sch_1):\PP5818\") )
				( member ( pinPairRef "@baseboard_fab2_lib.baseboard_fab2(sch_1):\PP5903\") )
				( member ( pinPairRef "@baseboard_fab2_lib.baseboard_fab2(sch_1):\PP5896\") )
				( member ( pinPairRef "@baseboard_fab2_lib.baseboard_fab2(sch_1):\PP5909\") )
				( member ( pinPairRef "@baseboard_fab2_lib.baseboard_fab2(sch_1):\PP5906\") )
				( member ( pinPairRef "@baseboard_fab2_lib.baseboard_fab2(sch_1):\PP6025\") )
				( member ( pinPairRef "@baseboard_fab2_lib.baseboard_fab2(sch_1):\PP6031\") )
				( member ( pinPairRef "@baseboard_fab2_lib.baseboard_fab2(sch_1):\PP6028\") )
				( member ( pinPairRef "@baseboard_fab2_lib.baseboard_fab2(sch_1):\PP6022\") )
				( member ( pinPairRef "@baseboard_fab2_lib.baseboard_fab2(sch_1):\PP6019\") )
				( member ( pinPairRef "@baseboard_fab2_lib.baseboard_fab2(sch_1):\PP6016\") )
				( member ( pinPairRef "@baseboard_fab2_lib.baseboard_fab2(sch_1):\PP6013\") )
				( member ( pinPairRef "@baseboard_fab2_lib.baseboard_fab2(sch_1):\PP5936\") )
				( member ( pinPairRef "@baseboard_fab2_lib.baseboard_fab2(sch_1):\PP5923\") )
				( member ( pinPairRef "@baseboard_fab2_lib.baseboard_fab2(sch_1):\PP5986\") )
				( member ( pinPairRef "@baseboard_fab2_lib.baseboard_fab2(sch_1):\PP6002\") )
				( member ( pinPairRef "@baseboard_fab2_lib.baseboard_fab2(sch_1):\PP6008\") )
				( member ( pinPairRef "@baseboard_fab2_lib.baseboard_fab2(sch_1):\PP6005\") )
				( member ( pinPairRef "@baseboard_fab2_lib.baseboard_fab2(sch_1):\PP5999\") )
				( objectStatus "MG_PCIE_ALL0" )
			)
			( matchGroup "@baseboard_fab2_lib.baseboard_fab2(sch_1):\MG_P3E_CPU0_PE1_PCH_PCIEUP_TX0809\"
				( memberType ( signal ) )
				( member ( pinPairRef "@baseboard_fab2_lib.baseboard_fab2(sch_1):\PP5852\") )
				( member ( pinPairRef "@baseboard_fab2_lib.baseboard_fab2(sch_1):\PP5842\") )
				( member ( pinPairRef "@baseboard_fab2_lib.baseboard_fab2(sch_1):\PP5853\") )
				( member ( pinPairRef "@baseboard_fab2_lib.baseboard_fab2(sch_1):\PP5851\") )
				( objectStatus "MG_P3E_CPU0_PE1_PCH_PCIEUP_TX0809" )
			)
			( matchGroup "@baseboard_fab2_lib.baseboard_fab2(sch_1):\MG_P3E_CPU0_PE1_PCH_PCIEUP_TX1011\"
				( memberType ( signal ) )
				( member ( pinPairRef "@baseboard_fab2_lib.baseboard_fab2(sch_1):\PP5855\") )
				( member ( pinPairRef "@baseboard_fab2_lib.baseboard_fab2(sch_1):\PP5854\") )
				( member ( pinPairRef "@baseboard_fab2_lib.baseboard_fab2(sch_1):\PP5849\") )
				( member ( pinPairRef "@baseboard_fab2_lib.baseboard_fab2(sch_1):\PP5856\") )
				( objectStatus "MG_P3E_CPU0_PE1_PCH_PCIEUP_TX1011" )
			)
			( matchGroup "@baseboard_fab2_lib.baseboard_fab2(sch_1):\MG_P3E_CPU0_PE1_PCH_PCIEUP_TX1213\"
				( memberType ( signal ) )
				( member ( pinPairRef "@baseboard_fab2_lib.baseboard_fab2(sch_1):\PP5859\") )
				( member ( pinPairRef "@baseboard_fab2_lib.baseboard_fab2(sch_1):\PP5850\") )
				( member ( pinPairRef "@baseboard_fab2_lib.baseboard_fab2(sch_1):\PP5860\") )
				( member ( pinPairRef "@baseboard_fab2_lib.baseboard_fab2(sch_1):\PP5858\") )
				( objectStatus "MG_P3E_CPU0_PE1_PCH_PCIEUP_TX1213" )
			)
			( matchGroup "@baseboard_fab2_lib.baseboard_fab2(sch_1):\MG_P3E_CPU0_PE1_PCH_PCIEUP_TX1415\"
				( memberType ( signal ) )
				( member ( pinPairRef "@baseboard_fab2_lib.baseboard_fab2(sch_1):\PP5863\") )
				( member ( pinPairRef "@baseboard_fab2_lib.baseboard_fab2(sch_1):\PP5861\") )
				( member ( pinPairRef "@baseboard_fab2_lib.baseboard_fab2(sch_1):\PP5867\") )
				( member ( pinPairRef "@baseboard_fab2_lib.baseboard_fab2(sch_1):\PP5862\") )
				( objectStatus "MG_P3E_CPU0_PE1_PCH_PCIEUP_TX1415" )
			)
			( matchGroup "@baseboard_fab2_lib.baseboard_fab2(sch_1):\MG_P3E_CPU0_PE2_SS_TX0001\"
				( memberType ( signal ) )
				( member ( pinPairRef "@baseboard_fab2_lib.baseboard_fab2(sch_1):\PP5911\") )
				( member ( pinPairRef "@baseboard_fab2_lib.baseboard_fab2(sch_1):\PP5910\") )
				( member ( pinPairRef "@baseboard_fab2_lib.baseboard_fab2(sch_1):\PP5819\") )
				( member ( pinPairRef "@baseboard_fab2_lib.baseboard_fab2(sch_1):\PP5900\") )
				( objectStatus "MG_P3E_CPU0_PE2_SS_TX0001" )
			)
			( matchGroup "@baseboard_fab2_lib.baseboard_fab2(sch_1):\MG_P3E_CPU0_PE2_SS_TX0203\"
				( memberType ( signal ) )
				( member ( pinPairRef "@baseboard_fab2_lib.baseboard_fab2(sch_1):\PP5826\") )
				( member ( pinPairRef "@baseboard_fab2_lib.baseboard_fab2(sch_1):\PP5825\") )
				( member ( pinPairRef "@baseboard_fab2_lib.baseboard_fab2(sch_1):\PP5857\") )
				( member ( pinPairRef "@baseboard_fab2_lib.baseboard_fab2(sch_1):\PP5815\") )
				( objectStatus "MG_P3E_CPU0_PE2_SS_TX0203" )
			)
			( matchGroup "@baseboard_fab2_lib.baseboard_fab2(sch_1):\MG_P3E_CPU0_PE2_SS_TX0405\"
				( memberType ( signal ) )
				( member ( pinPairRef "@baseboard_fab2_lib.baseboard_fab2(sch_1):\PP5821\") )
				( member ( pinPairRef "@baseboard_fab2_lib.baseboard_fab2(sch_1):\PP5820\") )
				( member ( pinPairRef "@baseboard_fab2_lib.baseboard_fab2(sch_1):\PP5912\") )
				( member ( pinPairRef "@baseboard_fab2_lib.baseboard_fab2(sch_1):\PP5827\") )
				( objectStatus "MG_P3E_CPU0_PE2_SS_TX0405" )
			)
			( matchGroup "@baseboard_fab2_lib.baseboard_fab2(sch_1):\MG_P3E_CPU0_PE2_SS_TX0607\"
				( memberType ( signal ) )
				( member ( pinPairRef "@baseboard_fab2_lib.baseboard_fab2(sch_1):\PP5917\") )
				( member ( pinPairRef "@baseboard_fab2_lib.baseboard_fab2(sch_1):\PP5913\") )
				( member ( pinPairRef "@baseboard_fab2_lib.baseboard_fab2(sch_1):\PP5919\") )
				( member ( pinPairRef "@baseboard_fab2_lib.baseboard_fab2(sch_1):\PP5918\") )
				( objectStatus "MG_P3E_CPU0_PE2_SS_TX0607" )
			)
			( matchGroup "@baseboard_fab2_lib.baseboard_fab2(sch_1):\MG_P3E_CPU0_PE2_SS_TX0809\"
				( memberType ( signal ) )
				( member ( pinPairRef "@baseboard_fab2_lib.baseboard_fab2(sch_1):\PP5915\") )
				( member ( pinPairRef "@baseboard_fab2_lib.baseboard_fab2(sch_1):\PP5920\") )
				( member ( pinPairRef "@baseboard_fab2_lib.baseboard_fab2(sch_1):\PP5925\") )
				( member ( pinPairRef "@baseboard_fab2_lib.baseboard_fab2(sch_1):\PP5914\") )
				( objectStatus "MG_P3E_CPU0_PE2_SS_TX0809" )
			)
			( matchGroup "@baseboard_fab2_lib.baseboard_fab2(sch_1):\MG_P3E_CPU0_PE2_SS_TX1011\"
				( memberType ( signal ) )
				( member ( pinPairRef "@baseboard_fab2_lib.baseboard_fab2(sch_1):\PP5927\") )
				( member ( pinPairRef "@baseboard_fab2_lib.baseboard_fab2(sch_1):\PP5924\") )
				( member ( pinPairRef "@baseboard_fab2_lib.baseboard_fab2(sch_1):\PP5929\") )
				( member ( pinPairRef "@baseboard_fab2_lib.baseboard_fab2(sch_1):\PP5928\") )
				( objectStatus "MG_P3E_CPU0_PE2_SS_TX1011" )
			)
			( matchGroup "@baseboard_fab2_lib.baseboard_fab2(sch_1):\MG_P3E_CPU0_PE2_SS_TX1213\"
				( memberType ( signal ) )
				( member ( pinPairRef "@baseboard_fab2_lib.baseboard_fab2(sch_1):\PP5931\") )
				( member ( pinPairRef "@baseboard_fab2_lib.baseboard_fab2(sch_1):\PP5930\") )
				( member ( pinPairRef "@baseboard_fab2_lib.baseboard_fab2(sch_1):\PP5933\") )
				( member ( pinPairRef "@baseboard_fab2_lib.baseboard_fab2(sch_1):\PP5926\") )
				( objectStatus "MG_P3E_CPU0_PE2_SS_TX1213" )
			)
			( matchGroup "@baseboard_fab2_lib.baseboard_fab2(sch_1):\MG_P3E_CPU0_PE2_SS_TX1415\"
				( memberType ( signal ) )
				( member ( pinPairRef "@baseboard_fab2_lib.baseboard_fab2(sch_1):\PP5938\") )
				( member ( pinPairRef "@baseboard_fab2_lib.baseboard_fab2(sch_1):\PP5937\") )
				( member ( pinPairRef "@baseboard_fab2_lib.baseboard_fab2(sch_1):\PP5941\") )
				( member ( pinPairRef "@baseboard_fab2_lib.baseboard_fab2(sch_1):\PP5939\") )
				( objectStatus "MG_P3E_CPU0_PE2_SS_TX1415" )
			)
			( matchGroup "@baseboard_fab2_lib.baseboard_fab2(sch_1):\MG_P3E_CPU0_PE3_OCP_TX0001\"
				( memberType ( signal ) )
				( member ( pinPairRef "@baseboard_fab2_lib.baseboard_fab2(sch_1):\PP5940\") )
				( member ( pinPairRef "@baseboard_fab2_lib.baseboard_fab2(sch_1):\PP5942\") )
				( member ( pinPairRef "@baseboard_fab2_lib.baseboard_fab2(sch_1):\PP5944\") )
				( member ( pinPairRef "@baseboard_fab2_lib.baseboard_fab2(sch_1):\PP5932\") )
				( objectStatus "MG_P3E_CPU0_PE3_OCP_TX0001" )
			)
			( matchGroup "@baseboard_fab2_lib.baseboard_fab2(sch_1):\MG_P3E_CPU0_PE3_OCP_TX0203\"
				( memberType ( signal ) )
				( member ( pinPairRef "@baseboard_fab2_lib.baseboard_fab2(sch_1):\PP5945\") )
				( member ( pinPairRef "@baseboard_fab2_lib.baseboard_fab2(sch_1):\PP5943\") )
				( member ( pinPairRef "@baseboard_fab2_lib.baseboard_fab2(sch_1):\PP5948\") )
				( member ( pinPairRef "@baseboard_fab2_lib.baseboard_fab2(sch_1):\PP5946\") )
				( objectStatus "MG_P3E_CPU0_PE3_OCP_TX0203" )
			)
			( matchGroup "@baseboard_fab2_lib.baseboard_fab2(sch_1):\MG_P3E_CPU0_PE3_OCP_TX0405\"
				( memberType ( signal ) )
				( member ( pinPairRef "@baseboard_fab2_lib.baseboard_fab2(sch_1):\PP5950\") )
				( member ( pinPairRef "@baseboard_fab2_lib.baseboard_fab2(sch_1):\PP5947\") )
				( member ( pinPairRef "@baseboard_fab2_lib.baseboard_fab2(sch_1):\PP5955\") )
				( member ( pinPairRef "@baseboard_fab2_lib.baseboard_fab2(sch_1):\PP5949\") )
				( objectStatus "MG_P3E_CPU0_PE3_OCP_TX0405" )
			)
			( matchGroup "@baseboard_fab2_lib.baseboard_fab2(sch_1):\MG_P3E_CPU0_PE3_OCP_TX0607\"
				( memberType ( signal ) )
				( member ( pinPairRef "@baseboard_fab2_lib.baseboard_fab2(sch_1):\PP5956\") )
				( member ( pinPairRef "@baseboard_fab2_lib.baseboard_fab2(sch_1):\PP5954\") )
				( member ( pinPairRef "@baseboard_fab2_lib.baseboard_fab2(sch_1):\PP5958\") )
				( member ( pinPairRef "@baseboard_fab2_lib.baseboard_fab2(sch_1):\PP5957\") )
				( objectStatus "MG_P3E_CPU0_PE3_OCP_TX0607" )
			)
			( matchGroup "@baseboard_fab2_lib.baseboard_fab2(sch_1):\MG_P3E_CPU0_PE3_OCP_TX0809\"
				( memberType ( signal ) )
				( member ( pinPairRef "@baseboard_fab2_lib.baseboard_fab2(sch_1):\PP6034\") )
				( member ( pinPairRef "@baseboard_fab2_lib.baseboard_fab2(sch_1):\PP5892\") )
				( member ( pinPairRef "@baseboard_fab2_lib.baseboard_fab2(sch_1):\PP5951\") )
				( member ( pinPairRef "@baseboard_fab2_lib.baseboard_fab2(sch_1):\PP5988\") )
				( objectStatus "MG_P3E_CPU0_PE3_OCP_TX0809" )
			)
			( matchGroup "@baseboard_fab2_lib.baseboard_fab2(sch_1):\MG_P3E_CPU0_PE3_OCP_TX1011\"
				( memberType ( signal ) )
				( member ( pinPairRef "@baseboard_fab2_lib.baseboard_fab2(sch_1):\PP6046\") )
				( member ( pinPairRef "@baseboard_fab2_lib.baseboard_fab2(sch_1):\PP6047\") )
				( member ( pinPairRef "@baseboard_fab2_lib.baseboard_fab2(sch_1):\PP6043\") )
				( member ( pinPairRef "@baseboard_fab2_lib.baseboard_fab2(sch_1):\PP6042\") )
				( objectStatus "MG_P3E_CPU0_PE3_OCP_TX1011" )
			)
			( matchGroup "@baseboard_fab2_lib.baseboard_fab2(sch_1):\MG_P3E_CPU0_PE3_OCP_TX1213\"
				( memberType ( signal ) )
				( member ( pinPairRef "@baseboard_fab2_lib.baseboard_fab2(sch_1):\PP6040\") )
				( member ( pinPairRef "@baseboard_fab2_lib.baseboard_fab2(sch_1):\PP6041\") )
				( member ( pinPairRef "@baseboard_fab2_lib.baseboard_fab2(sch_1):\PP6032\") )
				( member ( pinPairRef "@baseboard_fab2_lib.baseboard_fab2(sch_1):\PP6037\") )
				( objectStatus "MG_P3E_CPU0_PE3_OCP_TX1213" )
			)
			( matchGroup "@baseboard_fab2_lib.baseboard_fab2(sch_1):\MG_P3E_CPU0_PE3_OCP_TX1415\"
				( memberType ( signal ) )
				( member ( pinPairRef "@baseboard_fab2_lib.baseboard_fab2(sch_1):\PP6039\") )
				( member ( pinPairRef "@baseboard_fab2_lib.baseboard_fab2(sch_1):\PP6038\") )
				( member ( pinPairRef "@baseboard_fab2_lib.baseboard_fab2(sch_1):\PP6036\") )
				( member ( pinPairRef "@baseboard_fab2_lib.baseboard_fab2(sch_1):\PP6035\") )
				( objectStatus "MG_P3E_CPU0_PE3_OCP_TX1415" )
			)
			( matchGroup "@baseboard_fab2_lib.baseboard_fab2(sch_1):\MG_P3E_CPU1_PE3_MP_TX0001\"
				( memberType ( signal ) )
				( member ( pinPairRef "@baseboard_fab2_lib.baseboard_fab2(sch_1):\PP5952\") )
				( member ( pinPairRef "@baseboard_fab2_lib.baseboard_fab2(sch_1):\PP5959\") )
				( member ( pinPairRef "@baseboard_fab2_lib.baseboard_fab2(sch_1):\PP5961\") )
				( member ( pinPairRef "@baseboard_fab2_lib.baseboard_fab2(sch_1):\PP5953\") )
				( objectStatus "MG_P3E_CPU1_PE3_MP_TX0001" )
			)
			( matchGroup "@baseboard_fab2_lib.baseboard_fab2(sch_1):\MG_P3E_CPU0_PE1_PCH_PCIEUP_RX0809\"
				( memberType ( signal ) )
				( member ( pinPairRef "@baseboard_fab2_lib.baseboard_fab2(sch_1):\PP5829\") )
				( member ( pinPairRef "@baseboard_fab2_lib.baseboard_fab2(sch_1):\PP5836\") )
				( member ( pinPairRef "@baseboard_fab2_lib.baseboard_fab2(sch_1):\PP5835\") )
				( member ( pinPairRef "@baseboard_fab2_lib.baseboard_fab2(sch_1):\PP5837\") )
				( objectStatus "MG_P3E_CPU0_PE1_PCH_PCIEUP_RX0809" )
			)
			( matchGroup "@baseboard_fab2_lib.baseboard_fab2(sch_1):\MG_P3E_CPU1_PE3_MP_TX0203\"
				( memberType ( signal ) )
				( member ( pinPairRef "@baseboard_fab2_lib.baseboard_fab2(sch_1):\PP5963\") )
				( member ( pinPairRef "@baseboard_fab2_lib.baseboard_fab2(sch_1):\PP5960\") )
				( member ( pinPairRef "@baseboard_fab2_lib.baseboard_fab2(sch_1):\PP5965\") )
				( member ( pinPairRef "@baseboard_fab2_lib.baseboard_fab2(sch_1):\PP5964\") )
				( objectStatus "MG_P3E_CPU1_PE3_MP_TX0203" )
			)
			( matchGroup "@baseboard_fab2_lib.baseboard_fab2(sch_1):\MG_P3E_CPU1_PE3_MP_TX0405\"
				( memberType ( signal ) )
				( member ( pinPairRef "@baseboard_fab2_lib.baseboard_fab2(sch_1):\PP5967\") )
				( member ( pinPairRef "@baseboard_fab2_lib.baseboard_fab2(sch_1):\PP5966\") )
				( member ( pinPairRef "@baseboard_fab2_lib.baseboard_fab2(sch_1):\PP5968\") )
				( member ( pinPairRef "@baseboard_fab2_lib.baseboard_fab2(sch_1):\PP5962\") )
				( objectStatus "MG_P3E_CPU1_PE3_MP_TX0405" )
			)
			( matchGroup "@baseboard_fab2_lib.baseboard_fab2(sch_1):\MG_P3E_CPU1_PE3_MP_TX0607\"
				( memberType ( signal ) )
				( member ( pinPairRef "@baseboard_fab2_lib.baseboard_fab2(sch_1):\PP5971\") )
				( member ( pinPairRef "@baseboard_fab2_lib.baseboard_fab2(sch_1):\PP5970\") )
				( member ( pinPairRef "@baseboard_fab2_lib.baseboard_fab2(sch_1):\PP5981\") )
				( member ( pinPairRef "@baseboard_fab2_lib.baseboard_fab2(sch_1):\PP5980\") )
				( objectStatus "MG_P3E_CPU1_PE3_MP_TX0607" )
			)
			( matchGroup "@baseboard_fab2_lib.baseboard_fab2(sch_1):\MG_P3E_CPU1_PE3_MP_TX1213\"
				( memberType ( signal ) )
				( member ( pinPairRef "@baseboard_fab2_lib.baseboard_fab2(sch_1):\PP5973\") )
				( member ( pinPairRef "@baseboard_fab2_lib.baseboard_fab2(sch_1):\PP5975\") )
				( member ( pinPairRef "@baseboard_fab2_lib.baseboard_fab2(sch_1):\PP5976\") )
				( member ( pinPairRef "@baseboard_fab2_lib.baseboard_fab2(sch_1):\PP5969\") )
				( objectStatus "MG_P3E_CPU1_PE3_MP_TX1213" )
			)
			( matchGroup "@baseboard_fab2_lib.baseboard_fab2(sch_1):\MG_P3E_CPU1_PE3_MP_TX1415\"
				( memberType ( signal ) )
				( member ( pinPairRef "@baseboard_fab2_lib.baseboard_fab2(sch_1):\PP5979\") )
				( member ( pinPairRef "@baseboard_fab2_lib.baseboard_fab2(sch_1):\PP5977\") )
				( member ( pinPairRef "@baseboard_fab2_lib.baseboard_fab2(sch_1):\PP5987\") )
				( member ( pinPairRef "@baseboard_fab2_lib.baseboard_fab2(sch_1):\PP5978\") )
				( objectStatus "MG_P3E_CPU1_PE3_MP_TX1415" )
			)
			( matchGroup "@baseboard_fab2_lib.baseboard_fab2(sch_1):\MG_P3E_CPU1_PE3_MP_RX0001\"
				( memberType ( signal ) )
				( member ( pinPairRef "@baseboard_fab2_lib.baseboard_fab2(sch_1):\PP3033\") )
				( member ( pinPairRef "@baseboard_fab2_lib.baseboard_fab2(sch_1):\PP3031\") )
				( member ( pinPairRef "@baseboard_fab2_lib.baseboard_fab2(sch_1):\PP3034\") )
				( member ( pinPairRef "@baseboard_fab2_lib.baseboard_fab2(sch_1):\PP3032\") )
				( objectStatus "MG_P3E_CPU1_PE3_MP_RX0001" )
			)
			( matchGroup "@baseboard_fab2_lib.baseboard_fab2(sch_1):\MG_P3E_CPU1_PE3_MP_RX0203\"
				( memberType ( signal ) )
				( member ( pinPairRef "@baseboard_fab2_lib.baseboard_fab2(sch_1):\PP3029\") )
				( member ( pinPairRef "@baseboard_fab2_lib.baseboard_fab2(sch_1):\PP3027\") )
				( member ( pinPairRef "@baseboard_fab2_lib.baseboard_fab2(sch_1):\PP3030\") )
				( member ( pinPairRef "@baseboard_fab2_lib.baseboard_fab2(sch_1):\PP3028\") )
				( objectStatus "MG_P3E_CPU1_PE3_MP_RX0203" )
			)
			( matchGroup "@baseboard_fab2_lib.baseboard_fab2(sch_1):\MG_P3E_CPU1_PE3_MP_RX0405\"
				( memberType ( signal ) )
				( member ( pinPairRef "@baseboard_fab2_lib.baseboard_fab2(sch_1):\PP3025\") )
				( member ( pinPairRef "@baseboard_fab2_lib.baseboard_fab2(sch_1):\PP3023\") )
				( member ( pinPairRef "@baseboard_fab2_lib.baseboard_fab2(sch_1):\PP3026\") )
				( member ( pinPairRef "@baseboard_fab2_lib.baseboard_fab2(sch_1):\PP3024\") )
				( objectStatus "MG_P3E_CPU1_PE3_MP_RX0405" )
			)
			( matchGroup "@baseboard_fab2_lib.baseboard_fab2(sch_1):\MG_P3E_CPU1_PE3_MP_RX0607\"
				( memberType ( signal ) )
				( member ( pinPairRef "@baseboard_fab2_lib.baseboard_fab2(sch_1):\PP3021\") )
				( member ( pinPairRef "@baseboard_fab2_lib.baseboard_fab2(sch_1):\PP3019\") )
				( member ( pinPairRef "@baseboard_fab2_lib.baseboard_fab2(sch_1):\PP3022\") )
				( member ( pinPairRef "@baseboard_fab2_lib.baseboard_fab2(sch_1):\PP3020\") )
				( objectStatus "MG_P3E_CPU1_PE3_MP_RX0607" )
			)
			( matchGroup "@baseboard_fab2_lib.baseboard_fab2(sch_1):\MG_P3E_CPU0_PE2_SS_RX0001\"
				( memberType ( signal ) )
				( member ( pinPairRef "@baseboard_fab2_lib.baseboard_fab2(sch_1):\PP3105\") )
				( member ( pinPairRef "@baseboard_fab2_lib.baseboard_fab2(sch_1):\PP3103\") )
				( member ( pinPairRef "@baseboard_fab2_lib.baseboard_fab2(sch_1):\PP3106\") )
				( member ( pinPairRef "@baseboard_fab2_lib.baseboard_fab2(sch_1):\PP3104\") )
				( objectStatus "MG_P3E_CPU0_PE2_SS_RX0001" )
			)
			( matchGroup "@baseboard_fab2_lib.baseboard_fab2(sch_1):\MG_P3E_CPU0_PE2_SS_RX0203\"
				( memberType ( signal ) )
				( member ( pinPairRef "@baseboard_fab2_lib.baseboard_fab2(sch_1):\PP3101\") )
				( member ( pinPairRef "@baseboard_fab2_lib.baseboard_fab2(sch_1):\PP3099\") )
				( member ( pinPairRef "@baseboard_fab2_lib.baseboard_fab2(sch_1):\PP3102\") )
				( member ( pinPairRef "@baseboard_fab2_lib.baseboard_fab2(sch_1):\PP3100\") )
				( objectStatus "MG_P3E_CPU0_PE2_SS_RX0203" )
			)
			( matchGroup "@baseboard_fab2_lib.baseboard_fab2(sch_1):\MG_P3E_CPU0_PE2_SS_RX0405\"
				( memberType ( signal ) )
				( member ( pinPairRef "@baseboard_fab2_lib.baseboard_fab2(sch_1):\PP3097\") )
				( member ( pinPairRef "@baseboard_fab2_lib.baseboard_fab2(sch_1):\PP3095\") )
				( member ( pinPairRef "@baseboard_fab2_lib.baseboard_fab2(sch_1):\PP3098\") )
				( member ( pinPairRef "@baseboard_fab2_lib.baseboard_fab2(sch_1):\PP3096\") )
				( objectStatus "MG_P3E_CPU0_PE2_SS_RX0405" )
			)
			( matchGroup "@baseboard_fab2_lib.baseboard_fab2(sch_1):\MG_P3E_CPU0_PE2_SS_RX0607\"
				( memberType ( signal ) )
				( member ( pinPairRef "@baseboard_fab2_lib.baseboard_fab2(sch_1):\PP3093\") )
				( member ( pinPairRef "@baseboard_fab2_lib.baseboard_fab2(sch_1):\PP3091\") )
				( member ( pinPairRef "@baseboard_fab2_lib.baseboard_fab2(sch_1):\PP3094\") )
				( member ( pinPairRef "@baseboard_fab2_lib.baseboard_fab2(sch_1):\PP3092\") )
				( objectStatus "MG_P3E_CPU0_PE2_SS_RX0607" )
			)
			( matchGroup "@baseboard_fab2_lib.baseboard_fab2(sch_1):\MG_P3E_CPU0_PE2_SS_RX0809\"
				( memberType ( signal ) )
				( member ( pinPairRef "@baseboard_fab2_lib.baseboard_fab2(sch_1):\PP3089\") )
				( member ( pinPairRef "@baseboard_fab2_lib.baseboard_fab2(sch_1):\PP3087\") )
				( member ( pinPairRef "@baseboard_fab2_lib.baseboard_fab2(sch_1):\PP3090\") )
				( member ( pinPairRef "@baseboard_fab2_lib.baseboard_fab2(sch_1):\PP3088\") )
				( objectStatus "MG_P3E_CPU0_PE2_SS_RX0809" )
			)
			( matchGroup "@baseboard_fab2_lib.baseboard_fab2(sch_1):\MG_P3E_CPU0_PE2_SS_RX1415\"
				( memberType ( signal ) )
				( member ( pinPairRef "@baseboard_fab2_lib.baseboard_fab2(sch_1):\PP3078\") )
				( member ( pinPairRef "@baseboard_fab2_lib.baseboard_fab2(sch_1):\PP3076\") )
				( member ( pinPairRef "@baseboard_fab2_lib.baseboard_fab2(sch_1):\PP3077\") )
				( member ( pinPairRef "@baseboard_fab2_lib.baseboard_fab2(sch_1):\PP3075\") )
				( objectStatus "MG_P3E_CPU0_PE2_SS_RX1415" )
			)
			( matchGroup "@baseboard_fab2_lib.baseboard_fab2(sch_1):\MG_P3E_CPU0_PE2_SS_RX1213\"
				( memberType ( signal ) )
				( member ( pinPairRef "@baseboard_fab2_lib.baseboard_fab2(sch_1):\PP3082\") )
				( member ( pinPairRef "@baseboard_fab2_lib.baseboard_fab2(sch_1):\PP3080\") )
				( member ( pinPairRef "@baseboard_fab2_lib.baseboard_fab2(sch_1):\PP3081\") )
				( member ( pinPairRef "@baseboard_fab2_lib.baseboard_fab2(sch_1):\PP3079\") )
				( objectStatus "MG_P3E_CPU0_PE2_SS_RX1213" )
			)
			( matchGroup "@baseboard_fab2_lib.baseboard_fab2(sch_1):\MG_P3E_CPU0_PE2_SS_RX1011\"
				( memberType ( signal ) )
				( member ( pinPairRef "@baseboard_fab2_lib.baseboard_fab2(sch_1):\PP3086\") )
				( member ( pinPairRef "@baseboard_fab2_lib.baseboard_fab2(sch_1):\PP3084\") )
				( member ( pinPairRef "@baseboard_fab2_lib.baseboard_fab2(sch_1):\PP3085\") )
				( member ( pinPairRef "@baseboard_fab2_lib.baseboard_fab2(sch_1):\PP3083\") )
				( objectStatus "MG_P3E_CPU0_PE2_SS_RX1011" )
			)
			( matchGroup "@baseboard_fab2_lib.baseboard_fab2(sch_1):\MG_P3E_CPU1_PE3_MP_RX0809\"
				( memberType ( signal ) )
				( member ( pinPairRef "@baseboard_fab2_lib.baseboard_fab2(sch_1):\PP3017\") )
				( member ( pinPairRef "@baseboard_fab2_lib.baseboard_fab2(sch_1):\PP3015\") )
				( member ( pinPairRef "@baseboard_fab2_lib.baseboard_fab2(sch_1):\PP3018\") )
				( member ( pinPairRef "@baseboard_fab2_lib.baseboard_fab2(sch_1):\PP3016\") )
				( objectStatus "MG_P3E_CPU1_PE3_MP_RX0809" )
			)
			( matchGroup "@baseboard_fab2_lib.baseboard_fab2(sch_1):\MG_P3E_CPU1_PE3_MP_RX1011\"
				( memberType ( signal ) )
				( member ( pinPairRef "@baseboard_fab2_lib.baseboard_fab2(sch_1):\PP3013\") )
				( member ( pinPairRef "@baseboard_fab2_lib.baseboard_fab2(sch_1):\PP3011\") )
				( member ( pinPairRef "@baseboard_fab2_lib.baseboard_fab2(sch_1):\PP3014\") )
				( member ( pinPairRef "@baseboard_fab2_lib.baseboard_fab2(sch_1):\PP3012\") )
				( objectStatus "MG_P3E_CPU1_PE3_MP_RX1011" )
			)
			( matchGroup "@baseboard_fab2_lib.baseboard_fab2(sch_1):\MG_P3E_CPU1_PE3_MP_RX1213\"
				( memberType ( signal ) )
				( member ( pinPairRef "@baseboard_fab2_lib.baseboard_fab2(sch_1):\PP3009\") )
				( member ( pinPairRef "@baseboard_fab2_lib.baseboard_fab2(sch_1):\PP3007\") )
				( member ( pinPairRef "@baseboard_fab2_lib.baseboard_fab2(sch_1):\PP3010\") )
				( member ( pinPairRef "@baseboard_fab2_lib.baseboard_fab2(sch_1):\PP3008\") )
				( objectStatus "MG_P3E_CPU1_PE3_MP_RX1213" )
			)
			( matchGroup "@baseboard_fab2_lib.baseboard_fab2(sch_1):\MG_P3E_CPU1_PE3_MP_RX1415\"
				( memberType ( signal ) )
				( member ( pinPairRef "@baseboard_fab2_lib.baseboard_fab2(sch_1):\PP3005\") )
				( member ( pinPairRef "@baseboard_fab2_lib.baseboard_fab2(sch_1):\PP3003\") )
				( member ( pinPairRef "@baseboard_fab2_lib.baseboard_fab2(sch_1):\PP3006\") )
				( member ( pinPairRef "@baseboard_fab2_lib.baseboard_fab2(sch_1):\PP3004\") )
				( objectStatus "MG_P3E_CPU1_PE3_MP_RX1415" )
			)
			( matchGroup "@crescent_city_bb_fab1_lib.crescent_city_bb_fab1(sch_1):\SATA6G_S1_TX_L2\"
				( memberType ( signal ) )
				( attribute "RELATIVE_PROPAGATION_DELAY_SCOPE" "G"
					( Parent
						( matchGroupRef "@crescent_city_bb_fab1_lib.crescent_city_bb_fab1(sch_1):\SATA6G_S1_TX_L2\" )
					)
					( Origin gBackEnd )
				)
				( attribute "RELATIVE_PROPAGATION_DELAY_PATH_TYPE" "AD:AR"
					( Parent
						( matchGroupRef "@crescent_city_bb_fab1_lib.crescent_city_bb_fab1(sch_1):\SATA6G_S1_TX_L2\" )
					)
					( Origin gBackEnd )
				)
				( attribute "RELATIVE_PROPAGATION_DELAY" ",5.00 MIL"
					( Parent
						( matchGroupRef "@crescent_city_bb_fab1_lib.crescent_city_bb_fab1(sch_1):\SATA6G_S1_TX_L2\" )
					)
					( Units "uMatchProp" "ns" 1.000000)
					( Origin gBackEnd )
				)
				( member ( pinPairRef "@baseboard_fab2_lib.baseboard_fab2(sch_1):\PP5669\") )
				( member ( pinPairRef "@baseboard_fab2_lib.baseboard_fab2(sch_1):\PP5670\") )
				( objectStatus "MG_SATA6G_S1_TX_L2" )
			)
			( matchGroup "@crescent_city_bb_fab1_lib.crescent_city_bb_fab1(sch_1):\SATA6G_S1_TX_L1\"
				( memberType ( signal ) )
				( attribute "RELATIVE_PROPAGATION_DELAY_SCOPE" "G"
					( Parent
						( matchGroupRef "@crescent_city_bb_fab1_lib.crescent_city_bb_fab1(sch_1):\SATA6G_S1_TX_L1\" )
					)
					( Origin gBackEnd )
				)
				( attribute "RELATIVE_PROPAGATION_DELAY_PATH_TYPE" "AD:AR"
					( Parent
						( matchGroupRef "@crescent_city_bb_fab1_lib.crescent_city_bb_fab1(sch_1):\SATA6G_S1_TX_L1\" )
					)
					( Origin gBackEnd )
				)
				( attribute "RELATIVE_PROPAGATION_DELAY" ",5.00 MIL"
					( Parent
						( matchGroupRef "@crescent_city_bb_fab1_lib.crescent_city_bb_fab1(sch_1):\SATA6G_S1_TX_L1\" )
					)
					( Units "uMatchProp" "ns" 1.000000)
					( Origin gBackEnd )
				)
				( member ( pinPairRef "@baseboard_fab2_lib.baseboard_fab2(sch_1):\PP5671\") )
				( member ( pinPairRef "@baseboard_fab2_lib.baseboard_fab2(sch_1):\PP5668\") )
				( objectStatus "MG_SATA6G_S1_TX_L1" )
			)
			( matchGroup "@crescent_city_bb_fab1_lib.crescent_city_bb_fab1(sch_1):\SATA6G_S0_TX_L3\"
				( memberType ( signal ) )
				( attribute "RELATIVE_PROPAGATION_DELAY_SCOPE" "G"
					( Parent
						( matchGroupRef "@crescent_city_bb_fab1_lib.crescent_city_bb_fab1(sch_1):\SATA6G_S0_TX_L3\" )
					)
					( Origin gBackEnd )
				)
				( attribute "RELATIVE_PROPAGATION_DELAY_PATH_TYPE" "AD:AR"
					( Parent
						( matchGroupRef "@crescent_city_bb_fab1_lib.crescent_city_bb_fab1(sch_1):\SATA6G_S0_TX_L3\" )
					)
					( Origin gBackEnd )
				)
				( attribute "RELATIVE_PROPAGATION_DELAY" ",5.00 MIL"
					( Parent
						( matchGroupRef "@crescent_city_bb_fab1_lib.crescent_city_bb_fab1(sch_1):\SATA6G_S0_TX_L3\" )
					)
					( Units "uMatchProp" "ns" 1.000000)
					( Origin gBackEnd )
				)
				( member ( pinPairRef "@baseboard_fab2_lib.baseboard_fab2(sch_1):\PP6141\") )
				( member ( pinPairRef "@baseboard_fab2_lib.baseboard_fab2(sch_1):\PP6140\") )
				( objectStatus "MG_SATA6G_S0_TX_L3" )
			)
			( matchGroup "@crescent_city_bb_fab1_lib.crescent_city_bb_fab1(sch_1):\SATA6G_S0_TX_L2\"
				( memberType ( signal ) )
				( attribute "RELATIVE_PROPAGATION_DELAY_SCOPE" "G"
					( Parent
						( matchGroupRef "@crescent_city_bb_fab1_lib.crescent_city_bb_fab1(sch_1):\SATA6G_S0_TX_L2\" )
					)
					( Origin gBackEnd )
				)
				( attribute "RELATIVE_PROPAGATION_DELAY_PATH_TYPE" "AD:AR"
					( Parent
						( matchGroupRef "@crescent_city_bb_fab1_lib.crescent_city_bb_fab1(sch_1):\SATA6G_S0_TX_L2\" )
					)
					( Origin gBackEnd )
				)
				( attribute "RELATIVE_PROPAGATION_DELAY" ",5.00 MIL"
					( Parent
						( matchGroupRef "@crescent_city_bb_fab1_lib.crescent_city_bb_fab1(sch_1):\SATA6G_S0_TX_L2\" )
					)
					( Units "uMatchProp" "ns" 1.000000)
					( Origin gBackEnd )
				)
				( member ( pinPairRef "@baseboard_fab2_lib.baseboard_fab2(sch_1):\PP5689\") )
				( member ( pinPairRef "@baseboard_fab2_lib.baseboard_fab2(sch_1):\PP5686\") )
				( objectStatus "MG_SATA6G_S0_TX_L2" )
			)
			( matchGroup "@crescent_city_bb_fab1_lib.crescent_city_bb_fab1(sch_1):\SATA6G_S0_TX_L1\"
				( memberType ( signal ) )
				( attribute "RELATIVE_PROPAGATION_DELAY_SCOPE" "G"
					( Parent
						( matchGroupRef "@crescent_city_bb_fab1_lib.crescent_city_bb_fab1(sch_1):\SATA6G_S0_TX_L1\" )
					)
					( Origin gBackEnd )
				)
				( attribute "RELATIVE_PROPAGATION_DELAY_PATH_TYPE" "AD:AR"
					( Parent
						( matchGroupRef "@crescent_city_bb_fab1_lib.crescent_city_bb_fab1(sch_1):\SATA6G_S0_TX_L1\" )
					)
					( Origin gBackEnd )
				)
				( attribute "RELATIVE_PROPAGATION_DELAY" ",5.00 MIL"
					( Parent
						( matchGroupRef "@crescent_city_bb_fab1_lib.crescent_city_bb_fab1(sch_1):\SATA6G_S0_TX_L1\" )
					)
					( Units "uMatchProp" "ns" 1.000000)
					( Origin gBackEnd )
				)
				( member ( pinPairRef "@baseboard_fab2_lib.baseboard_fab2(sch_1):\PP5688\") )
				( member ( pinPairRef "@baseboard_fab2_lib.baseboard_fab2(sch_1):\PP5691\") )
				( objectStatus "MG_SATA6G_S0_TX_L1" )
			)
			( matchGroup "@crescent_city_bb_fab1_lib.crescent_city_bb_fab1(sch_1):\SATA6G_S0_RX_L3\"
				( memberType ( signal ) )
				( attribute "RELATIVE_PROPAGATION_DELAY_SCOPE" "G"
					( Parent
						( matchGroupRef "@crescent_city_bb_fab1_lib.crescent_city_bb_fab1(sch_1):\SATA6G_S0_RX_L3\" )
					)
					( Origin gBackEnd )
				)
				( attribute "RELATIVE_PROPAGATION_DELAY_PATH_TYPE" "AD:AR"
					( Parent
						( matchGroupRef "@crescent_city_bb_fab1_lib.crescent_city_bb_fab1(sch_1):\SATA6G_S0_RX_L3\" )
					)
					( Origin gBackEnd )
				)
				( attribute "RELATIVE_PROPAGATION_DELAY" ",5.00 MIL"
					( Parent
						( matchGroupRef "@crescent_city_bb_fab1_lib.crescent_city_bb_fab1(sch_1):\SATA6G_S0_RX_L3\" )
					)
					( Units "uMatchProp" "ns" 1.000000)
					( Origin gBackEnd )
				)
				( member ( pinPairRef "@baseboard_fab2_lib.baseboard_fab2(sch_1):\PP5685\") )
				( member ( pinPairRef "@baseboard_fab2_lib.baseboard_fab2(sch_1):\PP5684\") )
				( objectStatus "MG_SATA6G_S0_RX_L3" )
			)
			( matchGroup "@crescent_city_bb_fab1_lib.crescent_city_bb_fab1(sch_1):\SATA6G_S0_RX_L2\"
				( memberType ( signal ) )
				( attribute "RELATIVE_PROPAGATION_DELAY_SCOPE" "G"
					( Parent
						( matchGroupRef "@crescent_city_bb_fab1_lib.crescent_city_bb_fab1(sch_1):\SATA6G_S0_RX_L2\" )
					)
					( Origin gBackEnd )
				)
				( attribute "RELATIVE_PROPAGATION_DELAY_PATH_TYPE" "AD:AR"
					( Parent
						( matchGroupRef "@crescent_city_bb_fab1_lib.crescent_city_bb_fab1(sch_1):\SATA6G_S0_RX_L2\" )
					)
					( Origin gBackEnd )
				)
				( attribute "RELATIVE_PROPAGATION_DELAY" ",5.00 MIL"
					( Parent
						( matchGroupRef "@crescent_city_bb_fab1_lib.crescent_city_bb_fab1(sch_1):\SATA6G_S0_RX_L2\" )
					)
					( Units "uMatchProp" "ns" 1.000000)
					( Origin gBackEnd )
				)
				( member ( pinPairRef "@baseboard_fab2_lib.baseboard_fab2(sch_1):\PP6143\") )
				( member ( pinPairRef "@baseboard_fab2_lib.baseboard_fab2(sch_1):\PP6142\") )
				( objectStatus "MG_SATA6G_S0_RX_L2" )
			)
			( matchGroup "@crescent_city_bb_fab1_lib.crescent_city_bb_fab1(sch_1):\SATA6G_P11_TX_L2\"
				( memberType ( signal ) )
				( attribute "RELATIVE_PROPAGATION_DELAY_SCOPE" "G"
					( Parent
						( matchGroupRef "@crescent_city_bb_fab1_lib.crescent_city_bb_fab1(sch_1):\SATA6G_P11_TX_L2\" )
					)
					( Origin gBackEnd )
				)
				( attribute "RELATIVE_PROPAGATION_DELAY_PATH_TYPE" "AD:AR"
					( Parent
						( matchGroupRef "@crescent_city_bb_fab1_lib.crescent_city_bb_fab1(sch_1):\SATA6G_P11_TX_L2\" )
					)
					( Origin gBackEnd )
				)
				( attribute "RELATIVE_PROPAGATION_DELAY" ",5.00 MIL"
					( Parent
						( matchGroupRef "@crescent_city_bb_fab1_lib.crescent_city_bb_fab1(sch_1):\SATA6G_P11_TX_L2\" )
					)
					( Units "uMatchProp" "ns" 1.000000)
					( Origin gBackEnd )
				)
				( member ( pinPairRef "@baseboard_fab2_lib.baseboard_fab2(sch_1):\PP5710\") )
				( member ( pinPairRef "@baseboard_fab2_lib.baseboard_fab2(sch_1):\PP5713\") )
				( objectStatus "MG_SATA6G_P11_TX_L2" )
			)
			( matchGroup "@crescent_city_bb_fab1_lib.crescent_city_bb_fab1(sch_1):\SATA6G_P11_TX_L1\"
				( memberType ( signal ) )
				( attribute "RELATIVE_PROPAGATION_DELAY_SCOPE" "G"
					( Parent
						( matchGroupRef "@crescent_city_bb_fab1_lib.crescent_city_bb_fab1(sch_1):\SATA6G_P11_TX_L1\" )
					)
					( Origin gBackEnd )
				)
				( attribute "RELATIVE_PROPAGATION_DELAY_PATH_TYPE" "AD:AR"
					( Parent
						( matchGroupRef "@crescent_city_bb_fab1_lib.crescent_city_bb_fab1(sch_1):\SATA6G_P11_TX_L1\" )
					)
					( Origin gBackEnd )
				)
				( attribute "RELATIVE_PROPAGATION_DELAY" ",5.00 MIL"
					( Parent
						( matchGroupRef "@crescent_city_bb_fab1_lib.crescent_city_bb_fab1(sch_1):\SATA6G_P11_TX_L1\" )
					)
					( Units "uMatchProp" "ns" 1.000000)
					( Origin gBackEnd )
				)
				( member ( pinPairRef "@baseboard_fab2_lib.baseboard_fab2(sch_1):\PP5712\") )
				( member ( pinPairRef "@baseboard_fab2_lib.baseboard_fab2(sch_1):\PP5711\") )
				( objectStatus "MG_SATA6G_P11_TX_L1" )
			)
			( matchGroup "@crescent_city_bb_fab1_lib.crescent_city_bb_fab1(sch_1):\SATA6G_P11_RX_L2\"
				( memberType ( signal ) )
				( attribute "RELATIVE_PROPAGATION_DELAY_SCOPE" "G"
					( Parent
						( matchGroupRef "@crescent_city_bb_fab1_lib.crescent_city_bb_fab1(sch_1):\SATA6G_P11_RX_L2\" )
					)
					( Origin gBackEnd )
				)
				( attribute "RELATIVE_PROPAGATION_DELAY_PATH_TYPE" "AD:AR"
					( Parent
						( matchGroupRef "@crescent_city_bb_fab1_lib.crescent_city_bb_fab1(sch_1):\SATA6G_P11_RX_L2\" )
					)
					( Origin gBackEnd )
				)
				( attribute "RELATIVE_PROPAGATION_DELAY" ",5.00 MIL"
					( Parent
						( matchGroupRef "@crescent_city_bb_fab1_lib.crescent_city_bb_fab1(sch_1):\SATA6G_P11_RX_L2\" )
					)
					( Units "uMatchProp" "ns" 1.000000)
					( Origin gBackEnd )
				)
				( member ( pinPairRef "@baseboard_fab2_lib.baseboard_fab2(sch_1):\PP5706\") )
				( member ( pinPairRef "@baseboard_fab2_lib.baseboard_fab2(sch_1):\PP5709\") )
				( objectStatus "MG_SATA6G_P11_RX_L2" )
			)
			( matchGroup "@crescent_city_bb_fab1_lib.crescent_city_bb_fab1(sch_1):\SATA6G_P11_RX_L1\"
				( memberType ( signal ) )
				( attribute "RELATIVE_PROPAGATION_DELAY_SCOPE" "G"
					( Parent
						( matchGroupRef "@crescent_city_bb_fab1_lib.crescent_city_bb_fab1(sch_1):\SATA6G_P11_RX_L1\" )
					)
					( Origin gBackEnd )
				)
				( attribute "RELATIVE_PROPAGATION_DELAY_PATH_TYPE" "AD:AR"
					( Parent
						( matchGroupRef "@crescent_city_bb_fab1_lib.crescent_city_bb_fab1(sch_1):\SATA6G_P11_RX_L1\" )
					)
					( Origin gBackEnd )
				)
				( attribute "RELATIVE_PROPAGATION_DELAY" ",5.00 MIL"
					( Parent
						( matchGroupRef "@crescent_city_bb_fab1_lib.crescent_city_bb_fab1(sch_1):\SATA6G_P11_RX_L1\" )
					)
					( Units "uMatchProp" "ns" 1.000000)
					( Origin gBackEnd )
				)
				( member ( pinPairRef "@baseboard_fab2_lib.baseboard_fab2(sch_1):\PP5708\") )
				( member ( pinPairRef "@baseboard_fab2_lib.baseboard_fab2(sch_1):\PP5707\") )
				( objectStatus "MG_SATA6G_P11_RX_L1" )
			)
			( matchGroup "@crescent_city_bb_fab1_lib.crescent_city_bb_fab1(sch_1):\SATA6G_P10_TX_L2\"
				( memberType ( signal ) )
				( attribute "RELATIVE_PROPAGATION_DELAY_SCOPE" "G"
					( Parent
						( matchGroupRef "@crescent_city_bb_fab1_lib.crescent_city_bb_fab1(sch_1):\SATA6G_P10_TX_L2\" )
					)
					( Origin gBackEnd )
				)
				( attribute "RELATIVE_PROPAGATION_DELAY_PATH_TYPE" "AD:AR"
					( Parent
						( matchGroupRef "@crescent_city_bb_fab1_lib.crescent_city_bb_fab1(sch_1):\SATA6G_P10_TX_L2\" )
					)
					( Origin gBackEnd )
				)
				( attribute "RELATIVE_PROPAGATION_DELAY" ",5.00 MIL"
					( Parent
						( matchGroupRef "@crescent_city_bb_fab1_lib.crescent_city_bb_fab1(sch_1):\SATA6G_P10_TX_L2\" )
					)
					( Units "uMatchProp" "ns" 1.000000)
					( Origin gBackEnd )
				)
				( member ( pinPairRef "@baseboard_fab2_lib.baseboard_fab2(sch_1):\PP5702\") )
				( member ( pinPairRef "@baseboard_fab2_lib.baseboard_fab2(sch_1):\PP5705\") )
				( objectStatus "MG_SATA6G_P10_TX_L2" )
			)
			( matchGroup "@crescent_city_bb_fab1_lib.crescent_city_bb_fab1(sch_1):\SATA6G_P10_TX_L1\"
				( memberType ( signal ) )
				( attribute "RELATIVE_PROPAGATION_DELAY_SCOPE" "G"
					( Parent
						( matchGroupRef "@crescent_city_bb_fab1_lib.crescent_city_bb_fab1(sch_1):\SATA6G_P10_TX_L1\" )
					)
					( Origin gBackEnd )
				)
				( attribute "RELATIVE_PROPAGATION_DELAY_PATH_TYPE" "AD:AR"
					( Parent
						( matchGroupRef "@crescent_city_bb_fab1_lib.crescent_city_bb_fab1(sch_1):\SATA6G_P10_TX_L1\" )
					)
					( Origin gBackEnd )
				)
				( attribute "RELATIVE_PROPAGATION_DELAY" ",5.00 MIL"
					( Parent
						( matchGroupRef "@crescent_city_bb_fab1_lib.crescent_city_bb_fab1(sch_1):\SATA6G_P10_TX_L1\" )
					)
					( Units "uMatchProp" "ns" 1.000000)
					( Origin gBackEnd )
				)
				( member ( pinPairRef "@baseboard_fab2_lib.baseboard_fab2(sch_1):\PP5704\") )
				( member ( pinPairRef "@baseboard_fab2_lib.baseboard_fab2(sch_1):\PP5703\") )
				( objectStatus "MG_SATA6G_P10_TX_L1" )
			)
			( matchGroup "@crescent_city_bb_fab1_lib.crescent_city_bb_fab1(sch_1):\SATA6G_P10_RX_L2\"
				( memberType ( signal ) )
				( attribute "RELATIVE_PROPAGATION_DELAY_SCOPE" "G"
					( Parent
						( matchGroupRef "@crescent_city_bb_fab1_lib.crescent_city_bb_fab1(sch_1):\SATA6G_P10_RX_L2\" )
					)
					( Origin gBackEnd )
				)
				( attribute "RELATIVE_PROPAGATION_DELAY_PATH_TYPE" "AD:AR"
					( Parent
						( matchGroupRef "@crescent_city_bb_fab1_lib.crescent_city_bb_fab1(sch_1):\SATA6G_P10_RX_L2\" )
					)
					( Origin gBackEnd )
				)
				( attribute "RELATIVE_PROPAGATION_DELAY" ",5.00 MIL"
					( Parent
						( matchGroupRef "@crescent_city_bb_fab1_lib.crescent_city_bb_fab1(sch_1):\SATA6G_P10_RX_L2\" )
					)
					( Units "uMatchProp" "ns" 1.000000)
					( Origin gBackEnd )
				)
				( member ( pinPairRef "@baseboard_fab2_lib.baseboard_fab2(sch_1):\PP5701\") )
				( member ( pinPairRef "@baseboard_fab2_lib.baseboard_fab2(sch_1):\PP5698\") )
				( objectStatus "MG_SATA6G_P10_RX_L2" )
			)
			( matchGroup "@crescent_city_bb_fab1_lib.crescent_city_bb_fab1(sch_1):\SATA6G_P10_RX_L1\"
				( memberType ( signal ) )
				( attribute "RELATIVE_PROPAGATION_DELAY_SCOPE" "G"
					( Parent
						( matchGroupRef "@crescent_city_bb_fab1_lib.crescent_city_bb_fab1(sch_1):\SATA6G_P10_RX_L1\" )
					)
					( Origin gBackEnd )
				)
				( attribute "RELATIVE_PROPAGATION_DELAY_PATH_TYPE" "AD:AR"
					( Parent
						( matchGroupRef "@crescent_city_bb_fab1_lib.crescent_city_bb_fab1(sch_1):\SATA6G_P10_RX_L1\" )
					)
					( Origin gBackEnd )
				)
				( attribute "RELATIVE_PROPAGATION_DELAY" ",5.00 MIL"
					( Parent
						( matchGroupRef "@crescent_city_bb_fab1_lib.crescent_city_bb_fab1(sch_1):\SATA6G_P10_RX_L1\" )
					)
					( Units "uMatchProp" "ns" 1.000000)
					( Origin gBackEnd )
				)
				( member ( pinPairRef "@baseboard_fab2_lib.baseboard_fab2(sch_1):\PP5700\") )
				( member ( pinPairRef "@baseboard_fab2_lib.baseboard_fab2(sch_1):\PP5699\") )
				( objectStatus "MG_SATA6G_P10_RX_L1" )
			)
			( matchGroup "@crescent_city_bb_fab1_lib.crescent_city_bb_fab1(sch_1):\SATA6G_P9_TX_L2\"
				( memberType ( signal ) )
				( attribute "RELATIVE_PROPAGATION_DELAY_SCOPE" "G"
					( Parent
						( matchGroupRef "@crescent_city_bb_fab1_lib.crescent_city_bb_fab1(sch_1):\SATA6G_P9_TX_L2\" )
					)
					( Origin gBackEnd )
				)
				( attribute "RELATIVE_PROPAGATION_DELAY_PATH_TYPE" "AD:AR"
					( Parent
						( matchGroupRef "@crescent_city_bb_fab1_lib.crescent_city_bb_fab1(sch_1):\SATA6G_P9_TX_L2\" )
					)
					( Origin gBackEnd )
				)
				( attribute "RELATIVE_PROPAGATION_DELAY" ",5.00 MIL"
					( Parent
						( matchGroupRef "@crescent_city_bb_fab1_lib.crescent_city_bb_fab1(sch_1):\SATA6G_P9_TX_L2\" )
					)
					( Units "uMatchProp" "ns" 1.000000)
					( Origin gBackEnd )
				)
				( member ( pinPairRef "@baseboard_fab2_lib.baseboard_fab2(sch_1):\PP5726\") )
				( member ( pinPairRef "@baseboard_fab2_lib.baseboard_fab2(sch_1):\PP5729\") )
				( objectStatus "MG_SATA6G_P9_TX_L2" )
			)
			( matchGroup "@crescent_city_bb_fab1_lib.crescent_city_bb_fab1(sch_1):\SATA6G_P9_TX_L1\"
				( memberType ( signal ) )
				( attribute "RELATIVE_PROPAGATION_DELAY_SCOPE" "G"
					( Parent
						( matchGroupRef "@crescent_city_bb_fab1_lib.crescent_city_bb_fab1(sch_1):\SATA6G_P9_TX_L1\" )
					)
					( Origin gBackEnd )
				)
				( attribute "RELATIVE_PROPAGATION_DELAY_PATH_TYPE" "AD:AR"
					( Parent
						( matchGroupRef "@crescent_city_bb_fab1_lib.crescent_city_bb_fab1(sch_1):\SATA6G_P9_TX_L1\" )
					)
					( Origin gBackEnd )
				)
				( attribute "RELATIVE_PROPAGATION_DELAY" ",5.00 MIL"
					( Parent
						( matchGroupRef "@crescent_city_bb_fab1_lib.crescent_city_bb_fab1(sch_1):\SATA6G_P9_TX_L1\" )
					)
					( Units "uMatchProp" "ns" 1.000000)
					( Origin gBackEnd )
				)
				( member ( pinPairRef "@baseboard_fab2_lib.baseboard_fab2(sch_1):\PP5728\") )
				( member ( pinPairRef "@baseboard_fab2_lib.baseboard_fab2(sch_1):\PP5727\") )
				( objectStatus "MG_SATA6G_P9_TX_L1" )
			)
			( matchGroup "@crescent_city_bb_fab1_lib.crescent_city_bb_fab1(sch_1):\SATA6G_P9_RX_L2\"
				( memberType ( signal ) )
				( attribute "RELATIVE_PROPAGATION_DELAY_SCOPE" "G"
					( Parent
						( matchGroupRef "@crescent_city_bb_fab1_lib.crescent_city_bb_fab1(sch_1):\SATA6G_P9_RX_L2\" )
					)
					( Origin gBackEnd )
				)
				( attribute "RELATIVE_PROPAGATION_DELAY_PATH_TYPE" "AD:AR"
					( Parent
						( matchGroupRef "@crescent_city_bb_fab1_lib.crescent_city_bb_fab1(sch_1):\SATA6G_P9_RX_L2\" )
					)
					( Origin gBackEnd )
				)
				( attribute "RELATIVE_PROPAGATION_DELAY" ",5.00 MIL"
					( Parent
						( matchGroupRef "@crescent_city_bb_fab1_lib.crescent_city_bb_fab1(sch_1):\SATA6G_P9_RX_L2\" )
					)
					( Units "uMatchProp" "ns" 1.000000)
					( Origin gBackEnd )
				)
				( member ( pinPairRef "@baseboard_fab2_lib.baseboard_fab2(sch_1):\PP5722\") )
				( member ( pinPairRef "@baseboard_fab2_lib.baseboard_fab2(sch_1):\PP5725\") )
				( objectStatus "MG_SATA6G_P9_RX_L2" )
			)
			( matchGroup "@crescent_city_bb_fab1_lib.crescent_city_bb_fab1(sch_1):\SATA6G_P9_RX_L1\"
				( memberType ( signal ) )
				( attribute "RELATIVE_PROPAGATION_DELAY_SCOPE" "G"
					( Parent
						( matchGroupRef "@crescent_city_bb_fab1_lib.crescent_city_bb_fab1(sch_1):\SATA6G_P9_RX_L1\" )
					)
					( Origin gBackEnd )
				)
				( attribute "RELATIVE_PROPAGATION_DELAY_PATH_TYPE" "AD:AR"
					( Parent
						( matchGroupRef "@crescent_city_bb_fab1_lib.crescent_city_bb_fab1(sch_1):\SATA6G_P9_RX_L1\" )
					)
					( Origin gBackEnd )
				)
				( attribute "RELATIVE_PROPAGATION_DELAY" ",5.00 MIL"
					( Parent
						( matchGroupRef "@crescent_city_bb_fab1_lib.crescent_city_bb_fab1(sch_1):\SATA6G_P9_RX_L1\" )
					)
					( Units "uMatchProp" "ns" 1.000000)
					( Origin gBackEnd )
				)
				( member ( pinPairRef "@baseboard_fab2_lib.baseboard_fab2(sch_1):\PP5724\") )
				( member ( pinPairRef "@baseboard_fab2_lib.baseboard_fab2(sch_1):\PP5723\") )
				( objectStatus "MG_SATA6G_P9_RX_L1" )
			)
			( matchGroup "@crescent_city_bb_fab1_lib.crescent_city_bb_fab1(sch_1):\SATA6G_P8_TX_L2\"
				( memberType ( signal ) )
				( attribute "RELATIVE_PROPAGATION_DELAY_SCOPE" "G"
					( Parent
						( matchGroupRef "@crescent_city_bb_fab1_lib.crescent_city_bb_fab1(sch_1):\SATA6G_P8_TX_L2\" )
					)
					( Origin gBackEnd )
				)
				( attribute "RELATIVE_PROPAGATION_DELAY_PATH_TYPE" "AD:AR"
					( Parent
						( matchGroupRef "@crescent_city_bb_fab1_lib.crescent_city_bb_fab1(sch_1):\SATA6G_P8_TX_L2\" )
					)
					( Origin gBackEnd )
				)
				( attribute "RELATIVE_PROPAGATION_DELAY" ",5.00 MIL"
					( Parent
						( matchGroupRef "@crescent_city_bb_fab1_lib.crescent_city_bb_fab1(sch_1):\SATA6G_P8_TX_L2\" )
					)
					( Units "uMatchProp" "ns" 1.000000)
					( Origin gBackEnd )
				)
				( member ( pinPairRef "@baseboard_fab2_lib.baseboard_fab2(sch_1):\PP5718\") )
				( member ( pinPairRef "@baseboard_fab2_lib.baseboard_fab2(sch_1):\PP5721\") )
				( objectStatus "MG_SATA6G_P8_TX_L2" )
			)
			( matchGroup "@crescent_city_bb_fab1_lib.crescent_city_bb_fab1(sch_1):\SATA6G_P8_TX_L1\"
				( memberType ( signal ) )
				( attribute "RELATIVE_PROPAGATION_DELAY_SCOPE" "G"
					( Parent
						( matchGroupRef "@crescent_city_bb_fab1_lib.crescent_city_bb_fab1(sch_1):\SATA6G_P8_TX_L1\" )
					)
					( Origin gBackEnd )
				)
				( attribute "RELATIVE_PROPAGATION_DELAY_PATH_TYPE" "AD:AR"
					( Parent
						( matchGroupRef "@crescent_city_bb_fab1_lib.crescent_city_bb_fab1(sch_1):\SATA6G_P8_TX_L1\" )
					)
					( Origin gBackEnd )
				)
				( attribute "RELATIVE_PROPAGATION_DELAY" ",5.00 MIL"
					( Parent
						( matchGroupRef "@crescent_city_bb_fab1_lib.crescent_city_bb_fab1(sch_1):\SATA6G_P8_TX_L1\" )
					)
					( Units "uMatchProp" "ns" 1.000000)
					( Origin gBackEnd )
				)
				( member ( pinPairRef "@baseboard_fab2_lib.baseboard_fab2(sch_1):\PP5720\") )
				( member ( pinPairRef "@baseboard_fab2_lib.baseboard_fab2(sch_1):\PP5719\") )
				( objectStatus "MG_SATA6G_P8_TX_L1" )
			)
			( matchGroup "@crescent_city_bb_fab1_lib.crescent_city_bb_fab1(sch_1):\SATA6G_P8_RX_L2\"
				( memberType ( signal ) )
				( attribute "RELATIVE_PROPAGATION_DELAY_SCOPE" "G"
					( Parent
						( matchGroupRef "@crescent_city_bb_fab1_lib.crescent_city_bb_fab1(sch_1):\SATA6G_P8_RX_L2\" )
					)
					( Origin gBackEnd )
				)
				( attribute "RELATIVE_PROPAGATION_DELAY_PATH_TYPE" "AD:AR"
					( Parent
						( matchGroupRef "@crescent_city_bb_fab1_lib.crescent_city_bb_fab1(sch_1):\SATA6G_P8_RX_L2\" )
					)
					( Origin gBackEnd )
				)
				( attribute "RELATIVE_PROPAGATION_DELAY" ",5.00 MIL"
					( Parent
						( matchGroupRef "@crescent_city_bb_fab1_lib.crescent_city_bb_fab1(sch_1):\SATA6G_P8_RX_L2\" )
					)
					( Units "uMatchProp" "ns" 1.000000)
					( Origin gBackEnd )
				)
				( member ( pinPairRef "@baseboard_fab2_lib.baseboard_fab2(sch_1):\PP5714\") )
				( member ( pinPairRef "@baseboard_fab2_lib.baseboard_fab2(sch_1):\PP5717\") )
				( objectStatus "MG_SATA6G_P8_RX_L2" )
			)
			( matchGroup "@crescent_city_bb_fab1_lib.crescent_city_bb_fab1(sch_1):\SATA6G_P8_RX_L1\"
				( memberType ( signal ) )
				( attribute "RELATIVE_PROPAGATION_DELAY_SCOPE" "G"
					( Parent
						( matchGroupRef "@crescent_city_bb_fab1_lib.crescent_city_bb_fab1(sch_1):\SATA6G_P8_RX_L1\" )
					)
					( Origin gBackEnd )
				)
				( attribute "RELATIVE_PROPAGATION_DELAY_PATH_TYPE" "AD:AR"
					( Parent
						( matchGroupRef "@crescent_city_bb_fab1_lib.crescent_city_bb_fab1(sch_1):\SATA6G_P8_RX_L1\" )
					)
					( Origin gBackEnd )
				)
				( attribute "RELATIVE_PROPAGATION_DELAY" ",5.00 MIL"
					( Parent
						( matchGroupRef "@crescent_city_bb_fab1_lib.crescent_city_bb_fab1(sch_1):\SATA6G_P8_RX_L1\" )
					)
					( Units "uMatchProp" "ns" 1.000000)
					( Origin gBackEnd )
				)
				( member ( pinPairRef "@baseboard_fab2_lib.baseboard_fab2(sch_1):\PP5716\") )
				( member ( pinPairRef "@baseboard_fab2_lib.baseboard_fab2(sch_1):\PP5715\") )
				( objectStatus "MG_SATA6G_P8_RX_L1" )
			)
			( matchGroup "@crescent_city_bb_fab1_lib.crescent_city_bb_fab1(sch_1):\SATA6G_P7_TX_L2\"
				( memberType ( signal ) )
				( attribute "RELATIVE_PROPAGATION_DELAY_SCOPE" "G"
					( Parent
						( matchGroupRef "@crescent_city_bb_fab1_lib.crescent_city_bb_fab1(sch_1):\SATA6G_P7_TX_L2\" )
					)
					( Origin gBackEnd )
				)
				( attribute "RELATIVE_PROPAGATION_DELAY_PATH_TYPE" "AD:AR"
					( Parent
						( matchGroupRef "@crescent_city_bb_fab1_lib.crescent_city_bb_fab1(sch_1):\SATA6G_P7_TX_L2\" )
					)
					( Origin gBackEnd )
				)
				( attribute "RELATIVE_PROPAGATION_DELAY" ",5.00 MIL"
					( Parent
						( matchGroupRef "@crescent_city_bb_fab1_lib.crescent_city_bb_fab1(sch_1):\SATA6G_P7_TX_L2\" )
					)
					( Units "uMatchProp" "ns" 1.000000)
					( Origin gBackEnd )
				)
				( member ( pinPairRef "@baseboard_fab2_lib.baseboard_fab2(sch_1):\PP5758\") )
				( member ( pinPairRef "@baseboard_fab2_lib.baseboard_fab2(sch_1):\PP5761\") )
				( objectStatus "MG_SATA6G_P7_TX_L2" )
			)
			( matchGroup "@crescent_city_bb_fab1_lib.crescent_city_bb_fab1(sch_1):\SATA6G_P7_TX_L1\"
				( memberType ( signal ) )
				( attribute "RELATIVE_PROPAGATION_DELAY_SCOPE" "G"
					( Parent
						( matchGroupRef "@crescent_city_bb_fab1_lib.crescent_city_bb_fab1(sch_1):\SATA6G_P7_TX_L1\" )
					)
					( Origin gBackEnd )
				)
				( attribute "RELATIVE_PROPAGATION_DELAY_PATH_TYPE" "AD:AR"
					( Parent
						( matchGroupRef "@crescent_city_bb_fab1_lib.crescent_city_bb_fab1(sch_1):\SATA6G_P7_TX_L1\" )
					)
					( Origin gBackEnd )
				)
				( attribute "RELATIVE_PROPAGATION_DELAY" ",5.00 MIL"
					( Parent
						( matchGroupRef "@crescent_city_bb_fab1_lib.crescent_city_bb_fab1(sch_1):\SATA6G_P7_TX_L1\" )
					)
					( Units "uMatchProp" "ns" 1.000000)
					( Origin gBackEnd )
				)
				( member ( pinPairRef "@baseboard_fab2_lib.baseboard_fab2(sch_1):\PP5760\") )
				( member ( pinPairRef "@baseboard_fab2_lib.baseboard_fab2(sch_1):\PP5759\") )
				( objectStatus "MG_SATA6G_P7_TX_L1" )
			)
			( matchGroup "@crescent_city_bb_fab1_lib.crescent_city_bb_fab1(sch_1):\SATA6G_P7_RX_L2\"
				( memberType ( signal ) )
				( attribute "RELATIVE_PROPAGATION_DELAY_SCOPE" "G"
					( Parent
						( matchGroupRef "@crescent_city_bb_fab1_lib.crescent_city_bb_fab1(sch_1):\SATA6G_P7_RX_L2\" )
					)
					( Origin gBackEnd )
				)
				( attribute "RELATIVE_PROPAGATION_DELAY_PATH_TYPE" "AD:AR"
					( Parent
						( matchGroupRef "@crescent_city_bb_fab1_lib.crescent_city_bb_fab1(sch_1):\SATA6G_P7_RX_L2\" )
					)
					( Origin gBackEnd )
				)
				( attribute "RELATIVE_PROPAGATION_DELAY" ",5.00 MIL"
					( Parent
						( matchGroupRef "@crescent_city_bb_fab1_lib.crescent_city_bb_fab1(sch_1):\SATA6G_P7_RX_L2\" )
					)
					( Units "uMatchProp" "ns" 1.000000)
					( Origin gBackEnd )
				)
				( member ( pinPairRef "@baseboard_fab2_lib.baseboard_fab2(sch_1):\PP5791\") )
				( member ( pinPairRef "@baseboard_fab2_lib.baseboard_fab2(sch_1):\PP5792\") )
				( objectStatus "MG_SATA6G_P7_RX_L2" )
			)
			( matchGroup "@crescent_city_bb_fab1_lib.crescent_city_bb_fab1(sch_1):\SATA6G_P7_RX_L1\"
				( memberType ( signal ) )
				( attribute "RELATIVE_PROPAGATION_DELAY_SCOPE" "G"
					( Parent
						( matchGroupRef "@crescent_city_bb_fab1_lib.crescent_city_bb_fab1(sch_1):\SATA6G_P7_RX_L1\" )
					)
					( Origin gBackEnd )
				)
				( attribute "RELATIVE_PROPAGATION_DELAY_PATH_TYPE" "AD:AR"
					( Parent
						( matchGroupRef "@crescent_city_bb_fab1_lib.crescent_city_bb_fab1(sch_1):\SATA6G_P7_RX_L1\" )
					)
					( Origin gBackEnd )
				)
				( attribute "RELATIVE_PROPAGATION_DELAY" ",5.00 MIL"
					( Parent
						( matchGroupRef "@crescent_city_bb_fab1_lib.crescent_city_bb_fab1(sch_1):\SATA6G_P7_RX_L1\" )
					)
					( Units "uMatchProp" "ns" 1.000000)
					( Origin gBackEnd )
				)
				( member ( pinPairRef "@baseboard_fab2_lib.baseboard_fab2(sch_1):\PP5793\") )
				( member ( pinPairRef "@baseboard_fab2_lib.baseboard_fab2(sch_1):\PP5790\") )
				( objectStatus "MG_SATA6G_P7_RX_L1" )
			)
			( matchGroup "@crescent_city_bb_fab1_lib.crescent_city_bb_fab1(sch_1):\SATA6G_P6_TX_L2\"
				( memberType ( signal ) )
				( attribute "RELATIVE_PROPAGATION_DELAY_SCOPE" "G"
					( Parent
						( matchGroupRef "@crescent_city_bb_fab1_lib.crescent_city_bb_fab1(sch_1):\SATA6G_P6_TX_L2\" )
					)
					( Origin gBackEnd )
				)
				( attribute "RELATIVE_PROPAGATION_DELAY_PATH_TYPE" "AD:AR"
					( Parent
						( matchGroupRef "@crescent_city_bb_fab1_lib.crescent_city_bb_fab1(sch_1):\SATA6G_P6_TX_L2\" )
					)
					( Origin gBackEnd )
				)
				( attribute "RELATIVE_PROPAGATION_DELAY" ",5.00 MIL"
					( Parent
						( matchGroupRef "@crescent_city_bb_fab1_lib.crescent_city_bb_fab1(sch_1):\SATA6G_P6_TX_L2\" )
					)
					( Units "uMatchProp" "ns" 1.000000)
					( Origin gBackEnd )
				)
				( member ( pinPairRef "@baseboard_fab2_lib.baseboard_fab2(sch_1):\PP5754\") )
				( member ( pinPairRef "@baseboard_fab2_lib.baseboard_fab2(sch_1):\PP5757\") )
				( objectStatus "MG_SATA6G_P6_TX_L2" )
			)
			( matchGroup "@crescent_city_bb_fab1_lib.crescent_city_bb_fab1(sch_1):\SATA6G_P6_TX_L1\"
				( memberType ( signal ) )
				( attribute "RELATIVE_PROPAGATION_DELAY_SCOPE" "G"
					( Parent
						( matchGroupRef "@crescent_city_bb_fab1_lib.crescent_city_bb_fab1(sch_1):\SATA6G_P6_TX_L1\" )
					)
					( Origin gBackEnd )
				)
				( attribute "RELATIVE_PROPAGATION_DELAY_PATH_TYPE" "AD:AR"
					( Parent
						( matchGroupRef "@crescent_city_bb_fab1_lib.crescent_city_bb_fab1(sch_1):\SATA6G_P6_TX_L1\" )
					)
					( Origin gBackEnd )
				)
				( attribute "RELATIVE_PROPAGATION_DELAY" ",5.00 MIL"
					( Parent
						( matchGroupRef "@crescent_city_bb_fab1_lib.crescent_city_bb_fab1(sch_1):\SATA6G_P6_TX_L1\" )
					)
					( Units "uMatchProp" "ns" 1.000000)
					( Origin gBackEnd )
				)
				( member ( pinPairRef "@baseboard_fab2_lib.baseboard_fab2(sch_1):\PP5756\") )
				( member ( pinPairRef "@baseboard_fab2_lib.baseboard_fab2(sch_1):\PP5755\") )
				( objectStatus "MG_SATA6G_P6_TX_L1" )
			)
			( matchGroup "@crescent_city_bb_fab1_lib.crescent_city_bb_fab1(sch_1):\SATA6G_P6_RX_L2\"
				( memberType ( signal ) )
				( attribute "RELATIVE_PROPAGATION_DELAY_SCOPE" "G"
					( Parent
						( matchGroupRef "@crescent_city_bb_fab1_lib.crescent_city_bb_fab1(sch_1):\SATA6G_P6_RX_L2\" )
					)
					( Origin gBackEnd )
				)
				( attribute "RELATIVE_PROPAGATION_DELAY_PATH_TYPE" "AD:AR"
					( Parent
						( matchGroupRef "@crescent_city_bb_fab1_lib.crescent_city_bb_fab1(sch_1):\SATA6G_P6_RX_L2\" )
					)
					( Origin gBackEnd )
				)
				( attribute "RELATIVE_PROPAGATION_DELAY" ",5.00 MIL"
					( Parent
						( matchGroupRef "@crescent_city_bb_fab1_lib.crescent_city_bb_fab1(sch_1):\SATA6G_P6_RX_L2\" )
					)
					( Units "uMatchProp" "ns" 1.000000)
					( Origin gBackEnd )
				)
				( member ( pinPairRef "@baseboard_fab2_lib.baseboard_fab2(sch_1):\PP5788\") )
				( member ( pinPairRef "@baseboard_fab2_lib.baseboard_fab2(sch_1):\PP5787\") )
				( objectStatus "MG_SATA6G_P6_RX_L2" )
			)
			( matchGroup "@crescent_city_bb_fab1_lib.crescent_city_bb_fab1(sch_1):\SATA6G_P6_RX_L1\"
				( memberType ( signal ) )
				( attribute "RELATIVE_PROPAGATION_DELAY_SCOPE" "G"
					( Parent
						( matchGroupRef "@crescent_city_bb_fab1_lib.crescent_city_bb_fab1(sch_1):\SATA6G_P6_RX_L1\" )
					)
					( Origin gBackEnd )
				)
				( attribute "RELATIVE_PROPAGATION_DELAY_PATH_TYPE" "AD:AR"
					( Parent
						( matchGroupRef "@crescent_city_bb_fab1_lib.crescent_city_bb_fab1(sch_1):\SATA6G_P6_RX_L1\" )
					)
					( Origin gBackEnd )
				)
				( attribute "RELATIVE_PROPAGATION_DELAY" ",5.00 MIL"
					( Parent
						( matchGroupRef "@crescent_city_bb_fab1_lib.crescent_city_bb_fab1(sch_1):\SATA6G_P6_RX_L1\" )
					)
					( Units "uMatchProp" "ns" 1.000000)
					( Origin gBackEnd )
				)
				( member ( pinPairRef "@baseboard_fab2_lib.baseboard_fab2(sch_1):\PP5789\") )
				( member ( pinPairRef "@baseboard_fab2_lib.baseboard_fab2(sch_1):\PP5786\") )
				( objectStatus "MG_SATA6G_P6_RX_L1" )
			)
			( matchGroup "@crescent_city_bb_fab1_lib.crescent_city_bb_fab1(sch_1):\SATA6G_P5_TX_L2\"
				( memberType ( signal ) )
				( attribute "RELATIVE_PROPAGATION_DELAY_SCOPE" "G"
					( Parent
						( matchGroupRef "@crescent_city_bb_fab1_lib.crescent_city_bb_fab1(sch_1):\SATA6G_P5_TX_L2\" )
					)
					( Origin gBackEnd )
				)
				( attribute "RELATIVE_PROPAGATION_DELAY_PATH_TYPE" "AD:AR"
					( Parent
						( matchGroupRef "@crescent_city_bb_fab1_lib.crescent_city_bb_fab1(sch_1):\SATA6G_P5_TX_L2\" )
					)
					( Origin gBackEnd )
				)
				( attribute "RELATIVE_PROPAGATION_DELAY" ",5.00 MIL"
					( Parent
						( matchGroupRef "@crescent_city_bb_fab1_lib.crescent_city_bb_fab1(sch_1):\SATA6G_P5_TX_L2\" )
					)
					( Units "uMatchProp" "ns" 1.000000)
					( Origin gBackEnd )
				)
				( member ( pinPairRef "@baseboard_fab2_lib.baseboard_fab2(sch_1):\PP5750\") )
				( member ( pinPairRef "@baseboard_fab2_lib.baseboard_fab2(sch_1):\PP5753\") )
				( objectStatus "MG_SATA6G_P5_TX_L2" )
			)
			( matchGroup "@crescent_city_bb_fab1_lib.crescent_city_bb_fab1(sch_1):\SATA6G_P5_TX_L1\"
				( memberType ( signal ) )
				( attribute "RELATIVE_PROPAGATION_DELAY_SCOPE" "G"
					( Parent
						( matchGroupRef "@crescent_city_bb_fab1_lib.crescent_city_bb_fab1(sch_1):\SATA6G_P5_TX_L1\" )
					)
					( Origin gBackEnd )
				)
				( attribute "RELATIVE_PROPAGATION_DELAY_PATH_TYPE" "AD:AR"
					( Parent
						( matchGroupRef "@crescent_city_bb_fab1_lib.crescent_city_bb_fab1(sch_1):\SATA6G_P5_TX_L1\" )
					)
					( Origin gBackEnd )
				)
				( attribute "RELATIVE_PROPAGATION_DELAY" ",5.00 MIL"
					( Parent
						( matchGroupRef "@crescent_city_bb_fab1_lib.crescent_city_bb_fab1(sch_1):\SATA6G_P5_TX_L1\" )
					)
					( Units "uMatchProp" "ns" 1.000000)
					( Origin gBackEnd )
				)
				( member ( pinPairRef "@baseboard_fab2_lib.baseboard_fab2(sch_1):\PP5752\") )
				( member ( pinPairRef "@baseboard_fab2_lib.baseboard_fab2(sch_1):\PP5751\") )
				( objectStatus "MG_SATA6G_P5_TX_L1" )
			)
			( matchGroup "@crescent_city_bb_fab1_lib.crescent_city_bb_fab1(sch_1):\SATA6G_P5_RX_L2\"
				( memberType ( signal ) )
				( attribute "RELATIVE_PROPAGATION_DELAY_SCOPE" "G"
					( Parent
						( matchGroupRef "@crescent_city_bb_fab1_lib.crescent_city_bb_fab1(sch_1):\SATA6G_P5_RX_L2\" )
					)
					( Origin gBackEnd )
				)
				( attribute "RELATIVE_PROPAGATION_DELAY_PATH_TYPE" "AD:AR"
					( Parent
						( matchGroupRef "@crescent_city_bb_fab1_lib.crescent_city_bb_fab1(sch_1):\SATA6G_P5_RX_L2\" )
					)
					( Origin gBackEnd )
				)
				( attribute "RELATIVE_PROPAGATION_DELAY" ",5.00 MIL"
					( Parent
						( matchGroupRef "@crescent_city_bb_fab1_lib.crescent_city_bb_fab1(sch_1):\SATA6G_P5_RX_L2\" )
					)
					( Units "uMatchProp" "ns" 1.000000)
					( Origin gBackEnd )
				)
				( member ( pinPairRef "@baseboard_fab2_lib.baseboard_fab2(sch_1):\PP5784\") )
				( member ( pinPairRef "@baseboard_fab2_lib.baseboard_fab2(sch_1):\PP5783\") )
				( objectStatus "MG_SATA6G_P5_RX_L2" )
			)
			( matchGroup "@crescent_city_bb_fab1_lib.crescent_city_bb_fab1(sch_1):\SATA6G_P5_RX_L1\"
				( memberType ( signal ) )
				( attribute "RELATIVE_PROPAGATION_DELAY_SCOPE" "G"
					( Parent
						( matchGroupRef "@crescent_city_bb_fab1_lib.crescent_city_bb_fab1(sch_1):\SATA6G_P5_RX_L1\" )
					)
					( Origin gBackEnd )
				)
				( attribute "RELATIVE_PROPAGATION_DELAY_PATH_TYPE" "AD:AR"
					( Parent
						( matchGroupRef "@crescent_city_bb_fab1_lib.crescent_city_bb_fab1(sch_1):\SATA6G_P5_RX_L1\" )
					)
					( Origin gBackEnd )
				)
				( attribute "RELATIVE_PROPAGATION_DELAY" ",5.00 MIL"
					( Parent
						( matchGroupRef "@crescent_city_bb_fab1_lib.crescent_city_bb_fab1(sch_1):\SATA6G_P5_RX_L1\" )
					)
					( Units "uMatchProp" "ns" 1.000000)
					( Origin gBackEnd )
				)
				( member ( pinPairRef "@baseboard_fab2_lib.baseboard_fab2(sch_1):\PP5785\") )
				( member ( pinPairRef "@baseboard_fab2_lib.baseboard_fab2(sch_1):\PP5782\") )
				( objectStatus "MG_SATA6G_P5_RX_L1" )
			)
			( matchGroup "@crescent_city_bb_fab1_lib.crescent_city_bb_fab1(sch_1):\SATA6G_P4_TX_L2\"
				( memberType ( signal ) )
				( attribute "RELATIVE_PROPAGATION_DELAY_SCOPE" "G"
					( Parent
						( matchGroupRef "@crescent_city_bb_fab1_lib.crescent_city_bb_fab1(sch_1):\SATA6G_P4_TX_L2\" )
					)
					( Origin gBackEnd )
				)
				( attribute "RELATIVE_PROPAGATION_DELAY_PATH_TYPE" "AD:AR"
					( Parent
						( matchGroupRef "@crescent_city_bb_fab1_lib.crescent_city_bb_fab1(sch_1):\SATA6G_P4_TX_L2\" )
					)
					( Origin gBackEnd )
				)
				( attribute "RELATIVE_PROPAGATION_DELAY" ",5.00 MIL"
					( Parent
						( matchGroupRef "@crescent_city_bb_fab1_lib.crescent_city_bb_fab1(sch_1):\SATA6G_P4_TX_L2\" )
					)
					( Units "uMatchProp" "ns" 1.000000)
					( Origin gBackEnd )
				)
				( member ( pinPairRef "@baseboard_fab2_lib.baseboard_fab2(sch_1):\PP5746\") )
				( member ( pinPairRef "@baseboard_fab2_lib.baseboard_fab2(sch_1):\PP5749\") )
				( objectStatus "MG_SATA6G_P4_TX_L2" )
			)
			( matchGroup "@crescent_city_bb_fab1_lib.crescent_city_bb_fab1(sch_1):\SATA6G_P4_TX_L1\"
				( memberType ( signal ) )
				( attribute "RELATIVE_PROPAGATION_DELAY_SCOPE" "G"
					( Parent
						( matchGroupRef "@crescent_city_bb_fab1_lib.crescent_city_bb_fab1(sch_1):\SATA6G_P4_TX_L1\" )
					)
					( Origin gBackEnd )
				)
				( attribute "RELATIVE_PROPAGATION_DELAY_PATH_TYPE" "AD:AR"
					( Parent
						( matchGroupRef "@crescent_city_bb_fab1_lib.crescent_city_bb_fab1(sch_1):\SATA6G_P4_TX_L1\" )
					)
					( Origin gBackEnd )
				)
				( attribute "RELATIVE_PROPAGATION_DELAY" ",5.00 MIL"
					( Parent
						( matchGroupRef "@crescent_city_bb_fab1_lib.crescent_city_bb_fab1(sch_1):\SATA6G_P4_TX_L1\" )
					)
					( Units "uMatchProp" "ns" 1.000000)
					( Origin gBackEnd )
				)
				( member ( pinPairRef "@baseboard_fab2_lib.baseboard_fab2(sch_1):\PP5748\") )
				( member ( pinPairRef "@baseboard_fab2_lib.baseboard_fab2(sch_1):\PP5747\") )
				( objectStatus "MG_SATA6G_P4_TX_L1" )
			)
			( matchGroup "@crescent_city_bb_fab1_lib.crescent_city_bb_fab1(sch_1):\SATA6G_P4_RX_L2\"
				( memberType ( signal ) )
				( attribute "RELATIVE_PROPAGATION_DELAY_SCOPE" "G"
					( Parent
						( matchGroupRef "@crescent_city_bb_fab1_lib.crescent_city_bb_fab1(sch_1):\SATA6G_P4_RX_L2\" )
					)
					( Origin gBackEnd )
				)
				( attribute "RELATIVE_PROPAGATION_DELAY_PATH_TYPE" "AD:AR"
					( Parent
						( matchGroupRef "@crescent_city_bb_fab1_lib.crescent_city_bb_fab1(sch_1):\SATA6G_P4_RX_L2\" )
					)
					( Origin gBackEnd )
				)
				( attribute "RELATIVE_PROPAGATION_DELAY" ",5.00 MIL"
					( Parent
						( matchGroupRef "@crescent_city_bb_fab1_lib.crescent_city_bb_fab1(sch_1):\SATA6G_P4_RX_L2\" )
					)
					( Units "uMatchProp" "ns" 1.000000)
					( Origin gBackEnd )
				)
				( member ( pinPairRef "@baseboard_fab2_lib.baseboard_fab2(sch_1):\PP5779\") )
				( member ( pinPairRef "@baseboard_fab2_lib.baseboard_fab2(sch_1):\PP5780\") )
				( objectStatus "MG_SATA6G_P4_RX_L2" )
			)
			( matchGroup "@crescent_city_bb_fab1_lib.crescent_city_bb_fab1(sch_1):\SATA6G_P4_RX_L1\"
				( memberType ( signal ) )
				( attribute "RELATIVE_PROPAGATION_DELAY_SCOPE" "G"
					( Parent
						( matchGroupRef "@crescent_city_bb_fab1_lib.crescent_city_bb_fab1(sch_1):\SATA6G_P4_RX_L1\" )
					)
					( Origin gBackEnd )
				)
				( attribute "RELATIVE_PROPAGATION_DELAY_PATH_TYPE" "AD:AR"
					( Parent
						( matchGroupRef "@crescent_city_bb_fab1_lib.crescent_city_bb_fab1(sch_1):\SATA6G_P4_RX_L1\" )
					)
					( Origin gBackEnd )
				)
				( attribute "RELATIVE_PROPAGATION_DELAY" ",5.00 MIL"
					( Parent
						( matchGroupRef "@crescent_city_bb_fab1_lib.crescent_city_bb_fab1(sch_1):\SATA6G_P4_RX_L1\" )
					)
					( Units "uMatchProp" "ns" 1.000000)
					( Origin gBackEnd )
				)
				( member ( pinPairRef "@baseboard_fab2_lib.baseboard_fab2(sch_1):\PP5781\") )
				( member ( pinPairRef "@baseboard_fab2_lib.baseboard_fab2(sch_1):\PP5778\") )
				( objectStatus "MG_SATA6G_P4_RX_L1" )
			)
			( matchGroup "@crescent_city_bb_fab1_lib.crescent_city_bb_fab1(sch_1):\SATA6G_P3_TX_L2\"
				( memberType ( signal ) )
				( attribute "RELATIVE_PROPAGATION_DELAY_SCOPE" "G"
					( Parent
						( matchGroupRef "@crescent_city_bb_fab1_lib.crescent_city_bb_fab1(sch_1):\SATA6G_P3_TX_L2\" )
					)
					( Origin gBackEnd )
				)
				( attribute "RELATIVE_PROPAGATION_DELAY_PATH_TYPE" "AD:AR"
					( Parent
						( matchGroupRef "@crescent_city_bb_fab1_lib.crescent_city_bb_fab1(sch_1):\SATA6G_P3_TX_L2\" )
					)
					( Origin gBackEnd )
				)
				( attribute "RELATIVE_PROPAGATION_DELAY" ",5.00 MIL"
					( Parent
						( matchGroupRef "@crescent_city_bb_fab1_lib.crescent_city_bb_fab1(sch_1):\SATA6G_P3_TX_L2\" )
					)
					( Units "uMatchProp" "ns" 1.000000)
					( Origin gBackEnd )
				)
				( member ( pinPairRef "@baseboard_fab2_lib.baseboard_fab2(sch_1):\PP5742\") )
				( member ( pinPairRef "@baseboard_fab2_lib.baseboard_fab2(sch_1):\PP5745\") )
				( objectStatus "MG_SATA6G_P3_TX_L2" )
			)
			( matchGroup "@crescent_city_bb_fab1_lib.crescent_city_bb_fab1(sch_1):\SATA6G_P3_TX_L1\"
				( memberType ( signal ) )
				( attribute "RELATIVE_PROPAGATION_DELAY_SCOPE" "G"
					( Parent
						( matchGroupRef "@crescent_city_bb_fab1_lib.crescent_city_bb_fab1(sch_1):\SATA6G_P3_TX_L1\" )
					)
					( Origin gBackEnd )
				)
				( attribute "RELATIVE_PROPAGATION_DELAY_PATH_TYPE" "AD:AR"
					( Parent
						( matchGroupRef "@crescent_city_bb_fab1_lib.crescent_city_bb_fab1(sch_1):\SATA6G_P3_TX_L1\" )
					)
					( Origin gBackEnd )
				)
				( attribute "RELATIVE_PROPAGATION_DELAY" ",5.00 MIL"
					( Parent
						( matchGroupRef "@crescent_city_bb_fab1_lib.crescent_city_bb_fab1(sch_1):\SATA6G_P3_TX_L1\" )
					)
					( Units "uMatchProp" "ns" 1.000000)
					( Origin gBackEnd )
				)
				( member ( pinPairRef "@baseboard_fab2_lib.baseboard_fab2(sch_1):\PP5744\") )
				( member ( pinPairRef "@baseboard_fab2_lib.baseboard_fab2(sch_1):\PP5743\") )
				( objectStatus "MG_SATA6G_P3_TX_L1" )
			)
			( matchGroup "@crescent_city_bb_fab1_lib.crescent_city_bb_fab1(sch_1):\SATA6G_P3_RX_L2\"
				( memberType ( signal ) )
				( attribute "RELATIVE_PROPAGATION_DELAY_SCOPE" "G"
					( Parent
						( matchGroupRef "@crescent_city_bb_fab1_lib.crescent_city_bb_fab1(sch_1):\SATA6G_P3_RX_L2\" )
					)
					( Origin gBackEnd )
				)
				( attribute "RELATIVE_PROPAGATION_DELAY_PATH_TYPE" "AD:AR"
					( Parent
						( matchGroupRef "@crescent_city_bb_fab1_lib.crescent_city_bb_fab1(sch_1):\SATA6G_P3_RX_L2\" )
					)
					( Origin gBackEnd )
				)
				( attribute "RELATIVE_PROPAGATION_DELAY" ",5.00 MIL"
					( Parent
						( matchGroupRef "@crescent_city_bb_fab1_lib.crescent_city_bb_fab1(sch_1):\SATA6G_P3_RX_L2\" )
					)
					( Units "uMatchProp" "ns" 1.000000)
					( Origin gBackEnd )
				)
				( member ( pinPairRef "@baseboard_fab2_lib.baseboard_fab2(sch_1):\PP5776\") )
				( member ( pinPairRef "@baseboard_fab2_lib.baseboard_fab2(sch_1):\PP5775\") )
				( objectStatus "MG_SATA6G_P3_RX_L2" )
			)
			( matchGroup "@crescent_city_bb_fab1_lib.crescent_city_bb_fab1(sch_1):\SATA6G_P3_RX_L1\"
				( memberType ( signal ) )
				( attribute "RELATIVE_PROPAGATION_DELAY_SCOPE" "G"
					( Parent
						( matchGroupRef "@crescent_city_bb_fab1_lib.crescent_city_bb_fab1(sch_1):\SATA6G_P3_RX_L1\" )
					)
					( Origin gBackEnd )
				)
				( attribute "RELATIVE_PROPAGATION_DELAY_PATH_TYPE" "AD:AR"
					( Parent
						( matchGroupRef "@crescent_city_bb_fab1_lib.crescent_city_bb_fab1(sch_1):\SATA6G_P3_RX_L1\" )
					)
					( Origin gBackEnd )
				)
				( attribute "RELATIVE_PROPAGATION_DELAY" ",5.00 MIL"
					( Parent
						( matchGroupRef "@crescent_city_bb_fab1_lib.crescent_city_bb_fab1(sch_1):\SATA6G_P3_RX_L1\" )
					)
					( Units "uMatchProp" "ns" 1.000000)
					( Origin gBackEnd )
				)
				( member ( pinPairRef "@baseboard_fab2_lib.baseboard_fab2(sch_1):\PP5777\") )
				( member ( pinPairRef "@baseboard_fab2_lib.baseboard_fab2(sch_1):\PP5774\") )
				( objectStatus "MG_SATA6G_P3_RX_L1" )
			)
			( matchGroup "@crescent_city_bb_fab1_lib.crescent_city_bb_fab1(sch_1):\SATA6G_P2_TX_L2\"
				( memberType ( signal ) )
				( attribute "RELATIVE_PROPAGATION_DELAY_SCOPE" "G"
					( Parent
						( matchGroupRef "@crescent_city_bb_fab1_lib.crescent_city_bb_fab1(sch_1):\SATA6G_P2_TX_L2\" )
					)
					( Origin gBackEnd )
				)
				( attribute "RELATIVE_PROPAGATION_DELAY_PATH_TYPE" "AD:AR"
					( Parent
						( matchGroupRef "@crescent_city_bb_fab1_lib.crescent_city_bb_fab1(sch_1):\SATA6G_P2_TX_L2\" )
					)
					( Origin gBackEnd )
				)
				( attribute "RELATIVE_PROPAGATION_DELAY" ",5.00 MIL"
					( Parent
						( matchGroupRef "@crescent_city_bb_fab1_lib.crescent_city_bb_fab1(sch_1):\SATA6G_P2_TX_L2\" )
					)
					( Units "uMatchProp" "ns" 1.000000)
					( Origin gBackEnd )
				)
				( member ( pinPairRef "@baseboard_fab2_lib.baseboard_fab2(sch_1):\PP5738\") )
				( member ( pinPairRef "@baseboard_fab2_lib.baseboard_fab2(sch_1):\PP5741\") )
				( objectStatus "MG_SATA6G_P2_TX_L2" )
			)
			( matchGroup "@crescent_city_bb_fab1_lib.crescent_city_bb_fab1(sch_1):\SATA6G_P2_TX_L1\"
				( memberType ( signal ) )
				( attribute "RELATIVE_PROPAGATION_DELAY_SCOPE" "G"
					( Parent
						( matchGroupRef "@crescent_city_bb_fab1_lib.crescent_city_bb_fab1(sch_1):\SATA6G_P2_TX_L1\" )
					)
					( Origin gBackEnd )
				)
				( attribute "RELATIVE_PROPAGATION_DELAY_PATH_TYPE" "AD:AR"
					( Parent
						( matchGroupRef "@crescent_city_bb_fab1_lib.crescent_city_bb_fab1(sch_1):\SATA6G_P2_TX_L1\" )
					)
					( Origin gBackEnd )
				)
				( attribute "RELATIVE_PROPAGATION_DELAY" ",5.00 MIL"
					( Parent
						( matchGroupRef "@crescent_city_bb_fab1_lib.crescent_city_bb_fab1(sch_1):\SATA6G_P2_TX_L1\" )
					)
					( Units "uMatchProp" "ns" 1.000000)
					( Origin gBackEnd )
				)
				( member ( pinPairRef "@baseboard_fab2_lib.baseboard_fab2(sch_1):\PP5740\") )
				( member ( pinPairRef "@baseboard_fab2_lib.baseboard_fab2(sch_1):\PP5739\") )
				( objectStatus "MG_SATA6G_P2_TX_L1" )
			)
			( matchGroup "@crescent_city_bb_fab1_lib.crescent_city_bb_fab1(sch_1):\SATA6G_P2_RX_L2\"
				( memberType ( signal ) )
				( attribute "RELATIVE_PROPAGATION_DELAY_SCOPE" "G"
					( Parent
						( matchGroupRef "@crescent_city_bb_fab1_lib.crescent_city_bb_fab1(sch_1):\SATA6G_P2_RX_L2\" )
					)
					( Origin gBackEnd )
				)
				( attribute "RELATIVE_PROPAGATION_DELAY_PATH_TYPE" "AD:AR"
					( Parent
						( matchGroupRef "@crescent_city_bb_fab1_lib.crescent_city_bb_fab1(sch_1):\SATA6G_P2_RX_L2\" )
					)
					( Origin gBackEnd )
				)
				( attribute "RELATIVE_PROPAGATION_DELAY" ",5.00 MIL"
					( Parent
						( matchGroupRef "@crescent_city_bb_fab1_lib.crescent_city_bb_fab1(sch_1):\SATA6G_P2_RX_L2\" )
					)
					( Units "uMatchProp" "ns" 1.000000)
					( Origin gBackEnd )
				)
				( member ( pinPairRef "@baseboard_fab2_lib.baseboard_fab2(sch_1):\PP5772\") )
				( member ( pinPairRef "@baseboard_fab2_lib.baseboard_fab2(sch_1):\PP5771\") )
				( objectStatus "MG_SATA6G_P2_RX_L2" )
			)
			( matchGroup "@crescent_city_bb_fab1_lib.crescent_city_bb_fab1(sch_1):\SATA6G_P2_RX_L1\"
				( memberType ( signal ) )
				( attribute "RELATIVE_PROPAGATION_DELAY_SCOPE" "G"
					( Parent
						( matchGroupRef "@crescent_city_bb_fab1_lib.crescent_city_bb_fab1(sch_1):\SATA6G_P2_RX_L1\" )
					)
					( Origin gBackEnd )
				)
				( attribute "RELATIVE_PROPAGATION_DELAY_PATH_TYPE" "AD:AR"
					( Parent
						( matchGroupRef "@crescent_city_bb_fab1_lib.crescent_city_bb_fab1(sch_1):\SATA6G_P2_RX_L1\" )
					)
					( Origin gBackEnd )
				)
				( attribute "RELATIVE_PROPAGATION_DELAY" ",5.00 MIL"
					( Parent
						( matchGroupRef "@crescent_city_bb_fab1_lib.crescent_city_bb_fab1(sch_1):\SATA6G_P2_RX_L1\" )
					)
					( Units "uMatchProp" "ns" 1.000000)
					( Origin gBackEnd )
				)
				( member ( pinPairRef "@baseboard_fab2_lib.baseboard_fab2(sch_1):\PP5773\") )
				( member ( pinPairRef "@baseboard_fab2_lib.baseboard_fab2(sch_1):\PP5770\") )
				( objectStatus "MG_SATA6G_P2_RX_L1" )
			)
			( matchGroup "@crescent_city_bb_fab1_lib.crescent_city_bb_fab1(sch_1):\SATA6G_P1_TX_L2\"
				( memberType ( signal ) )
				( attribute "RELATIVE_PROPAGATION_DELAY_SCOPE" "G"
					( Parent
						( matchGroupRef "@crescent_city_bb_fab1_lib.crescent_city_bb_fab1(sch_1):\SATA6G_P1_TX_L2\" )
					)
					( Origin gBackEnd )
				)
				( attribute "RELATIVE_PROPAGATION_DELAY_PATH_TYPE" "AD:AR"
					( Parent
						( matchGroupRef "@crescent_city_bb_fab1_lib.crescent_city_bb_fab1(sch_1):\SATA6G_P1_TX_L2\" )
					)
					( Origin gBackEnd )
				)
				( attribute "RELATIVE_PROPAGATION_DELAY" ",5.00 MIL"
					( Parent
						( matchGroupRef "@crescent_city_bb_fab1_lib.crescent_city_bb_fab1(sch_1):\SATA6G_P1_TX_L2\" )
					)
					( Units "uMatchProp" "ns" 1.000000)
					( Origin gBackEnd )
				)
				( member ( pinPairRef "@baseboard_fab2_lib.baseboard_fab2(sch_1):\PP5734\") )
				( member ( pinPairRef "@baseboard_fab2_lib.baseboard_fab2(sch_1):\PP5737\") )
				( objectStatus "MG_SATA6G_P1_TX_L2" )
			)
			( matchGroup "@crescent_city_bb_fab1_lib.crescent_city_bb_fab1(sch_1):\SATA6G_P1_TX_L1\"
				( memberType ( signal ) )
				( attribute "RELATIVE_PROPAGATION_DELAY_SCOPE" "G"
					( Parent
						( matchGroupRef "@crescent_city_bb_fab1_lib.crescent_city_bb_fab1(sch_1):\SATA6G_P1_TX_L1\" )
					)
					( Origin gBackEnd )
				)
				( attribute "RELATIVE_PROPAGATION_DELAY_PATH_TYPE" "AD:AR"
					( Parent
						( matchGroupRef "@crescent_city_bb_fab1_lib.crescent_city_bb_fab1(sch_1):\SATA6G_P1_TX_L1\" )
					)
					( Origin gBackEnd )
				)
				( attribute "RELATIVE_PROPAGATION_DELAY" ",5.00 MIL"
					( Parent
						( matchGroupRef "@crescent_city_bb_fab1_lib.crescent_city_bb_fab1(sch_1):\SATA6G_P1_TX_L1\" )
					)
					( Units "uMatchProp" "ns" 1.000000)
					( Origin gBackEnd )
				)
				( member ( pinPairRef "@baseboard_fab2_lib.baseboard_fab2(sch_1):\PP5736\") )
				( member ( pinPairRef "@baseboard_fab2_lib.baseboard_fab2(sch_1):\PP5735\") )
				( objectStatus "MG_SATA6G_P1_TX_L1" )
			)
			( matchGroup "@crescent_city_bb_fab1_lib.crescent_city_bb_fab1(sch_1):\SATA6G_P1_RX_L2\"
				( memberType ( signal ) )
				( attribute "RELATIVE_PROPAGATION_DELAY_SCOPE" "G"
					( Parent
						( matchGroupRef "@crescent_city_bb_fab1_lib.crescent_city_bb_fab1(sch_1):\SATA6G_P1_RX_L2\" )
					)
					( Origin gBackEnd )
				)
				( attribute "RELATIVE_PROPAGATION_DELAY_PATH_TYPE" "AD:AR"
					( Parent
						( matchGroupRef "@crescent_city_bb_fab1_lib.crescent_city_bb_fab1(sch_1):\SATA6G_P1_RX_L2\" )
					)
					( Origin gBackEnd )
				)
				( attribute "RELATIVE_PROPAGATION_DELAY" ",5.00 MIL"
					( Parent
						( matchGroupRef "@crescent_city_bb_fab1_lib.crescent_city_bb_fab1(sch_1):\SATA6G_P1_RX_L2\" )
					)
					( Units "uMatchProp" "ns" 1.000000)
					( Origin gBackEnd )
				)
				( member ( pinPairRef "@baseboard_fab2_lib.baseboard_fab2(sch_1):\PP5767\") )
				( member ( pinPairRef "@baseboard_fab2_lib.baseboard_fab2(sch_1):\PP5768\") )
				( objectStatus "MG_SATA6G_P1_RX_L2" )
			)
			( matchGroup "@crescent_city_bb_fab1_lib.crescent_city_bb_fab1(sch_1):\SATA6G_P1_RX_L1\"
				( memberType ( signal ) )
				( attribute "RELATIVE_PROPAGATION_DELAY_SCOPE" "G"
					( Parent
						( matchGroupRef "@crescent_city_bb_fab1_lib.crescent_city_bb_fab1(sch_1):\SATA6G_P1_RX_L1\" )
					)
					( Origin gBackEnd )
				)
				( attribute "RELATIVE_PROPAGATION_DELAY_PATH_TYPE" "AD:AR"
					( Parent
						( matchGroupRef "@crescent_city_bb_fab1_lib.crescent_city_bb_fab1(sch_1):\SATA6G_P1_RX_L1\" )
					)
					( Origin gBackEnd )
				)
				( attribute "RELATIVE_PROPAGATION_DELAY" ",5.00 MIL"
					( Parent
						( matchGroupRef "@crescent_city_bb_fab1_lib.crescent_city_bb_fab1(sch_1):\SATA6G_P1_RX_L1\" )
					)
					( Units "uMatchProp" "ns" 1.000000)
					( Origin gBackEnd )
				)
				( member ( pinPairRef "@baseboard_fab2_lib.baseboard_fab2(sch_1):\PP5769\") )
				( member ( pinPairRef "@baseboard_fab2_lib.baseboard_fab2(sch_1):\PP5766\") )
				( objectStatus "MG_SATA6G_P1_RX_L1" )
			)
			( matchGroup "@crescent_city_bb_fab1_lib.crescent_city_bb_fab1(sch_1):\SATA6G_P0_TX_L2\"
				( memberType ( signal ) )
				( attribute "RELATIVE_PROPAGATION_DELAY_SCOPE" "G"
					( Parent
						( matchGroupRef "@crescent_city_bb_fab1_lib.crescent_city_bb_fab1(sch_1):\SATA6G_P0_TX_L2\" )
					)
					( Origin gBackEnd )
				)
				( attribute "RELATIVE_PROPAGATION_DELAY_PATH_TYPE" "AD:AR"
					( Parent
						( matchGroupRef "@crescent_city_bb_fab1_lib.crescent_city_bb_fab1(sch_1):\SATA6G_P0_TX_L2\" )
					)
					( Origin gBackEnd )
				)
				( attribute "RELATIVE_PROPAGATION_DELAY" ",5.00 MIL"
					( Parent
						( matchGroupRef "@crescent_city_bb_fab1_lib.crescent_city_bb_fab1(sch_1):\SATA6G_P0_TX_L2\" )
					)
					( Units "uMatchProp" "ns" 1.000000)
					( Origin gBackEnd )
				)
				( member ( pinPairRef "@baseboard_fab2_lib.baseboard_fab2(sch_1):\PP5730\") )
				( member ( pinPairRef "@baseboard_fab2_lib.baseboard_fab2(sch_1):\PP5733\") )
				( objectStatus "MG_SATA6G_P0_TX_L2" )
			)
			( matchGroup "@crescent_city_bb_fab1_lib.crescent_city_bb_fab1(sch_1):\SATA6G_P0_TX_L1\"
				( memberType ( signal ) )
				( attribute "RELATIVE_PROPAGATION_DELAY_SCOPE" "G"
					( Parent
						( matchGroupRef "@crescent_city_bb_fab1_lib.crescent_city_bb_fab1(sch_1):\SATA6G_P0_TX_L1\" )
					)
					( Origin gBackEnd )
				)
				( attribute "RELATIVE_PROPAGATION_DELAY_PATH_TYPE" "AD:AR"
					( Parent
						( matchGroupRef "@crescent_city_bb_fab1_lib.crescent_city_bb_fab1(sch_1):\SATA6G_P0_TX_L1\" )
					)
					( Origin gBackEnd )
				)
				( attribute "RELATIVE_PROPAGATION_DELAY" ",5.00 MIL"
					( Parent
						( matchGroupRef "@crescent_city_bb_fab1_lib.crescent_city_bb_fab1(sch_1):\SATA6G_P0_TX_L1\" )
					)
					( Units "uMatchProp" "ns" 1.000000)
					( Origin gBackEnd )
				)
				( member ( pinPairRef "@baseboard_fab2_lib.baseboard_fab2(sch_1):\PP5732\") )
				( member ( pinPairRef "@baseboard_fab2_lib.baseboard_fab2(sch_1):\PP5731\") )
				( objectStatus "MG_SATA6G_P0_TX_L1" )
			)
			( matchGroup "@crescent_city_bb_fab1_lib.crescent_city_bb_fab1(sch_1):\SATA6G_P0_RX_L2\"
				( memberType ( signal ) )
				( attribute "RELATIVE_PROPAGATION_DELAY_SCOPE" "G"
					( Parent
						( matchGroupRef "@crescent_city_bb_fab1_lib.crescent_city_bb_fab1(sch_1):\SATA6G_P0_RX_L2\" )
					)
					( Origin gBackEnd )
				)
				( attribute "RELATIVE_PROPAGATION_DELAY_PATH_TYPE" "AD:AR"
					( Parent
						( matchGroupRef "@crescent_city_bb_fab1_lib.crescent_city_bb_fab1(sch_1):\SATA6G_P0_RX_L2\" )
					)
					( Origin gBackEnd )
				)
				( attribute "RELATIVE_PROPAGATION_DELAY" ",5.00 MIL"
					( Parent
						( matchGroupRef "@crescent_city_bb_fab1_lib.crescent_city_bb_fab1(sch_1):\SATA6G_P0_RX_L2\" )
					)
					( Units "uMatchProp" "ns" 1.000000)
					( Origin gBackEnd )
				)
				( member ( pinPairRef "@baseboard_fab2_lib.baseboard_fab2(sch_1):\PP5763\") )
				( member ( pinPairRef "@baseboard_fab2_lib.baseboard_fab2(sch_1):\PP5764\") )
				( objectStatus "MG_SATA6G_P0_RX_L2" )
			)
			( matchGroup "@crescent_city_bb_fab1_lib.crescent_city_bb_fab1(sch_1):\SATA6G_P0_RX_L1\"
				( memberType ( signal ) )
				( attribute "RELATIVE_PROPAGATION_DELAY_SCOPE" "G"
					( Parent
						( matchGroupRef "@crescent_city_bb_fab1_lib.crescent_city_bb_fab1(sch_1):\SATA6G_P0_RX_L1\" )
					)
					( Origin gBackEnd )
				)
				( attribute "RELATIVE_PROPAGATION_DELAY_PATH_TYPE" "AD:AR"
					( Parent
						( matchGroupRef "@crescent_city_bb_fab1_lib.crescent_city_bb_fab1(sch_1):\SATA6G_P0_RX_L1\" )
					)
					( Origin gBackEnd )
				)
				( attribute "RELATIVE_PROPAGATION_DELAY" ",5.00 MIL"
					( Parent
						( matchGroupRef "@crescent_city_bb_fab1_lib.crescent_city_bb_fab1(sch_1):\SATA6G_P0_RX_L1\" )
					)
					( Units "uMatchProp" "ns" 1.000000)
					( Origin gBackEnd )
				)
				( member ( pinPairRef "@baseboard_fab2_lib.baseboard_fab2(sch_1):\PP5765\") )
				( member ( pinPairRef "@baseboard_fab2_lib.baseboard_fab2(sch_1):\PP5762\") )
				( objectStatus "MG_SATA6G_P0_RX_L1" )
			)
			( matchGroup "@crescent_city_bb_fab1_lib.crescent_city_bb_fab1(sch_1):\MG_P3E_PCH_M2_RX0001\"
				( memberType ( signal ) )
				( attribute "RELATIVE_PROPAGATION_DELAY_SCOPE" "G"
					( Parent
						( matchGroupRef "@crescent_city_bb_fab1_lib.crescent_city_bb_fab1(sch_1):\MG_P3E_PCH_M2_RX0001\" )
					)
					( Origin gBackEnd )
				)
				( attribute "RELATIVE_PROPAGATION_DELAY_PATH_TYPE" "AD:AR"
					( Parent
						( matchGroupRef "@crescent_city_bb_fab1_lib.crescent_city_bb_fab1(sch_1):\MG_P3E_PCH_M2_RX0001\" )
					)
					( Origin gBackEnd )
				)
				( attribute "RELATIVE_PROPAGATION_DELAY" ",500.00 MIL"
					( Parent
						( matchGroupRef "@crescent_city_bb_fab1_lib.crescent_city_bb_fab1(sch_1):\MG_P3E_PCH_M2_RX0001\" )
					)
					( Units "uMatchProp" "ns" 1.000000)
					( Origin gBackEnd )
				)
				( member ( signalRef "@baseboard_fab2_lib.baseboard_fab2(sch_1):p3e_pch_m2_rx_dn(1)") )
				( member ( signalRef "@baseboard_fab2_lib.baseboard_fab2(sch_1):p3e_pch_m2_rx_dp(1)") )
				( objectStatus "MG_P3E_PCH_M2_RX0001" )
			)
			( matchGroup "@crescent_city_bb_fab1_lib.crescent_city_bb_fab1(sch_1):\MG_P3E_PCH_M2_RX0203\"
				( memberType ( signal ) )
				( attribute "RELATIVE_PROPAGATION_DELAY_SCOPE" "G"
					( Parent
						( matchGroupRef "@crescent_city_bb_fab1_lib.crescent_city_bb_fab1(sch_1):\MG_P3E_PCH_M2_RX0203\" )
					)
					( Origin gBackEnd )
				)
				( attribute "RELATIVE_PROPAGATION_DELAY_PATH_TYPE" "AD:AR"
					( Parent
						( matchGroupRef "@crescent_city_bb_fab1_lib.crescent_city_bb_fab1(sch_1):\MG_P3E_PCH_M2_RX0203\" )
					)
					( Origin gBackEnd )
				)
				( attribute "RELATIVE_PROPAGATION_DELAY" ",500.00 MIL"
					( Parent
						( matchGroupRef "@crescent_city_bb_fab1_lib.crescent_city_bb_fab1(sch_1):\MG_P3E_PCH_M2_RX0203\" )
					)
					( Units "uMatchProp" "ns" 1.000000)
					( Origin gBackEnd )
				)
				( member ( signalRef "@baseboard_fab2_lib.baseboard_fab2(sch_1):p3e_pch_m2_rx_dn(2)") )
				( member ( signalRef "@baseboard_fab2_lib.baseboard_fab2(sch_1):p3e_pch_m2_rx_dn(3)") )
				( member ( signalRef "@baseboard_fab2_lib.baseboard_fab2(sch_1):p3e_pch_m2_rx_dp(2)") )
				( member ( signalRef "@baseboard_fab2_lib.baseboard_fab2(sch_1):p3e_pch_m2_rx_dp(3)") )
				( objectStatus "MG_P3E_PCH_M2_RX0203" )
			)
			( matchGroup "@crescent_city_bb_fab1_lib.crescent_city_bb_fab1(sch_1):\MG_BMC_DQ_DQS\"
				( memberType ( signal ) )
				( attribute "RELATIVE_PROPAGATION_DELAY_SCOPE" "G"
					( Parent
						( matchGroupRef "@crescent_city_bb_fab1_lib.crescent_city_bb_fab1(sch_1):\MG_BMC_DQ_DQS\" )
					)
					( Origin gBackEnd )
				)
				( attribute "RELATIVE_PROPAGATION_DELAY_PATH_TYPE" "AD:AR"
					( Parent
						( matchGroupRef "@crescent_city_bb_fab1_lib.crescent_city_bb_fab1(sch_1):\MG_BMC_DQ_DQS\" )
					)
					( Origin gBackEnd )
				)
				( attribute "RELATIVE_PROPAGATION_DELAY" ",200.00 MIL"
					( Parent
						( matchGroupRef "@crescent_city_bb_fab1_lib.crescent_city_bb_fab1(sch_1):\MG_BMC_DQ_DQS\" )
					)
					( Units "uMatchProp" "ns" 1.000000)
					( Origin gBackEnd )
				)
				( member ( signalRef "@baseboard_fab2_lib.baseboard_fab2(sch_1):m_bmc_ddr3_dq(0)") )
				( member ( signalRef "@baseboard_fab2_lib.baseboard_fab2(sch_1):m_bmc_ddr3_dq(1)") )
				( member ( signalRef "@baseboard_fab2_lib.baseboard_fab2(sch_1):m_bmc_ddr3_dq(2)") )
				( member ( signalRef "@baseboard_fab2_lib.baseboard_fab2(sch_1):m_bmc_ddr3_dq(3)") )
				( member ( signalRef "@baseboard_fab2_lib.baseboard_fab2(sch_1):m_bmc_ddr3_dq(4)") )
				( member ( signalRef "@baseboard_fab2_lib.baseboard_fab2(sch_1):m_bmc_ddr3_dq(5)") )
				( member ( signalRef "@baseboard_fab2_lib.baseboard_fab2(sch_1):m_bmc_ddr3_dq(6)") )
				( member ( signalRef "@baseboard_fab2_lib.baseboard_fab2(sch_1):m_bmc_ddr3_dq(7)") )
				( member ( signalRef "@baseboard_fab2_lib.baseboard_fab2(sch_1):m_bmc_ddr3_dq(8)") )
				( member ( signalRef "@baseboard_fab2_lib.baseboard_fab2(sch_1):m_bmc_ddr3_dq(9)") )
				( member ( signalRef "@baseboard_fab2_lib.baseboard_fab2(sch_1):m_bmc_ddr3_dq(10)") )
				( member ( signalRef "@baseboard_fab2_lib.baseboard_fab2(sch_1):m_bmc_ddr3_dq(11)") )
				( member ( signalRef "@baseboard_fab2_lib.baseboard_fab2(sch_1):m_bmc_ddr3_dq(12)") )
				( member ( signalRef "@baseboard_fab2_lib.baseboard_fab2(sch_1):m_bmc_ddr3_dq(13)") )
				( member ( signalRef "@baseboard_fab2_lib.baseboard_fab2(sch_1):m_bmc_ddr3_dq(14)") )
				( member ( signalRef "@baseboard_fab2_lib.baseboard_fab2(sch_1):m_bmc_ddr3_dq(15)") )
				( member ( signalRef "@baseboard_fab2_lib.baseboard_fab2(sch_1):m_bmc_ddr3_mdm_0") )
				( member ( signalRef "@baseboard_fab2_lib.baseboard_fab2(sch_1):m_bmc_ddr3_mdm_1") )
				( member ( signalRef "@baseboard_fab2_lib.baseboard_fab2(sch_1):m_bmc_ddr3_mdqs_0_dn") )
				( member ( signalRef "@baseboard_fab2_lib.baseboard_fab2(sch_1):m_bmc_ddr3_mdqs_0_dp") )
				( member ( signalRef "@baseboard_fab2_lib.baseboard_fab2(sch_1):m_bmc_ddr3_mdqs_1_dn") )
				( member ( signalRef "@baseboard_fab2_lib.baseboard_fab2(sch_1):m_bmc_ddr3_mdqs_1_dp") )
				( objectStatus "MG_BMC_DQS_DQ_DM" )
			)
			( matchGroup "@crescent_city_bb_fab1_lib.crescent_city_bb_fab1(sch_1):\MG_BMC_CMD_CLK\"
				( memberType ( signal ) )
				( attribute "RELATIVE_PROPAGATION_DELAY_SCOPE" "G"
					( Parent
						( matchGroupRef "@crescent_city_bb_fab1_lib.crescent_city_bb_fab1(sch_1):\MG_BMC_CMD_CLK\" )
					)
					( Origin gBackEnd )
				)
				( attribute "RELATIVE_PROPAGATION_DELAY_PATH_TYPE" "AD:AR"
					( Parent
						( matchGroupRef "@crescent_city_bb_fab1_lib.crescent_city_bb_fab1(sch_1):\MG_BMC_CMD_CLK\" )
					)
					( Origin gBackEnd )
				)
				( attribute "RELATIVE_PROPAGATION_DELAY" ",200.00 MIL"
					( Parent
						( matchGroupRef "@crescent_city_bb_fab1_lib.crescent_city_bb_fab1(sch_1):\MG_BMC_CMD_CLK\" )
					)
					( Units "uMatchProp" "ns" 1.000000)
					( Origin gBackEnd )
				)
				( member ( signalRef "@baseboard_fab2_lib.baseboard_fab2(sch_1):m_bmc_ddr3_ma(0)") )
				( member ( signalRef "@baseboard_fab2_lib.baseboard_fab2(sch_1):m_bmc_ddr3_ma(1)") )
				( member ( signalRef "@baseboard_fab2_lib.baseboard_fab2(sch_1):m_bmc_ddr3_ma(2)") )
				( member ( signalRef "@baseboard_fab2_lib.baseboard_fab2(sch_1):m_bmc_ddr3_ma(3)") )
				( member ( signalRef "@baseboard_fab2_lib.baseboard_fab2(sch_1):m_bmc_ddr3_ma(4)") )
				( member ( signalRef "@baseboard_fab2_lib.baseboard_fab2(sch_1):m_bmc_ddr3_ma(5)") )
				( member ( signalRef "@baseboard_fab2_lib.baseboard_fab2(sch_1):m_bmc_ddr3_ma(6)") )
				( member ( signalRef "@baseboard_fab2_lib.baseboard_fab2(sch_1):m_bmc_ddr3_ma(7)") )
				( member ( signalRef "@baseboard_fab2_lib.baseboard_fab2(sch_1):m_bmc_ddr3_ma(8)") )
				( member ( signalRef "@baseboard_fab2_lib.baseboard_fab2(sch_1):m_bmc_ddr3_ma(9)") )
				( member ( signalRef "@baseboard_fab2_lib.baseboard_fab2(sch_1):m_bmc_ddr3_ma(10)") )
				( member ( signalRef "@baseboard_fab2_lib.baseboard_fab2(sch_1):m_bmc_ddr3_ma(11)") )
				( member ( signalRef "@baseboard_fab2_lib.baseboard_fab2(sch_1):m_bmc_ddr3_ma(12)") )
				( member ( signalRef "@baseboard_fab2_lib.baseboard_fab2(sch_1):m_bmc_ddr3_ma(13)") )
				( member ( signalRef "@baseboard_fab2_lib.baseboard_fab2(sch_1):m_bmc_ddr3_ma(14)") )
				( member ( signalRef "@baseboard_fab2_lib.baseboard_fab2(sch_1):m_bmc_ddr3_mba_0") )
				( member ( signalRef "@baseboard_fab2_lib.baseboard_fab2(sch_1):m_bmc_ddr3_mba_1") )
				( member ( signalRef "@baseboard_fab2_lib.baseboard_fab2(sch_1):m_bmc_ddr3_mba_2") )
				( member ( signalRef "@baseboard_fab2_lib.baseboard_fab2(sch_1):m_bmc_ddr3_mcas_n") )
				( member ( signalRef "@baseboard_fab2_lib.baseboard_fab2(sch_1):m_bmc_ddr3_mcke") )
				( member ( signalRef "@baseboard_fab2_lib.baseboard_fab2(sch_1):m_bmc_ddr3_mck_n") )
				( member ( signalRef "@baseboard_fab2_lib.baseboard_fab2(sch_1):m_bmc_ddr3_mck_p") )
				( member ( signalRef "@baseboard_fab2_lib.baseboard_fab2(sch_1):m_bmc_ddr3_mcs_n") )
				( member ( signalRef "@baseboard_fab2_lib.baseboard_fab2(sch_1):m_bmc_ddr3_modt") )
				( member ( signalRef "@baseboard_fab2_lib.baseboard_fab2(sch_1):m_bmc_ddr3_mras_n") )
				( member ( signalRef "@baseboard_fab2_lib.baseboard_fab2(sch_1):m_bmc_ddr3_mwe_n") )
				( objectStatus "MG_BMC_CLK_CMD_CTL" )
			)
			( pinPair "@baseboard_fab2_lib.baseboard_fab2(sch_1):\PP6\"
				( pinRef "@baseboard_fab2_lib.baseboard_fab2(sch_1):page118_i73:LAN_RX_P0P" )
				( pinRef "@baseboard_fab2_lib.baseboard_fab2(sch_1):page188_i82:B" )
				( attribute "PROPAGATION_DELAY_MAX" "1000.00 MIL"
					( Units "uMaxMinProp" "ns" 1.000000)
					( Status sCSetFlattened )
					( Origin gBackEnd )
				)
			)
			( pinPair "@baseboard_fab2_lib.baseboard_fab2(sch_1):\PP5\"
				( pinRef "@baseboard_fab2_lib.baseboard_fab2(sch_1):page118_i73:LAN_RX_P0N" )
				( pinRef "@baseboard_fab2_lib.baseboard_fab2(sch_1):page188_i86:B" )
				( attribute "PROPAGATION_DELAY_MAX" "1000.00 MIL"
					( Units "uMaxMinProp" "ns" 1.000000)
					( Status sCSetFlattened )
					( Origin gBackEnd )
				)
			)
			( pinPair "@baseboard_fab2_lib.baseboard_fab2(sch_1):\PP8\"
				( pinRef "@baseboard_fab2_lib.baseboard_fab2(sch_1):page118_i73:LAN_RX_P1P" )
				( pinRef "@baseboard_fab2_lib.baseboard_fab2(sch_1):page188_i80:B" )
				( attribute "PROPAGATION_DELAY_MAX" "1000.00 MIL"
					( Units "uMaxMinProp" "ns" 1.000000)
					( Status sCSetFlattened )
					( Origin gBackEnd )
				)
			)
			( pinPair "@baseboard_fab2_lib.baseboard_fab2(sch_1):\PP7\"
				( pinRef "@baseboard_fab2_lib.baseboard_fab2(sch_1):page118_i73:LAN_RX_P1N" )
				( pinRef "@baseboard_fab2_lib.baseboard_fab2(sch_1):page188_i81:B" )
				( attribute "PROPAGATION_DELAY_MAX" "1000.00 MIL"
					( Units "uMaxMinProp" "ns" 1.000000)
					( Status sCSetFlattened )
					( Origin gBackEnd )
				)
			)
			( pinPair "@baseboard_fab2_lib.baseboard_fab2(sch_1):\PP10\"
				( pinRef "@baseboard_fab2_lib.baseboard_fab2(sch_1):page118_i73:LAN_RX_P2P" )
				( pinRef "@baseboard_fab2_lib.baseboard_fab2(sch_1):page188_i72:B" )
				( attribute "PROPAGATION_DELAY_MAX" "1000.00 MIL"
					( Units "uMaxMinProp" "ns" 1.000000)
					( Status sCSetFlattened )
					( Origin gBackEnd )
				)
			)
			( pinPair "@baseboard_fab2_lib.baseboard_fab2(sch_1):\PP9\"
				( pinRef "@baseboard_fab2_lib.baseboard_fab2(sch_1):page118_i73:LAN_RX_P2N" )
				( pinRef "@baseboard_fab2_lib.baseboard_fab2(sch_1):page188_i73:B" )
				( attribute "PROPAGATION_DELAY_MAX" "1000.00 MIL"
					( Units "uMaxMinProp" "ns" 1.000000)
					( Status sCSetFlattened )
					( Origin gBackEnd )
				)
			)
			( pinPair "@baseboard_fab2_lib.baseboard_fab2(sch_1):\PP12\"
				( pinRef "@baseboard_fab2_lib.baseboard_fab2(sch_1):page118_i73:LAN_RX_P3P" )
				( pinRef "@baseboard_fab2_lib.baseboard_fab2(sch_1):page188_i64:B" )
				( attribute "PROPAGATION_DELAY_MAX" "1000.00 MIL"
					( Units "uMaxMinProp" "ns" 1.000000)
					( Status sCSetFlattened )
					( Origin gBackEnd )
				)
			)
			( pinPair "@baseboard_fab2_lib.baseboard_fab2(sch_1):\PP11\"
				( pinRef "@baseboard_fab2_lib.baseboard_fab2(sch_1):page118_i73:LAN_RX_P3N" )
				( pinRef "@baseboard_fab2_lib.baseboard_fab2(sch_1):page188_i68:B" )
				( attribute "PROPAGATION_DELAY_MAX" "1000.00 MIL"
					( Units "uMaxMinProp" "ns" 1.000000)
					( Status sCSetFlattened )
					( Origin gBackEnd )
				)
			)
			( pinPair "@baseboard_fab2_lib.baseboard_fab2(sch_1):\PP5379\"
				( pinRef "@baseboard_fab2_lib.baseboard_fab2(sch_1):page114_i40:CLKOUT_SRCP(0)" )
				( pinRef "@baseboard_fab2_lib.baseboard_fab2(sch_1):page181_i111:IOH4" )
				( attribute "RELATIVE_PROPAGATION_DELAY_SCOPE" "G"
					( Parent
						( matchGroupRef "@crescent_city_bb_fab1_lib.crescent_city_bb_fab1(sch_1):\MG_CLK_G2-BCLK\" )
					)
					( Origin gBackEnd )
				)
				( attribute "RELATIVE_PROPAGATION_DELAY" "18000.00 MIL,5000.00 MIL"
					( Parent
						( matchGroupRef "@crescent_city_bb_fab1_lib.crescent_city_bb_fab1(sch_1):\MG_CLK_G2-BCLK\" )
					)
					( Units "uMatchProp" "ns" 1.000000)
					( Origin gBackEnd )
				)
			)
			( pinPair "@baseboard_fab2_lib.baseboard_fab2(sch_1):\PP5380\"
				( pinRef "@baseboard_fab2_lib.baseboard_fab2(sch_1):page114_i40:CLKOUT_SRCN(0)" )
				( pinRef "@baseboard_fab2_lib.baseboard_fab2(sch_1):page181_i111:IOI4" )
				( attribute "RELATIVE_PROPAGATION_DELAY_SCOPE" "G"
					( Parent
						( matchGroupRef "@crescent_city_bb_fab1_lib.crescent_city_bb_fab1(sch_1):\MG_CLK_G2-BCLK\" )
					)
					( Origin gBackEnd )
				)
				( attribute "RELATIVE_PROPAGATION_DELAY" "18000.00 MIL,5000.00 MIL"
					( Parent
						( matchGroupRef "@crescent_city_bb_fab1_lib.crescent_city_bb_fab1(sch_1):\MG_CLK_G2-BCLK\" )
					)
					( Units "uMatchProp" "ns" 1.000000)
					( Origin gBackEnd )
				)
			)
			( pinPair "@baseboard_fab2_lib.baseboard_fab2(sch_1):\PP6070\"
				( pinRef "@baseboard_fab2_lib.baseboard_fab2(sch_1):page21_i259:BCLK0_DN" )
				( pinRef "@baseboard_fab2_lib.baseboard_fab2(sch_1):page102_i1:DIF_0N" )
				( attribute "PROPAGATION_DELAY_MIN" "4000.00 MIL"
					( Units "uMaxMinProp" "ns" 1.000000)
					( Status sCSetFlattened )
					( Origin gBackEnd )
				)
				( attribute "PROPAGATION_DELAY_MAX" "16000.00 MIL"
					( Units "uMaxMinProp" "ns" 1.000000)
					( Status sCSetFlattened )
					( Origin gBackEnd )
				)
				( attribute "RELATIVE_PROPAGATION_DELAY_SCOPE" "G"
					( Parent
						( matchGroupRef "@crescent_city_bb_fab1_lib.crescent_city_bb_fab1(sch_1):\MG_CLK_G2-BCLK\" )
					)
					( Origin gBackEnd )
				)
				( attribute "RELATIVE_PROPAGATION_DELAY" "TARGET,TARGET"
					( Parent
						( matchGroupRef "@crescent_city_bb_fab1_lib.crescent_city_bb_fab1(sch_1):\MG_CLK_G2-BCLK\" )
					)
					( Units "uMatchProp" "ns" 1.000000)
					( Origin gBackEnd )
				)
				( attribute "RELATIVE_PROPAGATION_DELAY_SCOPE" "G"
					( Parent
						( matchGroupRef "@baseboard_fab2_lib.baseboard_fab2(sch_1):\MG_CPU_BCLK\" )
					)
					( Status sCSetFlattened )
					( Origin gBackEnd )
				)
				( attribute "RELATIVE_PROPAGATION_DELAY" ",500.00 MIL"
					( Parent
						( matchGroupRef "@baseboard_fab2_lib.baseboard_fab2(sch_1):\MG_CPU_BCLK\" )
					)
					( Units "uMatchProp" "ns" 1.000000)
					( Status sCSetFlattened )
					( Origin gBackEnd )
				)
			)
			( pinPair "@baseboard_fab2_lib.baseboard_fab2(sch_1):\PP6069\"
				( pinRef "@baseboard_fab2_lib.baseboard_fab2(sch_1):page21_i259:BCLK0_DP" )
				( pinRef "@baseboard_fab2_lib.baseboard_fab2(sch_1):page102_i1:DIF_0P" )
				( attribute "PROPAGATION_DELAY_MIN" "4000.00 MIL"
					( Units "uMaxMinProp" "ns" 1.000000)
					( Status sCSetFlattened )
					( Origin gBackEnd )
				)
				( attribute "PROPAGATION_DELAY_MAX" "16000.00 MIL"
					( Units "uMaxMinProp" "ns" 1.000000)
					( Status sCSetFlattened )
					( Origin gBackEnd )
				)
				( attribute "RELATIVE_PROPAGATION_DELAY_SCOPE" "G"
					( Parent
						( matchGroupRef "@baseboard_fab2_lib.baseboard_fab2(sch_1):\MG_CPU_BCLK\" )
					)
					( Status sCSetFlattened )
					( Origin gBackEnd )
				)
				( attribute "RELATIVE_PROPAGATION_DELAY" ",500.00 MIL"
					( Parent
						( matchGroupRef "@baseboard_fab2_lib.baseboard_fab2(sch_1):\MG_CPU_BCLK\" )
					)
					( Units "uMatchProp" "ns" 1.000000)
					( Status sCSetFlattened )
					( Origin gBackEnd )
				)
			)
			( pinPair "@baseboard_fab2_lib.baseboard_fab2(sch_1):\PP6068\"
				( pinRef "@baseboard_fab2_lib.baseboard_fab2(sch_1):page21_i259:BCLK1_DN" )
				( pinRef "@baseboard_fab2_lib.baseboard_fab2(sch_1):page102_i1:DIF_1N" )
				( attribute "PROPAGATION_DELAY_MIN" "4000.00 MIL"
					( Units "uMaxMinProp" "ns" 1.000000)
					( Status sCSetFlattened )
					( Origin gBackEnd )
				)
				( attribute "PROPAGATION_DELAY_MAX" "16000.00 MIL"
					( Units "uMaxMinProp" "ns" 1.000000)
					( Status sCSetFlattened )
					( Origin gBackEnd )
				)
				( attribute "RELATIVE_PROPAGATION_DELAY_SCOPE" "G"
					( Parent
						( matchGroupRef "@baseboard_fab2_lib.baseboard_fab2(sch_1):\MG_CPU_BCLK\" )
					)
					( Status sCSetFlattened )
					( Origin gBackEnd )
				)
				( attribute "RELATIVE_PROPAGATION_DELAY" ",500.00 MIL"
					( Parent
						( matchGroupRef "@baseboard_fab2_lib.baseboard_fab2(sch_1):\MG_CPU_BCLK\" )
					)
					( Units "uMatchProp" "ns" 1.000000)
					( Status sCSetFlattened )
					( Origin gBackEnd )
				)
			)
			( pinPair "@baseboard_fab2_lib.baseboard_fab2(sch_1):\PP6063\"
				( pinRef "@baseboard_fab2_lib.baseboard_fab2(sch_1):page21_i259:BCLK1_DP" )
				( pinRef "@baseboard_fab2_lib.baseboard_fab2(sch_1):page102_i1:DIF_1P" )
				( attribute "PROPAGATION_DELAY_MIN" "4000.00 MIL"
					( Units "uMaxMinProp" "ns" 1.000000)
					( Status sCSetFlattened )
					( Origin gBackEnd )
				)
				( attribute "PROPAGATION_DELAY_MAX" "16000.00 MIL"
					( Units "uMaxMinProp" "ns" 1.000000)
					( Status sCSetFlattened )
					( Origin gBackEnd )
				)
				( attribute "RELATIVE_PROPAGATION_DELAY_SCOPE" "G"
					( Parent
						( matchGroupRef "@baseboard_fab2_lib.baseboard_fab2(sch_1):\MG_CPU_BCLK\" )
					)
					( Status sCSetFlattened )
					( Origin gBackEnd )
				)
				( attribute "RELATIVE_PROPAGATION_DELAY" ",500.00 MIL"
					( Parent
						( matchGroupRef "@baseboard_fab2_lib.baseboard_fab2(sch_1):\MG_CPU_BCLK\" )
					)
					( Units "uMatchProp" "ns" 1.000000)
					( Status sCSetFlattened )
					( Origin gBackEnd )
				)
			)
			( pinPair "@baseboard_fab2_lib.baseboard_fab2(sch_1):\PP6057\"
				( pinRef "@baseboard_fab2_lib.baseboard_fab2(sch_1):page21_i259:BCLK2_DN" )
				( pinRef "@baseboard_fab2_lib.baseboard_fab2(sch_1):page102_i1:DIF_2N" )
				( attribute "PROPAGATION_DELAY_MIN" "4000.00 MIL"
					( Units "uMaxMinProp" "ns" 1.000000)
					( Status sCSetFlattened )
					( Origin gBackEnd )
				)
				( attribute "PROPAGATION_DELAY_MAX" "16000.00 MIL"
					( Units "uMaxMinProp" "ns" 1.000000)
					( Status sCSetFlattened )
					( Origin gBackEnd )
				)
				( attribute "RELATIVE_PROPAGATION_DELAY_SCOPE" "G"
					( Parent
						( matchGroupRef "@baseboard_fab2_lib.baseboard_fab2(sch_1):\MG_CPU_BCLK\" )
					)
					( Status sCSetFlattened )
					( Origin gBackEnd )
				)
				( attribute "RELATIVE_PROPAGATION_DELAY" ",500.00 MIL"
					( Parent
						( matchGroupRef "@baseboard_fab2_lib.baseboard_fab2(sch_1):\MG_CPU_BCLK\" )
					)
					( Units "uMatchProp" "ns" 1.000000)
					( Status sCSetFlattened )
					( Origin gBackEnd )
				)
			)
			( pinPair "@baseboard_fab2_lib.baseboard_fab2(sch_1):\PP6062\"
				( pinRef "@baseboard_fab2_lib.baseboard_fab2(sch_1):page21_i259:BCLK2_DP" )
				( pinRef "@baseboard_fab2_lib.baseboard_fab2(sch_1):page102_i1:DIF_2P" )
				( attribute "PROPAGATION_DELAY_MIN" "4000.00 MIL"
					( Units "uMaxMinProp" "ns" 1.000000)
					( Status sCSetFlattened )
					( Origin gBackEnd )
				)
				( attribute "PROPAGATION_DELAY_MAX" "16000.00 MIL"
					( Units "uMaxMinProp" "ns" 1.000000)
					( Status sCSetFlattened )
					( Origin gBackEnd )
				)
				( attribute "RELATIVE_PROPAGATION_DELAY_SCOPE" "G"
					( Parent
						( matchGroupRef "@baseboard_fab2_lib.baseboard_fab2(sch_1):\MG_CPU_BCLK\" )
					)
					( Status sCSetFlattened )
					( Origin gBackEnd )
				)
				( attribute "RELATIVE_PROPAGATION_DELAY" ",500.00 MIL"
					( Parent
						( matchGroupRef "@baseboard_fab2_lib.baseboard_fab2(sch_1):\MG_CPU_BCLK\" )
					)
					( Units "uMatchProp" "ns" 1.000000)
					( Status sCSetFlattened )
					( Origin gBackEnd )
				)
			)
			( pinPair "@baseboard_fab2_lib.baseboard_fab2(sch_1):\PP6053\"
				( pinRef "@baseboard_fab2_lib.baseboard_fab2(sch_1):page102_i1:DIF_4N" )
				( pinRef "@baseboard_fab2_lib.baseboard_fab2(sch_1):page22_i204:RSVD(195)" )
				( attribute "RELATIVE_PROPAGATION_DELAY_SCOPE" "G"
					( Parent
						( matchGroupRef "@baseboard_fab2_lib.baseboard_fab2(sch_1):\MG_CLK_G1-BCLK\" )
					)
					( Status sCSetFlattened )
					( Origin gBackEnd )
				)
				( attribute "RELATIVE_PROPAGATION_DELAY" "0.00 MIL,5000.00 MIL"
					( Parent
						( matchGroupRef "@baseboard_fab2_lib.baseboard_fab2(sch_1):\MG_CLK_G1-BCLK\" )
					)
					( Units "uMatchProp" "ns" 1.000000)
					( Status sCSetFlattened )
					( Origin gBackEnd )
				)
			)
			( pinPair "@baseboard_fab2_lib.baseboard_fab2(sch_1):\PP6052\"
				( pinRef "@baseboard_fab2_lib.baseboard_fab2(sch_1):page102_i1:DIF_4P" )
				( pinRef "@baseboard_fab2_lib.baseboard_fab2(sch_1):page22_i204:RSVD(206)" )
				( attribute "RELATIVE_PROPAGATION_DELAY_SCOPE" "G"
					( Parent
						( matchGroupRef "@baseboard_fab2_lib.baseboard_fab2(sch_1):\MG_CLK_G1-BCLK\" )
					)
					( Status sCSetFlattened )
					( Origin gBackEnd )
				)
				( attribute "RELATIVE_PROPAGATION_DELAY" "0.00 MIL,5000.00 MIL"
					( Parent
						( matchGroupRef "@baseboard_fab2_lib.baseboard_fab2(sch_1):\MG_CLK_G1-BCLK\" )
					)
					( Units "uMatchProp" "ns" 1.000000)
					( Status sCSetFlattened )
					( Origin gBackEnd )
				)
			)
			( pinPair "@baseboard_fab2_lib.baseboard_fab2(sch_1):\PP6044\"
				( pinRef "@baseboard_fab2_lib.baseboard_fab2(sch_1):page102_i1:DIF_5N" )
				( pinRef "@baseboard_fab2_lib.baseboard_fab2(sch_1):page36_i15:RSVD(165)" )
				( attribute "RELATIVE_PROPAGATION_DELAY_SCOPE" "G"
					( Parent
						( matchGroupRef "@baseboard_fab2_lib.baseboard_fab2(sch_1):\MG_CLK_G1-BCLK\" )
					)
					( Status sCSetFlattened )
					( Origin gBackEnd )
				)
				( attribute "RELATIVE_PROPAGATION_DELAY" "0.00 MIL,5000.00 MIL"
					( Parent
						( matchGroupRef "@baseboard_fab2_lib.baseboard_fab2(sch_1):\MG_CLK_G1-BCLK\" )
					)
					( Units "uMatchProp" "ns" 1.000000)
					( Status sCSetFlattened )
					( Origin gBackEnd )
				)
			)
			( pinPair "@baseboard_fab2_lib.baseboard_fab2(sch_1):\PP6054\"
				( pinRef "@baseboard_fab2_lib.baseboard_fab2(sch_1):page102_i1:DIF_5P" )
				( pinRef "@baseboard_fab2_lib.baseboard_fab2(sch_1):page36_i15:RSVD(153)" )
				( attribute "RELATIVE_PROPAGATION_DELAY_SCOPE" "G"
					( Parent
						( matchGroupRef "@baseboard_fab2_lib.baseboard_fab2(sch_1):\MG_CLK_G1-BCLK\" )
					)
					( Status sCSetFlattened )
					( Origin gBackEnd )
				)
				( attribute "RELATIVE_PROPAGATION_DELAY" "0.00 MIL,5000.00 MIL"
					( Parent
						( matchGroupRef "@baseboard_fab2_lib.baseboard_fab2(sch_1):\MG_CLK_G1-BCLK\" )
					)
					( Units "uMatchProp" "ns" 1.000000)
					( Status sCSetFlattened )
					( Origin gBackEnd )
				)
			)
			( pinPair "@baseboard_fab2_lib.baseboard_fab2(sch_1):\PP6056\"
				( pinRef "@baseboard_fab2_lib.baseboard_fab2(sch_1):page102_i1:DIF_3N" )
				( pinRef "@baseboard_fab2_lib.baseboard_fab2(sch_1):page29_i61:CD_PE_REFCLK_DN" )
				( attribute "RELATIVE_PROPAGATION_DELAY_SCOPE" "G"
					( Parent
						( matchGroupRef "@baseboard_fab2_lib.baseboard_fab2(sch_1):\MG_CLK_G1-BCLK\" )
					)
					( Status sCSetFlattened )
					( Origin gBackEnd )
				)
				( attribute "RELATIVE_PROPAGATION_DELAY" "0.00 MIL,5000.00 MIL"
					( Parent
						( matchGroupRef "@baseboard_fab2_lib.baseboard_fab2(sch_1):\MG_CLK_G1-BCLK\" )
					)
					( Units "uMatchProp" "ns" 1.000000)
					( Status sCSetFlattened )
					( Origin gBackEnd )
				)
			)
			( pinPair "@baseboard_fab2_lib.baseboard_fab2(sch_1):\PP6055\"
				( pinRef "@baseboard_fab2_lib.baseboard_fab2(sch_1):page102_i1:DIF_3P" )
				( pinRef "@baseboard_fab2_lib.baseboard_fab2(sch_1):page29_i61:CD_PE_REFCLK_DP" )
				( attribute "RELATIVE_PROPAGATION_DELAY_SCOPE" "G"
					( Parent
						( matchGroupRef "@baseboard_fab2_lib.baseboard_fab2(sch_1):\MG_CLK_G1-BCLK\" )
					)
					( Status sCSetFlattened )
					( Origin gBackEnd )
				)
				( attribute "RELATIVE_PROPAGATION_DELAY" "0.00 MIL,5000.00 MIL"
					( Parent
						( matchGroupRef "@baseboard_fab2_lib.baseboard_fab2(sch_1):\MG_CLK_G1-BCLK\" )
					)
					( Units "uMatchProp" "ns" 1.000000)
					( Status sCSetFlattened )
					( Origin gBackEnd )
				)
			)
			( pinPair "@baseboard_fab2_lib.baseboard_fab2(sch_1):\PP6061\"
				( pinRef "@baseboard_fab2_lib.baseboard_fab2(sch_1):page55_i172:BCLK0_DN" )
				( pinRef "@baseboard_fab2_lib.baseboard_fab2(sch_1):page102_i1:DIF_6N" )
				( attribute "PROPAGATION_DELAY_MIN" "4000.00 MIL"
					( Units "uMaxMinProp" "ns" 1.000000)
					( Status sCSetFlattened )
					( Origin gBackEnd )
				)
				( attribute "PROPAGATION_DELAY_MAX" "16000.00 MIL"
					( Units "uMaxMinProp" "ns" 1.000000)
					( Status sCSetFlattened )
					( Origin gBackEnd )
				)
				( attribute "RELATIVE_PROPAGATION_DELAY_SCOPE" "G"
					( Parent
						( matchGroupRef "@baseboard_fab2_lib.baseboard_fab2(sch_1):\MG_CPU_BCLK\" )
					)
					( Status sCSetFlattened )
					( Origin gBackEnd )
				)
				( attribute "RELATIVE_PROPAGATION_DELAY" ",500.00 MIL"
					( Parent
						( matchGroupRef "@baseboard_fab2_lib.baseboard_fab2(sch_1):\MG_CPU_BCLK\" )
					)
					( Units "uMatchProp" "ns" 1.000000)
					( Status sCSetFlattened )
					( Origin gBackEnd )
				)
			)
			( pinPair "@baseboard_fab2_lib.baseboard_fab2(sch_1):\PP6060\"
				( pinRef "@baseboard_fab2_lib.baseboard_fab2(sch_1):page55_i172:BCLK0_DP" )
				( pinRef "@baseboard_fab2_lib.baseboard_fab2(sch_1):page102_i1:DIF_6P" )
				( attribute "PROPAGATION_DELAY_MIN" "4000.00 MIL"
					( Units "uMaxMinProp" "ns" 1.000000)
					( Status sCSetFlattened )
					( Origin gBackEnd )
				)
				( attribute "PROPAGATION_DELAY_MAX" "16000.00 MIL"
					( Units "uMaxMinProp" "ns" 1.000000)
					( Status sCSetFlattened )
					( Origin gBackEnd )
				)
				( attribute "RELATIVE_PROPAGATION_DELAY_SCOPE" "G"
					( Parent
						( matchGroupRef "@baseboard_fab2_lib.baseboard_fab2(sch_1):\MG_CPU_BCLK\" )
					)
					( Status sCSetFlattened )
					( Origin gBackEnd )
				)
				( attribute "RELATIVE_PROPAGATION_DELAY" ",500.00 MIL"
					( Parent
						( matchGroupRef "@baseboard_fab2_lib.baseboard_fab2(sch_1):\MG_CPU_BCLK\" )
					)
					( Units "uMatchProp" "ns" 1.000000)
					( Status sCSetFlattened )
					( Origin gBackEnd )
				)
			)
			( pinPair "@baseboard_fab2_lib.baseboard_fab2(sch_1):\PP6059\"
				( pinRef "@baseboard_fab2_lib.baseboard_fab2(sch_1):page55_i172:BCLK1_DN" )
				( pinRef "@baseboard_fab2_lib.baseboard_fab2(sch_1):page102_i1:DIF_7N" )
				( attribute "PROPAGATION_DELAY_MIN" "4000.00 MIL"
					( Units "uMaxMinProp" "ns" 1.000000)
					( Status sCSetFlattened )
					( Origin gBackEnd )
				)
				( attribute "PROPAGATION_DELAY_MAX" "16000.00 MIL"
					( Units "uMaxMinProp" "ns" 1.000000)
					( Status sCSetFlattened )
					( Origin gBackEnd )
				)
				( attribute "RELATIVE_PROPAGATION_DELAY_SCOPE" "G"
					( Parent
						( matchGroupRef "@baseboard_fab2_lib.baseboard_fab2(sch_1):\MG_CPU_BCLK\" )
					)
					( Status sCSetFlattened )
					( Origin gBackEnd )
				)
				( attribute "RELATIVE_PROPAGATION_DELAY" ",500.00 MIL"
					( Parent
						( matchGroupRef "@baseboard_fab2_lib.baseboard_fab2(sch_1):\MG_CPU_BCLK\" )
					)
					( Units "uMatchProp" "ns" 1.000000)
					( Status sCSetFlattened )
					( Origin gBackEnd )
				)
			)
			( pinPair "@baseboard_fab2_lib.baseboard_fab2(sch_1):\PP6058\"
				( pinRef "@baseboard_fab2_lib.baseboard_fab2(sch_1):page55_i172:BCLK1_DP" )
				( pinRef "@baseboard_fab2_lib.baseboard_fab2(sch_1):page102_i1:DIF_7P" )
				( attribute "PROPAGATION_DELAY_MIN" "4000.00 MIL"
					( Units "uMaxMinProp" "ns" 1.000000)
					( Status sCSetFlattened )
					( Origin gBackEnd )
				)
				( attribute "PROPAGATION_DELAY_MAX" "16000.00 MIL"
					( Units "uMaxMinProp" "ns" 1.000000)
					( Status sCSetFlattened )
					( Origin gBackEnd )
				)
				( attribute "RELATIVE_PROPAGATION_DELAY_SCOPE" "G"
					( Parent
						( matchGroupRef "@baseboard_fab2_lib.baseboard_fab2(sch_1):\MG_CPU_BCLK\" )
					)
					( Status sCSetFlattened )
					( Origin gBackEnd )
				)
				( attribute "RELATIVE_PROPAGATION_DELAY" ",500.00 MIL"
					( Parent
						( matchGroupRef "@baseboard_fab2_lib.baseboard_fab2(sch_1):\MG_CPU_BCLK\" )
					)
					( Units "uMatchProp" "ns" 1.000000)
					( Status sCSetFlattened )
					( Origin gBackEnd )
				)
			)
			( pinPair "@baseboard_fab2_lib.baseboard_fab2(sch_1):\PP6010\"
				( pinRef "@baseboard_fab2_lib.baseboard_fab2(sch_1):page55_i172:BCLK2_DN" )
				( pinRef "@baseboard_fab2_lib.baseboard_fab2(sch_1):page102_i1:DIF_8N" )
				( attribute "PROPAGATION_DELAY_MIN" "4000.00 MIL"
					( Units "uMaxMinProp" "ns" 1.000000)
					( Status sCSetFlattened )
					( Origin gBackEnd )
				)
				( attribute "PROPAGATION_DELAY_MAX" "16000.00 MIL"
					( Units "uMaxMinProp" "ns" 1.000000)
					( Status sCSetFlattened )
					( Origin gBackEnd )
				)
				( attribute "RELATIVE_PROPAGATION_DELAY_SCOPE" "G"
					( Parent
						( matchGroupRef "@baseboard_fab2_lib.baseboard_fab2(sch_1):\MG_CPU_BCLK\" )
					)
					( Status sCSetFlattened )
					( Origin gBackEnd )
				)
				( attribute "RELATIVE_PROPAGATION_DELAY" ",500.00 MIL"
					( Parent
						( matchGroupRef "@baseboard_fab2_lib.baseboard_fab2(sch_1):\MG_CPU_BCLK\" )
					)
					( Units "uMatchProp" "ns" 1.000000)
					( Status sCSetFlattened )
					( Origin gBackEnd )
				)
			)
			( pinPair "@baseboard_fab2_lib.baseboard_fab2(sch_1):\PP6009\"
				( pinRef "@baseboard_fab2_lib.baseboard_fab2(sch_1):page55_i172:BCLK2_DP" )
				( pinRef "@baseboard_fab2_lib.baseboard_fab2(sch_1):page102_i1:DIF_8P" )
				( attribute "PROPAGATION_DELAY_MIN" "4000.00 MIL"
					( Units "uMaxMinProp" "ns" 1.000000)
					( Status sCSetFlattened )
					( Origin gBackEnd )
				)
				( attribute "PROPAGATION_DELAY_MAX" "16000.00 MIL"
					( Units "uMaxMinProp" "ns" 1.000000)
					( Status sCSetFlattened )
					( Origin gBackEnd )
				)
				( attribute "RELATIVE_PROPAGATION_DELAY_SCOPE" "G"
					( Parent
						( matchGroupRef "@baseboard_fab2_lib.baseboard_fab2(sch_1):\MG_CPU_BCLK\" )
					)
					( Status sCSetFlattened )
					( Origin gBackEnd )
				)
				( attribute "RELATIVE_PROPAGATION_DELAY" ",500.00 MIL"
					( Parent
						( matchGroupRef "@baseboard_fab2_lib.baseboard_fab2(sch_1):\MG_CPU_BCLK\" )
					)
					( Units "uMatchProp" "ns" 1.000000)
					( Status sCSetFlattened )
					( Origin gBackEnd )
				)
			)
			( pinPair "@baseboard_fab2_lib.baseboard_fab2(sch_1):\PP6048\"
				( pinRef "@baseboard_fab2_lib.baseboard_fab2(sch_1):page102_i1:DIF_10N" )
				( pinRef "@baseboard_fab2_lib.baseboard_fab2(sch_1):page56_i169:RSVD(195)" )
				( attribute "RELATIVE_PROPAGATION_DELAY_SCOPE" "G"
					( Parent
						( matchGroupRef "@baseboard_fab2_lib.baseboard_fab2(sch_1):\MG_CLK_G1-BCLK\" )
					)
					( Status sCSetFlattened )
					( Origin gBackEnd )
				)
				( attribute "RELATIVE_PROPAGATION_DELAY" "0.00 MIL,5000.00 MIL"
					( Parent
						( matchGroupRef "@baseboard_fab2_lib.baseboard_fab2(sch_1):\MG_CLK_G1-BCLK\" )
					)
					( Units "uMatchProp" "ns" 1.000000)
					( Status sCSetFlattened )
					( Origin gBackEnd )
				)
			)
			( pinPair "@baseboard_fab2_lib.baseboard_fab2(sch_1):\PP6045\"
				( pinRef "@baseboard_fab2_lib.baseboard_fab2(sch_1):page102_i1:DIF_10P" )
				( pinRef "@baseboard_fab2_lib.baseboard_fab2(sch_1):page56_i169:RSVD(206)" )
				( attribute "RELATIVE_PROPAGATION_DELAY_SCOPE" "G"
					( Parent
						( matchGroupRef "@baseboard_fab2_lib.baseboard_fab2(sch_1):\MG_CLK_G1-BCLK\" )
					)
					( Status sCSetFlattened )
					( Origin gBackEnd )
				)
				( attribute "RELATIVE_PROPAGATION_DELAY" "0.00 MIL,5000.00 MIL"
					( Parent
						( matchGroupRef "@baseboard_fab2_lib.baseboard_fab2(sch_1):\MG_CLK_G1-BCLK\" )
					)
					( Units "uMatchProp" "ns" 1.000000)
					( Status sCSetFlattened )
					( Origin gBackEnd )
				)
			)
			( pinPair "@baseboard_fab2_lib.baseboard_fab2(sch_1):\PP6051\"
				( pinRef "@baseboard_fab2_lib.baseboard_fab2(sch_1):page102_i1:DIF_9N" )
				( pinRef "@baseboard_fab2_lib.baseboard_fab2(sch_1):page63_i23:CD_PE_REFCLK_DN" )
				( attribute "RELATIVE_PROPAGATION_DELAY_SCOPE" "G"
					( Parent
						( matchGroupRef "@baseboard_fab2_lib.baseboard_fab2(sch_1):\MG_CLK_G1-BCLK\" )
					)
					( Status sCSetFlattened )
					( Origin gBackEnd )
				)
				( attribute "RELATIVE_PROPAGATION_DELAY" "0.00 MIL,5000.00 MIL"
					( Parent
						( matchGroupRef "@baseboard_fab2_lib.baseboard_fab2(sch_1):\MG_CLK_G1-BCLK\" )
					)
					( Units "uMatchProp" "ns" 1.000000)
					( Status sCSetFlattened )
					( Origin gBackEnd )
				)
			)
			( pinPair "@baseboard_fab2_lib.baseboard_fab2(sch_1):\PP6050\"
				( pinRef "@baseboard_fab2_lib.baseboard_fab2(sch_1):page102_i1:DIF_9P" )
				( pinRef "@baseboard_fab2_lib.baseboard_fab2(sch_1):page63_i23:CD_PE_REFCLK_DP" )
				( attribute "RELATIVE_PROPAGATION_DELAY_SCOPE" "G"
					( Parent
						( matchGroupRef "@baseboard_fab2_lib.baseboard_fab2(sch_1):\MG_CLK_G1-BCLK\" )
					)
					( Status sCSetFlattened )
					( Origin gBackEnd )
				)
				( attribute "RELATIVE_PROPAGATION_DELAY" "0.00 MIL,5000.00 MIL"
					( Parent
						( matchGroupRef "@baseboard_fab2_lib.baseboard_fab2(sch_1):\MG_CLK_G1-BCLK\" )
					)
					( Units "uMatchProp" "ns" 1.000000)
					( Status sCSetFlattened )
					( Origin gBackEnd )
				)
			)
			( pinPair "@baseboard_fab2_lib.baseboard_fab2(sch_1):\PP5399\"
				( pinRef "@baseboard_fab2_lib.baseboard_fab2(sch_1):page186_i336:IO48" )
				( pinRef "@baseboard_fab2_lib.baseboard_fab2(sch_1):page114_i40:CLKOUT_SRCP(8)" )
				( attribute "RELATIVE_PROPAGATION_DELAY_SCOPE" "G"
					( Parent
						( matchGroupRef "@crescent_city_bb_fab1_lib.crescent_city_bb_fab1(sch_1):\MG_CLK_G2-BCLK\" )
					)
					( Origin gBackEnd )
				)
				( attribute "RELATIVE_PROPAGATION_DELAY" "5609.00 MIL,5000.00 MIL"
					( Parent
						( matchGroupRef "@crescent_city_bb_fab1_lib.crescent_city_bb_fab1(sch_1):\MG_CLK_G2-BCLK\" )
					)
					( Units "uMatchProp" "ns" 1.000000)
					( Origin gBackEnd )
				)
			)
			( pinPair "@baseboard_fab2_lib.baseboard_fab2(sch_1):\PP5400\"
				( pinRef "@baseboard_fab2_lib.baseboard_fab2(sch_1):page186_i336:IO50" )
				( pinRef "@baseboard_fab2_lib.baseboard_fab2(sch_1):page114_i40:CLKOUT_SRCN(8)" )
				( attribute "RELATIVE_PROPAGATION_DELAY_SCOPE" "G"
					( Parent
						( matchGroupRef "@crescent_city_bb_fab1_lib.crescent_city_bb_fab1(sch_1):\MG_CLK_G2-BCLK\" )
					)
					( Origin gBackEnd )
				)
				( attribute "RELATIVE_PROPAGATION_DELAY" "5609.00 MIL,5000.00 MIL"
					( Parent
						( matchGroupRef "@crescent_city_bb_fab1_lib.crescent_city_bb_fab1(sch_1):\MG_CLK_G2-BCLK\" )
					)
					( Units "uMatchProp" "ns" 1.000000)
					( Origin gBackEnd )
				)
			)
			( pinPair "@baseboard_fab2_lib.baseboard_fab2(sch_1):\PP5397\"
				( pinRef "@baseboard_fab2_lib.baseboard_fab2(sch_1):page186_i336:IO51" )
				( pinRef "@baseboard_fab2_lib.baseboard_fab2(sch_1):page114_i40:CLKOUT_SRCP(9)" )
				( attribute "RELATIVE_PROPAGATION_DELAY_SCOPE" "G"
					( Parent
						( matchGroupRef "@crescent_city_bb_fab1_lib.crescent_city_bb_fab1(sch_1):\MG_CLK_G2-BCLK\" )
					)
					( Origin gBackEnd )
				)
				( attribute "RELATIVE_PROPAGATION_DELAY" "5112.00 MIL,5000.00 MIL"
					( Parent
						( matchGroupRef "@crescent_city_bb_fab1_lib.crescent_city_bb_fab1(sch_1):\MG_CLK_G2-BCLK\" )
					)
					( Units "uMatchProp" "ns" 1.000000)
					( Origin gBackEnd )
				)
			)
			( pinPair "@baseboard_fab2_lib.baseboard_fab2(sch_1):\PP5398\"
				( pinRef "@baseboard_fab2_lib.baseboard_fab2(sch_1):page186_i336:IO53" )
				( pinRef "@baseboard_fab2_lib.baseboard_fab2(sch_1):page114_i40:CLKOUT_SRCN(9)" )
				( attribute "RELATIVE_PROPAGATION_DELAY_SCOPE" "G"
					( Parent
						( matchGroupRef "@crescent_city_bb_fab1_lib.crescent_city_bb_fab1(sch_1):\MG_CLK_G2-BCLK\" )
					)
					( Origin gBackEnd )
				)
				( attribute "RELATIVE_PROPAGATION_DELAY" "5112.00 MIL,5000.00 MIL"
					( Parent
						( matchGroupRef "@crescent_city_bb_fab1_lib.crescent_city_bb_fab1(sch_1):\MG_CLK_G2-BCLK\" )
					)
					( Units "uMatchProp" "ns" 1.000000)
					( Origin gBackEnd )
				)
			)
			( pinPair "@baseboard_fab2_lib.baseboard_fab2(sch_1):\PP5385\"
				( pinRef "@baseboard_fab2_lib.baseboard_fab2(sch_1):page114_i40:CLKOUT_SRCP(10)" )
				( pinRef "@baseboard_fab2_lib.baseboard_fab2(sch_1):page187_i119:IO69" )
				( attribute "RELATIVE_PROPAGATION_DELAY_SCOPE" "G"
					( Parent
						( matchGroupRef "@crescent_city_bb_fab1_lib.crescent_city_bb_fab1(sch_1):\MG_CLK_G2-BCLK\" )
					)
					( Origin gBackEnd )
				)
				( attribute "RELATIVE_PROPAGATION_DELAY" "6931.00 MIL,5000.00 MIL"
					( Parent
						( matchGroupRef "@crescent_city_bb_fab1_lib.crescent_city_bb_fab1(sch_1):\MG_CLK_G2-BCLK\" )
					)
					( Units "uMatchProp" "ns" 1.000000)
					( Origin gBackEnd )
				)
			)
			( pinPair "@baseboard_fab2_lib.baseboard_fab2(sch_1):\PP5386\"
				( pinRef "@baseboard_fab2_lib.baseboard_fab2(sch_1):page114_i40:CLKOUT_SRCN(10)" )
				( pinRef "@baseboard_fab2_lib.baseboard_fab2(sch_1):page187_i119:IO71" )
				( attribute "RELATIVE_PROPAGATION_DELAY_SCOPE" "G"
					( Parent
						( matchGroupRef "@crescent_city_bb_fab1_lib.crescent_city_bb_fab1(sch_1):\MG_CLK_G2-BCLK\" )
					)
					( Origin gBackEnd )
				)
				( attribute "RELATIVE_PROPAGATION_DELAY" "6931.00 MIL,5000.00 MIL"
					( Parent
						( matchGroupRef "@crescent_city_bb_fab1_lib.crescent_city_bb_fab1(sch_1):\MG_CLK_G2-BCLK\" )
					)
					( Units "uMatchProp" "ns" 1.000000)
					( Origin gBackEnd )
				)
			)
			( pinPair "@baseboard_fab2_lib.baseboard_fab2(sch_1):\PP5383\"
				( pinRef "@baseboard_fab2_lib.baseboard_fab2(sch_1):page114_i40:CLKOUT_SRCP(11)" )
				( pinRef "@baseboard_fab2_lib.baseboard_fab2(sch_1):page187_i119:IO74" )
				( attribute "RELATIVE_PROPAGATION_DELAY_SCOPE" "G"
					( Parent
						( matchGroupRef "@crescent_city_bb_fab1_lib.crescent_city_bb_fab1(sch_1):\MG_CLK_G2-BCLK\" )
					)
					( Origin gBackEnd )
				)
				( attribute "RELATIVE_PROPAGATION_DELAY" "7014.00 MIL,5000.00 MIL"
					( Parent
						( matchGroupRef "@crescent_city_bb_fab1_lib.crescent_city_bb_fab1(sch_1):\MG_CLK_G2-BCLK\" )
					)
					( Units "uMatchProp" "ns" 1.000000)
					( Origin gBackEnd )
				)
			)
			( pinPair "@baseboard_fab2_lib.baseboard_fab2(sch_1):\PP5384\"
				( pinRef "@baseboard_fab2_lib.baseboard_fab2(sch_1):page114_i40:CLKOUT_SRCN(11)" )
				( pinRef "@baseboard_fab2_lib.baseboard_fab2(sch_1):page187_i119:IO76" )
				( attribute "RELATIVE_PROPAGATION_DELAY_SCOPE" "G"
					( Parent
						( matchGroupRef "@crescent_city_bb_fab1_lib.crescent_city_bb_fab1(sch_1):\MG_CLK_G2-BCLK\" )
					)
					( Origin gBackEnd )
				)
				( attribute "RELATIVE_PROPAGATION_DELAY" "7014.00 MIL,5000.00 MIL"
					( Parent
						( matchGroupRef "@crescent_city_bb_fab1_lib.crescent_city_bb_fab1(sch_1):\MG_CLK_G2-BCLK\" )
					)
					( Units "uMatchProp" "ns" 1.000000)
					( Origin gBackEnd )
				)
			)
			( pinPair "@baseboard_fab2_lib.baseboard_fab2(sch_1):\PP5377\"
				( pinRef "@baseboard_fab2_lib.baseboard_fab2(sch_1):page114_i40:CLKOUT_SRCP(2)" )
				( pinRef "@baseboard_fab2_lib.baseboard_fab2(sch_1):page108_i258:IO33" )
				( attribute "RELATIVE_PROPAGATION_DELAY_SCOPE" "G"
					( Parent
						( matchGroupRef "@crescent_city_bb_fab1_lib.crescent_city_bb_fab1(sch_1):\MG_CLK_G2-BCLK\" )
					)
					( Origin gBackEnd )
				)
				( attribute "RELATIVE_PROPAGATION_DELAY" "4976.00 MIL,5000.00 MIL"
					( Parent
						( matchGroupRef "@crescent_city_bb_fab1_lib.crescent_city_bb_fab1(sch_1):\MG_CLK_G2-BCLK\" )
					)
					( Units "uMatchProp" "ns" 1.000000)
					( Origin gBackEnd )
				)
			)
			( pinPair "@baseboard_fab2_lib.baseboard_fab2(sch_1):\PP5378\"
				( pinRef "@baseboard_fab2_lib.baseboard_fab2(sch_1):page114_i40:CLKOUT_SRCN(2)" )
				( pinRef "@baseboard_fab2_lib.baseboard_fab2(sch_1):page108_i258:IO35" )
				( attribute "RELATIVE_PROPAGATION_DELAY_SCOPE" "G"
					( Parent
						( matchGroupRef "@crescent_city_bb_fab1_lib.crescent_city_bb_fab1(sch_1):\MG_CLK_G2-BCLK\" )
					)
					( Origin gBackEnd )
				)
				( attribute "RELATIVE_PROPAGATION_DELAY" "4976.00 MIL,5000.00 MIL"
					( Parent
						( matchGroupRef "@crescent_city_bb_fab1_lib.crescent_city_bb_fab1(sch_1):\MG_CLK_G2-BCLK\" )
					)
					( Units "uMatchProp" "ns" 1.000000)
					( Origin gBackEnd )
				)
			)
			( pinPair "@baseboard_fab2_lib.baseboard_fab2(sch_1):\PP5395\"
				( pinRef "@baseboard_fab2_lib.baseboard_fab2(sch_1):page114_i40:CLKOUT_SRCP(3)" )
				( pinRef "@baseboard_fab2_lib.baseboard_fab2(sch_1):page108_i258:IO36" )
				( attribute "RELATIVE_PROPAGATION_DELAY_SCOPE" "G"
					( Parent
						( matchGroupRef "@crescent_city_bb_fab1_lib.crescent_city_bb_fab1(sch_1):\MG_CLK_G2-BCLK\" )
					)
					( Origin gBackEnd )
				)
				( attribute "RELATIVE_PROPAGATION_DELAY" "4976.00 MIL,5000.00 MIL"
					( Parent
						( matchGroupRef "@crescent_city_bb_fab1_lib.crescent_city_bb_fab1(sch_1):\MG_CLK_G2-BCLK\" )
					)
					( Units "uMatchProp" "ns" 1.000000)
					( Origin gBackEnd )
				)
			)
			( pinPair "@baseboard_fab2_lib.baseboard_fab2(sch_1):\PP5396\"
				( pinRef "@baseboard_fab2_lib.baseboard_fab2(sch_1):page114_i40:CLKOUT_SRCN(3)" )
				( pinRef "@baseboard_fab2_lib.baseboard_fab2(sch_1):page108_i258:IO38" )
				( attribute "RELATIVE_PROPAGATION_DELAY_SCOPE" "G"
					( Parent
						( matchGroupRef "@crescent_city_bb_fab1_lib.crescent_city_bb_fab1(sch_1):\MG_CLK_G2-BCLK\" )
					)
					( Origin gBackEnd )
				)
				( attribute "RELATIVE_PROPAGATION_DELAY" "4976.00 MIL,5000.00 MIL"
					( Parent
						( matchGroupRef "@crescent_city_bb_fab1_lib.crescent_city_bb_fab1(sch_1):\MG_CLK_G2-BCLK\" )
					)
					( Units "uMatchProp" "ns" 1.000000)
					( Origin gBackEnd )
				)
			)
			( pinPair "@baseboard_fab2_lib.baseboard_fab2(sch_1):\PP5393\"
				( pinRef "@baseboard_fab2_lib.baseboard_fab2(sch_1):page114_i40:CLKOUT_SRCP(4)" )
				( pinRef "@baseboard_fab2_lib.baseboard_fab2(sch_1):page108_i258:IO39" )
				( attribute "RELATIVE_PROPAGATION_DELAY_SCOPE" "G"
					( Parent
						( matchGroupRef "@crescent_city_bb_fab1_lib.crescent_city_bb_fab1(sch_1):\MG_CLK_G2-BCLK\" )
					)
					( Origin gBackEnd )
				)
				( attribute "RELATIVE_PROPAGATION_DELAY" "4976.00 MIL,5000.00 MIL"
					( Parent
						( matchGroupRef "@crescent_city_bb_fab1_lib.crescent_city_bb_fab1(sch_1):\MG_CLK_G2-BCLK\" )
					)
					( Units "uMatchProp" "ns" 1.000000)
					( Origin gBackEnd )
				)
			)
			( pinPair "@baseboard_fab2_lib.baseboard_fab2(sch_1):\PP5394\"
				( pinRef "@baseboard_fab2_lib.baseboard_fab2(sch_1):page114_i40:CLKOUT_SRCN(4)" )
				( pinRef "@baseboard_fab2_lib.baseboard_fab2(sch_1):page108_i258:IO41" )
				( attribute "RELATIVE_PROPAGATION_DELAY_SCOPE" "G"
					( Parent
						( matchGroupRef "@crescent_city_bb_fab1_lib.crescent_city_bb_fab1(sch_1):\MG_CLK_G2-BCLK\" )
					)
					( Origin gBackEnd )
				)
				( attribute "RELATIVE_PROPAGATION_DELAY" "4976.00 MIL,5000.00 MIL"
					( Parent
						( matchGroupRef "@crescent_city_bb_fab1_lib.crescent_city_bb_fab1(sch_1):\MG_CLK_G2-BCLK\" )
					)
					( Units "uMatchProp" "ns" 1.000000)
					( Origin gBackEnd )
				)
			)
			( pinPair "@baseboard_fab2_lib.baseboard_fab2(sch_1):\PP5391\"
				( pinRef "@baseboard_fab2_lib.baseboard_fab2(sch_1):page114_i40:CLKOUT_SRCP(5)" )
				( pinRef "@baseboard_fab2_lib.baseboard_fab2(sch_1):page108_i258:IO42" )
				( attribute "RELATIVE_PROPAGATION_DELAY_SCOPE" "G"
					( Parent
						( matchGroupRef "@crescent_city_bb_fab1_lib.crescent_city_bb_fab1(sch_1):\MG_CLK_G2-BCLK\" )
					)
					( Origin gBackEnd )
				)
				( attribute "RELATIVE_PROPAGATION_DELAY" "4976.00 MIL,5000.00 MIL"
					( Parent
						( matchGroupRef "@crescent_city_bb_fab1_lib.crescent_city_bb_fab1(sch_1):\MG_CLK_G2-BCLK\" )
					)
					( Units "uMatchProp" "ns" 1.000000)
					( Origin gBackEnd )
				)
			)
			( pinPair "@baseboard_fab2_lib.baseboard_fab2(sch_1):\PP5392\"
				( pinRef "@baseboard_fab2_lib.baseboard_fab2(sch_1):page114_i40:CLKOUT_SRCN(5)" )
				( pinRef "@baseboard_fab2_lib.baseboard_fab2(sch_1):page108_i258:IO44" )
				( attribute "RELATIVE_PROPAGATION_DELAY_SCOPE" "G"
					( Parent
						( matchGroupRef "@crescent_city_bb_fab1_lib.crescent_city_bb_fab1(sch_1):\MG_CLK_G2-BCLK\" )
					)
					( Origin gBackEnd )
				)
				( attribute "RELATIVE_PROPAGATION_DELAY" "4976.00 MIL,5000.00 MIL"
					( Parent
						( matchGroupRef "@crescent_city_bb_fab1_lib.crescent_city_bb_fab1(sch_1):\MG_CLK_G2-BCLK\" )
					)
					( Units "uMatchProp" "ns" 1.000000)
					( Origin gBackEnd )
				)
			)
			( pinPair "@baseboard_fab2_lib.baseboard_fab2(sch_1):\PP5375\"
				( pinRef "@baseboard_fab2_lib.baseboard_fab2(sch_1):page114_i40:CLKOUT_SRCP(6)" )
				( pinRef "@baseboard_fab2_lib.baseboard_fab2(sch_1):page108_i258:IO45" )
				( attribute "RELATIVE_PROPAGATION_DELAY_SCOPE" "G"
					( Parent
						( matchGroupRef "@crescent_city_bb_fab1_lib.crescent_city_bb_fab1(sch_1):\MG_CLK_G2-BCLK\" )
					)
					( Origin gBackEnd )
				)
				( attribute "RELATIVE_PROPAGATION_DELAY" "4976.00 MIL,5000.00 MIL"
					( Parent
						( matchGroupRef "@crescent_city_bb_fab1_lib.crescent_city_bb_fab1(sch_1):\MG_CLK_G2-BCLK\" )
					)
					( Units "uMatchProp" "ns" 1.000000)
					( Origin gBackEnd )
				)
			)
			( pinPair "@baseboard_fab2_lib.baseboard_fab2(sch_1):\PP5376\"
				( pinRef "@baseboard_fab2_lib.baseboard_fab2(sch_1):page114_i40:CLKOUT_SRCN(6)" )
				( pinRef "@baseboard_fab2_lib.baseboard_fab2(sch_1):page108_i258:IO47" )
				( attribute "RELATIVE_PROPAGATION_DELAY_SCOPE" "G"
					( Parent
						( matchGroupRef "@crescent_city_bb_fab1_lib.crescent_city_bb_fab1(sch_1):\MG_CLK_G2-BCLK\" )
					)
					( Origin gBackEnd )
				)
				( attribute "RELATIVE_PROPAGATION_DELAY" "4976.00 MIL,5000.00 MIL"
					( Parent
						( matchGroupRef "@crescent_city_bb_fab1_lib.crescent_city_bb_fab1(sch_1):\MG_CLK_G2-BCLK\" )
					)
					( Units "uMatchProp" "ns" 1.000000)
					( Origin gBackEnd )
				)
			)
			( pinPair "@baseboard_fab2_lib.baseboard_fab2(sch_1):\PP5373\"
				( pinRef "@baseboard_fab2_lib.baseboard_fab2(sch_1):page114_i40:CLKOUT_SRCP(7)" )
				( pinRef "@baseboard_fab2_lib.baseboard_fab2(sch_1):page108_i258:IO48" )
				( attribute "RELATIVE_PROPAGATION_DELAY_SCOPE" "G"
					( Parent
						( matchGroupRef "@crescent_city_bb_fab1_lib.crescent_city_bb_fab1(sch_1):\MG_CLK_G2-BCLK\" )
					)
					( Origin gBackEnd )
				)
				( attribute "RELATIVE_PROPAGATION_DELAY" "4976.00 MIL,5000.00 MIL"
					( Parent
						( matchGroupRef "@crescent_city_bb_fab1_lib.crescent_city_bb_fab1(sch_1):\MG_CLK_G2-BCLK\" )
					)
					( Units "uMatchProp" "ns" 1.000000)
					( Origin gBackEnd )
				)
			)
			( pinPair "@baseboard_fab2_lib.baseboard_fab2(sch_1):\PP5374\"
				( pinRef "@baseboard_fab2_lib.baseboard_fab2(sch_1):page114_i40:CLKOUT_SRCN(7)" )
				( pinRef "@baseboard_fab2_lib.baseboard_fab2(sch_1):page108_i258:IO50" )
				( attribute "RELATIVE_PROPAGATION_DELAY_SCOPE" "G"
					( Parent
						( matchGroupRef "@crescent_city_bb_fab1_lib.crescent_city_bb_fab1(sch_1):\MG_CLK_G2-BCLK\" )
					)
					( Origin gBackEnd )
				)
				( attribute "RELATIVE_PROPAGATION_DELAY" "4976.00 MIL,5000.00 MIL"
					( Parent
						( matchGroupRef "@crescent_city_bb_fab1_lib.crescent_city_bb_fab1(sch_1):\MG_CLK_G2-BCLK\" )
					)
					( Units "uMatchProp" "ns" 1.000000)
					( Origin gBackEnd )
				)
			)
			( pinPair "@baseboard_fab2_lib.baseboard_fab2(sch_1):\PP6095\"
				( pinRef "@baseboard_fab2_lib.baseboard_fab2(sch_1):page147_i1:RGMII2RXD0_RMII2RXD0_GPIOV4" )
				( pinRef "@baseboard_fab2_lib.baseboard_fab2(sch_1):page121_i34:GPP_K1_LAN_NCSI_TXD0" )
				( attribute "PROPAGATION_DELAY_MIN" "1000.00 MIL"
					( Units "uMaxMinProp" "ns" 1.000000)
					( Status sCSetFlattened )
					( Origin gBackEnd )
				)
				( attribute "PROPAGATION_DELAY_MAX" "8000.00 MIL"
					( Units "uMaxMinProp" "ns" 1.000000)
					( Status sCSetFlattened )
					( Origin gBackEnd )
				)
			)
			( pinPair "@baseboard_fab2_lib.baseboard_fab2(sch_1):\PP6086\"
				( pinRef "@baseboard_fab2_lib.baseboard_fab2(sch_1):page147_i1:RGMII2RXD1_RMII2RXD1_GPIOV5" )
				( pinRef "@baseboard_fab2_lib.baseboard_fab2(sch_1):page121_i34:GPP_K2_LAN_NCSI_TXD1" )
				( attribute "PROPAGATION_DELAY_MIN" "1000.00 MIL"
					( Units "uMaxMinProp" "ns" 1.000000)
					( Status sCSetFlattened )
					( Origin gBackEnd )
				)
				( attribute "PROPAGATION_DELAY_MAX" "8000.00 MIL"
					( Units "uMaxMinProp" "ns" 1.000000)
					( Status sCSetFlattened )
					( Origin gBackEnd )
				)
			)
			( pinPair "@baseboard_fab2_lib.baseboard_fab2(sch_1):\PP39\"
				( pinRef "@baseboard_fab2_lib.baseboard_fab2(sch_1):page147_i1:RGMII2TXCK_RMII2TXEN_GPIOT6" )
				( pinRef "@baseboard_fab2_lib.baseboard_fab2(sch_1):page147_i116:A" )
				( attribute "PROPAGATION_DELAY_MAX" "500.00 MIL"
					( Units "uMaxMinProp" "ns" 1.000000)
					( Status sCSetFlattened )
					( Origin gBackEnd )
				)
			)
			( pinPair "@baseboard_fab2_lib.baseboard_fab2(sch_1):\PP6100\"
				( pinRef "@baseboard_fab2_lib.baseboard_fab2(sch_1):page147_i1:RGMII2TXD0_RMII2TXD0_GPIOU0" )
				( pinRef "@baseboard_fab2_lib.baseboard_fab2(sch_1):page121_i34:GPP_K5_LAN_NCSI_RXD0" )
				( attribute "PROPAGATION_DELAY_MIN" "1000.00 MIL"
					( Units "uMaxMinProp" "ns" 1.000000)
					( Status sCSetFlattened )
					( Origin gBackEnd )
				)
				( attribute "PROPAGATION_DELAY_MAX" "8000.00 MIL"
					( Units "uMaxMinProp" "ns" 1.000000)
					( Status sCSetFlattened )
					( Origin gBackEnd )
				)
			)
			( pinPair "@baseboard_fab2_lib.baseboard_fab2(sch_1):\PP6102\"
				( pinRef "@baseboard_fab2_lib.baseboard_fab2(sch_1):page147_i1:RGMII2TXD1_RMII2TXD1_GPIOU1" )
				( pinRef "@baseboard_fab2_lib.baseboard_fab2(sch_1):page121_i34:GPP_K6_LAN_NCSI_RXD1" )
				( attribute "PROPAGATION_DELAY_MIN" "1000.00 MIL"
					( Units "uMaxMinProp" "ns" 1.000000)
					( Status sCSetFlattened )
					( Origin gBackEnd )
				)
				( attribute "PROPAGATION_DELAY_MAX" "8000.00 MIL"
					( Units "uMaxMinProp" "ns" 1.000000)
					( Status sCSetFlattened )
					( Origin gBackEnd )
				)
			)
			( pinPair "@baseboard_fab2_lib.baseboard_fab2(sch_1):\PP6101\"
				( pinRef "@baseboard_fab2_lib.baseboard_fab2(sch_1):page147_i1:RGMII2TXCK_RMII2TXEN_GPIOT6" )
				( pinRef "@baseboard_fab2_lib.baseboard_fab2(sch_1):page121_i34:GPP_K4_LAN_NCSI_CRS_DV" )
				( attribute "PROPAGATION_DELAY_MIN" "1000.00 MIL"
					( Units "uMaxMinProp" "ns" 1.000000)
					( Status sCSetFlattened )
					( Origin gBackEnd )
				)
				( attribute "PROPAGATION_DELAY_MAX" "8000.00 MIL"
					( Units "uMaxMinProp" "ns" 1.000000)
					( Status sCSetFlattened )
					( Origin gBackEnd )
				)
			)
			( pinPair "@baseboard_fab2_lib.baseboard_fab2(sch_1):\PP6131\"
				( pinRef "@baseboard_fab2_lib.baseboard_fab2(sch_1):page154_i74:IA1" )
				( pinRef "@baseboard_fab2_lib.baseboard_fab2(sch_1):page144_i347:GPIOI5_SPICK_VBCK" )
				( attribute "RELATIVE_PROPAGATION_DELAY_SCOPE" "G"
					( Parent
						( matchGroupRef "@crescent_city_bb_fab1_lib.crescent_city_bb_fab1(sch_1):\SPI_BMC-MUX\" )
					)
					( Origin gBackEnd )
				)
				( attribute "RELATIVE_PROPAGATION_DELAY" "TARGET,TARGET"
					( Parent
						( matchGroupRef "@crescent_city_bb_fab1_lib.crescent_city_bb_fab1(sch_1):\SPI_BMC-MUX\" )
					)
					( Units "uMatchProp" "ns" 1.000000)
					( Origin gBackEnd )
				)
			)
			( pinPair "@baseboard_fab2_lib.baseboard_fab2(sch_1):\PP6132\"
				( pinRef "@baseboard_fab2_lib.baseboard_fab2(sch_1):page154_i74:IC1" )
				( pinRef "@baseboard_fab2_lib.baseboard_fab2(sch_1):page144_i347:GPIOI4_SPICS0_N_VBCS_N" )
			)
			( pinPair "@baseboard_fab2_lib.baseboard_fab2(sch_1):\PP6129\"
				( pinRef "@baseboard_fab2_lib.baseboard_fab2(sch_1):page154_i74:ID1" )
				( pinRef "@baseboard_fab2_lib.baseboard_fab2(sch_1):page144_i347:GPIOI7_SPIDI_VBDI" )
			)
			( pinPair "@baseboard_fab2_lib.baseboard_fab2(sch_1):\PP6130\"
				( pinRef "@baseboard_fab2_lib.baseboard_fab2(sch_1):page154_i74:IB1" )
				( pinRef "@baseboard_fab2_lib.baseboard_fab2(sch_1):page144_i347:GPIOI6_SPIDO_VBDO" )
			)
			( pinPair "@baseboard_fab2_lib.baseboard_fab2(sch_1):\PP6071\"
				( pinRef "@baseboard_fab2_lib.baseboard_fab2(sch_1):page154_i74:YC" )
				( pinRef "@baseboard_fab2_lib.baseboard_fab2(sch_1):page153_i165:CS_N" )
				( attribute "RELATIVE_PROPAGATION_DELAY_SCOPE" "G"
					( Parent
						( matchGroupRef "@crescent_city_bb_fab1_lib.crescent_city_bb_fab1(sch_1):\SPI_MUX-U3T1\" )
					)
					( Status sCSetFlattened )
					( Origin gBackEnd )
				)
				( attribute "RELATIVE_PROPAGATION_DELAY" "0.00 MIL,250.00 MIL"
					( Parent
						( matchGroupRef "@crescent_city_bb_fab1_lib.crescent_city_bb_fab1(sch_1):\SPI_MUX-U3T1\" )
					)
					( Units "uMatchProp" "ns" 1.000000)
					( Status sCSetFlattened )
					( Origin gBackEnd )
				)
			)
			( pinPair "@baseboard_fab2_lib.baseboard_fab2(sch_1):\PP6072\"
				( pinRef "@baseboard_fab2_lib.baseboard_fab2(sch_1):page154_i74:YC" )
				( pinRef "@baseboard_fab2_lib.baseboard_fab2(sch_1):page153_i146:CS_N" )
				( attribute "RELATIVE_PROPAGATION_DELAY_SCOPE" "G"
					( Parent
						( matchGroupRef "@crescent_city_bb_fab1_lib.crescent_city_bb_fab1(sch_1):\SPI_MUX-U7F1\" )
					)
					( Status sCSetFlattened )
					( Origin gBackEnd )
				)
				( attribute "RELATIVE_PROPAGATION_DELAY" "0.00 MIL,250.00 MIL"
					( Parent
						( matchGroupRef "@crescent_city_bb_fab1_lib.crescent_city_bb_fab1(sch_1):\SPI_MUX-U7F1\" )
					)
					( Units "uMatchProp" "ns" 1.000000)
					( Status sCSetFlattened )
					( Origin gBackEnd )
				)
			)
			( pinPair "@baseboard_fab2_lib.baseboard_fab2(sch_1):\PP6097\"
				( pinRef "@baseboard_fab2_lib.baseboard_fab2(sch_1):page121_i34:SPI0_MOSI_IO0" )
				( pinRef "@baseboard_fab2_lib.baseboard_fab2(sch_1):page184_i87:IO3" )
				( attribute "RELATIVE_PROPAGATION_DELAY_SCOPE" "G"
					( Parent
						( matchGroupRef "@baseboard_fab2_lib.baseboard_fab2(sch_1):\SPI_PCH-TPM\" )
					)
					( Status sCSetFlattened )
					( Origin gBackEnd )
				)
				( attribute "RELATIVE_PROPAGATION_DELAY" "0.00 MIL,250.00 MIL"
					( Parent
						( matchGroupRef "@baseboard_fab2_lib.baseboard_fab2(sch_1):\SPI_PCH-TPM\" )
					)
					( Units "uMatchProp" "ns" 1.000000)
					( Status sCSetFlattened )
					( Origin gBackEnd )
				)
			)
			( pinPair "@baseboard_fab2_lib.baseboard_fab2(sch_1):\PP6098\"
				( pinRef "@baseboard_fab2_lib.baseboard_fab2(sch_1):page121_i34:SPI0_MOSI_IO0" )
				( pinRef "@baseboard_fab2_lib.baseboard_fab2(sch_1):page154_i74:IB0" )
				( attribute "RELATIVE_PROPAGATION_DELAY_SCOPE" "G"
					( Parent
						( matchGroupRef "@crescent_city_bb_fab1_lib.crescent_city_bb_fab1(sch_1):\SPI_PCH-MUX\" )
					)
					( Status sCSetFlattened )
					( Origin gBackEnd )
				)
				( attribute "RELATIVE_PROPAGATION_DELAY" "0.00 MIL,125.00 MIL"
					( Parent
						( matchGroupRef "@crescent_city_bb_fab1_lib.crescent_city_bb_fab1(sch_1):\SPI_PCH-MUX\" )
					)
					( Units "uMatchProp" "ns" 1.000000)
					( Status sCSetFlattened )
					( Origin gBackEnd )
				)
			)
			( pinPair "@baseboard_fab2_lib.baseboard_fab2(sch_1):\PP6111\"
				( pinRef "@baseboard_fab2_lib.baseboard_fab2(sch_1):page121_i34:SPI0_IO2" )
				( pinRef "@baseboard_fab2_lib.baseboard_fab2(sch_1):page154_i75:IA0" )
				( attribute "RELATIVE_PROPAGATION_DELAY_SCOPE" "G"
					( Parent
						( matchGroupRef "@crescent_city_bb_fab1_lib.crescent_city_bb_fab1(sch_1):\SPI_PCH-MUX\" )
					)
					( Status sCSetFlattened )
					( Origin gBackEnd )
				)
				( attribute "RELATIVE_PROPAGATION_DELAY" "0.00 MIL,125.00 MIL"
					( Parent
						( matchGroupRef "@crescent_city_bb_fab1_lib.crescent_city_bb_fab1(sch_1):\SPI_PCH-MUX\" )
					)
					( Units "uMatchProp" "ns" 1.000000)
					( Status sCSetFlattened )
					( Origin gBackEnd )
				)
			)
			( pinPair "@baseboard_fab2_lib.baseboard_fab2(sch_1):\PP6090\"
				( pinRef "@baseboard_fab2_lib.baseboard_fab2(sch_1):page154_i74:YB" )
				( pinRef "@baseboard_fab2_lib.baseboard_fab2(sch_1):page153_i165:DI_IO(0)" )
				( attribute "RELATIVE_PROPAGATION_DELAY_SCOPE" "G"
					( Parent
						( matchGroupRef "@crescent_city_bb_fab1_lib.crescent_city_bb_fab1(sch_1):\SPI_MUX-U3T1\" )
					)
					( Status sCSetFlattened )
					( Origin gBackEnd )
				)
				( attribute "RELATIVE_PROPAGATION_DELAY" "0.00 MIL,125.00 MIL"
					( Parent
						( matchGroupRef "@crescent_city_bb_fab1_lib.crescent_city_bb_fab1(sch_1):\SPI_MUX-U3T1\" )
					)
					( Units "uMatchProp" "ns" 1.000000)
					( Status sCSetFlattened )
					( Origin gBackEnd )
				)
			)
			( pinPair "@baseboard_fab2_lib.baseboard_fab2(sch_1):\PP6091\"
				( pinRef "@baseboard_fab2_lib.baseboard_fab2(sch_1):page154_i74:YB" )
				( pinRef "@baseboard_fab2_lib.baseboard_fab2(sch_1):page153_i146:DI_IO(0)" )
				( attribute "RELATIVE_PROPAGATION_DELAY_SCOPE" "G"
					( Parent
						( matchGroupRef "@crescent_city_bb_fab1_lib.crescent_city_bb_fab1(sch_1):\SPI_MUX-U7F1\" )
					)
					( Status sCSetFlattened )
					( Origin gBackEnd )
				)
				( attribute "RELATIVE_PROPAGATION_DELAY" "0.00 MIL,125.00 MIL"
					( Parent
						( matchGroupRef "@crescent_city_bb_fab1_lib.crescent_city_bb_fab1(sch_1):\SPI_MUX-U7F1\" )
					)
					( Units "uMatchProp" "ns" 1.000000)
					( Status sCSetFlattened )
					( Origin gBackEnd )
				)
			)
			( pinPair "@baseboard_fab2_lib.baseboard_fab2(sch_1):\PP6099\"
				( pinRef "@baseboard_fab2_lib.baseboard_fab2(sch_1):page121_i34:SPI0_TPM_CS_N" )
				( pinRef "@baseboard_fab2_lib.baseboard_fab2(sch_1):page184_i87:IO5" )
				( attribute "RELATIVE_PROPAGATION_DELAY_SCOPE" "L"
					( Parent
						( matchGroupRef "@baseboard_fab2_lib.baseboard_fab2(sch_1):\SPI_PCH-TPM\" )
					)
					( Status sCSetFlattened )
					( Origin gBackEnd )
				)
				( attribute "RELATIVE_PROPAGATION_DELAY" "0.00 MIL,250.00 MIL"
					( Parent
						( matchGroupRef "@baseboard_fab2_lib.baseboard_fab2(sch_1):\SPI_PCH-TPM\" )
					)
					( Units "uMatchProp" "ns" 1.000000)
					( Status sCSetFlattened )
					( Origin gBackEnd )
				)
			)
			( pinPair "@baseboard_fab2_lib.baseboard_fab2(sch_1):\PP34\"
				( pinRef "@baseboard_fab2_lib.baseboard_fab2(sch_1):page153_i167:B" )
				( pinRef "@baseboard_fab2_lib.baseboard_fab2(sch_1):page153_i165:CLK" )
				( attribute "PROPAGATION_DELAY_MAX" "4000.00 MIL"
					( Units "uMaxMinProp" "ns" 1.000000)
					( Status sCSetFlattened )
					( Origin gBackEnd )
				)
			)
			( pinPair "@baseboard_fab2_lib.baseboard_fab2(sch_1):\PP35\"
				( pinRef "@baseboard_fab2_lib.baseboard_fab2(sch_1):page153_i167:A" )
				( pinRef "@baseboard_fab2_lib.baseboard_fab2(sch_1):spi_switch_clk:\T.1\" )
				( attribute "PROPAGATION_DELAY_MAX" "200.00 MIL"
					( Units "uMaxMinProp" "ns" 1.000000)
					( Status sCSetFlattened )
					( Origin gBackEnd )
				)
			)
			( pinPair "@baseboard_fab2_lib.baseboard_fab2(sch_1):\PP36\"
				( pinRef "@baseboard_fab2_lib.baseboard_fab2(sch_1):page153_i166:A" )
				( pinRef "@baseboard_fab2_lib.baseboard_fab2(sch_1):spi_switch_clk:\T.1\" )
				( attribute "PROPAGATION_DELAY_MAX" "200.00 MIL"
					( Units "uMaxMinProp" "ns" 1.000000)
					( Status sCSetFlattened )
					( Origin gBackEnd )
				)
			)
			( pinPair "@baseboard_fab2_lib.baseboard_fab2(sch_1):\PP38\"
				( pinRef "@baseboard_fab2_lib.baseboard_fab2(sch_1):page153_i146:CLK" )
				( pinRef "@baseboard_fab2_lib.baseboard_fab2(sch_1):page153_i166:B" )
				( attribute "PROPAGATION_DELAY_MAX" "4000.00 MIL"
					( Units "uMaxMinProp" "ns" 1.000000)
					( Status sCSetFlattened )
					( Origin gBackEnd )
				)
			)
			( pinPair "@baseboard_fab2_lib.baseboard_fab2(sch_1):\PP6093\"
				( pinRef "@baseboard_fab2_lib.baseboard_fab2(sch_1):page154_i74:YA" )
				( pinRef "@baseboard_fab2_lib.baseboard_fab2(sch_1):page153_i165:CLK" )
				( attribute "RELATIVE_PROPAGATION_DELAY_SCOPE" "G"
					( Parent
						( matchGroupRef "@crescent_city_bb_fab1_lib.crescent_city_bb_fab1(sch_1):\SPI_MUX-U3T1\" )
					)
					( Origin gBackEnd )
				)
				( attribute "RELATIVE_PROPAGATION_DELAY" "TARGET,TARGET"
					( Parent
						( matchGroupRef "@crescent_city_bb_fab1_lib.crescent_city_bb_fab1(sch_1):\SPI_MUX-U3T1\" )
					)
					( Units "uMatchProp" "ns" 1.000000)
					( Origin gBackEnd )
				)
			)
			( pinPair "@baseboard_fab2_lib.baseboard_fab2(sch_1):\PP6094\"
				( pinRef "@baseboard_fab2_lib.baseboard_fab2(sch_1):page154_i74:YA" )
				( pinRef "@baseboard_fab2_lib.baseboard_fab2(sch_1):page153_i146:CLK" )
				( attribute "RELATIVE_PROPAGATION_DELAY_SCOPE" "G"
					( Parent
						( matchGroupRef "@crescent_city_bb_fab1_lib.crescent_city_bb_fab1(sch_1):\SPI_MUX-U7F1\" )
					)
					( Origin gBackEnd )
				)
				( attribute "RELATIVE_PROPAGATION_DELAY" "TARGET,TARGET"
					( Parent
						( matchGroupRef "@crescent_city_bb_fab1_lib.crescent_city_bb_fab1(sch_1):\SPI_MUX-U7F1\" )
					)
					( Units "uMatchProp" "ns" 1.000000)
					( Origin gBackEnd )
				)
			)
			( pinPair "@baseboard_fab2_lib.baseboard_fab2(sch_1):\PP6104\"
				( pinRef "@baseboard_fab2_lib.baseboard_fab2(sch_1):page121_i34:SPI0_MISO_IO1" )
				( pinRef "@baseboard_fab2_lib.baseboard_fab2(sch_1):page154_i74:ID0" )
				( attribute "RELATIVE_PROPAGATION_DELAY_SCOPE" "G"
					( Parent
						( matchGroupRef "@crescent_city_bb_fab1_lib.crescent_city_bb_fab1(sch_1):\SPI_PCH-MUX\" )
					)
					( Status sCSetFlattened )
					( Origin gBackEnd )
				)
				( attribute "RELATIVE_PROPAGATION_DELAY" "0.00 MIL,125.00 MIL"
					( Parent
						( matchGroupRef "@crescent_city_bb_fab1_lib.crescent_city_bb_fab1(sch_1):\SPI_PCH-MUX\" )
					)
					( Units "uMatchProp" "ns" 1.000000)
					( Status sCSetFlattened )
					( Origin gBackEnd )
				)
			)
			( pinPair "@baseboard_fab2_lib.baseboard_fab2(sch_1):\PP6105\"
				( pinRef "@baseboard_fab2_lib.baseboard_fab2(sch_1):page121_i34:SPI0_MISO_IO1" )
				( pinRef "@baseboard_fab2_lib.baseboard_fab2(sch_1):page184_i87:IO4" )
				( attribute "RELATIVE_PROPAGATION_DELAY_SCOPE" "G"
					( Parent
						( matchGroupRef "@baseboard_fab2_lib.baseboard_fab2(sch_1):\SPI_PCH-TPM\" )
					)
					( Status sCSetFlattened )
					( Origin gBackEnd )
				)
				( attribute "RELATIVE_PROPAGATION_DELAY" "0.00 MIL,250.00 MIL"
					( Parent
						( matchGroupRef "@baseboard_fab2_lib.baseboard_fab2(sch_1):\SPI_PCH-TPM\" )
					)
					( Units "uMatchProp" "ns" 1.000000)
					( Status sCSetFlattened )
					( Origin gBackEnd )
				)
			)
			( pinPair "@baseboard_fab2_lib.baseboard_fab2(sch_1):\PP26\"
				( pinRef "@baseboard_fab2_lib.baseboard_fab2(sch_1):page184_i88:A" )
				( pinRef "@baseboard_fab2_lib.baseboard_fab2(sch_1):spi_pch_clk:\T.1\" )
				( attribute "PROPAGATION_DELAY_MAX" "200.00 MIL"
					( Units "uMaxMinProp" "ns" 1.000000)
					( Status sCSetFlattened )
					( Origin gBackEnd )
				)
			)
			( pinPair "@baseboard_fab2_lib.baseboard_fab2(sch_1):\PP29\"
				( pinRef "@baseboard_fab2_lib.baseboard_fab2(sch_1):page154_i74:IA0" )
				( pinRef "@baseboard_fab2_lib.baseboard_fab2(sch_1):page121_i34:SPI0_CLK" )
				( attribute "RELATIVE_PROPAGATION_DELAY_SCOPE" "G"
					( Parent
						( matchGroupRef "@crescent_city_bb_fab1_lib.crescent_city_bb_fab1(sch_1):\SPI_PCH-MUX\" )
					)
					( Origin gBackEnd )
				)
				( attribute "RELATIVE_PROPAGATION_DELAY" "TARGET,TARGET"
					( Parent
						( matchGroupRef "@crescent_city_bb_fab1_lib.crescent_city_bb_fab1(sch_1):\SPI_PCH-MUX\" )
					)
					( Units "uMatchProp" "ns" 1.000000)
					( Origin gBackEnd )
				)
			)
			( pinPair "@baseboard_fab2_lib.baseboard_fab2(sch_1):\PP30\"
				( pinRef "@baseboard_fab2_lib.baseboard_fab2(sch_1):page184_i87:IO1" )
				( pinRef "@baseboard_fab2_lib.baseboard_fab2(sch_1):page184_i88:B" )
				( attribute "PROPAGATION_DELAY_MAX" "4000.00 MIL"
					( Units "uMaxMinProp" "ns" 1.000000)
					( Status sCSetFlattened )
					( Origin gBackEnd )
				)
			)
			( pinPair "@baseboard_fab2_lib.baseboard_fab2(sch_1):\PP6103\"
				( pinRef "@baseboard_fab2_lib.baseboard_fab2(sch_1):page121_i34:SPI0_CLK" )
				( pinRef "@baseboard_fab2_lib.baseboard_fab2(sch_1):page184_i87:IO1" )
				( attribute "RELATIVE_PROPAGATION_DELAY_SCOPE" "G"
					( Parent
						( matchGroupRef "@baseboard_fab2_lib.baseboard_fab2(sch_1):\SPI_PCH-TPM\" )
					)
					( Status sCSetFlattened )
					( Origin gBackEnd )
				)
				( attribute "RELATIVE_PROPAGATION_DELAY" "0.00 MIL,250.00 MIL"
					( Parent
						( matchGroupRef "@baseboard_fab2_lib.baseboard_fab2(sch_1):\SPI_PCH-TPM\" )
					)
					( Units "uMatchProp" "ns" 1.000000)
					( Status sCSetFlattened )
					( Origin gBackEnd )
				)
			)
			( pinPair "@baseboard_fab2_lib.baseboard_fab2(sch_1):\PP5809\"
				( pinRef "@baseboard_fab2_lib.baseboard_fab2(sch_1):page146_i1:ROMD2" )
				( pinRef "@baseboard_fab2_lib.baseboard_fab2(sch_1):page162_i32:DO_IO(1)" )
			)
			( pinPair "@baseboard_fab2_lib.baseboard_fab2(sch_1):\PP5801\"
				( pinRef "@baseboard_fab2_lib.baseboard_fab2(sch_1):page146_i1:ROMD1" )
				( pinRef "@baseboard_fab2_lib.baseboard_fab2(sch_1):page162_i32:DI_IO(0)" )
			)
			( pinPair "@baseboard_fab2_lib.baseboard_fab2(sch_1):\PP5802\"
				( pinRef "@baseboard_fab2_lib.baseboard_fab2(sch_1):page146_i1:ROMD0" )
				( pinRef "@baseboard_fab2_lib.baseboard_fab2(sch_1):page162_i32:CLK" )
				( attribute "RELATIVE_PROPAGATION_DELAY_SCOPE" "G"
					( Parent
						( matchGroupRef "@crescent_city_bb_fab1_lib.crescent_city_bb_fab1(sch_1):\SPI_BMC\" )
					)
					( Origin gBackEnd )
				)
				( attribute "RELATIVE_PROPAGATION_DELAY" "TARGET,TARGET"
					( Parent
						( matchGroupRef "@crescent_city_bb_fab1_lib.crescent_city_bb_fab1(sch_1):\SPI_BMC\" )
					)
					( Units "uMatchProp" "ns" 1.000000)
					( Origin gBackEnd )
				)
			)
			( pinPair "@baseboard_fab2_lib.baseboard_fab2(sch_1):\PP5807\"
				( pinRef "@baseboard_fab2_lib.baseboard_fab2(sch_1):page146_i1:ROMCS0_N" )
				( pinRef "@baseboard_fab2_lib.baseboard_fab2(sch_1):page162_i32:CS_N" )
			)
			( pinPair "@baseboard_fab2_lib.baseboard_fab2(sch_1):\PP6112\"
				( pinRef "@baseboard_fab2_lib.baseboard_fab2(sch_1):page121_i34:SPI0_IO3" )
				( pinRef "@baseboard_fab2_lib.baseboard_fab2(sch_1):page154_i75:IB0" )
				( attribute "RELATIVE_PROPAGATION_DELAY_SCOPE" "G"
					( Parent
						( matchGroupRef "@crescent_city_bb_fab1_lib.crescent_city_bb_fab1(sch_1):\SPI_PCH-MUX\" )
					)
					( Status sCSetFlattened )
					( Origin gBackEnd )
				)
				( attribute "RELATIVE_PROPAGATION_DELAY" "0.00 MIL,125.00 MIL"
					( Parent
						( matchGroupRef "@crescent_city_bb_fab1_lib.crescent_city_bb_fab1(sch_1):\SPI_PCH-MUX\" )
					)
					( Units "uMatchProp" "ns" 1.000000)
					( Status sCSetFlattened )
					( Origin gBackEnd )
				)
			)
			( pinPair "@baseboard_fab2_lib.baseboard_fab2(sch_1):\PP22\"
				( pinRef "@baseboard_fab2_lib.baseboard_fab2(sch_1):page153_i98:A" )
				( pinRef "@baseboard_fab2_lib.baseboard_fab2(sch_1):spi_switch_miso:\T.1\" )
				( attribute "PROPAGATION_DELAY_MAX" "200.00 MIL"
					( Units "uMaxMinProp" "ns" 1.000000)
					( Status sCSetFlattened )
					( Origin gBackEnd )
				)
			)
			( pinPair "@baseboard_fab2_lib.baseboard_fab2(sch_1):\PP23\"
				( pinRef "@baseboard_fab2_lib.baseboard_fab2(sch_1):page153_i155:A" )
				( pinRef "@baseboard_fab2_lib.baseboard_fab2(sch_1):spi_switch_miso:\T.1\" )
				( attribute "PROPAGATION_DELAY_MAX" "200.00 MIL"
					( Units "uMaxMinProp" "ns" 1.000000)
					( Status sCSetFlattened )
					( Origin gBackEnd )
				)
			)
			( pinPair "@baseboard_fab2_lib.baseboard_fab2(sch_1):\PP24\"
				( pinRef "@baseboard_fab2_lib.baseboard_fab2(sch_1):page153_i146:DO_IO(1)" )
				( pinRef "@baseboard_fab2_lib.baseboard_fab2(sch_1):page153_i98:B" )
				( attribute "PROPAGATION_DELAY_MAX" "4000.00 MIL"
					( Units "uMaxMinProp" "ns" 1.000000)
					( Status sCSetFlattened )
					( Origin gBackEnd )
				)
			)
			( pinPair "@baseboard_fab2_lib.baseboard_fab2(sch_1):\PP25\"
				( pinRef "@baseboard_fab2_lib.baseboard_fab2(sch_1):page153_i165:DO_IO(1)" )
				( pinRef "@baseboard_fab2_lib.baseboard_fab2(sch_1):page153_i155:B" )
				( attribute "PROPAGATION_DELAY_MAX" "4000.00 MIL"
					( Units "uMaxMinProp" "ns" 1.000000)
					( Status sCSetFlattened )
					( Origin gBackEnd )
				)
			)
			( pinPair "@baseboard_fab2_lib.baseboard_fab2(sch_1):\PP6108\"
				( pinRef "@baseboard_fab2_lib.baseboard_fab2(sch_1):page154_i74:YD" )
				( pinRef "@baseboard_fab2_lib.baseboard_fab2(sch_1):page153_i165:DO_IO(1)" )
				( attribute "RELATIVE_PROPAGATION_DELAY_SCOPE" "G"
					( Parent
						( matchGroupRef "@crescent_city_bb_fab1_lib.crescent_city_bb_fab1(sch_1):\SPI_MUX-U3T1\" )
					)
					( Status sCSetFlattened )
					( Origin gBackEnd )
				)
				( attribute "RELATIVE_PROPAGATION_DELAY" "0.00 MIL,125.00 MIL"
					( Parent
						( matchGroupRef "@crescent_city_bb_fab1_lib.crescent_city_bb_fab1(sch_1):\SPI_MUX-U3T1\" )
					)
					( Units "uMatchProp" "ns" 1.000000)
					( Status sCSetFlattened )
					( Origin gBackEnd )
				)
			)
			( pinPair "@baseboard_fab2_lib.baseboard_fab2(sch_1):\PP6109\"
				( pinRef "@baseboard_fab2_lib.baseboard_fab2(sch_1):page153_i146:DO_IO(1)" )
				( pinRef "@baseboard_fab2_lib.baseboard_fab2(sch_1):page154_i74:YD" )
				( attribute "RELATIVE_PROPAGATION_DELAY_SCOPE" "G"
					( Parent
						( matchGroupRef "@crescent_city_bb_fab1_lib.crescent_city_bb_fab1(sch_1):\SPI_MUX-U7F1\" )
					)
					( Status sCSetFlattened )
					( Origin gBackEnd )
				)
				( attribute "RELATIVE_PROPAGATION_DELAY" "0.00 MIL,125.00 MIL"
					( Parent
						( matchGroupRef "@crescent_city_bb_fab1_lib.crescent_city_bb_fab1(sch_1):\SPI_MUX-U7F1\" )
					)
					( Units "uMatchProp" "ns" 1.000000)
					( Status sCSetFlattened )
					( Origin gBackEnd )
				)
			)
			( pinPair "@baseboard_fab2_lib.baseboard_fab2(sch_1):\PP5803\"
				( pinRef "@baseboard_fab2_lib.baseboard_fab2(sch_1):page139_i72:NVM_CS_N" )
				( pinRef "@baseboard_fab2_lib.baseboard_fab2(sch_1):page140_i1:S_N" )
			)
			( pinPair "@baseboard_fab2_lib.baseboard_fab2(sch_1):\PP5808\"
				( pinRef "@baseboard_fab2_lib.baseboard_fab2(sch_1):page140_i1:DQ1" )
				( pinRef "@baseboard_fab2_lib.baseboard_fab2(sch_1):page139_i72:NVM_SO" )
			)
			( pinPair "@baseboard_fab2_lib.baseboard_fab2(sch_1):\PP5805\"
				( pinRef "@baseboard_fab2_lib.baseboard_fab2(sch_1):page139_i72:NVM_SI" )
				( pinRef "@baseboard_fab2_lib.baseboard_fab2(sch_1):page140_i1:DQ0" )
			)
			( pinPair "@baseboard_fab2_lib.baseboard_fab2(sch_1):\PP6110\"
				( pinRef "@baseboard_fab2_lib.baseboard_fab2(sch_1):page140_i1:C" )
				( pinRef "@baseboard_fab2_lib.baseboard_fab2(sch_1):page139_i72:NVM_SK" )
				( attribute "RELATIVE_PROPAGATION_DELAY_SCOPE" "G"
					( Parent
						( matchGroupRef "@crescent_city_bb_fab1_lib.crescent_city_bb_fab1(sch_1):\SPI_NIC\" )
					)
					( Origin gBackEnd )
				)
				( attribute "RELATIVE_PROPAGATION_DELAY" "TARGET,TARGET"
					( Parent
						( matchGroupRef "@crescent_city_bb_fab1_lib.crescent_city_bb_fab1(sch_1):\SPI_NIC\" )
					)
					( Units "uMatchProp" "ns" 1.000000)
					( Origin gBackEnd )
				)
			)
			( pinPair "@baseboard_fab2_lib.baseboard_fab2(sch_1):\PP6096\"
				( pinRef "@baseboard_fab2_lib.baseboard_fab2(sch_1):page121_i34:SPI0_FLASH_CS0_N" )
				( pinRef "@baseboard_fab2_lib.baseboard_fab2(sch_1):page154_i74:IC0" )
				( attribute "RELATIVE_PROPAGATION_DELAY_SCOPE" "G"
					( Parent
						( matchGroupRef "@crescent_city_bb_fab1_lib.crescent_city_bb_fab1(sch_1):\SPI_PCH-MUX\" )
					)
					( Status sCSetFlattened )
					( Origin gBackEnd )
				)
				( attribute "RELATIVE_PROPAGATION_DELAY" "0.00 MIL,125.00 MIL"
					( Parent
						( matchGroupRef "@crescent_city_bb_fab1_lib.crescent_city_bb_fab1(sch_1):\SPI_PCH-MUX\" )
					)
					( Units "uMatchProp" "ns" 1.000000)
					( Status sCSetFlattened )
					( Origin gBackEnd )
				)
			)
			( pinPair "@baseboard_fab2_lib.baseboard_fab2(sch_1):\PP5575\"
				( pinRef "@baseboard_fab2_lib.baseboard_fab2(sch_1):page213_i37:B" )
				( pinRef "@baseboard_fab2_lib.baseboard_fab2(sch_1):page213_i96:VDIO" )
				( attribute "PROPAGATION_DELAY_MAX" "1000.00 MIL"
					( Units "uMaxMinProp" "ns" 1.000000)
					( Origin gBackEnd )
				)
			)
			( pinPair "@baseboard_fab2_lib.baseboard_fab2(sch_1):\PP5577\"
				( pinRef "@baseboard_fab2_lib.baseboard_fab2(sch_1):page55_i29:B" )
				( pinRef "@baseboard_fab2_lib.baseboard_fab2(sch_1):page206_i38:B" )
				( attribute "PROPAGATION_DELAY_MAX" "27000.00 MIL"
					( Units "uMaxMinProp" "ns" 1.000000)
					( Origin gBackEnd )
				)
			)
			( pinPair "@baseboard_fab2_lib.baseboard_fab2(sch_1):\PP5578\"
				( pinRef "@baseboard_fab2_lib.baseboard_fab2(sch_1):page55_i29:B" )
				( pinRef "@baseboard_fab2_lib.baseboard_fab2(sch_1):page55_i21:A" )
				( attribute "PROPAGATION_DELAY_MAX" "400.00 MIL"
					( Units "uMaxMinProp" "ns" 1.000000)
					( Origin gBackEnd )
				)
			)
			( pinPair "@baseboard_fab2_lib.baseboard_fab2(sch_1):\PP5579\"
				( pinRef "@baseboard_fab2_lib.baseboard_fab2(sch_1):page206_i38:B" )
				( pinRef "@baseboard_fab2_lib.baseboard_fab2(sch_1):page206_i4:B" )
				( attribute "PROPAGATION_DELAY_MAX" "200.00 MIL"
					( Units "uMaxMinProp" "ns" 1.000000)
					( Origin gBackEnd )
				)
			)
			( pinPair "@baseboard_fab2_lib.baseboard_fab2(sch_1):\PP5580\"
				( pinRef "@baseboard_fab2_lib.baseboard_fab2(sch_1):page55_i172:SVIDDATA(0)" )
				( pinRef "@baseboard_fab2_lib.baseboard_fab2(sch_1):page55_i29:A" )
				( attribute "PROPAGATION_DELAY_MAX" "4500.00 MIL"
					( Units "uMaxMinProp" "ns" 1.000000)
					( Origin gBackEnd )
				)
			)
			( pinPair "@baseboard_fab2_lib.baseboard_fab2(sch_1):\PP5581\"
				( pinRef "@baseboard_fab2_lib.baseboard_fab2(sch_1):page206_i130:VDIO" )
				( pinRef "@baseboard_fab2_lib.baseboard_fab2(sch_1):page206_i38:A" )
				( attribute "PROPAGATION_DELAY_MAX" "1000.00 MIL"
					( Units "uMaxMinProp" "ns" 1.000000)
					( Origin gBackEnd )
				)
			)
			( pinPair "@baseboard_fab2_lib.baseboard_fab2(sch_1):\PP5568\"
				( pinRef "@baseboard_fab2_lib.baseboard_fab2(sch_1):page211_i16:B" )
				( pinRef "@baseboard_fab2_lib.baseboard_fab2(sch_1):page211_i93:VDIO" )
				( attribute "PROPAGATION_DELAY_MAX" "1000.00 MIL"
					( Units "uMaxMinProp" "ns" 1.000000)
					( Origin gBackEnd )
				)
			)
			( pinPair "@baseboard_fab2_lib.baseboard_fab2(sch_1):\PP5570\"
				( pinRef "@baseboard_fab2_lib.baseboard_fab2(sch_1):page211_i16:A" )
				( pinRef "@baseboard_fab2_lib.baseboard_fab2(sch_1):page21_i151:B" )
				( attribute "PROPAGATION_DELAY_MAX" "27000.00 MIL"
					( Units "uMaxMinProp" "ns" 1.000000)
					( Origin gBackEnd )
				)
			)
			( pinPair "@baseboard_fab2_lib.baseboard_fab2(sch_1):\PP5571\"
				( pinRef "@baseboard_fab2_lib.baseboard_fab2(sch_1):page211_i16:A" )
				( pinRef "@baseboard_fab2_lib.baseboard_fab2(sch_1):page211_i17:B" )
				( attribute "PROPAGATION_DELAY_MAX" "200.00 MIL"
					( Units "uMaxMinProp" "ns" 1.000000)
					( Origin gBackEnd )
				)
			)
			( pinPair "@baseboard_fab2_lib.baseboard_fab2(sch_1):\PP5572\"
				( pinRef "@baseboard_fab2_lib.baseboard_fab2(sch_1):page21_i163:A" )
				( pinRef "@baseboard_fab2_lib.baseboard_fab2(sch_1):page21_i151:B" )
				( attribute "PROPAGATION_DELAY_MAX" "400.00 MIL"
					( Units "uMaxMinProp" "ns" 1.000000)
					( Origin gBackEnd )
				)
			)
			( pinPair "@baseboard_fab2_lib.baseboard_fab2(sch_1):\PP5573\"
				( pinRef "@baseboard_fab2_lib.baseboard_fab2(sch_1):page201_i155:VDIO" )
				( pinRef "@baseboard_fab2_lib.baseboard_fab2(sch_1):page201_i98:A" )
				( attribute "PROPAGATION_DELAY_MAX" "1000.00 MIL"
					( Units "uMaxMinProp" "ns" 1.000000)
					( Origin gBackEnd )
				)
			)
			( pinPair "@baseboard_fab2_lib.baseboard_fab2(sch_1):\PP5574\"
				( pinRef "@baseboard_fab2_lib.baseboard_fab2(sch_1):page21_i259:SVIDDATA(0)" )
				( pinRef "@baseboard_fab2_lib.baseboard_fab2(sch_1):page21_i151:A" )
				( attribute "PROPAGATION_DELAY_MAX" "4500.00 MIL"
					( Units "uMaxMinProp" "ns" 1.000000)
					( Origin gBackEnd )
				)
			)
			( pinPair "@baseboard_fab2_lib.baseboard_fab2(sch_1):\PP5477\"
				( pinRef "@baseboard_fab2_lib.baseboard_fab2(sch_1):page226_i53:B" )
				( pinRef "@baseboard_fab2_lib.baseboard_fab2(sch_1):page226_i90:VCLK" )
				( attribute "PROPAGATION_DELAY_MAX" "1000.00 MIL"
					( Units "uMaxMinProp" "ns" 1.000000)
					( Origin gBackEnd )
				)
			)
			( pinPair "@baseboard_fab2_lib.baseboard_fab2(sch_1):\PP5479\"
				( pinRef "@baseboard_fab2_lib.baseboard_fab2(sch_1):page226_i53:A" )
				( pinRef "@baseboard_fab2_lib.baseboard_fab2(sch_1):page55_i25:B" )
				( attribute "PROPAGATION_DELAY_MAX" "27000.00 MIL"
					( Units "uMaxMinProp" "ns" 1.000000)
					( Origin gBackEnd )
				)
			)
			( pinPair "@baseboard_fab2_lib.baseboard_fab2(sch_1):\PP5480\"
				( pinRef "@baseboard_fab2_lib.baseboard_fab2(sch_1):page226_i53:A" )
				( pinRef "@baseboard_fab2_lib.baseboard_fab2(sch_1):page226_i50:B" )
				( attribute "PROPAGATION_DELAY_MAX" "200.00 MIL"
					( Units "uMaxMinProp" "ns" 1.000000)
					( Origin gBackEnd )
				)
			)
			( pinPair "@baseboard_fab2_lib.baseboard_fab2(sch_1):\PP5481\"
				( pinRef "@baseboard_fab2_lib.baseboard_fab2(sch_1):page55_i172:SVIDCLK(1)" )
				( pinRef "@baseboard_fab2_lib.baseboard_fab2(sch_1):page55_i25:A" )
				( attribute "PROPAGATION_DELAY_MAX" "4500.00 MIL"
					( Units "uMaxMinProp" "ns" 1.000000)
					( Origin gBackEnd )
				)
			)
			( pinPair "@baseboard_fab2_lib.baseboard_fab2(sch_1):\PP5482\"
				( pinRef "@baseboard_fab2_lib.baseboard_fab2(sch_1):page223_i90:VCLK" )
				( pinRef "@baseboard_fab2_lib.baseboard_fab2(sch_1):page223_i53:B" )
				( attribute "PROPAGATION_DELAY_MAX" "1000.00 MIL"
					( Units "uMaxMinProp" "ns" 1.000000)
					( Origin gBackEnd )
				)
			)
			( pinPair "@baseboard_fab2_lib.baseboard_fab2(sch_1):\PP5475\"
				( pinRef "@baseboard_fab2_lib.baseboard_fab2(sch_1):page21_i259:SVIDCLK(1)" )
				( pinRef "@baseboard_fab2_lib.baseboard_fab2(sch_1):page21_i153:A" )
				( attribute "PROPAGATION_DELAY_MAX" "4500.00 MIL"
					( Units "uMaxMinProp" "ns" 1.000000)
					( Origin gBackEnd )
				)
			)
			( pinPair "@baseboard_fab2_lib.baseboard_fab2(sch_1):\PP5476\"
				( pinRef "@baseboard_fab2_lib.baseboard_fab2(sch_1):page215_i331:B" )
				( pinRef "@baseboard_fab2_lib.baseboard_fab2(sch_1):page215_i358:VCLK" )
				( attribute "PROPAGATION_DELAY_MAX" "1000.00 MIL"
					( Units "uMaxMinProp" "ns" 1.000000)
					( Origin gBackEnd )
				)
			)
			( pinPair "@baseboard_fab2_lib.baseboard_fab2(sch_1):\PP5562\"
				( pinRef "@baseboard_fab2_lib.baseboard_fab2(sch_1):page213_i96:VCLK" )
				( pinRef "@baseboard_fab2_lib.baseboard_fab2(sch_1):page213_i46:B" )
				( attribute "PROPAGATION_DELAY_MAX" "1000.00 MIL"
					( Units "uMaxMinProp" "ns" 1.000000)
					( Origin gBackEnd )
				)
			)
			( pinPair "@baseboard_fab2_lib.baseboard_fab2(sch_1):\PP5563\"
				( pinRef "@baseboard_fab2_lib.baseboard_fab2(sch_1):page55_i28:B" )
				( pinRef "@baseboard_fab2_lib.baseboard_fab2(sch_1):page206_i54:A" )
				( attribute "PROPAGATION_DELAY_MAX" "27000.00 MIL"
					( Units "uMaxMinProp" "ns" 1.000000)
					( Origin gBackEnd )
				)
			)
			( pinPair "@baseboard_fab2_lib.baseboard_fab2(sch_1):\PP5565\"
				( pinRef "@baseboard_fab2_lib.baseboard_fab2(sch_1):page206_i54:A" )
				( pinRef "@baseboard_fab2_lib.baseboard_fab2(sch_1):page206_i53:B" )
				( attribute "PROPAGATION_DELAY_MAX" "200.00 MIL"
					( Units "uMaxMinProp" "ns" 1.000000)
					( Origin gBackEnd )
				)
			)
			( pinPair "@baseboard_fab2_lib.baseboard_fab2(sch_1):\PP5566\"
				( pinRef "@baseboard_fab2_lib.baseboard_fab2(sch_1):page206_i130:VCLK" )
				( pinRef "@baseboard_fab2_lib.baseboard_fab2(sch_1):page206_i54:B" )
				( attribute "PROPAGATION_DELAY_MAX" "1000.00 MIL"
					( Units "uMaxMinProp" "ns" 1.000000)
					( Origin gBackEnd )
				)
			)
			( pinPair "@baseboard_fab2_lib.baseboard_fab2(sch_1):\PP5567\"
				( pinRef "@baseboard_fab2_lib.baseboard_fab2(sch_1):page55_i172:SVIDCLK(0)" )
				( pinRef "@baseboard_fab2_lib.baseboard_fab2(sch_1):page55_i28:A" )
				( attribute "PROPAGATION_DELAY_MAX" "4500.00 MIL"
					( Units "uMaxMinProp" "ns" 1.000000)
					( Origin gBackEnd )
				)
			)
			( pinPair "@baseboard_fab2_lib.baseboard_fab2(sch_1):\PP5556\"
				( pinRef "@baseboard_fab2_lib.baseboard_fab2(sch_1):page211_i29:B" )
				( pinRef "@baseboard_fab2_lib.baseboard_fab2(sch_1):page211_i93:VCLK" )
				( attribute "PROPAGATION_DELAY_MAX" "1000.00 MIL"
					( Units "uMaxMinProp" "ns" 1.000000)
					( Origin gBackEnd )
				)
			)
			( pinPair "@baseboard_fab2_lib.baseboard_fab2(sch_1):\PP5558\"
				( pinRef "@baseboard_fab2_lib.baseboard_fab2(sch_1):page211_i29:A" )
				( pinRef "@baseboard_fab2_lib.baseboard_fab2(sch_1):page201_i56:A" )
				( attribute "PROPAGATION_DELAY_MAX" "27000.00 MIL"
					( Units "uMaxMinProp" "ns" 1.000000)
					( Origin gBackEnd )
				)
			)
			( pinPair "@baseboard_fab2_lib.baseboard_fab2(sch_1):\PP5559\"
				( pinRef "@baseboard_fab2_lib.baseboard_fab2(sch_1):page201_i52:B" )
				( pinRef "@baseboard_fab2_lib.baseboard_fab2(sch_1):page201_i56:A" )
				( attribute "PROPAGATION_DELAY_MAX" "200.00 MIL"
					( Units "uMaxMinProp" "ns" 1.000000)
					( Origin gBackEnd )
				)
			)
			( pinPair "@baseboard_fab2_lib.baseboard_fab2(sch_1):\PP5560\"
				( pinRef "@baseboard_fab2_lib.baseboard_fab2(sch_1):page201_i56:B" )
				( pinRef "@baseboard_fab2_lib.baseboard_fab2(sch_1):page201_i155:VCLK" )
				( attribute "PROPAGATION_DELAY_MAX" "1000.00 MIL"
					( Units "uMaxMinProp" "ns" 1.000000)
					( Origin gBackEnd )
				)
			)
			( pinPair "@baseboard_fab2_lib.baseboard_fab2(sch_1):\PP5561\"
				( pinRef "@baseboard_fab2_lib.baseboard_fab2(sch_1):page21_i259:SVIDCLK(0)" )
				( pinRef "@baseboard_fab2_lib.baseboard_fab2(sch_1):page21_i150:A" )
				( attribute "PROPAGATION_DELAY_MAX" "4500.00 MIL"
					( Units "uMaxMinProp" "ns" 1.000000)
					( Origin gBackEnd )
				)
			)
			( pinPair "@baseboard_fab2_lib.baseboard_fab2(sch_1):\PP5550\"
				( pinRef "@baseboard_fab2_lib.baseboard_fab2(sch_1):page213_i96:VALRT_N" )
				( pinRef "@baseboard_fab2_lib.baseboard_fab2(sch_1):page213_i16:A" )
				( attribute "PROPAGATION_DELAY_MAX" "1000.00 MIL"
					( Units "uMaxMinProp" "ns" 1.000000)
					( Origin gBackEnd )
				)
			)
			( pinPair "@baseboard_fab2_lib.baseboard_fab2(sch_1):\PP5552\"
				( pinRef "@baseboard_fab2_lib.baseboard_fab2(sch_1):page206_i37:B" )
				( pinRef "@baseboard_fab2_lib.baseboard_fab2(sch_1):page55_i27:B" )
				( attribute "PROPAGATION_DELAY_MAX" "27000.00 MIL"
					( Units "uMaxMinProp" "ns" 1.000000)
					( Origin gBackEnd )
				)
			)
			( pinPair "@baseboard_fab2_lib.baseboard_fab2(sch_1):\PP5553\"
				( pinRef "@baseboard_fab2_lib.baseboard_fab2(sch_1):page55_i27:B" )
				( pinRef "@baseboard_fab2_lib.baseboard_fab2(sch_1):page55_i19:A" )
				( attribute "PROPAGATION_DELAY_MAX" "400.00 MIL"
					( Units "uMaxMinProp" "ns" 1.000000)
					( Origin gBackEnd )
				)
			)
			( pinPair "@baseboard_fab2_lib.baseboard_fab2(sch_1):\PP5555\"
				( pinRef "@baseboard_fab2_lib.baseboard_fab2(sch_1):page206_i130:VALRT_N" )
				( pinRef "@baseboard_fab2_lib.baseboard_fab2(sch_1):page206_i37:A" )
				( attribute "PROPAGATION_DELAY_MAX" "1000.00 MIL"
					( Units "uMaxMinProp" "ns" 1.000000)
					( Origin gBackEnd )
				)
			)
			( pinPair "@baseboard_fab2_lib.baseboard_fab2(sch_1):\PP5544\"
				( pinRef "@baseboard_fab2_lib.baseboard_fab2(sch_1):page211_i61:A" )
				( pinRef "@baseboard_fab2_lib.baseboard_fab2(sch_1):page211_i93:VALRT_N" )
				( attribute "PROPAGATION_DELAY_MAX" "1000.00 MIL"
					( Units "uMaxMinProp" "ns" 1.000000)
					( Origin gBackEnd )
				)
			)
			( pinPair "@baseboard_fab2_lib.baseboard_fab2(sch_1):\PP5546\"
				( pinRef "@baseboard_fab2_lib.baseboard_fab2(sch_1):page21_i149:B" )
				( pinRef "@baseboard_fab2_lib.baseboard_fab2(sch_1):page211_i61:B" )
				( attribute "PROPAGATION_DELAY_MAX" "27000.00 MIL"
					( Units "uMaxMinProp" "ns" 1.000000)
					( Origin gBackEnd )
				)
			)
			( pinPair "@baseboard_fab2_lib.baseboard_fab2(sch_1):\PP5547\"
				( pinRef "@baseboard_fab2_lib.baseboard_fab2(sch_1):page21_i164:A" )
				( pinRef "@baseboard_fab2_lib.baseboard_fab2(sch_1):page21_i149:B" )
				( attribute "PROPAGATION_DELAY_MAX" "400.00 MIL"
					( Units "uMaxMinProp" "ns" 1.000000)
					( Origin gBackEnd )
				)
			)
			( pinPair "@baseboard_fab2_lib.baseboard_fab2(sch_1):\PP5548\"
				( pinRef "@baseboard_fab2_lib.baseboard_fab2(sch_1):page201_i155:VALRT_N" )
				( pinRef "@baseboard_fab2_lib.baseboard_fab2(sch_1):page201_i26:A" )
				( attribute "PROPAGATION_DELAY_MAX" "1000.00 MIL"
					( Units "uMaxMinProp" "ns" 1.000000)
					( Origin gBackEnd )
				)
			)
			( pinPair "@baseboard_fab2_lib.baseboard_fab2(sch_1):\PP5549\"
				( pinRef "@baseboard_fab2_lib.baseboard_fab2(sch_1):page21_i259:SVIDALERT_N(0)" )
				( pinRef "@baseboard_fab2_lib.baseboard_fab2(sch_1):page21_i149:A" )
				( attribute "PROPAGATION_DELAY_MAX" "4500.00 MIL"
					( Units "uMaxMinProp" "ns" 1.000000)
					( Origin gBackEnd )
				)
			)
			( pinPair "@baseboard_fab2_lib.baseboard_fab2(sch_1):\PP5491\"
				( pinRef "@baseboard_fab2_lib.baseboard_fab2(sch_1):page226_i23:A" )
				( pinRef "@baseboard_fab2_lib.baseboard_fab2(sch_1):page226_i90:VDIO" )
				( attribute "PROPAGATION_DELAY_MAX" "1000.00 MIL"
					( Units "uMaxMinProp" "ns" 1.000000)
					( Origin gBackEnd )
				)
			)
			( pinPair "@baseboard_fab2_lib.baseboard_fab2(sch_1):\PP5493\"
				( pinRef "@baseboard_fab2_lib.baseboard_fab2(sch_1):page55_i24:B" )
				( pinRef "@baseboard_fab2_lib.baseboard_fab2(sch_1):page223_i23:B" )
				( attribute "PROPAGATION_DELAY_MAX" "27000.00 MIL"
					( Units "uMaxMinProp" "ns" 1.000000)
					( Origin gBackEnd )
				)
			)
			( pinPair "@baseboard_fab2_lib.baseboard_fab2(sch_1):\PP5494\"
				( pinRef "@baseboard_fab2_lib.baseboard_fab2(sch_1):page223_i8:B" )
				( pinRef "@baseboard_fab2_lib.baseboard_fab2(sch_1):page223_i23:B" )
				( attribute "PROPAGATION_DELAY_MAX" "200.00 MIL"
					( Units "uMaxMinProp" "ns" 1.000000)
					( Origin gBackEnd )
				)
			)
			( pinPair "@baseboard_fab2_lib.baseboard_fab2(sch_1):\PP5495\"
				( pinRef "@baseboard_fab2_lib.baseboard_fab2(sch_1):page226_i23:B" )
				( pinRef "@baseboard_fab2_lib.baseboard_fab2(sch_1):page226_i8:B" )
				( attribute "PROPAGATION_DELAY_MAX" "200.00 MIL"
					( Units "uMaxMinProp" "ns" 1.000000)
					( Origin gBackEnd )
				)
			)
			( pinPair "@baseboard_fab2_lib.baseboard_fab2(sch_1):\PP5496\"
				( pinRef "@baseboard_fab2_lib.baseboard_fab2(sch_1):page55_i24:B" )
				( pinRef "@baseboard_fab2_lib.baseboard_fab2(sch_1):page55_i7:B" )
				( attribute "PROPAGATION_DELAY_MAX" "400.00 MIL"
					( Units "uMaxMinProp" "ns" 1.000000)
					( Origin gBackEnd )
				)
			)
			( pinPair "@baseboard_fab2_lib.baseboard_fab2(sch_1):\PP5497\"
				( pinRef "@baseboard_fab2_lib.baseboard_fab2(sch_1):page223_i90:VDIO" )
				( pinRef "@baseboard_fab2_lib.baseboard_fab2(sch_1):page223_i23:A" )
				( attribute "PROPAGATION_DELAY_MAX" "1000.00 MIL"
					( Units "uMaxMinProp" "ns" 1.000000)
					( Origin gBackEnd )
				)
			)
			( pinPair "@baseboard_fab2_lib.baseboard_fab2(sch_1):\PP5498\"
				( pinRef "@baseboard_fab2_lib.baseboard_fab2(sch_1):page55_i172:SVIDDATA(1)" )
				( pinRef "@baseboard_fab2_lib.baseboard_fab2(sch_1):page55_i24:A" )
				( attribute "PROPAGATION_DELAY_MAX" "4500.00 MIL"
					( Units "uMaxMinProp" "ns" 1.000000)
					( Origin gBackEnd )
				)
			)
			( pinPair "@baseboard_fab2_lib.baseboard_fab2(sch_1):\PP5483\"
				( pinRef "@baseboard_fab2_lib.baseboard_fab2(sch_1):page218_i75:VDIO" )
				( pinRef "@baseboard_fab2_lib.baseboard_fab2(sch_1):page218_i25:A" )
				( attribute "PROPAGATION_DELAY_MAX" "1000.00 MIL"
					( Units "uMaxMinProp" "ns" 1.000000)
					( Origin gBackEnd )
				)
			)
			( pinPair "@baseboard_fab2_lib.baseboard_fab2(sch_1):\PP5486\"
				( pinRef "@baseboard_fab2_lib.baseboard_fab2(sch_1):page215_i295:B" )
				( pinRef "@baseboard_fab2_lib.baseboard_fab2(sch_1):page215_i307:B" )
				( attribute "PROPAGATION_DELAY_MAX" "2000.00 MIL"
					( Units "uMaxMinProp" "ns" 1.000000)
					( Origin gBackEnd )
				)
			)
			( pinPair "@baseboard_fab2_lib.baseboard_fab2(sch_1):\PP5487\"
				( pinRef "@baseboard_fab2_lib.baseboard_fab2(sch_1):page21_i159:B" )
				( pinRef "@baseboard_fab2_lib.baseboard_fab2(sch_1):page21_i154:B" )
				( attribute "PROPAGATION_DELAY_MAX" "400.00 MIL"
					( Units "uMaxMinProp" "ns" 1.000000)
					( Origin gBackEnd )
				)
			)
			( pinPair "@baseboard_fab2_lib.baseboard_fab2(sch_1):\PP5488\"
				( pinRef "@baseboard_fab2_lib.baseboard_fab2(sch_1):page218_i25:B" )
				( pinRef "@baseboard_fab2_lib.baseboard_fab2(sch_1):page218_i7:B" )
				( attribute "PROPAGATION_DELAY_MAX" "200.00 MIL"
					( Units "uMaxMinProp" "ns" 1.000000)
					( Origin gBackEnd )
				)
			)
			( pinPair "@baseboard_fab2_lib.baseboard_fab2(sch_1):\PP5489\"
				( pinRef "@baseboard_fab2_lib.baseboard_fab2(sch_1):page215_i358:VDIO" )
				( pinRef "@baseboard_fab2_lib.baseboard_fab2(sch_1):page215_i307:A" )
				( attribute "PROPAGATION_DELAY_MAX" "1000.00 MIL"
					( Units "uMaxMinProp" "ns" 1.000000)
					( Origin gBackEnd )
				)
			)
			( pinPair "@baseboard_fab2_lib.baseboard_fab2(sch_1):\PP5490\"
				( pinRef "@baseboard_fab2_lib.baseboard_fab2(sch_1):page21_i259:SVIDDATA(1)" )
				( pinRef "@baseboard_fab2_lib.baseboard_fab2(sch_1):page21_i154:A" )
				( attribute "PROPAGATION_DELAY_MAX" "4500.00 MIL"
					( Units "uMaxMinProp" "ns" 1.000000)
					( Origin gBackEnd )
				)
			)
			( pinPair "@baseboard_fab2_lib.baseboard_fab2(sch_1):\PP5465\"
				( pinRef "@baseboard_fab2_lib.baseboard_fab2(sch_1):page226_i16:A" )
				( pinRef "@baseboard_fab2_lib.baseboard_fab2(sch_1):page226_i90:VALRT_N" )
				( attribute "PROPAGATION_DELAY_MAX" "1000.00 MIL"
					( Units "uMaxMinProp" "ns" 1.000000)
					( Origin gBackEnd )
				)
			)
			( pinPair "@baseboard_fab2_lib.baseboard_fab2(sch_1):\PP5467\"
				( pinRef "@baseboard_fab2_lib.baseboard_fab2(sch_1):page223_i16:B" )
				( pinRef "@baseboard_fab2_lib.baseboard_fab2(sch_1):page55_i26:B" )
				( attribute "PROPAGATION_DELAY_MAX" "27000.00 MIL"
					( Units "uMaxMinProp" "ns" 1.000000)
					( Origin gBackEnd )
				)
			)
			( pinPair "@baseboard_fab2_lib.baseboard_fab2(sch_1):\PP5468\"
				( pinRef "@baseboard_fab2_lib.baseboard_fab2(sch_1):page55_i26:B" )
				( pinRef "@baseboard_fab2_lib.baseboard_fab2(sch_1):page55_i4:B" )
				( attribute "PROPAGATION_DELAY_MAX" "400.00 MIL"
					( Units "uMaxMinProp" "ns" 1.000000)
					( Origin gBackEnd )
				)
			)
			( pinPair "@baseboard_fab2_lib.baseboard_fab2(sch_1):\PP5469\"
				( pinRef "@baseboard_fab2_lib.baseboard_fab2(sch_1):page223_i16:A" )
				( pinRef "@baseboard_fab2_lib.baseboard_fab2(sch_1):page223_i90:VALRT_N" )
				( attribute "PROPAGATION_DELAY_MAX" "10000.00 MIL"
					( Units "uMaxMinProp" "ns" 1.000000)
					( Origin gBackEnd )
				)
			)
			( pinPair "@baseboard_fab2_lib.baseboard_fab2(sch_1):\PP5470\"
				( pinRef "@baseboard_fab2_lib.baseboard_fab2(sch_1):page55_i172:SVIDALERT_N(1)" )
				( pinRef "@baseboard_fab2_lib.baseboard_fab2(sch_1):page55_i26:A" )
				( attribute "PROPAGATION_DELAY_MAX" "4500.00 MIL"
					( Units "uMaxMinProp" "ns" 1.000000)
					( Origin gBackEnd )
				)
			)
			( pinPair "@baseboard_fab2_lib.baseboard_fab2(sch_1):\PP5457\"
				( pinRef "@baseboard_fab2_lib.baseboard_fab2(sch_1):page218_i75:VALRT_N" )
				( pinRef "@baseboard_fab2_lib.baseboard_fab2(sch_1):page218_i15:A" )
				( attribute "PROPAGATION_DELAY_MAX" "1000.00 MIL"
					( Units "uMaxMinProp" "ns" 1.000000)
					( Origin gBackEnd )
				)
			)
			( pinPair "@baseboard_fab2_lib.baseboard_fab2(sch_1):\PP5461\"
				( pinRef "@baseboard_fab2_lib.baseboard_fab2(sch_1):page215_i302:B" )
				( pinRef "@baseboard_fab2_lib.baseboard_fab2(sch_1):page21_i152:B" )
				( attribute "PROPAGATION_DELAY_MAX" "27000.00 MIL"
					( Units "uMaxMinProp" "ns" 1.000000)
					( Origin gBackEnd )
				)
			)
			( pinPair "@baseboard_fab2_lib.baseboard_fab2(sch_1):\PP5462\"
				( pinRef "@baseboard_fab2_lib.baseboard_fab2(sch_1):page21_i161:B" )
				( pinRef "@baseboard_fab2_lib.baseboard_fab2(sch_1):page21_i152:B" )
				( attribute "PROPAGATION_DELAY_MAX" "400.00 MIL"
					( Units "uMaxMinProp" "ns" 1.000000)
					( Origin gBackEnd )
				)
			)
			( pinPair "@baseboard_fab2_lib.baseboard_fab2(sch_1):\PP5463\"
				( pinRef "@baseboard_fab2_lib.baseboard_fab2(sch_1):page215_i302:A" )
				( pinRef "@baseboard_fab2_lib.baseboard_fab2(sch_1):page215_i358:VALRT_N" )
				( attribute "PROPAGATION_DELAY_MAX" "1000.00 MIL"
					( Units "uMaxMinProp" "ns" 1.000000)
					( Origin gBackEnd )
				)
			)
			( pinPair "@baseboard_fab2_lib.baseboard_fab2(sch_1):\PP5464\"
				( pinRef "@baseboard_fab2_lib.baseboard_fab2(sch_1):page21_i259:SVIDALERT_N(1)" )
				( pinRef "@baseboard_fab2_lib.baseboard_fab2(sch_1):page21_i152:A" )
				( attribute "PROPAGATION_DELAY_MAX" "4500.00 MIL"
					( Units "uMaxMinProp" "ns" 1.000000)
					( Origin gBackEnd )
				)
			)
			( pinPair "@baseboard_fab2_lib.baseboard_fab2(sch_1):\PP6133\"
				( pinRef "@baseboard_fab2_lib.baseboard_fab2(sch_1):page120_i147:GPP_G0_FANTACH0_FANTACH0IE" )
				( pinRef "@baseboard_fab2_lib.baseboard_fab2(sch_1):page181_i268:A" )
				( attribute "PROPAGATION_DELAY_MAX" "20000.00 MIL"
					( Units "uMaxMinProp" "ns" 1.000000)
					( Origin gBackEnd )
				)
			)
			( pinPair "@baseboard_fab2_lib.baseboard_fab2(sch_1):\PP6128\"
				( pinRef "@baseboard_fab2_lib.baseboard_fab2(sch_1):page161_i42:C" )
				( pinRef "@baseboard_fab2_lib.baseboard_fab2(sch_1):page161_i1:IO3" )
				( attribute "PROPAGATION_DELAY_MAX" "20000.00 MIL"
					( Units "uMaxMinProp" "ns" 1.000000)
					( Origin gBackEnd )
				)
			)
			( pinPair "@baseboard_fab2_lib.baseboard_fab2(sch_1):\PP6127\"
				( pinRef "@baseboard_fab2_lib.baseboard_fab2(sch_1):page161_i42:A" )
				( pinRef "@baseboard_fab2_lib.baseboard_fab2(sch_1):page161_i43:B" )
				( attribute "PROPAGATION_DELAY_MAX" "20000.00 MIL"
					( Units "uMaxMinProp" "ns" 1.000000)
					( Origin gBackEnd )
				)
			)
			( pinPair "@baseboard_fab2_lib.baseboard_fab2(sch_1):\PP6126\"
				( pinRef "@baseboard_fab2_lib.baseboard_fab2(sch_1):page161_i62:C" )
				( pinRef "@baseboard_fab2_lib.baseboard_fab2(sch_1):page161_i32:IO3" )
				( attribute "PROPAGATION_DELAY_MAX" "20000.00 MIL"
					( Units "uMaxMinProp" "ns" 1.000000)
					( Origin gBackEnd )
				)
			)
			( pinPair "@baseboard_fab2_lib.baseboard_fab2(sch_1):\PP6125\"
				( pinRef "@baseboard_fab2_lib.baseboard_fab2(sch_1):page161_i62:A" )
				( pinRef "@baseboard_fab2_lib.baseboard_fab2(sch_1):page161_i67:B" )
				( attribute "PROPAGATION_DELAY_MAX" "20000.00 MIL"
					( Units "uMaxMinProp" "ns" 1.000000)
					( Origin gBackEnd )
				)
			)
			( pinPair "@baseboard_fab2_lib.baseboard_fab2(sch_1):\PP5811\"
				( pinRef "@baseboard_fab2_lib.baseboard_fab2(sch_1):page120_i147:GPP_G3_FANTACH3_FANTACH3IE" )
				( pinRef "@baseboard_fab2_lib.baseboard_fab2(sch_1):page181_i111:GNDA4" )
				( attribute "PROPAGATION_DELAY_MAX" "20000.00 MIL"
					( Units "uMaxMinProp" "ns" 1.000000)
					( Origin gBackEnd )
				)
			)
			( pinPair "@baseboard_fab2_lib.baseboard_fab2(sch_1):\PP5814\"
				( pinRef "@baseboard_fab2_lib.baseboard_fab2(sch_1):page181_i111:IOB4" )
				( pinRef "@baseboard_fab2_lib.baseboard_fab2(sch_1):page120_i147:GPP_G2_FANTACH2_FANTACH2IE" )
				( attribute "PROPAGATION_DELAY_MAX" "20000.00 MIL"
					( Units "uMaxMinProp" "ns" 1.000000)
					( Origin gBackEnd )
				)
			)
			( pinPair "@baseboard_fab2_lib.baseboard_fab2(sch_1):\PP5812\"
				( pinRef "@baseboard_fab2_lib.baseboard_fab2(sch_1):page181_i111:IOC4" )
				( pinRef "@baseboard_fab2_lib.baseboard_fab2(sch_1):page120_i147:GPP_G1_FANTACH1_FANTACH1IE" )
				( attribute "PROPAGATION_DELAY_MAX" "20000.00 MIL"
					( Units "uMaxMinProp" "ns" 1.000000)
					( Origin gBackEnd )
				)
			)
			( pinPair "@baseboard_fab2_lib.baseboard_fab2(sch_1):\PP5796\"
				( pinRef "@baseboard_fab2_lib.baseboard_fab2(sch_1):page181_i261:B" )
				( pinRef "@baseboard_fab2_lib.baseboard_fab2(sch_1):page182_i107:B" )
				( attribute "PROPAGATION_DELAY_MIN" "1000.00 MIL"
					( Units "uMaxMinProp" "ns" 1.000000)
					( Origin gBackEnd )
				)
				( attribute "PROPAGATION_DELAY_MAX" "20000.00 MIL"
					( Units "uMaxMinProp" "ns" 1.000000)
					( Origin gBackEnd )
				)
			)
			( pinPair "@baseboard_fab2_lib.baseboard_fab2(sch_1):\PP5813\"
				( pinRef "@baseboard_fab2_lib.baseboard_fab2(sch_1):page161_i88:Y" )
				( pinRef "@baseboard_fab2_lib.baseboard_fab2(sch_1):page181_i111:IOF4" )
				( attribute "PROPAGATION_DELAY_MAX" "20000.00 MIL"
					( Units "uMaxMinProp" "ns" 1.000000)
					( Origin gBackEnd )
				)
			)
			( pinPair "@baseboard_fab2_lib.baseboard_fab2(sch_1):\PP5542\"
				( pinRef "@baseboard_fab2_lib.baseboard_fab2(sch_1):page161_i102:B" )
				( pinRef "@baseboard_fab2_lib.baseboard_fab2(sch_1):page161_i65:B" )
				( attribute "PROPAGATION_DELAY_MIN" "1000.00 MIL"
					( Units "uMaxMinProp" "ns" 1.000000)
					( Origin gBackEnd )
				)
				( attribute "PROPAGATION_DELAY_MAX" "20000.00 MIL"
					( Units "uMaxMinProp" "ns" 1.000000)
					( Origin gBackEnd )
				)
			)
			( pinPair "@baseboard_fab2_lib.baseboard_fab2(sch_1):\PP5543\"
				( pinRef "@baseboard_fab2_lib.baseboard_fab2(sch_1):page161_i64:A" )
				( pinRef "@baseboard_fab2_lib.baseboard_fab2(sch_1):page161_i65:B" )
				( attribute "PROPAGATION_DELAY_MIN" "1000.00 MIL"
					( Units "uMaxMinProp" "ns" 1.000000)
					( Origin gBackEnd )
				)
				( attribute "PROPAGATION_DELAY_MAX" "20000.00 MIL"
					( Units "uMaxMinProp" "ns" 1.000000)
					( Origin gBackEnd )
				)
			)
			( pinPair "@baseboard_fab2_lib.baseboard_fab2(sch_1):\PP5804\"
				( pinRef "@baseboard_fab2_lib.baseboard_fab2(sch_1):page161_i92:Y" )
				( pinRef "@baseboard_fab2_lib.baseboard_fab2(sch_1):page161_i32:IO4" )
				( attribute "PROPAGATION_DELAY_MAX" "20000.00 MIL"
					( Units "uMaxMinProp" "ns" 1.000000)
					( Origin gBackEnd )
				)
			)
			( pinPair "@baseboard_fab2_lib.baseboard_fab2(sch_1):\PP5608\"
				( pinRef "@baseboard_fab2_lib.baseboard_fab2(sch_1):page189_i47:IO4" )
				( pinRef "@baseboard_fab2_lib.baseboard_fab2(sch_1):page189_i7:B" )
				( attribute "PROPAGATION_DELAY_MAX" "1000.00 MIL"
					( Units "uMaxMinProp" "ns" 1.000000)
					( Origin gBackEnd )
				)
			)
			( pinPair "@baseboard_fab2_lib.baseboard_fab2(sch_1):\PP5609\"
				( pinRef "@baseboard_fab2_lib.baseboard_fab2(sch_1):page189_i47:IO4" )
				( pinRef "@baseboard_fab2_lib.baseboard_fab2(sch_1):page189_i9:B" )
				( attribute "PROPAGATION_DELAY_MAX" "1000.00 MIL"
					( Units "uMaxMinProp" "ns" 1.000000)
					( Origin gBackEnd )
				)
			)
			( pinPair "@baseboard_fab2_lib.baseboard_fab2(sch_1):\PP6138\"
				( pinRef "@baseboard_fab2_lib.baseboard_fab2(sch_1):page112_i57:B" )
				( pinRef "@baseboard_fab2_lib.baseboard_fab2(sch_1):page21_i259:BPM_N(0)" )
				( attribute "PROPAGATION_DELAY_MAX" "1100.00 MIL"
					( Units "uMaxMinProp" "ns" 1.000000)
					( Origin gBackEnd )
				)
			)
			( pinPair "@baseboard_fab2_lib.baseboard_fab2(sch_1):\PP6139\"
				( pinRef "@baseboard_fab2_lib.baseboard_fab2(sch_1):page112_i50:B" )
				( pinRef "@baseboard_fab2_lib.baseboard_fab2(sch_1):page55_i172:BPM_N(0)" )
				( attribute "PROPAGATION_DELAY_MAX" "1100.00 MIL"
					( Units "uMaxMinProp" "ns" 1.000000)
					( Origin gBackEnd )
				)
			)
			( pinPair "@baseboard_fab2_lib.baseboard_fab2(sch_1):\PP6136\"
				( pinRef "@baseboard_fab2_lib.baseboard_fab2(sch_1):page112_i53:B" )
				( pinRef "@baseboard_fab2_lib.baseboard_fab2(sch_1):page21_i259:BPM_N(1)" )
				( attribute "PROPAGATION_DELAY_MAX" "1100.00 MIL"
					( Units "uMaxMinProp" "ns" 1.000000)
					( Origin gBackEnd )
				)
			)
			( pinPair "@baseboard_fab2_lib.baseboard_fab2(sch_1):\PP6137\"
				( pinRef "@baseboard_fab2_lib.baseboard_fab2(sch_1):page55_i172:BPM_N(1)" )
				( pinRef "@baseboard_fab2_lib.baseboard_fab2(sch_1):page112_i49:B" )
				( attribute "PROPAGATION_DELAY_MAX" "1100.00 MIL"
					( Units "uMaxMinProp" "ns" 1.000000)
					( Origin gBackEnd )
				)
			)
			( pinPair "@baseboard_fab2_lib.baseboard_fab2(sch_1):\PP6134\"
				( pinRef "@baseboard_fab2_lib.baseboard_fab2(sch_1):page111_i26:IO55" )
				( pinRef "@baseboard_fab2_lib.baseboard_fab2(sch_1):page118_i73:JTAG_TCK" )
				( attribute "PROPAGATION_DELAY_MAX" "24000.00 MIL"
					( Units "uMaxMinProp" "ns" 1.000000)
					( Origin gBackEnd )
				)
			)
			( pinPair "@baseboard_fab2_lib.baseboard_fab2(sch_1):\PP6135\"
				( pinRef "@baseboard_fab2_lib.baseboard_fab2(sch_1):page118_i73:JTAG_TCK" )
				( pinRef "@baseboard_fab2_lib.baseboard_fab2(sch_1):page112_i95:A" )
				( attribute "PROPAGATION_DELAY_MAX" "1100.00 MIL"
					( Units "uMaxMinProp" "ns" 1.000000)
					( Origin gBackEnd )
				)
			)
			( pinPair "@baseboard_fab2_lib.baseboard_fab2(sch_1):\PP5610\"
				( pinRef "@baseboard_fab2_lib.baseboard_fab2(sch_1):page112_i55:B" )
				( pinRef "@baseboard_fab2_lib.baseboard_fab2(sch_1):page55_i172:TDO" )
				( attribute "PROPAGATION_DELAY_MAX" "1100.00 MIL"
					( Units "uMaxMinProp" "ns" 1.000000)
					( Origin gBackEnd )
				)
			)
			( pinPair "@baseboard_fab2_lib.baseboard_fab2(sch_1):\PP5611\"
				( pinRef "@baseboard_fab2_lib.baseboard_fab2(sch_1):page112_i40:B0" )
				( pinRef "@baseboard_fab2_lib.baseboard_fab2(sch_1):page55_i172:TDO" )
				( attribute "PROPAGATION_DELAY_MAX" "24000.00 MIL"
					( Units "uMaxMinProp" "ns" 1.000000)
					( Origin gBackEnd )
				)
			)
			( pinPair "@baseboard_fab2_lib.baseboard_fab2(sch_1):\PP5612\"
				( pinRef "@baseboard_fab2_lib.baseboard_fab2(sch_1):page112_i108(1):B(1)" )
				( pinRef "@baseboard_fab2_lib.baseboard_fab2(sch_1):page112_i40:A" )
				( attribute "PROPAGATION_DELAY_MAX" "24000.00 MIL"
					( Units "uMaxMinProp" "ns" 1.000000)
					( Origin gBackEnd )
				)
			)
			( pinPair "@baseboard_fab2_lib.baseboard_fab2(sch_1):\PP5613\"
				( pinRef "@baseboard_fab2_lib.baseboard_fab2(sch_1):page118_i73:JTAG_TDO" )
				( pinRef "@baseboard_fab2_lib.baseboard_fab2(sch_1):page112_i108(1):A(1)" )
				( attribute "PROPAGATION_DELAY_MAX" "24000.00 MIL"
					( Units "uMaxMinProp" "ns" 1.000000)
					( Origin gBackEnd )
				)
			)
			( pinPair "@baseboard_fab2_lib.baseboard_fab2(sch_1):\PP5614\"
				( pinRef "@baseboard_fab2_lib.baseboard_fab2(sch_1):page111_i26:IO52" )
				( pinRef "@baseboard_fab2_lib.baseboard_fab2(sch_1):page118_i73:JTAG_TDO" )
				( attribute "PROPAGATION_DELAY_MAX" "24000.00 MIL"
					( Units "uMaxMinProp" "ns" 1.000000)
					( Origin gBackEnd )
				)
			)
			( pinPair "@baseboard_fab2_lib.baseboard_fab2(sch_1):\PP5615\"
				( pinRef "@baseboard_fab2_lib.baseboard_fab2(sch_1):page111_i26:IO52" )
				( pinRef "@baseboard_fab2_lib.baseboard_fab2(sch_1):page112_i108(1):A(1)" )
				( attribute "PROPAGATION_DELAY_MAX" "1100.00 MIL"
					( Units "uMaxMinProp" "ns" 1.000000)
					( Origin gBackEnd )
				)
			)
			( pinPair "@baseboard_fab2_lib.baseboard_fab2(sch_1):\PP5616\"
				( pinRef "@baseboard_fab2_lib.baseboard_fab2(sch_1):page111_i26:IO52" )
				( pinRef "@baseboard_fab2_lib.baseboard_fab2(sch_1):page112_i78:B" )
				( attribute "PROPAGATION_DELAY_MAX" "250.00 MIL"
					( Units "uMaxMinProp" "ns" 1.000000)
					( Origin gBackEnd )
				)
			)
			( pinPair "@baseboard_fab2_lib.baseboard_fab2(sch_1):\PP5617\"
				( pinRef "@baseboard_fab2_lib.baseboard_fab2(sch_1):page112_i127:A" )
				( pinRef "@baseboard_fab2_lib.baseboard_fab2(sch_1):page21_i259:TDO" )
				( attribute "PROPAGATION_DELAY_MAX" "24000.00 MIL"
					( Units "uMaxMinProp" "ns" 1.000000)
					( Origin gBackEnd )
				)
			)
			( pinPair "@baseboard_fab2_lib.baseboard_fab2(sch_1):\PP5618\"
				( pinRef "@baseboard_fab2_lib.baseboard_fab2(sch_1):page112_i127:A" )
				( pinRef "@baseboard_fab2_lib.baseboard_fab2(sch_1):page112_i40:B1" )
				( attribute "PROPAGATION_DELAY_MAX" "2000.00 MIL"
					( Units "uMaxMinProp" "ns" 1.000000)
					( Origin gBackEnd )
				)
			)
			( pinPair "@baseboard_fab2_lib.baseboard_fab2(sch_1):\PP5619\"
				( pinRef "@baseboard_fab2_lib.baseboard_fab2(sch_1):page21_i259:TDO" )
				( pinRef "@baseboard_fab2_lib.baseboard_fab2(sch_1):page112_i58:B" )
				( attribute "PROPAGATION_DELAY_MAX" "1100.00 MIL"
					( Units "uMaxMinProp" "ns" 1.000000)
					( Origin gBackEnd )
				)
			)
			( pinPair "@baseboard_fab2_lib.baseboard_fab2(sch_1):\PP5620\"
				( pinRef "@baseboard_fab2_lib.baseboard_fab2(sch_1):page112_i127:B" )
				( pinRef "@baseboard_fab2_lib.baseboard_fab2(sch_1):page55_i172:TDI" )
				( attribute "PROPAGATION_DELAY_MAX" "24000.00 MIL"
					( Units "uMaxMinProp" "ns" 1.000000)
					( Origin gBackEnd )
				)
			)
			( pinPair "@baseboard_fab2_lib.baseboard_fab2(sch_1):\PP5621\"
				( pinRef "@baseboard_fab2_lib.baseboard_fab2(sch_1):page55_i172:TDI" )
				( pinRef "@baseboard_fab2_lib.baseboard_fab2(sch_1):page112_i56:B" )
				( attribute "PROPAGATION_DELAY_MAX" "1100.00 MIL"
					( Units "uMaxMinProp" "ns" 1.000000)
					( Origin gBackEnd )
				)
			)
			( pinPair "@baseboard_fab2_lib.baseboard_fab2(sch_1):\PP5622\"
				( pinRef "@baseboard_fab2_lib.baseboard_fab2(sch_1):page118_i73:JTAGX" )
				( pinRef "@baseboard_fab2_lib.baseboard_fab2(sch_1):page111_i83:A" )
				( attribute "PROPAGATION_DELAY_MAX" "24000.00 MIL"
					( Units "uMaxMinProp" "ns" 1.000000)
					( Origin gBackEnd )
				)
			)
			( pinPair "@baseboard_fab2_lib.baseboard_fab2(sch_1):\PP5623\"
				( pinRef "@baseboard_fab2_lib.baseboard_fab2(sch_1):page118_i73:JTAGX" )
				( pinRef "@baseboard_fab2_lib.baseboard_fab2(sch_1):page112_i85:A" )
				( attribute "PROPAGATION_DELAY_MAX" "1100.00 MIL"
					( Units "uMaxMinProp" "ns" 1.000000)
					( Origin gBackEnd )
				)
			)
			( pinPair "@baseboard_fab2_lib.baseboard_fab2(sch_1):\PP5624\"
				( pinRef "@baseboard_fab2_lib.baseboard_fab2(sch_1):page111_i93:E(0)" )
				( pinRef "@baseboard_fab2_lib.baseboard_fab2(sch_1):page111_i83:B" )
				( attribute "PROPAGATION_DELAY_MAX" "24000.00 MIL"
					( Units "uMaxMinProp" "ns" 1.000000)
					( Origin gBackEnd )
				)
			)
			( pinPair "@baseboard_fab2_lib.baseboard_fab2(sch_1):\PP5625\"
				( pinRef "@baseboard_fab2_lib.baseboard_fab2(sch_1):page112_i61:A" )
				( pinRef "@baseboard_fab2_lib.baseboard_fab2(sch_1):page111_i94:E(0)" )
				( attribute "PROPAGATION_DELAY_MAX" "24000.00 MIL"
					( Units "uMaxMinProp" "ns" 1.000000)
					( Origin gBackEnd )
				)
			)
			( pinPair "@baseboard_fab2_lib.baseboard_fab2(sch_1):\PP5626\"
				( pinRef "@baseboard_fab2_lib.baseboard_fab2(sch_1):page111_i26:IO57" )
				( pinRef "@baseboard_fab2_lib.baseboard_fab2(sch_1):page55_i172:TCK" )
				( attribute "PROPAGATION_DELAY_MAX" "24000.00 MIL"
					( Units "uMaxMinProp" "ns" 1.000000)
					( Origin gBackEnd )
				)
			)
			( pinPair "@baseboard_fab2_lib.baseboard_fab2(sch_1):\PP5627\"
				( pinRef "@baseboard_fab2_lib.baseboard_fab2(sch_1):page55_i172:TCK" )
				( pinRef "@baseboard_fab2_lib.baseboard_fab2(sch_1):page112_i61:A" )
				( attribute "PROPAGATION_DELAY_MAX" "1100.00 MIL"
					( Units "uMaxMinProp" "ns" 1.000000)
					( Origin gBackEnd )
				)
			)
			( pinPair "@baseboard_fab2_lib.baseboard_fab2(sch_1):\PP5525\"
				( pinRef "@baseboard_fab2_lib.baseboard_fab2(sch_1):page118_i73:CPU_TRST_N" )
				( pinRef "@baseboard_fab2_lib.baseboard_fab2(sch_1):page112_i108(3):A(3)" )
				( attribute "PROPAGATION_DELAY_MAX" "24000.00 MIL"
					( Units "uMaxMinProp" "ns" 1.000000)
					( Origin gBackEnd )
				)
			)
			( pinPair "@baseboard_fab2_lib.baseboard_fab2(sch_1):\PP5526\"
				( pinRef "@baseboard_fab2_lib.baseboard_fab2(sch_1):page111_i26:IO54" )
				( pinRef "@baseboard_fab2_lib.baseboard_fab2(sch_1):page112_i108(3):A(3)" )
				( attribute "PROPAGATION_DELAY_MAX" "1100.00 MIL"
					( Units "uMaxMinProp" "ns" 1.000000)
					( Origin gBackEnd )
				)
			)
			( pinPair "@baseboard_fab2_lib.baseboard_fab2(sch_1):\PP5527\"
				( pinRef "@baseboard_fab2_lib.baseboard_fab2(sch_1):page112_i94:A" )
				( pinRef "@baseboard_fab2_lib.baseboard_fab2(sch_1):page118_i73:CPU_TRST_N" )
				( attribute "PROPAGATION_DELAY_MAX" "1100.00 MIL"
					( Units "uMaxMinProp" "ns" 1.000000)
					( Origin gBackEnd )
				)
			)
			( pinPair "@baseboard_fab2_lib.baseboard_fab2(sch_1):\PP5528\"
				( pinRef "@baseboard_fab2_lib.baseboard_fab2(sch_1):page55_i172:TRST_N" )
				( pinRef "@baseboard_fab2_lib.baseboard_fab2(sch_1):page112_i108(3):B(3)" )
				( attribute "PROPAGATION_DELAY_MAX" "24000.00 MIL"
					( Units "uMaxMinProp" "ns" 1.000000)
					( Origin gBackEnd )
				)
			)
			( pinPair "@baseboard_fab2_lib.baseboard_fab2(sch_1):\PP5529\"
				( pinRef "@baseboard_fab2_lib.baseboard_fab2(sch_1):page55_i172:TRST_N" )
				( pinRef "@baseboard_fab2_lib.baseboard_fab2(sch_1):page112_i62:A" )
				( attribute "PROPAGATION_DELAY_MAX" "1000.00 MIL"
					( Units "uMaxMinProp" "ns" 1.000000)
					( Origin gBackEnd )
				)
			)
			( pinPair "@baseboard_fab2_lib.baseboard_fab2(sch_1):\PP5521\"
				( pinRef "@baseboard_fab2_lib.baseboard_fab2(sch_1):page118_i73:JTAG_TMS" )
				( pinRef "@baseboard_fab2_lib.baseboard_fab2(sch_1):page112_i108(2):A(2)" )
				( attribute "PROPAGATION_DELAY_MAX" "24000.00 MIL"
					( Units "uMaxMinProp" "ns" 1.000000)
					( Origin gBackEnd )
				)
			)
			( pinPair "@baseboard_fab2_lib.baseboard_fab2(sch_1):\PP5522\"
				( pinRef "@baseboard_fab2_lib.baseboard_fab2(sch_1):page111_i26:IO58" )
				( pinRef "@baseboard_fab2_lib.baseboard_fab2(sch_1):page112_i108(2):A(2)" )
				( attribute "PROPAGATION_DELAY_MAX" "1100.00 MIL"
					( Units "uMaxMinProp" "ns" 1.000000)
					( Origin gBackEnd )
				)
			)
			( pinPair "@baseboard_fab2_lib.baseboard_fab2(sch_1):\PP5523\"
				( pinRef "@baseboard_fab2_lib.baseboard_fab2(sch_1):page112_i80:B" )
				( pinRef "@baseboard_fab2_lib.baseboard_fab2(sch_1):page118_i73:JTAG_TMS" )
				( attribute "PROPAGATION_DELAY_MAX" "1100.00 MIL"
					( Units "uMaxMinProp" "ns" 1.000000)
					( Origin gBackEnd )
				)
			)
			( pinPair "@baseboard_fab2_lib.baseboard_fab2(sch_1):\PP5524\"
				( pinRef "@baseboard_fab2_lib.baseboard_fab2(sch_1):page55_i172:TMS" )
				( pinRef "@baseboard_fab2_lib.baseboard_fab2(sch_1):page112_i108(2):B(2)" )
				( attribute "PROPAGATION_DELAY_MAX" "24000.00 MIL"
					( Units "uMaxMinProp" "ns" 1.000000)
					( Origin gBackEnd )
				)
			)
			( pinPair "@baseboard_fab2_lib.baseboard_fab2(sch_1):\PP5515\"
				( pinRef "@baseboard_fab2_lib.baseboard_fab2(sch_1):page118_i73:JTAG_TDI" )
				( pinRef "@baseboard_fab2_lib.baseboard_fab2(sch_1):page112_i108(0):A(0)" )
				( attribute "PROPAGATION_DELAY_MAX" "24000.00 MIL"
					( Units "uMaxMinProp" "ns" 1.000000)
					( Origin gBackEnd )
				)
			)
			( pinPair "@baseboard_fab2_lib.baseboard_fab2(sch_1):\PP5516\"
				( pinRef "@baseboard_fab2_lib.baseboard_fab2(sch_1):page111_i26:IO56" )
				( pinRef "@baseboard_fab2_lib.baseboard_fab2(sch_1):page118_i73:JTAG_TDI" )
				( attribute "PROPAGATION_DELAY_MAX" "24000.00 MIL"
					( Units "uMaxMinProp" "ns" 1.000000)
					( Origin gBackEnd )
				)
			)
			( pinPair "@baseboard_fab2_lib.baseboard_fab2(sch_1):\PP5517\"
				( pinRef "@baseboard_fab2_lib.baseboard_fab2(sch_1):page111_i26:IO56" )
				( pinRef "@baseboard_fab2_lib.baseboard_fab2(sch_1):page112_i108(0):A(0)" )
				( attribute "PROPAGATION_DELAY_MAX" "1100.00 MIL"
					( Units "uMaxMinProp" "ns" 1.000000)
					( Origin gBackEnd )
				)
			)
			( pinPair "@baseboard_fab2_lib.baseboard_fab2(sch_1):\PP5518\"
				( pinRef "@baseboard_fab2_lib.baseboard_fab2(sch_1):page118_i73:JTAG_TDI" )
				( pinRef "@baseboard_fab2_lib.baseboard_fab2(sch_1):page112_i79:B" )
				( attribute "PROPAGATION_DELAY_MAX" "1100.00 MIL"
					( Units "uMaxMinProp" "ns" 1.000000)
					( Origin gBackEnd )
				)
			)
			( pinPair "@baseboard_fab2_lib.baseboard_fab2(sch_1):\PP5519\"
				( pinRef "@baseboard_fab2_lib.baseboard_fab2(sch_1):page112_i108(0):B(0)" )
				( pinRef "@baseboard_fab2_lib.baseboard_fab2(sch_1):page21_i259:TDI" )
				( attribute "PROPAGATION_DELAY_MAX" "24000.00 MIL"
					( Units "uMaxMinProp" "ns" 1.000000)
					( Origin gBackEnd )
				)
			)
			( pinPair "@baseboard_fab2_lib.baseboard_fab2(sch_1):\PP5520\"
				( pinRef "@baseboard_fab2_lib.baseboard_fab2(sch_1):page112_i59:B" )
				( pinRef "@baseboard_fab2_lib.baseboard_fab2(sch_1):page21_i259:TDI" )
				( attribute "PROPAGATION_DELAY_MAX" "1100.00 MIL"
					( Units "uMaxMinProp" "ns" 1.000000)
					( Origin gBackEnd )
				)
			)
			( pinPair "@baseboard_fab2_lib.baseboard_fab2(sch_1):\PP5513\"
				( pinRef "@baseboard_fab2_lib.baseboard_fab2(sch_1):page111_i60:B" )
				( pinRef "@baseboard_fab2_lib.baseboard_fab2(sch_1):page111_i26:IO39" )
				( attribute "PROPAGATION_DELAY_MAX" "24000.00 MIL"
					( Units "uMaxMinProp" "ns" 1.000000)
					( Origin gBackEnd )
				)
			)
			( pinPair "@baseboard_fab2_lib.baseboard_fab2(sch_1):\PP5514\"
				( pinRef "@baseboard_fab2_lib.baseboard_fab2(sch_1):page118_i73:RSMRST_N" )
				( pinRef "@baseboard_fab2_lib.baseboard_fab2(sch_1):page111_i60:A" )
				( attribute "PROPAGATION_DELAY_MAX" "24000.00 MIL"
					( Units "uMaxMinProp" "ns" 1.000000)
					( Origin gBackEnd )
				)
			)
			( pinPair "@baseboard_fab2_lib.baseboard_fab2(sch_1):\PP5510\"
				( pinRef "@baseboard_fab2_lib.baseboard_fab2(sch_1):page118_i73:PREQ_N" )
				( pinRef "@baseboard_fab2_lib.baseboard_fab2(sch_1):page112_i77:B" )
				( attribute "PROPAGATION_DELAY_MAX" "24000.00 MIL"
					( Units "uMaxMinProp" "ns" 1.000000)
					( Origin gBackEnd )
				)
			)
			( pinPair "@baseboard_fab2_lib.baseboard_fab2(sch_1):\PP5511\"
				( pinRef "@baseboard_fab2_lib.baseboard_fab2(sch_1):page111_i26:IO3" )
				( pinRef "@baseboard_fab2_lib.baseboard_fab2(sch_1):page112_i109(0):A(0)" )
				( attribute "PROPAGATION_DELAY_MAX" "1100.00 MIL"
					( Units "uMaxMinProp" "ns" 1.000000)
					( Origin gBackEnd )
				)
			)
			( pinPair "@baseboard_fab2_lib.baseboard_fab2(sch_1):\PP5512\"
				( pinRef "@baseboard_fab2_lib.baseboard_fab2(sch_1):page112_i109(0):B(0)" )
				( pinRef "@baseboard_fab2_lib.baseboard_fab2(sch_1):page55_i172:PREQ_N" )
				( attribute "PROPAGATION_DELAY_MAX" "24000.00 MIL"
					( Units "uMaxMinProp" "ns" 1.000000)
					( Origin gBackEnd )
				)
			)
			( pinPair "@baseboard_fab2_lib.baseboard_fab2(sch_1):\PP5507\"
				( pinRef "@baseboard_fab2_lib.baseboard_fab2(sch_1):page118_i73:PRDY_N" )
				( pinRef "@baseboard_fab2_lib.baseboard_fab2(sch_1):page112_i76:B" )
				( attribute "PROPAGATION_DELAY_MAX" "24000.00 MIL"
					( Units "uMaxMinProp" "ns" 1.000000)
					( Origin gBackEnd )
				)
			)
			( pinPair "@baseboard_fab2_lib.baseboard_fab2(sch_1):\PP5508\"
				( pinRef "@baseboard_fab2_lib.baseboard_fab2(sch_1):page111_i26:IO5" )
				( pinRef "@baseboard_fab2_lib.baseboard_fab2(sch_1):page112_i109(1):A(1)" )
				( attribute "PROPAGATION_DELAY_MAX" "1100.00 MIL"
					( Units "uMaxMinProp" "ns" 1.000000)
					( Origin gBackEnd )
				)
			)
			( pinPair "@baseboard_fab2_lib.baseboard_fab2(sch_1):\PP5509\"
				( pinRef "@baseboard_fab2_lib.baseboard_fab2(sch_1):page112_i109(1):B(1)" )
				( pinRef "@baseboard_fab2_lib.baseboard_fab2(sch_1):page55_i172:PRDY_N" )
				( attribute "PROPAGATION_DELAY_MAX" "24000.00 MIL"
					( Units "uMaxMinProp" "ns" 1.000000)
					( Origin gBackEnd )
				)
			)
			( pinPair "@baseboard_fab2_lib.baseboard_fab2(sch_1):\PP5505\"
				( pinRef "@baseboard_fab2_lib.baseboard_fab2(sch_1):page111_i26:IO24" )
				( pinRef "@baseboard_fab2_lib.baseboard_fab2(sch_1):page112_i109(3):A(3)" )
				( attribute "PROPAGATION_DELAY_MAX" "24000.00 MIL"
					( Units "uMaxMinProp" "ns" 1.000000)
					( Origin gBackEnd )
				)
			)
			( pinPair "@baseboard_fab2_lib.baseboard_fab2(sch_1):\PP5506\"
				( pinRef "@baseboard_fab2_lib.baseboard_fab2(sch_1):page55_i172:BPM_N(7)" )
				( pinRef "@baseboard_fab2_lib.baseboard_fab2(sch_1):page112_i120:B" )
				( attribute "PROPAGATION_DELAY_MAX" "1100.00 MIL"
					( Units "uMaxMinProp" "ns" 1.000000)
					( Origin gBackEnd )
				)
			)
			( pinPair "@baseboard_fab2_lib.baseboard_fab2(sch_1):\PP5503\"
				( pinRef "@baseboard_fab2_lib.baseboard_fab2(sch_1):page112_i109(2):A(2)" )
				( pinRef "@baseboard_fab2_lib.baseboard_fab2(sch_1):page111_i26:IO22" )
				( attribute "PROPAGATION_DELAY_MAX" "24000.00 MIL"
					( Units "uMaxMinProp" "ns" 1.000000)
					( Origin gBackEnd )
				)
			)
			( pinPair "@baseboard_fab2_lib.baseboard_fab2(sch_1):\PP5504\"
				( pinRef "@baseboard_fab2_lib.baseboard_fab2(sch_1):page55_i172:BPM_N(6)" )
				( pinRef "@baseboard_fab2_lib.baseboard_fab2(sch_1):page112_i121:B" )
				( attribute "PROPAGATION_DELAY_MAX" "1100.00 MIL"
					( Units "uMaxMinProp" "ns" 1.000000)
					( Origin gBackEnd )
				)
			)
			( pinPair "@baseboard_fab2_lib.baseboard_fab2(sch_1):\PP5654\"
				( pinRef "@baseboard_fab2_lib.baseboard_fab2(sch_1):page163_i15:B" )
				( pinRef "@baseboard_fab2_lib.baseboard_fab2(sch_1):page163_i25:A" )
				( attribute "PROPAGATION_DELAY_MAX" "25100.00 MIL"
					( Units "uMaxMinProp" "ns" 1.000000)
					( Origin gBackEnd )
				)
			)
			( pinPair "@baseboard_fab2_lib.baseboard_fab2(sch_1):\PP5655\"
				( pinRef "@baseboard_fab2_lib.baseboard_fab2(sch_1):page108_i339:A" )
				( pinRef "@baseboard_fab2_lib.baseboard_fab2(sch_1):page163_i25:B" )
				( attribute "PROPAGATION_DELAY_MAX" "25100.00 MIL"
					( Units "uMaxMinProp" "ns" 1.000000)
					( Origin gBackEnd )
				)
			)
			( pinPair "@baseboard_fab2_lib.baseboard_fab2(sch_1):\PP5656\"
				( pinRef "@baseboard_fab2_lib.baseboard_fab2(sch_1):page108_i258:IO17" )
				( pinRef "@baseboard_fab2_lib.baseboard_fab2(sch_1):page108_i340:B" )
				( attribute "PROPAGATION_DELAY_MAX" "25100.00 MIL"
					( Units "uMaxMinProp" "ns" 1.000000)
					( Origin gBackEnd )
				)
			)
			( pinPair "@baseboard_fab2_lib.baseboard_fab2(sch_1):\PP5657\"
				( pinRef "@baseboard_fab2_lib.baseboard_fab2(sch_1):page190_i179:PL9C" )
				( pinRef "@baseboard_fab2_lib.baseboard_fab2(sch_1):page183_i1:SCL" )
				( attribute "PROPAGATION_DELAY_MAX" "25100.00 MIL"
					( Units "uMaxMinProp" "ns" 1.000000)
					( Origin gBackEnd )
				)
			)
			( pinPair "@baseboard_fab2_lib.baseboard_fab2(sch_1):\PP5658\"
				( pinRef "@baseboard_fab2_lib.baseboard_fab2(sch_1):page138_i174:A" )
				( pinRef "@baseboard_fab2_lib.baseboard_fab2(sch_1):page119_i115:GPP_D13_SML0BCLK_IE" )
				( attribute "PROPAGATION_DELAY_MAX" "25100.00 MIL"
					( Units "uMaxMinProp" "ns" 1.000000)
					( Origin gBackEnd )
				)
			)
			( pinPair "@baseboard_fab2_lib.baseboard_fab2(sch_1):\PP5659\"
				( pinRef "@baseboard_fab2_lib.baseboard_fab2(sch_1):page144_i347:SCL(2)" )
				( pinRef "@baseboard_fab2_lib.baseboard_fab2(sch_1):page160_i49:B" )
				( attribute "PROPAGATION_DELAY_MAX" "25100.00 MIL"
					( Units "uMaxMinProp" "ns" 1.000000)
					( Origin gBackEnd )
				)
			)
			( pinPair "@baseboard_fab2_lib.baseboard_fab2(sch_1):\PP5660\"
				( pinRef "@baseboard_fab2_lib.baseboard_fab2(sch_1):page182_i18:IOC6" )
				( pinRef "@baseboard_fab2_lib.baseboard_fab2(sch_1):page163_i20:B" )
				( attribute "PROPAGATION_DELAY_MAX" "25100.00 MIL"
					( Units "uMaxMinProp" "ns" 1.000000)
					( Origin gBackEnd )
				)
			)
			( pinPair "@baseboard_fab2_lib.baseboard_fab2(sch_1):\PP5628\"
				( pinRef "@baseboard_fab2_lib.baseboard_fab2(sch_1):page184_i87:IO10" )
				( pinRef "@baseboard_fab2_lib.baseboard_fab2(sch_1):page167_i75:B" )
				( attribute "PROPAGATION_DELAY_MAX" "25100.00 MIL"
					( Units "uMaxMinProp" "ns" 1.000000)
					( Origin gBackEnd )
				)
			)
			( pinPair "@baseboard_fab2_lib.baseboard_fab2(sch_1):\PP5629\"
				( pinRef "@baseboard_fab2_lib.baseboard_fab2(sch_1):page167_i30:SCL" )
				( pinRef "@baseboard_fab2_lib.baseboard_fab2(sch_1):page167_i75:A" )
				( attribute "PROPAGATION_DELAY_MAX" "25100.00 MIL"
					( Units "uMaxMinProp" "ns" 1.000000)
					( Origin gBackEnd )
				)
			)
			( pinPair "@baseboard_fab2_lib.baseboard_fab2(sch_1):\PP5630\"
				( pinRef "@baseboard_fab2_lib.baseboard_fab2(sch_1):page167_i74:A" )
				( pinRef "@baseboard_fab2_lib.baseboard_fab2(sch_1):page167_i1:SCL" )
				( attribute "PROPAGATION_DELAY_MAX" "25100.00 MIL"
					( Units "uMaxMinProp" "ns" 1.000000)
					( Origin gBackEnd )
				)
			)
			( pinPair "@baseboard_fab2_lib.baseboard_fab2(sch_1):\PP5631\"
				( pinRef "@baseboard_fab2_lib.baseboard_fab2(sch_1):page167_i77:A" )
				( pinRef "@baseboard_fab2_lib.baseboard_fab2(sch_1):page144_i347:GPIOK4_SCL7" )
				( attribute "PROPAGATION_DELAY_MAX" "25100.00 MIL"
					( Units "uMaxMinProp" "ns" 1.000000)
					( Origin gBackEnd )
				)
			)
			( pinPair "@baseboard_fab2_lib.baseboard_fab2(sch_1):\PP5632\"
				( pinRef "@baseboard_fab2_lib.baseboard_fab2(sch_1):page165_i52:SCL" )
				( pinRef "@baseboard_fab2_lib.baseboard_fab2(sch_1):page138_i161:B" )
				( attribute "PROPAGATION_DELAY_MAX" "25100.00 MIL"
					( Units "uMaxMinProp" "ns" 1.000000)
					( Origin gBackEnd )
				)
			)
			( pinPair "@baseboard_fab2_lib.baseboard_fab2(sch_1):\PP5633\"
				( pinRef "@baseboard_fab2_lib.baseboard_fab2(sch_1):page120_i147:GPP_H13_SML3CLK_IE" )
				( pinRef "@baseboard_fab2_lib.baseboard_fab2(sch_1):page138_i161:A" )
				( attribute "PROPAGATION_DELAY_MAX" "25100.00 MIL"
					( Units "uMaxMinProp" "ns" 1.000000)
					( Origin gBackEnd )
				)
			)
			( pinPair "@baseboard_fab2_lib.baseboard_fab2(sch_1):\PP5678\"
				( pinRef "@baseboard_fab2_lib.baseboard_fab2(sch_1):page182_i18:IOD5" )
				( pinRef "@baseboard_fab2_lib.baseboard_fab2(sch_1):page138_i165:B" )
				( attribute "PROPAGATION_DELAY_MAX" "25100.00 MIL"
					( Units "uMaxMinProp" "ns" 1.000000)
					( Origin gBackEnd )
				)
			)
			( pinPair "@baseboard_fab2_lib.baseboard_fab2(sch_1):\PP5679\"
				( pinRef "@baseboard_fab2_lib.baseboard_fab2(sch_1):page120_i147:GPP_F20_LAN_SMBDATA" )
				( pinRef "@baseboard_fab2_lib.baseboard_fab2(sch_1):page138_i171:A" )
				( attribute "PROPAGATION_DELAY_MAX" "25100.00 MIL"
					( Units "uMaxMinProp" "ns" 1.000000)
					( Origin gBackEnd )
				)
			)
			( pinPair "@baseboard_fab2_lib.baseboard_fab2(sch_1):\PP5680\"
				( pinRef "@baseboard_fab2_lib.baseboard_fab2(sch_1):page144_i347:SDA(1)" )
				( pinRef "@baseboard_fab2_lib.baseboard_fab2(sch_1):page160_i51:A" )
				( attribute "PROPAGATION_DELAY_MAX" "25100.00 MIL"
					( Units "uMaxMinProp" "ns" 1.000000)
					( Origin gBackEnd )
				)
			)
			( pinPair "@baseboard_fab2_lib.baseboard_fab2(sch_1):\PP5681\"
				( pinRef "@baseboard_fab2_lib.baseboard_fab2(sch_1):page186_i336:IO32" )
				( pinRef "@baseboard_fab2_lib.baseboard_fab2(sch_1):page159_i221:B" )
				( attribute "PROPAGATION_DELAY_MAX" "25100.00 MIL"
					( Units "uMaxMinProp" "ns" 1.000000)
					( Origin gBackEnd )
				)
			)
			( pinPair "@baseboard_fab2_lib.baseboard_fab2(sch_1):\PP5682\"
				( pinRef "@baseboard_fab2_lib.baseboard_fab2(sch_1):page144_i347:GPIOA5_TIMER6_SDA9" )
				( pinRef "@baseboard_fab2_lib.baseboard_fab2(sch_1):page159_i216:B" )
				( attribute "PROPAGATION_DELAY_MAX" "25100.00 MIL"
					( Units "uMaxMinProp" "ns" 1.000000)
					( Origin gBackEnd )
				)
			)
			( pinPair "@baseboard_fab2_lib.baseboard_fab2(sch_1):\PP5683\"
				( pinRef "@baseboard_fab2_lib.baseboard_fab2(sch_1):page120_i147:GPP_H17_SML4DATA_IE" )
				( pinRef "@baseboard_fab2_lib.baseboard_fab2(sch_1):page138_i165:A" )
				( attribute "PROPAGATION_DELAY_MAX" "25100.00 MIL"
					( Units "uMaxMinProp" "ns" 1.000000)
					( Origin gBackEnd )
				)
			)
			( pinPair "@baseboard_fab2_lib.baseboard_fab2(sch_1):\PP5672\"
				( pinRef "@baseboard_fab2_lib.baseboard_fab2(sch_1):page182_i18:IOE5" )
				( pinRef "@baseboard_fab2_lib.baseboard_fab2(sch_1):page138_i158:A" )
				( attribute "PROPAGATION_DELAY_MAX" "25100.00 MIL"
					( Units "uMaxMinProp" "ns" 1.000000)
					( Origin gBackEnd )
				)
			)
			( pinPair "@baseboard_fab2_lib.baseboard_fab2(sch_1):\PP5673\"
				( pinRef "@baseboard_fab2_lib.baseboard_fab2(sch_1):page120_i147:GPP_F19_LAN_SMBCLK" )
				( pinRef "@baseboard_fab2_lib.baseboard_fab2(sch_1):page138_i175:A" )
				( attribute "PROPAGATION_DELAY_MAX" "25100.00 MIL"
					( Units "uMaxMinProp" "ns" 1.000000)
					( Origin gBackEnd )
				)
			)
			( pinPair "@baseboard_fab2_lib.baseboard_fab2(sch_1):\PP5674\"
				( pinRef "@baseboard_fab2_lib.baseboard_fab2(sch_1):page144_i347:SCL(1)" )
				( pinRef "@baseboard_fab2_lib.baseboard_fab2(sch_1):page160_i52:A" )
				( attribute "PROPAGATION_DELAY_MAX" "25100.00 MIL"
					( Units "uMaxMinProp" "ns" 1.000000)
					( Origin gBackEnd )
				)
			)
			( pinPair "@baseboard_fab2_lib.baseboard_fab2(sch_1):\PP5675\"
				( pinRef "@baseboard_fab2_lib.baseboard_fab2(sch_1):page186_i336:IO30" )
				( pinRef "@baseboard_fab2_lib.baseboard_fab2(sch_1):page159_i220:B" )
				( attribute "PROPAGATION_DELAY_MAX" "25100.00 MIL"
					( Units "uMaxMinProp" "ns" 1.000000)
					( Origin gBackEnd )
				)
			)
			( pinPair "@baseboard_fab2_lib.baseboard_fab2(sch_1):\PP5676\"
				( pinRef "@baseboard_fab2_lib.baseboard_fab2(sch_1):page144_i347:GPIOA4_TIMER5_SCL9" )
				( pinRef "@baseboard_fab2_lib.baseboard_fab2(sch_1):page159_i220:A" )
				( attribute "PROPAGATION_DELAY_MAX" "25100.00 MIL"
					( Units "uMaxMinProp" "ns" 1.000000)
					( Origin gBackEnd )
				)
			)
			( pinPair "@baseboard_fab2_lib.baseboard_fab2(sch_1):\PP5677\"
				( pinRef "@baseboard_fab2_lib.baseboard_fab2(sch_1):page120_i147:GPP_H16_SML4CLK_IE" )
				( pinRef "@baseboard_fab2_lib.baseboard_fab2(sch_1):page138_i166:A" )
				( attribute "PROPAGATION_DELAY_MAX" "25100.00 MIL"
					( Units "uMaxMinProp" "ns" 1.000000)
					( Origin gBackEnd )
				)
			)
			( pinPair "@baseboard_fab2_lib.baseboard_fab2(sch_1):\PP5538\"
				( pinRef "@baseboard_fab2_lib.baseboard_fab2(sch_1):page138_i116:A" )
				( pinRef "@baseboard_fab2_lib.baseboard_fab2(sch_1):page119_i115:GPP_C7_SML1DATA_IE" )
				( attribute "PROPAGATION_DELAY_MAX" "25100.00 MIL"
					( Units "uMaxMinProp" "ns" 1.000000)
					( Origin gBackEnd )
				)
			)
			( pinPair "@baseboard_fab2_lib.baseboard_fab2(sch_1):\PP5539\"
				( pinRef "@baseboard_fab2_lib.baseboard_fab2(sch_1):page181_i111:IOB6" )
				( pinRef "@baseboard_fab2_lib.baseboard_fab2(sch_1):page159_i219:B" )
				( attribute "PROPAGATION_DELAY_MAX" "25100.00 MIL"
					( Units "uMaxMinProp" "ns" 1.000000)
					( Origin gBackEnd )
				)
			)
			( pinPair "@baseboard_fab2_lib.baseboard_fab2(sch_1):\PP5540\"
				( pinRef "@baseboard_fab2_lib.baseboard_fab2(sch_1):page199_i10:SDA" )
				( pinRef "@baseboard_fab2_lib.baseboard_fab2(sch_1):page199_i28:B" )
				( attribute "PROPAGATION_DELAY_MAX" "25100.00 MIL"
					( Units "uMaxMinProp" "ns" 1.000000)
					( Origin gBackEnd )
				)
			)
			( pinPair "@baseboard_fab2_lib.baseboard_fab2(sch_1):\PP5541\"
				( pinRef "@baseboard_fab2_lib.baseboard_fab2(sch_1):page159_i219:A" )
				( pinRef "@baseboard_fab2_lib.baseboard_fab2(sch_1):page144_i347:GPIOK7_SDA8" )
				( attribute "PROPAGATION_DELAY_MAX" "25100.00 MIL"
					( Units "uMaxMinProp" "ns" 1.000000)
					( Origin gBackEnd )
				)
			)
			( pinPair "@baseboard_fab2_lib.baseboard_fab2(sch_1):\PP5534\"
				( pinRef "@baseboard_fab2_lib.baseboard_fab2(sch_1):page138_i160:A" )
				( pinRef "@baseboard_fab2_lib.baseboard_fab2(sch_1):page119_i115:GPP_C6_SML1CLK_IE" )
				( attribute "PROPAGATION_DELAY_MAX" "25100.00 MIL"
					( Units "uMaxMinProp" "ns" 1.000000)
					( Origin gBackEnd )
				)
			)
			( pinPair "@baseboard_fab2_lib.baseboard_fab2(sch_1):\PP5535\"
				( pinRef "@baseboard_fab2_lib.baseboard_fab2(sch_1):page181_i111:IOC6" )
				( pinRef "@baseboard_fab2_lib.baseboard_fab2(sch_1):page159_i218:B" )
				( attribute "PROPAGATION_DELAY_MAX" "25100.00 MIL"
					( Units "uMaxMinProp" "ns" 1.000000)
					( Origin gBackEnd )
				)
			)
			( pinPair "@baseboard_fab2_lib.baseboard_fab2(sch_1):\PP5536\"
				( pinRef "@baseboard_fab2_lib.baseboard_fab2(sch_1):page199_i10:SCL" )
				( pinRef "@baseboard_fab2_lib.baseboard_fab2(sch_1):page199_i27:B" )
				( attribute "PROPAGATION_DELAY_MAX" "25100.00 MIL"
					( Units "uMaxMinProp" "ns" 1.000000)
					( Origin gBackEnd )
				)
			)
			( pinPair "@baseboard_fab2_lib.baseboard_fab2(sch_1):\PP5537\"
				( pinRef "@baseboard_fab2_lib.baseboard_fab2(sch_1):page144_i347:GPIOK6_SCL8" )
				( pinRef "@baseboard_fab2_lib.baseboard_fab2(sch_1):page159_i218:A" )
				( attribute "PROPAGATION_DELAY_MAX" "25100.00 MIL"
					( Units "uMaxMinProp" "ns" 1.000000)
					( Origin gBackEnd )
				)
			)
			( pinPair "@baseboard_fab2_lib.baseboard_fab2(sch_1):\PP5661\"
				( pinRef "@baseboard_fab2_lib.baseboard_fab2(sch_1):page163_i1:SDAB" )
				( pinRef "@baseboard_fab2_lib.baseboard_fab2(sch_1):page163_i21:A" )
				( attribute "PROPAGATION_DELAY_MAX" "25100.00 MIL"
					( Units "uMaxMinProp" "ns" 1.000000)
					( Origin gBackEnd )
				)
			)
			( pinPair "@baseboard_fab2_lib.baseboard_fab2(sch_1):\PP5662\"
				( pinRef "@baseboard_fab2_lib.baseboard_fab2(sch_1):page108_i330:A" )
				( pinRef "@baseboard_fab2_lib.baseboard_fab2(sch_1):page163_i24:B" )
				( attribute "PROPAGATION_DELAY_MAX" "25100.00 MIL"
					( Units "uMaxMinProp" "ns" 1.000000)
					( Origin gBackEnd )
				)
			)
			( pinPair "@baseboard_fab2_lib.baseboard_fab2(sch_1):\PP5663\"
				( pinRef "@baseboard_fab2_lib.baseboard_fab2(sch_1):page144_i347:SDA(2)" )
				( pinRef "@baseboard_fab2_lib.baseboard_fab2(sch_1):page160_i4:A" )
				( attribute "PROPAGATION_DELAY_MAX" "25100.00 MIL"
					( Units "uMaxMinProp" "ns" 1.000000)
					( Origin gBackEnd )
				)
			)
			( pinPair "@baseboard_fab2_lib.baseboard_fab2(sch_1):\PP5664\"
				( pinRef "@baseboard_fab2_lib.baseboard_fab2(sch_1):page108_i258:IO15" )
				( pinRef "@baseboard_fab2_lib.baseboard_fab2(sch_1):page108_i320:B" )
				( attribute "PROPAGATION_DELAY_MAX" "25100.00 MIL"
					( Units "uMaxMinProp" "ns" 1.000000)
					( Origin gBackEnd )
				)
			)
			( pinPair "@baseboard_fab2_lib.baseboard_fab2(sch_1):\PP5665\"
				( pinRef "@baseboard_fab2_lib.baseboard_fab2(sch_1):page183_i1:SDA" )
				( pinRef "@baseboard_fab2_lib.baseboard_fab2(sch_1):page138_i95:B" )
				( attribute "PROPAGATION_DELAY_MAX" "25100.00 MIL"
					( Units "uMaxMinProp" "ns" 1.000000)
					( Origin gBackEnd )
				)
			)
			( pinPair "@baseboard_fab2_lib.baseboard_fab2(sch_1):\PP5666\"
				( pinRef "@baseboard_fab2_lib.baseboard_fab2(sch_1):page119_i115:GPP_D14_SML0BDATA_IE" )
				( pinRef "@baseboard_fab2_lib.baseboard_fab2(sch_1):page138_i173:A" )
				( attribute "PROPAGATION_DELAY_MAX" "25100.00 MIL"
					( Units "uMaxMinProp" "ns" 1.000000)
					( Origin gBackEnd )
				)
			)
			( pinPair "@baseboard_fab2_lib.baseboard_fab2(sch_1):\PP5667\"
				( pinRef "@baseboard_fab2_lib.baseboard_fab2(sch_1):page163_i21:B" )
				( pinRef "@baseboard_fab2_lib.baseboard_fab2(sch_1):page182_i18:IOB6" )
				( attribute "PROPAGATION_DELAY_MAX" "25100.00 MIL"
					( Units "uMaxMinProp" "ns" 1.000000)
					( Origin gBackEnd )
				)
			)
			( pinPair "@baseboard_fab2_lib.baseboard_fab2(sch_1):\PP5646\"
				( pinRef "@baseboard_fab2_lib.baseboard_fab2(sch_1):page139_i72:SMB_DATA" )
				( pinRef "@baseboard_fab2_lib.baseboard_fab2(sch_1):page159_i225:B" )
				( attribute "PROPAGATION_DELAY_MAX" "25100.00 MIL"
					( Units "uMaxMinProp" "ns" 1.000000)
					( Origin gBackEnd )
				)
			)
			( pinPair "@baseboard_fab2_lib.baseboard_fab2(sch_1):\PP5647\"
				( pinRef "@baseboard_fab2_lib.baseboard_fab2(sch_1):page138_i89:B" )
				( pinRef "@baseboard_fab2_lib.baseboard_fab2(sch_1):page159_i225:A" )
				( attribute "PROPAGATION_DELAY_MAX" "25100.00 MIL"
					( Units "uMaxMinProp" "ns" 1.000000)
					( Origin gBackEnd )
				)
			)
			( pinPair "@baseboard_fab2_lib.baseboard_fab2(sch_1):\PP5648\"
				( pinRef "@baseboard_fab2_lib.baseboard_fab2(sch_1):page144_i347:GPIOK1_SDA5" )
				( pinRef "@baseboard_fab2_lib.baseboard_fab2(sch_1):page159_i233:A" )
				( attribute "PROPAGATION_DELAY_MAX" "25100.00 MIL"
					( Units "uMaxMinProp" "ns" 1.000000)
					( Origin gBackEnd )
				)
			)
			( pinPair "@baseboard_fab2_lib.baseboard_fab2(sch_1):\PP5649\"
				( pinRef "@baseboard_fab2_lib.baseboard_fab2(sch_1):page138_i169:A" )
				( pinRef "@baseboard_fab2_lib.baseboard_fab2(sch_1):page119_i115:GPP_C4_SML0DATA_IE" )
				( attribute "PROPAGATION_DELAY_MAX" "25100.00 MIL"
					( Units "uMaxMinProp" "ns" 1.000000)
					( Origin gBackEnd )
				)
			)
			( pinPair "@baseboard_fab2_lib.baseboard_fab2(sch_1):\PP5650\"
				( pinRef "@baseboard_fab2_lib.baseboard_fab2(sch_1):page186_i336:IO37" )
				( pinRef "@baseboard_fab2_lib.baseboard_fab2(sch_1):page159_i228:B" )
				( attribute "PROPAGATION_DELAY_MAX" "25100.00 MIL"
					( Units "uMaxMinProp" "ns" 1.000000)
					( Origin gBackEnd )
				)
			)
			( pinPair "@baseboard_fab2_lib.baseboard_fab2(sch_1):\PP5651\"
				( pinRef "@baseboard_fab2_lib.baseboard_fab2(sch_1):page144_i347:GPIOQ1_SDA3" )
				( pinRef "@baseboard_fab2_lib.baseboard_fab2(sch_1):page159_i212:B" )
				( attribute "PROPAGATION_DELAY_MAX" "25100.00 MIL"
					( Units "uMaxMinProp" "ns" 1.000000)
					( Origin gBackEnd )
				)
			)
			( pinPair "@baseboard_fab2_lib.baseboard_fab2(sch_1):\PP5640\"
				( pinRef "@baseboard_fab2_lib.baseboard_fab2(sch_1):page139_i72:SMB_CLK" )
				( pinRef "@baseboard_fab2_lib.baseboard_fab2(sch_1):page159_i226:B" )
				( attribute "PROPAGATION_DELAY_MAX" "25100.00 MIL"
					( Units "uMaxMinProp" "ns" 1.000000)
					( Origin gBackEnd )
				)
			)
			( pinPair "@baseboard_fab2_lib.baseboard_fab2(sch_1):\PP5641\"
				( pinRef "@baseboard_fab2_lib.baseboard_fab2(sch_1):page186_i336:IO35" )
				( pinRef "@baseboard_fab2_lib.baseboard_fab2(sch_1):page159_i229:B" )
				( attribute "PROPAGATION_DELAY_MAX" "25100.00 MIL"
					( Units "uMaxMinProp" "ns" 1.000000)
					( Origin gBackEnd )
				)
			)
			( pinPair "@baseboard_fab2_lib.baseboard_fab2(sch_1):\PP5642\"
				( pinRef "@baseboard_fab2_lib.baseboard_fab2(sch_1):page144_i347:GPIOQ0_SCL3" )
				( pinRef "@baseboard_fab2_lib.baseboard_fab2(sch_1):page159_i210:B" )
				( attribute "PROPAGATION_DELAY_MAX" "25100.00 MIL"
					( Units "uMaxMinProp" "ns" 1.000000)
					( Origin gBackEnd )
				)
			)
			( pinPair "@baseboard_fab2_lib.baseboard_fab2(sch_1):\PP5643\"
				( pinRef "@baseboard_fab2_lib.baseboard_fab2(sch_1):page138_i170:B" )
				( pinRef "@baseboard_fab2_lib.baseboard_fab2(sch_1):page159_i226:A" )
				( attribute "PROPAGATION_DELAY_MAX" "25100.00 MIL"
					( Units "uMaxMinProp" "ns" 1.000000)
					( Origin gBackEnd )
				)
			)
			( pinPair "@baseboard_fab2_lib.baseboard_fab2(sch_1):\PP5644\"
				( pinRef "@baseboard_fab2_lib.baseboard_fab2(sch_1):page159_i232:A" )
				( pinRef "@baseboard_fab2_lib.baseboard_fab2(sch_1):page144_i347:GPIOK0_SCL5" )
				( attribute "PROPAGATION_DELAY_MAX" "25100.00 MIL"
					( Units "uMaxMinProp" "ns" 1.000000)
					( Origin gBackEnd )
				)
			)
			( pinPair "@baseboard_fab2_lib.baseboard_fab2(sch_1):\PP5645\"
				( pinRef "@baseboard_fab2_lib.baseboard_fab2(sch_1):page138_i170:A" )
				( pinRef "@baseboard_fab2_lib.baseboard_fab2(sch_1):page119_i115:GPP_C3_SML0CLK_IE" )
				( attribute "PROPAGATION_DELAY_MAX" "25100.00 MIL"
					( Units "uMaxMinProp" "ns" 1.000000)
					( Origin gBackEnd )
				)
			)
			( pinPair "@baseboard_fab2_lib.baseboard_fab2(sch_1):\PP5634\"
				( pinRef "@baseboard_fab2_lib.baseboard_fab2(sch_1):page184_i87:IO6" )
				( pinRef "@baseboard_fab2_lib.baseboard_fab2(sch_1):page167_i76:B" )
				( attribute "PROPAGATION_DELAY_MAX" "25100.00 MIL"
					( Units "uMaxMinProp" "ns" 1.000000)
					( Origin gBackEnd )
				)
			)
			( pinPair "@baseboard_fab2_lib.baseboard_fab2(sch_1):\PP5635\"
				( pinRef "@baseboard_fab2_lib.baseboard_fab2(sch_1):page165_i52:SDA" )
				( pinRef "@baseboard_fab2_lib.baseboard_fab2(sch_1):page138_i162:B" )
				( attribute "PROPAGATION_DELAY_MAX" "25100.00 MIL"
					( Units "uMaxMinProp" "ns" 1.000000)
					( Origin gBackEnd )
				)
			)
			( pinPair "@baseboard_fab2_lib.baseboard_fab2(sch_1):\PP5636\"
				( pinRef "@baseboard_fab2_lib.baseboard_fab2(sch_1):page120_i147:GPP_H14_SML3DATA_IE" )
				( pinRef "@baseboard_fab2_lib.baseboard_fab2(sch_1):page138_i162:A" )
				( attribute "PROPAGATION_DELAY_MAX" "25100.00 MIL"
					( Units "uMaxMinProp" "ns" 1.000000)
					( Origin gBackEnd )
				)
			)
			( pinPair "@baseboard_fab2_lib.baseboard_fab2(sch_1):\PP5637\"
				( pinRef "@baseboard_fab2_lib.baseboard_fab2(sch_1):page144_i347:GPIOK5_SDA7" )
				( pinRef "@baseboard_fab2_lib.baseboard_fab2(sch_1):page167_i58:A" )
				( attribute "PROPAGATION_DELAY_MAX" "25100.00 MIL"
					( Units "uMaxMinProp" "ns" 1.000000)
					( Origin gBackEnd )
				)
			)
			( pinPair "@baseboard_fab2_lib.baseboard_fab2(sch_1):\PP5638\"
				( pinRef "@baseboard_fab2_lib.baseboard_fab2(sch_1):page167_i76:A" )
				( pinRef "@baseboard_fab2_lib.baseboard_fab2(sch_1):page167_i30:SDA" )
				( attribute "PROPAGATION_DELAY_MAX" "25100.00 MIL"
					( Units "uMaxMinProp" "ns" 1.000000)
					( Origin gBackEnd )
				)
			)
			( pinPair "@baseboard_fab2_lib.baseboard_fab2(sch_1):\PP5639\"
				( pinRef "@baseboard_fab2_lib.baseboard_fab2(sch_1):page167_i1:SDA" )
				( pinRef "@baseboard_fab2_lib.baseboard_fab2(sch_1):page167_i8:A" )
				( attribute "PROPAGATION_DELAY_MAX" "25100.00 MIL"
					( Units "uMaxMinProp" "ns" 1.000000)
					( Origin gBackEnd )
				)
			)
			( pinPair "@baseboard_fab2_lib.baseboard_fab2(sch_1):\PP5596\"
				( pinRef "@baseboard_fab2_lib.baseboard_fab2(sch_1):page235_i172:B" )
				( pinRef "@baseboard_fab2_lib.baseboard_fab2(sch_1):page235_i229:SDA" )
				( attribute "PROPAGATION_DELAY_MAX" "25100.00 MIL"
					( Units "uMaxMinProp" "ns" 1.000000)
					( Origin gBackEnd )
				)
			)
			( pinPair "@baseboard_fab2_lib.baseboard_fab2(sch_1):\PP5597\"
				( pinRef "@baseboard_fab2_lib.baseboard_fab2(sch_1):page194_i56:IOB18" )
				( pinRef "@baseboard_fab2_lib.baseboard_fab2(sch_1):page223_i22:B" )
				( attribute "PROPAGATION_DELAY_MAX" "25100.00 MIL"
					( Units "uMaxMinProp" "ns" 1.000000)
					( Origin gBackEnd )
				)
			)
			( pinPair "@baseboard_fab2_lib.baseboard_fab2(sch_1):\PP5598\"
				( pinRef "@baseboard_fab2_lib.baseboard_fab2(sch_1):page215_i304:A" )
				( pinRef "@baseboard_fab2_lib.baseboard_fab2(sch_1):page215_i358:SDA" )
				( attribute "PROPAGATION_DELAY_MAX" "25100.00 MIL"
					( Units "uMaxMinProp" "ns" 1.000000)
					( Origin gBackEnd )
				)
			)
			( pinPair "@baseboard_fab2_lib.baseboard_fab2(sch_1):\PP5599\"
				( pinRef "@baseboard_fab2_lib.baseboard_fab2(sch_1):page226_i90:SDA" )
				( pinRef "@baseboard_fab2_lib.baseboard_fab2(sch_1):page226_i22:A" )
				( attribute "PROPAGATION_DELAY_MAX" "25100.00 MIL"
					( Units "uMaxMinProp" "ns" 1.000000)
					( Origin gBackEnd )
				)
			)
			( pinPair "@baseboard_fab2_lib.baseboard_fab2(sch_1):\PP5600\"
				( pinRef "@baseboard_fab2_lib.baseboard_fab2(sch_1):page213_i96:SDA" )
				( pinRef "@baseboard_fab2_lib.baseboard_fab2(sch_1):page213_i38:B" )
				( attribute "PROPAGATION_DELAY_MAX" "25100.00 MIL"
					( Units "uMaxMinProp" "ns" 1.000000)
					( Origin gBackEnd )
				)
			)
			( pinPair "@baseboard_fab2_lib.baseboard_fab2(sch_1):\PP5601\"
				( pinRef "@baseboard_fab2_lib.baseboard_fab2(sch_1):page211_i93:SDA" )
				( pinRef "@baseboard_fab2_lib.baseboard_fab2(sch_1):page211_i47:B" )
				( attribute "PROPAGATION_DELAY_MAX" "25100.00 MIL"
					( Units "uMaxMinProp" "ns" 1.000000)
					( Origin gBackEnd )
				)
			)
			( pinPair "@baseboard_fab2_lib.baseboard_fab2(sch_1):\PP5602\"
				( pinRef "@baseboard_fab2_lib.baseboard_fab2(sch_1):page120_i147:GPP_H11_SML2DATA_IE" )
				( pinRef "@baseboard_fab2_lib.baseboard_fab2(sch_1):page138_i163:A" )
				( attribute "PROPAGATION_DELAY_MAX" "25100.00 MIL"
					( Units "uMaxMinProp" "ns" 1.000000)
					( Origin gBackEnd )
				)
			)
			( pinPair "@baseboard_fab2_lib.baseboard_fab2(sch_1):\PP5603\"
				( pinRef "@baseboard_fab2_lib.baseboard_fab2(sch_1):page201_i28:A" )
				( pinRef "@baseboard_fab2_lib.baseboard_fab2(sch_1):page201_i155:SDA" )
				( attribute "PROPAGATION_DELAY_MAX" "25100.00 MIL"
					( Units "uMaxMinProp" "ns" 1.000000)
					( Origin gBackEnd )
				)
			)
			( pinPair "@baseboard_fab2_lib.baseboard_fab2(sch_1):\PP5604\"
				( pinRef "@baseboard_fab2_lib.baseboard_fab2(sch_1):page206_i27:A" )
				( pinRef "@baseboard_fab2_lib.baseboard_fab2(sch_1):page206_i130:SDA" )
				( attribute "PROPAGATION_DELAY_MAX" "25100.00 MIL"
					( Units "uMaxMinProp" "ns" 1.000000)
					( Origin gBackEnd )
				)
			)
			( pinPair "@baseboard_fab2_lib.baseboard_fab2(sch_1):\PP5605\"
				( pinRef "@baseboard_fab2_lib.baseboard_fab2(sch_1):page218_i75:SDA" )
				( pinRef "@baseboard_fab2_lib.baseboard_fab2(sch_1):page218_i24:A" )
				( attribute "PROPAGATION_DELAY_MAX" "25100.00 MIL"
					( Units "uMaxMinProp" "ns" 1.000000)
					( Origin gBackEnd )
				)
			)
			( pinPair "@baseboard_fab2_lib.baseboard_fab2(sch_1):\PP5606\"
				( pinRef "@baseboard_fab2_lib.baseboard_fab2(sch_1):page144_i347:GPIOK3_SDA6" )
				( pinRef "@baseboard_fab2_lib.baseboard_fab2(sch_1):page159_i223:A" )
				( attribute "PROPAGATION_DELAY_MAX" "25100.00 MIL"
					( Units "uMaxMinProp" "ns" 1.000000)
					( Origin gBackEnd )
				)
			)
			( pinPair "@baseboard_fab2_lib.baseboard_fab2(sch_1):\PP5607\"
				( pinRef "@baseboard_fab2_lib.baseboard_fab2(sch_1):page223_i90:SDA" )
				( pinRef "@baseboard_fab2_lib.baseboard_fab2(sch_1):page223_i22:A" )
				( attribute "PROPAGATION_DELAY_MAX" "25100.00 MIL"
					( Units "uMaxMinProp" "ns" 1.000000)
					( Origin gBackEnd )
				)
			)
			( pinPair "@baseboard_fab2_lib.baseboard_fab2(sch_1):\PP5584\"
				( pinRef "@baseboard_fab2_lib.baseboard_fab2(sch_1):page235_i229:SCL" )
				( pinRef "@baseboard_fab2_lib.baseboard_fab2(sch_1):page235_i173:B" )
				( attribute "PROPAGATION_DELAY_MAX" "25100.00 MIL"
					( Units "uMaxMinProp" "ns" 1.000000)
					( Origin gBackEnd )
				)
			)
			( pinPair "@baseboard_fab2_lib.baseboard_fab2(sch_1):\PP5585\"
				( pinRef "@baseboard_fab2_lib.baseboard_fab2(sch_1):page194_i56:IOA18" )
				( pinRef "@baseboard_fab2_lib.baseboard_fab2(sch_1):page223_i21:B" )
				( attribute "PROPAGATION_DELAY_MAX" "25100.00 MIL"
					( Units "uMaxMinProp" "ns" 1.000000)
					( Origin gBackEnd )
				)
			)
			( pinPair "@baseboard_fab2_lib.baseboard_fab2(sch_1):\PP5586\"
				( pinRef "@baseboard_fab2_lib.baseboard_fab2(sch_1):page226_i21:A" )
				( pinRef "@baseboard_fab2_lib.baseboard_fab2(sch_1):page226_i90:SCL" )
				( attribute "PROPAGATION_DELAY_MAX" "25100.00 MIL"
					( Units "uMaxMinProp" "ns" 1.000000)
					( Origin gBackEnd )
				)
			)
			( pinPair "@baseboard_fab2_lib.baseboard_fab2(sch_1):\PP5587\"
				( pinRef "@baseboard_fab2_lib.baseboard_fab2(sch_1):page211_i93:SCL" )
				( pinRef "@baseboard_fab2_lib.baseboard_fab2(sch_1):page211_i46:B" )
				( attribute "PROPAGATION_DELAY_MAX" "25100.00 MIL"
					( Units "uMaxMinProp" "ns" 1.000000)
					( Origin gBackEnd )
				)
			)
			( pinPair "@baseboard_fab2_lib.baseboard_fab2(sch_1):\PP5588\"
				( pinRef "@baseboard_fab2_lib.baseboard_fab2(sch_1):page201_i155:SCL" )
				( pinRef "@baseboard_fab2_lib.baseboard_fab2(sch_1):page201_i31:A" )
				( attribute "PROPAGATION_DELAY_MAX" "25100.00 MIL"
					( Units "uMaxMinProp" "ns" 1.000000)
					( Origin gBackEnd )
				)
			)
			( pinPair "@baseboard_fab2_lib.baseboard_fab2(sch_1):\PP5589\"
				( pinRef "@baseboard_fab2_lib.baseboard_fab2(sch_1):page213_i39:B" )
				( pinRef "@baseboard_fab2_lib.baseboard_fab2(sch_1):page213_i96:SCL" )
				( attribute "PROPAGATION_DELAY_MAX" "25100.00 MIL"
					( Units "uMaxMinProp" "ns" 1.000000)
					( Origin gBackEnd )
				)
			)
			( pinPair "@baseboard_fab2_lib.baseboard_fab2(sch_1):\PP5590\"
				( pinRef "@baseboard_fab2_lib.baseboard_fab2(sch_1):page206_i130:SCL" )
				( pinRef "@baseboard_fab2_lib.baseboard_fab2(sch_1):page206_i28:A" )
				( attribute "PROPAGATION_DELAY_MAX" "25100.00 MIL"
					( Units "uMaxMinProp" "ns" 1.000000)
					( Origin gBackEnd )
				)
			)
			( pinPair "@baseboard_fab2_lib.baseboard_fab2(sch_1):\PP5591\"
				( pinRef "@baseboard_fab2_lib.baseboard_fab2(sch_1):page218_i75:SCL" )
				( pinRef "@baseboard_fab2_lib.baseboard_fab2(sch_1):page218_i21:A" )
				( attribute "PROPAGATION_DELAY_MAX" "25100.00 MIL"
					( Units "uMaxMinProp" "ns" 1.000000)
					( Origin gBackEnd )
				)
			)
			( pinPair "@baseboard_fab2_lib.baseboard_fab2(sch_1):\PP5592\"
				( pinRef "@baseboard_fab2_lib.baseboard_fab2(sch_1):page223_i90:SCL" )
				( pinRef "@baseboard_fab2_lib.baseboard_fab2(sch_1):page223_i21:A" )
				( attribute "PROPAGATION_DELAY_MAX" "25100.00 MIL"
					( Units "uMaxMinProp" "ns" 1.000000)
					( Origin gBackEnd )
				)
			)
			( pinPair "@baseboard_fab2_lib.baseboard_fab2(sch_1):\PP5593\"
				( pinRef "@baseboard_fab2_lib.baseboard_fab2(sch_1):page138_i164:A" )
				( pinRef "@baseboard_fab2_lib.baseboard_fab2(sch_1):page120_i147:GPP_H10_SML2CLK_IE" )
				( attribute "PROPAGATION_DELAY_MAX" "25100.00 MIL"
					( Units "uMaxMinProp" "ns" 1.000000)
					( Origin gBackEnd )
				)
			)
			( pinPair "@baseboard_fab2_lib.baseboard_fab2(sch_1):\PP5594\"
				( pinRef "@baseboard_fab2_lib.baseboard_fab2(sch_1):page144_i347:GPIOK2_SCL6" )
				( pinRef "@baseboard_fab2_lib.baseboard_fab2(sch_1):page159_i222:A" )
				( attribute "PROPAGATION_DELAY_MAX" "25100.00 MIL"
					( Units "uMaxMinProp" "ns" 1.000000)
					( Origin gBackEnd )
				)
			)
			( pinPair "@baseboard_fab2_lib.baseboard_fab2(sch_1):\PP5595\"
				( pinRef "@baseboard_fab2_lib.baseboard_fab2(sch_1):page215_i358:SCL" )
				( pinRef "@baseboard_fab2_lib.baseboard_fab2(sch_1):page215_i298:A" )
				( attribute "PROPAGATION_DELAY_MAX" "25100.00 MIL"
					( Units "uMaxMinProp" "ns" 1.000000)
					( Origin gBackEnd )
				)
			)
			( pinPair "@baseboard_fab2_lib.baseboard_fab2(sch_1):\PP5449\"
				( pinRef "@baseboard_fab2_lib.baseboard_fab2(sch_1):page99_i55:A" )
				( pinRef "@baseboard_fab2_lib.baseboard_fab2(sch_1):page99_i75:SDAB" )
				( attribute "PROPAGATION_DELAY_MAX" "25100.00 MIL"
					( Units "uMaxMinProp" "ns" 1.000000)
					( Origin gBackEnd )
				)
			)
			( pinPair "@baseboard_fab2_lib.baseboard_fab2(sch_1):\PP5450\"
				( pinRef "@baseboard_fab2_lib.baseboard_fab2(sch_1):page99_i107:B" )
				( pinRef "@baseboard_fab2_lib.baseboard_fab2(sch_1):page99_i55:A" )
				( attribute "PROPAGATION_DELAY_MAX" "200.00 MIL"
					( Units "uMaxMinProp" "ns" 1.000000)
					( Origin gBackEnd )
				)
			)
			( pinPair "@baseboard_fab2_lib.baseboard_fab2(sch_1):\PP5451\"
				( pinRef "@baseboard_fab2_lib.baseboard_fab2(sch_1):page99_i107:B" )
				( pinRef "@baseboard_fab2_lib.baseboard_fab2(sch_1):page99_i75:SDAB" )
				( attribute "PROPAGATION_DELAY_MAX" "1000.00 MIL"
					( Units "uMaxMinProp" "ns" 1.000000)
					( Origin gBackEnd )
				)
			)
			( pinPair "@baseboard_fab2_lib.baseboard_fab2(sch_1):\PP5452\"
				( pinRef "@baseboard_fab2_lib.baseboard_fab2(sch_1):page87_i186:SDA" )
				( pinRef "@baseboard_fab2_lib.baseboard_fab2(sch_1):page99_i55:B" )
				( attribute "PROPAGATION_DELAY_MAX" "25100.00 MIL"
					( Units "uMaxMinProp" "ns" 1.000000)
					( Origin gBackEnd )
				)
			)
			( pinPair "@baseboard_fab2_lib.baseboard_fab2(sch_1):\PP5445\"
				( pinRef "@baseboard_fab2_lib.baseboard_fab2(sch_1):page99_i75:SCLB" )
				( pinRef "@baseboard_fab2_lib.baseboard_fab2(sch_1):page99_i56:A" )
				( attribute "PROPAGATION_DELAY_MAX" "25100.00 MIL"
					( Units "uMaxMinProp" "ns" 1.000000)
					( Origin gBackEnd )
				)
			)
			( pinPair "@baseboard_fab2_lib.baseboard_fab2(sch_1):\PP5446\"
				( pinRef "@baseboard_fab2_lib.baseboard_fab2(sch_1):page99_i109:B" )
				( pinRef "@baseboard_fab2_lib.baseboard_fab2(sch_1):page99_i56:A" )
				( attribute "PROPAGATION_DELAY_MAX" "200.00 MIL"
					( Units "uMaxMinProp" "ns" 1.000000)
					( Origin gBackEnd )
				)
			)
			( pinPair "@baseboard_fab2_lib.baseboard_fab2(sch_1):\PP5447\"
				( pinRef "@baseboard_fab2_lib.baseboard_fab2(sch_1):page99_i109:B" )
				( pinRef "@baseboard_fab2_lib.baseboard_fab2(sch_1):page99_i75:SCLB" )
				( attribute "PROPAGATION_DELAY_MAX" "1000.00 MIL"
					( Units "uMaxMinProp" "ns" 1.000000)
					( Origin gBackEnd )
				)
			)
			( pinPair "@baseboard_fab2_lib.baseboard_fab2(sch_1):\PP5448\"
				( pinRef "@baseboard_fab2_lib.baseboard_fab2(sch_1):page87_i186:SCL" )
				( pinRef "@baseboard_fab2_lib.baseboard_fab2(sch_1):page99_i56:B" )
				( attribute "PROPAGATION_DELAY_MAX" "25100.00 MIL"
					( Units "uMaxMinProp" "ns" 1.000000)
					( Origin gBackEnd )
				)
			)
			( pinPair "@baseboard_fab2_lib.baseboard_fab2(sch_1):\PP5435\"
				( pinRef "@baseboard_fab2_lib.baseboard_fab2(sch_1):page99_i63:SDAB" )
				( pinRef "@baseboard_fab2_lib.baseboard_fab2(sch_1):page99_i43:A" )
				( attribute "PROPAGATION_DELAY_MAX" "25100.00 MIL"
					( Units "uMaxMinProp" "ns" 1.000000)
					( Origin gBackEnd )
				)
			)
			( pinPair "@baseboard_fab2_lib.baseboard_fab2(sch_1):\PP5436\"
				( pinRef "@baseboard_fab2_lib.baseboard_fab2(sch_1):page99_i104:B" )
				( pinRef "@baseboard_fab2_lib.baseboard_fab2(sch_1):page99_i43:A" )
				( attribute "PROPAGATION_DELAY_MAX" "200.00 MIL"
					( Units "uMaxMinProp" "ns" 1.000000)
					( Origin gBackEnd )
				)
			)
			( pinPair "@baseboard_fab2_lib.baseboard_fab2(sch_1):\PP5437\"
				( pinRef "@baseboard_fab2_lib.baseboard_fab2(sch_1):page99_i104:B" )
				( pinRef "@baseboard_fab2_lib.baseboard_fab2(sch_1):page99_i63:SDAB" )
				( attribute "PROPAGATION_DELAY_MAX" "1000.00 MIL"
					( Units "uMaxMinProp" "ns" 1.000000)
					( Origin gBackEnd )
				)
			)
			( pinPair "@baseboard_fab2_lib.baseboard_fab2(sch_1):\PP5438\"
				( pinRef "@baseboard_fab2_lib.baseboard_fab2(sch_1):page78_i13:SDA" )
				( pinRef "@baseboard_fab2_lib.baseboard_fab2(sch_1):page99_i43:B" )
				( attribute "PROPAGATION_DELAY_MAX" "25100.00 MIL"
					( Units "uMaxMinProp" "ns" 1.000000)
					( Origin gBackEnd )
				)
			)
			( pinPair "@baseboard_fab2_lib.baseboard_fab2(sch_1):\PP5432\"
				( pinRef "@baseboard_fab2_lib.baseboard_fab2(sch_1):page99_i106:B" )
				( pinRef "@baseboard_fab2_lib.baseboard_fab2(sch_1):page99_i42:A" )
				( attribute "PROPAGATION_DELAY_MAX" "200.00 MIL"
					( Units "uMaxMinProp" "ns" 1.000000)
					( Origin gBackEnd )
				)
			)
			( pinPair "@baseboard_fab2_lib.baseboard_fab2(sch_1):\PP5433\"
				( pinRef "@baseboard_fab2_lib.baseboard_fab2(sch_1):page99_i106:B" )
				( pinRef "@baseboard_fab2_lib.baseboard_fab2(sch_1):page99_i63:SCLB" )
				( attribute "PROPAGATION_DELAY_MAX" "1000.00 MIL"
					( Units "uMaxMinProp" "ns" 1.000000)
					( Origin gBackEnd )
				)
			)
			( pinPair "@baseboard_fab2_lib.baseboard_fab2(sch_1):\PP5434\"
				( pinRef "@baseboard_fab2_lib.baseboard_fab2(sch_1):page78_i13:SCL" )
				( pinRef "@baseboard_fab2_lib.baseboard_fab2(sch_1):page99_i42:B" )
				( attribute "PROPAGATION_DELAY_MAX" "25100.00 MIL"
					( Units "uMaxMinProp" "ns" 1.000000)
					( Origin gBackEnd )
				)
			)
			( pinPair "@baseboard_fab2_lib.baseboard_fab2(sch_1):\PP5428\"
				( pinRef "@baseboard_fab2_lib.baseboard_fab2(sch_1):page99_i34:A" )
				( pinRef "@baseboard_fab2_lib.baseboard_fab2(sch_1):page99_i61:SDAB" )
				( attribute "PROPAGATION_DELAY_MAX" "25100.00 MIL"
					( Units "uMaxMinProp" "ns" 1.000000)
					( Origin gBackEnd )
				)
			)
			( pinPair "@baseboard_fab2_lib.baseboard_fab2(sch_1):\PP5429\"
				( pinRef "@baseboard_fab2_lib.baseboard_fab2(sch_1):page99_i101:B" )
				( pinRef "@baseboard_fab2_lib.baseboard_fab2(sch_1):page99_i34:A" )
				( attribute "PROPAGATION_DELAY_MAX" "200.00 MIL"
					( Units "uMaxMinProp" "ns" 1.000000)
					( Origin gBackEnd )
				)
			)
			( pinPair "@baseboard_fab2_lib.baseboard_fab2(sch_1):\PP5430\"
				( pinRef "@baseboard_fab2_lib.baseboard_fab2(sch_1):page99_i101:B" )
				( pinRef "@baseboard_fab2_lib.baseboard_fab2(sch_1):page99_i61:SDAB" )
				( attribute "PROPAGATION_DELAY_MAX" "1000.00 MIL"
					( Units "uMaxMinProp" "ns" 1.000000)
					( Origin gBackEnd )
				)
			)
			( pinPair "@baseboard_fab2_lib.baseboard_fab2(sch_1):\PP5431\"
				( pinRef "@baseboard_fab2_lib.baseboard_fab2(sch_1):page53_i111:SDA" )
				( pinRef "@baseboard_fab2_lib.baseboard_fab2(sch_1):page99_i34:B" )
				( attribute "PROPAGATION_DELAY_MAX" "25100.00 MIL"
					( Units "uMaxMinProp" "ns" 1.000000)
					( Origin gBackEnd )
				)
			)
			( pinPair "@baseboard_fab2_lib.baseboard_fab2(sch_1):\PP5424\"
				( pinRef "@baseboard_fab2_lib.baseboard_fab2(sch_1):page99_i35:A" )
				( pinRef "@baseboard_fab2_lib.baseboard_fab2(sch_1):page99_i61:SCLB" )
				( attribute "PROPAGATION_DELAY_MAX" "25100.00 MIL"
					( Units "uMaxMinProp" "ns" 1.000000)
					( Origin gBackEnd )
				)
			)
			( pinPair "@baseboard_fab2_lib.baseboard_fab2(sch_1):\PP5425\"
				( pinRef "@baseboard_fab2_lib.baseboard_fab2(sch_1):page99_i103:B" )
				( pinRef "@baseboard_fab2_lib.baseboard_fab2(sch_1):page99_i35:A" )
				( attribute "PROPAGATION_DELAY_MAX" "200.00 MIL"
					( Units "uMaxMinProp" "ns" 1.000000)
					( Origin gBackEnd )
				)
			)
			( pinPair "@baseboard_fab2_lib.baseboard_fab2(sch_1):\PP5426\"
				( pinRef "@baseboard_fab2_lib.baseboard_fab2(sch_1):page99_i103:B" )
				( pinRef "@baseboard_fab2_lib.baseboard_fab2(sch_1):page99_i61:SCLB" )
				( attribute "PROPAGATION_DELAY_MAX" "1000.00 MIL"
					( Units "uMaxMinProp" "ns" 1.000000)
					( Origin gBackEnd )
				)
			)
			( pinPair "@baseboard_fab2_lib.baseboard_fab2(sch_1):\PP5427\"
				( pinRef "@baseboard_fab2_lib.baseboard_fab2(sch_1):page53_i111:SCL" )
				( pinRef "@baseboard_fab2_lib.baseboard_fab2(sch_1):page99_i35:B" )
				( attribute "PROPAGATION_DELAY_MAX" "25100.00 MIL"
					( Units "uMaxMinProp" "ns" 1.000000)
					( Origin gBackEnd )
				)
			)
			( pinPair "@baseboard_fab2_lib.baseboard_fab2(sch_1):\PP5415\"
				( pinRef "@baseboard_fab2_lib.baseboard_fab2(sch_1):page99_i11:B" )
				( pinRef "@baseboard_fab2_lib.baseboard_fab2(sch_1):page99_i10:A" )
				( attribute "PROPAGATION_DELAY_MAX" "200.00 MIL"
					( Units "uMaxMinProp" "ns" 1.000000)
					( Origin gBackEnd )
				)
			)
			( pinPair "@baseboard_fab2_lib.baseboard_fab2(sch_1):\PP5416\"
				( pinRef "@baseboard_fab2_lib.baseboard_fab2(sch_1):page99_i11:B" )
				( pinRef "@baseboard_fab2_lib.baseboard_fab2(sch_1):page99_i15:SDAB" )
				( attribute "PROPAGATION_DELAY_MAX" "1000.00 MIL"
					( Units "uMaxMinProp" "ns" 1.000000)
					( Origin gBackEnd )
				)
			)
			( pinPair "@baseboard_fab2_lib.baseboard_fab2(sch_1):\PP5417\"
				( pinRef "@baseboard_fab2_lib.baseboard_fab2(sch_1):page47_i111:SDA" )
				( pinRef "@baseboard_fab2_lib.baseboard_fab2(sch_1):page99_i10:B" )
				( attribute "PROPAGATION_DELAY_MAX" "25100.00 MIL"
					( Units "uMaxMinProp" "ns" 1.000000)
					( Origin gBackEnd )
				)
			)
			( pinPair "@baseboard_fab2_lib.baseboard_fab2(sch_1):\PP5412\"
				( pinRef "@baseboard_fab2_lib.baseboard_fab2(sch_1):page99_i13:B" )
				( pinRef "@baseboard_fab2_lib.baseboard_fab2(sch_1):page99_i9:A" )
				( attribute "PROPAGATION_DELAY_MAX" "200.00 MIL"
					( Units "uMaxMinProp" "ns" 1.000000)
					( Origin gBackEnd )
				)
			)
			( pinPair "@baseboard_fab2_lib.baseboard_fab2(sch_1):\PP5413\"
				( pinRef "@baseboard_fab2_lib.baseboard_fab2(sch_1):page99_i15:SCLB" )
				( pinRef "@baseboard_fab2_lib.baseboard_fab2(sch_1):page99_i13:B" )
				( attribute "PROPAGATION_DELAY_MAX" "1000.00 MIL"
					( Units "uMaxMinProp" "ns" 1.000000)
					( Origin gBackEnd )
				)
			)
			( pinPair "@baseboard_fab2_lib.baseboard_fab2(sch_1):\PP5414\"
				( pinRef "@baseboard_fab2_lib.baseboard_fab2(sch_1):page47_i111:SCL" )
				( pinRef "@baseboard_fab2_lib.baseboard_fab2(sch_1):page99_i9:B" )
				( attribute "PROPAGATION_DELAY_MAX" "25100.00 MIL"
					( Units "uMaxMinProp" "ns" 1.000000)
					( Origin gBackEnd )
				)
			)
			( pinPair "@baseboard_fab2_lib.baseboard_fab2(sch_1):\PP5456\"
				( pinRef "@baseboard_fab2_lib.baseboard_fab2(sch_1):page99_i77:B" )
				( pinRef "@baseboard_fab2_lib.baseboard_fab2(sch_1):page99_i112:B" )
				( attribute "PROPAGATION_DELAY_MAX" "200.00 MIL"
					( Units "uMaxMinProp" "ns" 1.000000)
					( Origin gBackEnd )
				)
			)
			( pinPair "@baseboard_fab2_lib.baseboard_fab2(sch_1):\PP5453\"
				( pinRef "@baseboard_fab2_lib.baseboard_fab2(sch_1):page55_i172:DDR345_SPDSCL" )
				( pinRef "@baseboard_fab2_lib.baseboard_fab2(sch_1):page99_i98:A" )
				( attribute "PROPAGATION_DELAY_MAX" "2500.00 MIL"
					( Units "uMaxMinProp" "ns" 1.000000)
					( Origin gBackEnd )
				)
			)
			( pinPair "@baseboard_fab2_lib.baseboard_fab2(sch_1):\PP5454\"
				( pinRef "@baseboard_fab2_lib.baseboard_fab2(sch_1):page99_i79:B" )
				( pinRef "@baseboard_fab2_lib.baseboard_fab2(sch_1):page99_i75:SCLA" )
				( attribute "PROPAGATION_DELAY_MAX" "30000.00 MIL"
					( Units "uMaxMinProp" "ns" 1.000000)
					( Origin gBackEnd )
				)
			)
			( pinPair "@baseboard_fab2_lib.baseboard_fab2(sch_1):\PP5455\"
				( pinRef "@baseboard_fab2_lib.baseboard_fab2(sch_1):page99_i98:B" )
				( pinRef "@baseboard_fab2_lib.baseboard_fab2(sch_1):page99_i79:B" )
				( attribute "PROPAGATION_DELAY_MAX" "200.00 MIL"
					( Units "uMaxMinProp" "ns" 1.000000)
					( Origin gBackEnd )
				)
			)
			( pinPair "@baseboard_fab2_lib.baseboard_fab2(sch_1):\PP5442\"
				( pinRef "@baseboard_fab2_lib.baseboard_fab2(sch_1):page55_i172:DDR012_SPDSDA" )
				( pinRef "@baseboard_fab2_lib.baseboard_fab2(sch_1):page99_i111:A" )
				( attribute "PROPAGATION_DELAY_MAX" "2500.00 MIL"
					( Units "uMaxMinProp" "ns" 1.000000)
					( Origin gBackEnd )
				)
			)
			( pinPair "@baseboard_fab2_lib.baseboard_fab2(sch_1):\PP5443\"
				( pinRef "@baseboard_fab2_lib.baseboard_fab2(sch_1):page99_i70:B" )
				( pinRef "@baseboard_fab2_lib.baseboard_fab2(sch_1):page99_i63:SDAA" )
				( attribute "PROPAGATION_DELAY_MAX" "30000.00 MIL"
					( Units "uMaxMinProp" "ns" 1.000000)
					( Origin gBackEnd )
				)
			)
			( pinPair "@baseboard_fab2_lib.baseboard_fab2(sch_1):\PP5444\"
				( pinRef "@baseboard_fab2_lib.baseboard_fab2(sch_1):page99_i111:B" )
				( pinRef "@baseboard_fab2_lib.baseboard_fab2(sch_1):page99_i70:B" )
				( attribute "PROPAGATION_DELAY_MAX" "200.00 MIL"
					( Units "uMaxMinProp" "ns" 1.000000)
					( Origin gBackEnd )
				)
			)
			( pinPair "@baseboard_fab2_lib.baseboard_fab2(sch_1):\PP5439\"
				( pinRef "@baseboard_fab2_lib.baseboard_fab2(sch_1):page55_i172:DDR012_SPDSCL" )
				( pinRef "@baseboard_fab2_lib.baseboard_fab2(sch_1):page99_i92:A" )
				( attribute "PROPAGATION_DELAY_MAX" "2500.00 MIL"
					( Units "uMaxMinProp" "ns" 1.000000)
					( Origin gBackEnd )
				)
			)
			( pinPair "@baseboard_fab2_lib.baseboard_fab2(sch_1):\PP5440\"
				( pinRef "@baseboard_fab2_lib.baseboard_fab2(sch_1):page99_i72:B" )
				( pinRef "@baseboard_fab2_lib.baseboard_fab2(sch_1):page99_i63:SCLA" )
				( attribute "PROPAGATION_DELAY_MAX" "30000.00 MIL"
					( Units "uMaxMinProp" "ns" 1.000000)
					( Origin gBackEnd )
				)
			)
			( pinPair "@baseboard_fab2_lib.baseboard_fab2(sch_1):\PP5441\"
				( pinRef "@baseboard_fab2_lib.baseboard_fab2(sch_1):page99_i92:B" )
				( pinRef "@baseboard_fab2_lib.baseboard_fab2(sch_1):page99_i72:B" )
				( attribute "PROPAGATION_DELAY_MAX" "200.00 MIL"
					( Units "uMaxMinProp" "ns" 1.000000)
					( Origin gBackEnd )
				)
			)
			( pinPair "@baseboard_fab2_lib.baseboard_fab2(sch_1):\PP5421\"
				( pinRef "@baseboard_fab2_lib.baseboard_fab2(sch_1):page21_i259:DDR345_SPDSDA" )
				( pinRef "@baseboard_fab2_lib.baseboard_fab2(sch_1):page99_i110:A" )
				( attribute "PROPAGATION_DELAY_MAX" "2500.00 MIL"
					( Units "uMaxMinProp" "ns" 1.000000)
					( Origin gBackEnd )
				)
			)
			( pinPair "@baseboard_fab2_lib.baseboard_fab2(sch_1):\PP5422\"
				( pinRef "@baseboard_fab2_lib.baseboard_fab2(sch_1):page99_i65:B" )
				( pinRef "@baseboard_fab2_lib.baseboard_fab2(sch_1):page99_i61:SDAA" )
				( attribute "PROPAGATION_DELAY_MAX" "30000.00 MIL"
					( Units "uMaxMinProp" "ns" 1.000000)
					( Origin gBackEnd )
				)
			)
			( pinPair "@baseboard_fab2_lib.baseboard_fab2(sch_1):\PP5423\"
				( pinRef "@baseboard_fab2_lib.baseboard_fab2(sch_1):page99_i110:B" )
				( pinRef "@baseboard_fab2_lib.baseboard_fab2(sch_1):page99_i65:B" )
				( attribute "PROPAGATION_DELAY_MAX" "200.00 MIL"
					( Units "uMaxMinProp" "ns" 1.000000)
					( Origin gBackEnd )
				)
			)
			( pinPair "@baseboard_fab2_lib.baseboard_fab2(sch_1):\PP5418\"
				( pinRef "@baseboard_fab2_lib.baseboard_fab2(sch_1):page21_i259:DDR345_SPDSCL" )
				( pinRef "@baseboard_fab2_lib.baseboard_fab2(sch_1):page99_i88:A" )
				( attribute "PROPAGATION_DELAY_MAX" "2500.00 MIL"
					( Units "uMaxMinProp" "ns" 1.000000)
					( Origin gBackEnd )
				)
			)
			( pinPair "@baseboard_fab2_lib.baseboard_fab2(sch_1):\PP5419\"
				( pinRef "@baseboard_fab2_lib.baseboard_fab2(sch_1):page99_i67:B" )
				( pinRef "@baseboard_fab2_lib.baseboard_fab2(sch_1):page99_i61:SCLA" )
				( attribute "PROPAGATION_DELAY_MAX" "30000.00 MIL"
					( Units "uMaxMinProp" "ns" 1.000000)
					( Origin gBackEnd )
				)
			)
			( pinPair "@baseboard_fab2_lib.baseboard_fab2(sch_1):\PP5420\"
				( pinRef "@baseboard_fab2_lib.baseboard_fab2(sch_1):page99_i88:B" )
				( pinRef "@baseboard_fab2_lib.baseboard_fab2(sch_1):page99_i67:B" )
				( attribute "PROPAGATION_DELAY_MAX" "200.00 MIL"
					( Units "uMaxMinProp" "ns" 1.000000)
					( Origin gBackEnd )
				)
			)
			( pinPair "@baseboard_fab2_lib.baseboard_fab2(sch_1):\PP5409\"
				( pinRef "@baseboard_fab2_lib.baseboard_fab2(sch_1):page21_i259:DDR012_SPDSDA" )
				( pinRef "@baseboard_fab2_lib.baseboard_fab2(sch_1):page99_i20:A" )
				( attribute "PROPAGATION_DELAY_MAX" "2500.00 MIL"
					( Units "uMaxMinProp" "ns" 1.000000)
					( Origin gBackEnd )
				)
			)
			( pinPair "@baseboard_fab2_lib.baseboard_fab2(sch_1):\PP5410\"
				( pinRef "@baseboard_fab2_lib.baseboard_fab2(sch_1):page99_i17:B" )
				( pinRef "@baseboard_fab2_lib.baseboard_fab2(sch_1):page99_i15:SDAA" )
				( attribute "PROPAGATION_DELAY_MAX" "30000.00 MIL"
					( Units "uMaxMinProp" "ns" 1.000000)
					( Origin gBackEnd )
				)
			)
			( pinPair "@baseboard_fab2_lib.baseboard_fab2(sch_1):\PP5411\"
				( pinRef "@baseboard_fab2_lib.baseboard_fab2(sch_1):page99_i20:B" )
				( pinRef "@baseboard_fab2_lib.baseboard_fab2(sch_1):page99_i17:B" )
				( attribute "PROPAGATION_DELAY_MAX" "200.00 MIL"
					( Units "uMaxMinProp" "ns" 1.000000)
					( Origin gBackEnd )
				)
			)
			( pinPair "@baseboard_fab2_lib.baseboard_fab2(sch_1):\PP5406\"
				( pinRef "@baseboard_fab2_lib.baseboard_fab2(sch_1):page21_i259:DDR012_SPDSCL" )
				( pinRef "@baseboard_fab2_lib.baseboard_fab2(sch_1):page99_i83:A" )
				( attribute "PROPAGATION_DELAY_MAX" "2500.00 MIL"
					( Units "uMaxMinProp" "ns" 1.000000)
					( Origin gBackEnd )
				)
			)
			( pinPair "@baseboard_fab2_lib.baseboard_fab2(sch_1):\PP5407\"
				( pinRef "@baseboard_fab2_lib.baseboard_fab2(sch_1):page99_i19:B" )
				( pinRef "@baseboard_fab2_lib.baseboard_fab2(sch_1):page99_i15:SCLA" )
				( attribute "PROPAGATION_DELAY_MAX" "30000.00 MIL"
					( Units "uMaxMinProp" "ns" 1.000000)
					( Origin gBackEnd )
				)
			)
			( pinPair "@baseboard_fab2_lib.baseboard_fab2(sch_1):\PP5408\"
				( pinRef "@baseboard_fab2_lib.baseboard_fab2(sch_1):page99_i83:B" )
				( pinRef "@baseboard_fab2_lib.baseboard_fab2(sch_1):page99_i19:B" )
				( attribute "PROPAGATION_DELAY_MAX" "1200.00 MIL"
					( Units "uMaxMinProp" "ns" 1.000000)
					( Origin gBackEnd )
				)
			)
			( pinPair "@baseboard_fab2_lib.baseboard_fab2(sch_1):\PP5762\"
				( pinRef "@baseboard_fab2_lib.baseboard_fab2(sch_1):page173_i163:RXA0_DN" )
				( pinRef "@baseboard_fab2_lib.baseboard_fab2(sch_1):page173_i174:B" )
				( attribute "PROPAGATION_DELAY_MAX" "250.00 MIL"
					( Units "uMaxMinProp" "ns" 1.000000)
					( Origin gBackEnd )
				)
			)
			( pinPair "@baseboard_fab2_lib.baseboard_fab2(sch_1):\PP5763\"
				( pinRef "@baseboard_fab2_lib.baseboard_fab2(sch_1):page116_i220:PCIE12_UP0_SATA0_RXN" )
				( pinRef "@baseboard_fab2_lib.baseboard_fab2(sch_1):page173_i174:A" )
			)
			( pinPair "@baseboard_fab2_lib.baseboard_fab2(sch_1):\PP5764\"
				( pinRef "@baseboard_fab2_lib.baseboard_fab2(sch_1):page116_i220:PCIE12_UP0_SATA0_RXP" )
				( pinRef "@baseboard_fab2_lib.baseboard_fab2(sch_1):page173_i172:A" )
			)
			( pinPair "@baseboard_fab2_lib.baseboard_fab2(sch_1):\PP5765\"
				( pinRef "@baseboard_fab2_lib.baseboard_fab2(sch_1):page173_i163:RXA0_DP" )
				( pinRef "@baseboard_fab2_lib.baseboard_fab2(sch_1):page173_i172:B" )
				( attribute "PROPAGATION_DELAY_MAX" "250.00 MIL"
					( Units "uMaxMinProp" "ns" 1.000000)
					( Origin gBackEnd )
				)
			)
			( pinPair "@baseboard_fab2_lib.baseboard_fab2(sch_1):\PP5766\"
				( pinRef "@baseboard_fab2_lib.baseboard_fab2(sch_1):page173_i163:RXA1_DN" )
				( pinRef "@baseboard_fab2_lib.baseboard_fab2(sch_1):page173_i166:B" )
				( attribute "PROPAGATION_DELAY_MAX" "250.00 MIL"
					( Units "uMaxMinProp" "ns" 1.000000)
					( Origin gBackEnd )
				)
			)
			( pinPair "@baseboard_fab2_lib.baseboard_fab2(sch_1):\PP5767\"
				( pinRef "@baseboard_fab2_lib.baseboard_fab2(sch_1):page116_i220:PCIE13_UP1_SATA1_RXN" )
				( pinRef "@baseboard_fab2_lib.baseboard_fab2(sch_1):page173_i166:A" )
			)
			( pinPair "@baseboard_fab2_lib.baseboard_fab2(sch_1):\PP5768\"
				( pinRef "@baseboard_fab2_lib.baseboard_fab2(sch_1):page116_i220:PCIE13_UP1_SATA1_RXP" )
				( pinRef "@baseboard_fab2_lib.baseboard_fab2(sch_1):page173_i173:A" )
			)
			( pinPair "@baseboard_fab2_lib.baseboard_fab2(sch_1):\PP5769\"
				( pinRef "@baseboard_fab2_lib.baseboard_fab2(sch_1):page173_i163:RXA1_DP" )
				( pinRef "@baseboard_fab2_lib.baseboard_fab2(sch_1):page173_i173:B" )
				( attribute "PROPAGATION_DELAY_MAX" "250.00 MIL"
					( Units "uMaxMinProp" "ns" 1.000000)
					( Origin gBackEnd )
				)
			)
			( pinPair "@baseboard_fab2_lib.baseboard_fab2(sch_1):\PP5770\"
				( pinRef "@baseboard_fab2_lib.baseboard_fab2(sch_1):page173_i163:RXA2_DN" )
				( pinRef "@baseboard_fab2_lib.baseboard_fab2(sch_1):page173_i165:B" )
				( attribute "PROPAGATION_DELAY_MAX" "250.00 MIL"
					( Units "uMaxMinProp" "ns" 1.000000)
					( Origin gBackEnd )
				)
			)
			( pinPair "@baseboard_fab2_lib.baseboard_fab2(sch_1):\PP5771\"
				( pinRef "@baseboard_fab2_lib.baseboard_fab2(sch_1):page116_i220:PCIE14_UP2_SATA2_RXN" )
				( pinRef "@baseboard_fab2_lib.baseboard_fab2(sch_1):page173_i165:A" )
			)
			( pinPair "@baseboard_fab2_lib.baseboard_fab2(sch_1):\PP5772\"
				( pinRef "@baseboard_fab2_lib.baseboard_fab2(sch_1):page116_i220:PCIE14_UP2_SATA2_RXP" )
				( pinRef "@baseboard_fab2_lib.baseboard_fab2(sch_1):page173_i191:A" )
			)
			( pinPair "@baseboard_fab2_lib.baseboard_fab2(sch_1):\PP5773\"
				( pinRef "@baseboard_fab2_lib.baseboard_fab2(sch_1):page173_i163:RXA2_DP" )
				( pinRef "@baseboard_fab2_lib.baseboard_fab2(sch_1):page173_i191:B" )
				( attribute "PROPAGATION_DELAY_MAX" "250.00 MIL"
					( Units "uMaxMinProp" "ns" 1.000000)
					( Origin gBackEnd )
				)
			)
			( pinPair "@baseboard_fab2_lib.baseboard_fab2(sch_1):\PP5774\"
				( pinRef "@baseboard_fab2_lib.baseboard_fab2(sch_1):page173_i163:RXA3_DN" )
				( pinRef "@baseboard_fab2_lib.baseboard_fab2(sch_1):page173_i194:B" )
				( attribute "PROPAGATION_DELAY_MAX" "250.00 MIL"
					( Units "uMaxMinProp" "ns" 1.000000)
					( Origin gBackEnd )
				)
			)
			( pinPair "@baseboard_fab2_lib.baseboard_fab2(sch_1):\PP5775\"
				( pinRef "@baseboard_fab2_lib.baseboard_fab2(sch_1):page116_i220:PCIE15_UP3_SATA3_RXN" )
				( pinRef "@baseboard_fab2_lib.baseboard_fab2(sch_1):page173_i194:A" )
			)
			( pinPair "@baseboard_fab2_lib.baseboard_fab2(sch_1):\PP5776\"
				( pinRef "@baseboard_fab2_lib.baseboard_fab2(sch_1):page116_i220:PCIE15_UP3_SATA3_RXP" )
				( pinRef "@baseboard_fab2_lib.baseboard_fab2(sch_1):page173_i192:A" )
			)
			( pinPair "@baseboard_fab2_lib.baseboard_fab2(sch_1):\PP5777\"
				( pinRef "@baseboard_fab2_lib.baseboard_fab2(sch_1):page173_i163:RXA3_DP" )
				( pinRef "@baseboard_fab2_lib.baseboard_fab2(sch_1):page173_i192:B" )
				( attribute "PROPAGATION_DELAY_MAX" "250.00 MIL"
					( Units "uMaxMinProp" "ns" 1.000000)
					( Origin gBackEnd )
				)
			)
			( pinPair "@baseboard_fab2_lib.baseboard_fab2(sch_1):\PP5778\"
				( pinRef "@baseboard_fab2_lib.baseboard_fab2(sch_1):page173_i163:RXB0_DN" )
				( pinRef "@baseboard_fab2_lib.baseboard_fab2(sch_1):page173_i197:B" )
				( attribute "PROPAGATION_DELAY_MAX" "250.00 MIL"
					( Units "uMaxMinProp" "ns" 1.000000)
					( Origin gBackEnd )
				)
			)
			( pinPair "@baseboard_fab2_lib.baseboard_fab2(sch_1):\PP5779\"
				( pinRef "@baseboard_fab2_lib.baseboard_fab2(sch_1):page116_i220:PCIE16_UP4_SATA4_RXN" )
				( pinRef "@baseboard_fab2_lib.baseboard_fab2(sch_1):page173_i197:A" )
			)
			( pinPair "@baseboard_fab2_lib.baseboard_fab2(sch_1):\PP5780\"
				( pinRef "@baseboard_fab2_lib.baseboard_fab2(sch_1):page116_i220:PCIE16_UP4_SATA4_RXP" )
				( pinRef "@baseboard_fab2_lib.baseboard_fab2(sch_1):page173_i195:A" )
			)
			( pinPair "@baseboard_fab2_lib.baseboard_fab2(sch_1):\PP5781\"
				( pinRef "@baseboard_fab2_lib.baseboard_fab2(sch_1):page173_i163:RXB0_DP" )
				( pinRef "@baseboard_fab2_lib.baseboard_fab2(sch_1):page173_i195:B" )
				( attribute "PROPAGATION_DELAY_MAX" "250.00 MIL"
					( Units "uMaxMinProp" "ns" 1.000000)
					( Origin gBackEnd )
				)
			)
			( pinPair "@baseboard_fab2_lib.baseboard_fab2(sch_1):\PP5782\"
				( pinRef "@baseboard_fab2_lib.baseboard_fab2(sch_1):page173_i163:RXB1_DN" )
				( pinRef "@baseboard_fab2_lib.baseboard_fab2(sch_1):page173_i207:B" )
				( attribute "PROPAGATION_DELAY_MAX" "250.00 MIL"
					( Units "uMaxMinProp" "ns" 1.000000)
					( Origin gBackEnd )
				)
			)
			( pinPair "@baseboard_fab2_lib.baseboard_fab2(sch_1):\PP5783\"
				( pinRef "@baseboard_fab2_lib.baseboard_fab2(sch_1):page116_i220:PCIE17_UP5_SATA5_RXN" )
				( pinRef "@baseboard_fab2_lib.baseboard_fab2(sch_1):page173_i207:A" )
			)
			( pinPair "@baseboard_fab2_lib.baseboard_fab2(sch_1):\PP5784\"
				( pinRef "@baseboard_fab2_lib.baseboard_fab2(sch_1):page116_i220:PCIE17_UP5_SATA5_RXP" )
				( pinRef "@baseboard_fab2_lib.baseboard_fab2(sch_1):page173_i196:A" )
			)
			( pinPair "@baseboard_fab2_lib.baseboard_fab2(sch_1):\PP5785\"
				( pinRef "@baseboard_fab2_lib.baseboard_fab2(sch_1):page173_i163:RXB1_DP" )
				( pinRef "@baseboard_fab2_lib.baseboard_fab2(sch_1):page173_i196:B" )
				( attribute "PROPAGATION_DELAY_MAX" "250.00 MIL"
					( Units "uMaxMinProp" "ns" 1.000000)
					( Origin gBackEnd )
				)
			)
			( pinPair "@baseboard_fab2_lib.baseboard_fab2(sch_1):\PP5786\"
				( pinRef "@baseboard_fab2_lib.baseboard_fab2(sch_1):page173_i163:RXB2_DN" )
				( pinRef "@baseboard_fab2_lib.baseboard_fab2(sch_1):page173_i208:B" )
				( attribute "PROPAGATION_DELAY_MAX" "250.00 MIL"
					( Units "uMaxMinProp" "ns" 1.000000)
					( Origin gBackEnd )
				)
			)
			( pinPair "@baseboard_fab2_lib.baseboard_fab2(sch_1):\PP5787\"
				( pinRef "@baseboard_fab2_lib.baseboard_fab2(sch_1):page116_i220:PCIE18_UP6_SATA6_RXN" )
				( pinRef "@baseboard_fab2_lib.baseboard_fab2(sch_1):page173_i208:A" )
			)
			( pinPair "@baseboard_fab2_lib.baseboard_fab2(sch_1):\PP5788\"
				( pinRef "@baseboard_fab2_lib.baseboard_fab2(sch_1):page116_i220:PCIE18_UP6_SATA6_RXP" )
				( pinRef "@baseboard_fab2_lib.baseboard_fab2(sch_1):page173_i205:A" )
			)
			( pinPair "@baseboard_fab2_lib.baseboard_fab2(sch_1):\PP5789\"
				( pinRef "@baseboard_fab2_lib.baseboard_fab2(sch_1):page173_i163:RXB2_DP" )
				( pinRef "@baseboard_fab2_lib.baseboard_fab2(sch_1):page173_i205:B" )
				( attribute "PROPAGATION_DELAY_MAX" "250.00 MIL"
					( Units "uMaxMinProp" "ns" 1.000000)
					( Origin gBackEnd )
				)
			)
			( pinPair "@baseboard_fab2_lib.baseboard_fab2(sch_1):\PP5790\"
				( pinRef "@baseboard_fab2_lib.baseboard_fab2(sch_1):page173_i163:RXB3_DN" )
				( pinRef "@baseboard_fab2_lib.baseboard_fab2(sch_1):page173_i209:B" )
				( attribute "PROPAGATION_DELAY_MAX" "250.00 MIL"
					( Units "uMaxMinProp" "ns" 1.000000)
					( Origin gBackEnd )
				)
			)
			( pinPair "@baseboard_fab2_lib.baseboard_fab2(sch_1):\PP5791\"
				( pinRef "@baseboard_fab2_lib.baseboard_fab2(sch_1):page116_i220:PCIE19_UP7_SATA7_RXN" )
				( pinRef "@baseboard_fab2_lib.baseboard_fab2(sch_1):page173_i209:A" )
			)
			( pinPair "@baseboard_fab2_lib.baseboard_fab2(sch_1):\PP5792\"
				( pinRef "@baseboard_fab2_lib.baseboard_fab2(sch_1):page116_i220:PCIE19_UP7_SATA7_RXP" )
				( pinRef "@baseboard_fab2_lib.baseboard_fab2(sch_1):page173_i206:A" )
			)
			( pinPair "@baseboard_fab2_lib.baseboard_fab2(sch_1):\PP5793\"
				( pinRef "@baseboard_fab2_lib.baseboard_fab2(sch_1):page173_i163:RXB3_DP" )
				( pinRef "@baseboard_fab2_lib.baseboard_fab2(sch_1):page173_i206:B" )
				( attribute "PROPAGATION_DELAY_MAX" "250.00 MIL"
					( Units "uMaxMinProp" "ns" 1.000000)
					( Origin gBackEnd )
				)
			)
			( pinPair "@baseboard_fab2_lib.baseboard_fab2(sch_1):\PP5730\"
				( pinRef "@baseboard_fab2_lib.baseboard_fab2(sch_1):page116_i220:PCIE12_UP0_SATA0_TXN" )
				( pinRef "@baseboard_fab2_lib.baseboard_fab2(sch_1):page173_i220:B" )
			)
			( pinPair "@baseboard_fab2_lib.baseboard_fab2(sch_1):\PP5731\"
				( pinRef "@baseboard_fab2_lib.baseboard_fab2(sch_1):page173_i163:TXA0_DN" )
				( pinRef "@baseboard_fab2_lib.baseboard_fab2(sch_1):page173_i220:A" )
				( attribute "PROPAGATION_DELAY_MAX" "250.00 MIL"
					( Units "uMaxMinProp" "ns" 1.000000)
					( Origin gBackEnd )
				)
			)
			( pinPair "@baseboard_fab2_lib.baseboard_fab2(sch_1):\PP5732\"
				( pinRef "@baseboard_fab2_lib.baseboard_fab2(sch_1):page173_i163:TXA0_DP" )
				( pinRef "@baseboard_fab2_lib.baseboard_fab2(sch_1):page173_i221:A" )
				( attribute "PROPAGATION_DELAY_MAX" "250.00 MIL"
					( Units "uMaxMinProp" "ns" 1.000000)
					( Origin gBackEnd )
				)
			)
			( pinPair "@baseboard_fab2_lib.baseboard_fab2(sch_1):\PP5733\"
				( pinRef "@baseboard_fab2_lib.baseboard_fab2(sch_1):page116_i220:PCIE12_UP0_SATA0_TXP" )
				( pinRef "@baseboard_fab2_lib.baseboard_fab2(sch_1):page173_i221:B" )
			)
			( pinPair "@baseboard_fab2_lib.baseboard_fab2(sch_1):\PP5734\"
				( pinRef "@baseboard_fab2_lib.baseboard_fab2(sch_1):page116_i220:PCIE13_UP1_SATA1_TXN" )
				( pinRef "@baseboard_fab2_lib.baseboard_fab2(sch_1):page173_i228:B" )
			)
			( pinPair "@baseboard_fab2_lib.baseboard_fab2(sch_1):\PP5735\"
				( pinRef "@baseboard_fab2_lib.baseboard_fab2(sch_1):page173_i163:TXA1_DN" )
				( pinRef "@baseboard_fab2_lib.baseboard_fab2(sch_1):page173_i228:A" )
				( attribute "PROPAGATION_DELAY_MAX" "250.00 MIL"
					( Units "uMaxMinProp" "ns" 1.000000)
					( Origin gBackEnd )
				)
			)
			( pinPair "@baseboard_fab2_lib.baseboard_fab2(sch_1):\PP5736\"
				( pinRef "@baseboard_fab2_lib.baseboard_fab2(sch_1):page173_i163:TXA1_DP" )
				( pinRef "@baseboard_fab2_lib.baseboard_fab2(sch_1):page173_i222:A" )
				( attribute "PROPAGATION_DELAY_MAX" "250.00 MIL"
					( Units "uMaxMinProp" "ns" 1.000000)
					( Origin gBackEnd )
				)
			)
			( pinPair "@baseboard_fab2_lib.baseboard_fab2(sch_1):\PP5737\"
				( pinRef "@baseboard_fab2_lib.baseboard_fab2(sch_1):page116_i220:PCIE13_UP1_SATA1_TXP" )
				( pinRef "@baseboard_fab2_lib.baseboard_fab2(sch_1):page173_i222:B" )
			)
			( pinPair "@baseboard_fab2_lib.baseboard_fab2(sch_1):\PP5738\"
				( pinRef "@baseboard_fab2_lib.baseboard_fab2(sch_1):page116_i220:PCIE14_UP2_SATA2_TXN" )
				( pinRef "@baseboard_fab2_lib.baseboard_fab2(sch_1):page173_i233:B" )
			)
			( pinPair "@baseboard_fab2_lib.baseboard_fab2(sch_1):\PP5739\"
				( pinRef "@baseboard_fab2_lib.baseboard_fab2(sch_1):page173_i163:TXA2_DN" )
				( pinRef "@baseboard_fab2_lib.baseboard_fab2(sch_1):page173_i233:A" )
				( attribute "PROPAGATION_DELAY_MAX" "250.00 MIL"
					( Units "uMaxMinProp" "ns" 1.000000)
					( Origin gBackEnd )
				)
			)
			( pinPair "@baseboard_fab2_lib.baseboard_fab2(sch_1):\PP5740\"
				( pinRef "@baseboard_fab2_lib.baseboard_fab2(sch_1):page173_i163:TXA2_DP" )
				( pinRef "@baseboard_fab2_lib.baseboard_fab2(sch_1):page173_i242:A" )
				( attribute "PROPAGATION_DELAY_MAX" "250.00 MIL"
					( Units "uMaxMinProp" "ns" 1.000000)
					( Origin gBackEnd )
				)
			)
			( pinPair "@baseboard_fab2_lib.baseboard_fab2(sch_1):\PP5741\"
				( pinRef "@baseboard_fab2_lib.baseboard_fab2(sch_1):page116_i220:PCIE14_UP2_SATA2_TXP" )
				( pinRef "@baseboard_fab2_lib.baseboard_fab2(sch_1):page173_i242:B" )
			)
			( pinPair "@baseboard_fab2_lib.baseboard_fab2(sch_1):\PP5742\"
				( pinRef "@baseboard_fab2_lib.baseboard_fab2(sch_1):page116_i220:PCIE15_UP3_SATA3_TXN" )
				( pinRef "@baseboard_fab2_lib.baseboard_fab2(sch_1):page173_i234:B" )
			)
			( pinPair "@baseboard_fab2_lib.baseboard_fab2(sch_1):\PP5743\"
				( pinRef "@baseboard_fab2_lib.baseboard_fab2(sch_1):page173_i163:TXA3_DN" )
				( pinRef "@baseboard_fab2_lib.baseboard_fab2(sch_1):page173_i234:A" )
				( attribute "PROPAGATION_DELAY_MAX" "250.00 MIL"
					( Units "uMaxMinProp" "ns" 1.000000)
					( Origin gBackEnd )
				)
			)
			( pinPair "@baseboard_fab2_lib.baseboard_fab2(sch_1):\PP5744\"
				( pinRef "@baseboard_fab2_lib.baseboard_fab2(sch_1):page173_i163:TXA3_DP" )
				( pinRef "@baseboard_fab2_lib.baseboard_fab2(sch_1):page173_i241:A" )
				( attribute "PROPAGATION_DELAY_MAX" "250.00 MIL"
					( Units "uMaxMinProp" "ns" 1.000000)
					( Origin gBackEnd )
				)
			)
			( pinPair "@baseboard_fab2_lib.baseboard_fab2(sch_1):\PP5745\"
				( pinRef "@baseboard_fab2_lib.baseboard_fab2(sch_1):page116_i220:PCIE15_UP3_SATA3_TXP" )
				( pinRef "@baseboard_fab2_lib.baseboard_fab2(sch_1):page173_i241:B" )
			)
			( pinPair "@baseboard_fab2_lib.baseboard_fab2(sch_1):\PP5746\"
				( pinRef "@baseboard_fab2_lib.baseboard_fab2(sch_1):page116_i220:PCIE16_UP4_SATA4_TXN" )
				( pinRef "@baseboard_fab2_lib.baseboard_fab2(sch_1):page173_i238:B" )
			)
			( pinPair "@baseboard_fab2_lib.baseboard_fab2(sch_1):\PP5747\"
				( pinRef "@baseboard_fab2_lib.baseboard_fab2(sch_1):page173_i163:TXB0_DN" )
				( pinRef "@baseboard_fab2_lib.baseboard_fab2(sch_1):page173_i238:A" )
				( attribute "PROPAGATION_DELAY_MAX" "250.00 MIL"
					( Units "uMaxMinProp" "ns" 1.000000)
					( Origin gBackEnd )
				)
			)
			( pinPair "@baseboard_fab2_lib.baseboard_fab2(sch_1):\PP5748\"
				( pinRef "@baseboard_fab2_lib.baseboard_fab2(sch_1):page173_i163:TXB0_DP" )
				( pinRef "@baseboard_fab2_lib.baseboard_fab2(sch_1):page173_i239:A" )
				( attribute "PROPAGATION_DELAY_MAX" "250.00 MIL"
					( Units "uMaxMinProp" "ns" 1.000000)
					( Origin gBackEnd )
				)
			)
			( pinPair "@baseboard_fab2_lib.baseboard_fab2(sch_1):\PP5749\"
				( pinRef "@baseboard_fab2_lib.baseboard_fab2(sch_1):page116_i220:PCIE16_UP4_SATA4_TXP" )
				( pinRef "@baseboard_fab2_lib.baseboard_fab2(sch_1):page173_i239:B" )
			)
			( pinPair "@baseboard_fab2_lib.baseboard_fab2(sch_1):\PP5750\"
				( pinRef "@baseboard_fab2_lib.baseboard_fab2(sch_1):page116_i220:PCIE17_UP5_SATA5_TXN" )
				( pinRef "@baseboard_fab2_lib.baseboard_fab2(sch_1):page173_i255:B" )
			)
			( pinPair "@baseboard_fab2_lib.baseboard_fab2(sch_1):\PP5751\"
				( pinRef "@baseboard_fab2_lib.baseboard_fab2(sch_1):page173_i163:TXB1_DN" )
				( pinRef "@baseboard_fab2_lib.baseboard_fab2(sch_1):page173_i255:A" )
				( attribute "PROPAGATION_DELAY_MAX" "250.00 MIL"
					( Units "uMaxMinProp" "ns" 1.000000)
					( Origin gBackEnd )
				)
			)
			( pinPair "@baseboard_fab2_lib.baseboard_fab2(sch_1):\PP5752\"
				( pinRef "@baseboard_fab2_lib.baseboard_fab2(sch_1):page173_i163:TXB1_DP" )
				( pinRef "@baseboard_fab2_lib.baseboard_fab2(sch_1):page173_i240:A" )
				( attribute "PROPAGATION_DELAY_MAX" "250.00 MIL"
					( Units "uMaxMinProp" "ns" 1.000000)
					( Origin gBackEnd )
				)
			)
			( pinPair "@baseboard_fab2_lib.baseboard_fab2(sch_1):\PP5753\"
				( pinRef "@baseboard_fab2_lib.baseboard_fab2(sch_1):page116_i220:PCIE17_UP5_SATA5_TXP" )
				( pinRef "@baseboard_fab2_lib.baseboard_fab2(sch_1):page173_i240:B" )
			)
			( pinPair "@baseboard_fab2_lib.baseboard_fab2(sch_1):\PP5754\"
				( pinRef "@baseboard_fab2_lib.baseboard_fab2(sch_1):page116_i220:PCIE18_UP6_SATA6_TXN" )
				( pinRef "@baseboard_fab2_lib.baseboard_fab2(sch_1):page173_i256:B" )
			)
			( pinPair "@baseboard_fab2_lib.baseboard_fab2(sch_1):\PP5755\"
				( pinRef "@baseboard_fab2_lib.baseboard_fab2(sch_1):page173_i163:TXB2_DN" )
				( pinRef "@baseboard_fab2_lib.baseboard_fab2(sch_1):page173_i256:A" )
				( attribute "PROPAGATION_DELAY_MAX" "250.00 MIL"
					( Units "uMaxMinProp" "ns" 1.000000)
					( Origin gBackEnd )
				)
			)
			( pinPair "@baseboard_fab2_lib.baseboard_fab2(sch_1):\PP5756\"
				( pinRef "@baseboard_fab2_lib.baseboard_fab2(sch_1):page173_i163:TXB2_DP" )
				( pinRef "@baseboard_fab2_lib.baseboard_fab2(sch_1):page173_i257:A" )
				( attribute "PROPAGATION_DELAY_MAX" "500.00 MIL"
					( Units "uMaxMinProp" "ns" 1.000000)
					( Origin gBackEnd )
				)
			)
			( pinPair "@baseboard_fab2_lib.baseboard_fab2(sch_1):\PP5757\"
				( pinRef "@baseboard_fab2_lib.baseboard_fab2(sch_1):page116_i220:PCIE18_UP6_SATA6_TXP" )
				( pinRef "@baseboard_fab2_lib.baseboard_fab2(sch_1):page173_i257:B" )
			)
			( pinPair "@baseboard_fab2_lib.baseboard_fab2(sch_1):\PP5758\"
				( pinRef "@baseboard_fab2_lib.baseboard_fab2(sch_1):page116_i220:PCIE19_UP7_SATA7_TXN" )
				( pinRef "@baseboard_fab2_lib.baseboard_fab2(sch_1):page173_i259:B" )
			)
			( pinPair "@baseboard_fab2_lib.baseboard_fab2(sch_1):\PP5759\"
				( pinRef "@baseboard_fab2_lib.baseboard_fab2(sch_1):page173_i163:TXB3_DN" )
				( pinRef "@baseboard_fab2_lib.baseboard_fab2(sch_1):page173_i259:A" )
				( attribute "PROPAGATION_DELAY_MAX" "250.00 MIL"
					( Units "uMaxMinProp" "ns" 1.000000)
					( Origin gBackEnd )
				)
			)
			( pinPair "@baseboard_fab2_lib.baseboard_fab2(sch_1):\PP5760\"
				( pinRef "@baseboard_fab2_lib.baseboard_fab2(sch_1):page173_i163:TXB3_DP" )
				( pinRef "@baseboard_fab2_lib.baseboard_fab2(sch_1):page173_i258:A" )
				( attribute "PROPAGATION_DELAY_MAX" "250.00 MIL"
					( Units "uMaxMinProp" "ns" 1.000000)
					( Origin gBackEnd )
				)
			)
			( pinPair "@baseboard_fab2_lib.baseboard_fab2(sch_1):\PP5761\"
				( pinRef "@baseboard_fab2_lib.baseboard_fab2(sch_1):page116_i220:PCIE19_UP7_SATA7_TXP" )
				( pinRef "@baseboard_fab2_lib.baseboard_fab2(sch_1):page173_i258:B" )
			)
			( pinPair "@baseboard_fab2_lib.baseboard_fab2(sch_1):\PP5714\"
				( pinRef "@baseboard_fab2_lib.baseboard_fab2(sch_1):page116_i220:PCIE8_SSATA2_GBE_RXN" )
				( pinRef "@baseboard_fab2_lib.baseboard_fab2(sch_1):page174_i29:A" )
			)
			( pinPair "@baseboard_fab2_lib.baseboard_fab2(sch_1):\PP5715\"
				( pinRef "@baseboard_fab2_lib.baseboard_fab2(sch_1):page174_i26:RXA0_DN" )
				( pinRef "@baseboard_fab2_lib.baseboard_fab2(sch_1):page174_i29:B" )
				( attribute "PROPAGATION_DELAY_MAX" "250.00 MIL"
					( Units "uMaxMinProp" "ns" 1.000000)
					( Origin gBackEnd )
				)
			)
			( pinPair "@baseboard_fab2_lib.baseboard_fab2(sch_1):\PP5716\"
				( pinRef "@baseboard_fab2_lib.baseboard_fab2(sch_1):page174_i26:RXA0_DP" )
				( pinRef "@baseboard_fab2_lib.baseboard_fab2(sch_1):page174_i28:B" )
				( attribute "PROPAGATION_DELAY_MAX" "250.00 MIL"
					( Units "uMaxMinProp" "ns" 1.000000)
					( Origin gBackEnd )
				)
			)
			( pinPair "@baseboard_fab2_lib.baseboard_fab2(sch_1):\PP5717\"
				( pinRef "@baseboard_fab2_lib.baseboard_fab2(sch_1):page116_i220:PCIE8_SSATA2_GBE_RXP" )
				( pinRef "@baseboard_fab2_lib.baseboard_fab2(sch_1):page174_i28:A" )
			)
			( pinPair "@baseboard_fab2_lib.baseboard_fab2(sch_1):\PP5722\"
				( pinRef "@baseboard_fab2_lib.baseboard_fab2(sch_1):page116_i220:PCIE9_SSATA3_RXN" )
				( pinRef "@baseboard_fab2_lib.baseboard_fab2(sch_1):page174_i32:A" )
			)
			( pinPair "@baseboard_fab2_lib.baseboard_fab2(sch_1):\PP5723\"
				( pinRef "@baseboard_fab2_lib.baseboard_fab2(sch_1):page174_i26:RXA1_DN" )
				( pinRef "@baseboard_fab2_lib.baseboard_fab2(sch_1):page174_i32:B" )
				( attribute "PROPAGATION_DELAY_MAX" "250.00 MIL"
					( Units "uMaxMinProp" "ns" 1.000000)
					( Origin gBackEnd )
				)
			)
			( pinPair "@baseboard_fab2_lib.baseboard_fab2(sch_1):\PP5724\"
				( pinRef "@baseboard_fab2_lib.baseboard_fab2(sch_1):page174_i26:RXA1_DP" )
				( pinRef "@baseboard_fab2_lib.baseboard_fab2(sch_1):page174_i30:B" )
				( attribute "PROPAGATION_DELAY_MAX" "250.00 MIL"
					( Units "uMaxMinProp" "ns" 1.000000)
					( Origin gBackEnd )
				)
			)
			( pinPair "@baseboard_fab2_lib.baseboard_fab2(sch_1):\PP5725\"
				( pinRef "@baseboard_fab2_lib.baseboard_fab2(sch_1):page116_i220:PCIE9_SSATA3_RXP" )
				( pinRef "@baseboard_fab2_lib.baseboard_fab2(sch_1):page174_i30:A" )
			)
			( pinPair "@baseboard_fab2_lib.baseboard_fab2(sch_1):\PP5698\"
				( pinRef "@baseboard_fab2_lib.baseboard_fab2(sch_1):page116_i220:PCIE10_SSATA4_RXN" )
				( pinRef "@baseboard_fab2_lib.baseboard_fab2(sch_1):page174_i39:A" )
			)
			( pinPair "@baseboard_fab2_lib.baseboard_fab2(sch_1):\PP5699\"
				( pinRef "@baseboard_fab2_lib.baseboard_fab2(sch_1):page174_i26:RXA2_DN" )
				( pinRef "@baseboard_fab2_lib.baseboard_fab2(sch_1):page174_i39:B" )
				( attribute "PROPAGATION_DELAY_MAX" "250.00 MIL"
					( Units "uMaxMinProp" "ns" 1.000000)
					( Origin gBackEnd )
				)
			)
			( pinPair "@baseboard_fab2_lib.baseboard_fab2(sch_1):\PP5700\"
				( pinRef "@baseboard_fab2_lib.baseboard_fab2(sch_1):page174_i26:RXA2_DP" )
				( pinRef "@baseboard_fab2_lib.baseboard_fab2(sch_1):page174_i31:B" )
				( attribute "PROPAGATION_DELAY_MAX" "250.00 MIL"
					( Units "uMaxMinProp" "ns" 1.000000)
					( Origin gBackEnd )
				)
			)
			( pinPair "@baseboard_fab2_lib.baseboard_fab2(sch_1):\PP5701\"
				( pinRef "@baseboard_fab2_lib.baseboard_fab2(sch_1):page116_i220:PCIE10_SSATA4_RXP" )
				( pinRef "@baseboard_fab2_lib.baseboard_fab2(sch_1):page174_i31:A" )
			)
			( pinPair "@baseboard_fab2_lib.baseboard_fab2(sch_1):\PP5706\"
				( pinRef "@baseboard_fab2_lib.baseboard_fab2(sch_1):page116_i220:PCIE11_SSATA5_GBE_RXN" )
				( pinRef "@baseboard_fab2_lib.baseboard_fab2(sch_1):page174_i41:A" )
			)
			( pinPair "@baseboard_fab2_lib.baseboard_fab2(sch_1):\PP5707\"
				( pinRef "@baseboard_fab2_lib.baseboard_fab2(sch_1):page174_i26:RXA3_DN" )
				( pinRef "@baseboard_fab2_lib.baseboard_fab2(sch_1):page174_i41:B" )
				( attribute "PROPAGATION_DELAY_MAX" "250.00 MIL"
					( Units "uMaxMinProp" "ns" 1.000000)
					( Origin gBackEnd )
				)
			)
			( pinPair "@baseboard_fab2_lib.baseboard_fab2(sch_1):\PP5708\"
				( pinRef "@baseboard_fab2_lib.baseboard_fab2(sch_1):page174_i26:RXA3_DP" )
				( pinRef "@baseboard_fab2_lib.baseboard_fab2(sch_1):page174_i40:B" )
				( attribute "PROPAGATION_DELAY_MAX" "250.00 MIL"
					( Units "uMaxMinProp" "ns" 1.000000)
					( Origin gBackEnd )
				)
			)
			( pinPair "@baseboard_fab2_lib.baseboard_fab2(sch_1):\PP5709\"
				( pinRef "@baseboard_fab2_lib.baseboard_fab2(sch_1):page116_i220:PCIE11_SSATA5_GBE_RXP" )
				( pinRef "@baseboard_fab2_lib.baseboard_fab2(sch_1):page174_i40:A" )
			)
			( pinPair "@baseboard_fab2_lib.baseboard_fab2(sch_1):\PP5668\"
				( pinRef "@baseboard_fab2_lib.baseboard_fab2(sch_1):page172_i17:SATA_TXN" )
				( pinRef "@baseboard_fab2_lib.baseboard_fab2(sch_1):page172_i8:A" )
				( attribute "PROPAGATION_DELAY_MAX" "250.00 MIL"
					( Units "uMaxMinProp" "ns" 1.000000)
					( Origin gBackEnd )
				)
			)
			( pinPair "@baseboard_fab2_lib.baseboard_fab2(sch_1):\PP5669\"
				( pinRef "@baseboard_fab2_lib.baseboard_fab2(sch_1):page116_i220:PCIE7_SSATA1_TXN" )
				( pinRef "@baseboard_fab2_lib.baseboard_fab2(sch_1):page172_i8:B" )
			)
			( pinPair "@baseboard_fab2_lib.baseboard_fab2(sch_1):\PP5670\"
				( pinRef "@baseboard_fab2_lib.baseboard_fab2(sch_1):page116_i220:PCIE7_SSATA1_TXP" )
				( pinRef "@baseboard_fab2_lib.baseboard_fab2(sch_1):page172_i6:B" )
			)
			( pinPair "@baseboard_fab2_lib.baseboard_fab2(sch_1):\PP5671\"
				( pinRef "@baseboard_fab2_lib.baseboard_fab2(sch_1):page172_i17:SATA_TXP" )
				( pinRef "@baseboard_fab2_lib.baseboard_fab2(sch_1):page172_i6:A" )
				( attribute "PROPAGATION_DELAY_MAX" "250.00 MIL"
					( Units "uMaxMinProp" "ns" 1.000000)
					( Origin gBackEnd )
				)
			)
			( pinPair "@baseboard_fab2_lib.baseboard_fab2(sch_1):\PP5718\"
				( pinRef "@baseboard_fab2_lib.baseboard_fab2(sch_1):page116_i220:PCIE8_SSATA2_GBE_TXN" )
				( pinRef "@baseboard_fab2_lib.baseboard_fab2(sch_1):page174_i8:B" )
			)
			( pinPair "@baseboard_fab2_lib.baseboard_fab2(sch_1):\PP5719\"
				( pinRef "@baseboard_fab2_lib.baseboard_fab2(sch_1):page174_i26:TXA0_DN" )
				( pinRef "@baseboard_fab2_lib.baseboard_fab2(sch_1):page174_i8:A" )
				( attribute "PROPAGATION_DELAY_MAX" "500.00 MIL"
					( Units "uMaxMinProp" "ns" 1.000000)
					( Origin gBackEnd )
				)
			)
			( pinPair "@baseboard_fab2_lib.baseboard_fab2(sch_1):\PP5720\"
				( pinRef "@baseboard_fab2_lib.baseboard_fab2(sch_1):page174_i26:TXA0_DP" )
				( pinRef "@baseboard_fab2_lib.baseboard_fab2(sch_1):page174_i9:A" )
				( attribute "PROPAGATION_DELAY_MAX" "250.00 MIL"
					( Units "uMaxMinProp" "ns" 1.000000)
					( Origin gBackEnd )
				)
			)
			( pinPair "@baseboard_fab2_lib.baseboard_fab2(sch_1):\PP5721\"
				( pinRef "@baseboard_fab2_lib.baseboard_fab2(sch_1):page116_i220:PCIE8_SSATA2_GBE_TXP" )
				( pinRef "@baseboard_fab2_lib.baseboard_fab2(sch_1):page174_i9:B" )
			)
			( pinPair "@baseboard_fab2_lib.baseboard_fab2(sch_1):\PP5726\"
				( pinRef "@baseboard_fab2_lib.baseboard_fab2(sch_1):page116_i220:PCIE9_SSATA3_TXN" )
				( pinRef "@baseboard_fab2_lib.baseboard_fab2(sch_1):page174_i12:B" )
			)
			( pinPair "@baseboard_fab2_lib.baseboard_fab2(sch_1):\PP5727\"
				( pinRef "@baseboard_fab2_lib.baseboard_fab2(sch_1):page174_i26:TXA1_DN" )
				( pinRef "@baseboard_fab2_lib.baseboard_fab2(sch_1):page174_i12:A" )
				( attribute "PROPAGATION_DELAY_MAX" "250.00 MIL"
					( Units "uMaxMinProp" "ns" 1.000000)
					( Origin gBackEnd )
				)
			)
			( pinPair "@baseboard_fab2_lib.baseboard_fab2(sch_1):\PP5728\"
				( pinRef "@baseboard_fab2_lib.baseboard_fab2(sch_1):page174_i26:TXA1_DP" )
				( pinRef "@baseboard_fab2_lib.baseboard_fab2(sch_1):page174_i13:A" )
				( attribute "PROPAGATION_DELAY_MAX" "250.00 MIL"
					( Units "uMaxMinProp" "ns" 1.000000)
					( Origin gBackEnd )
				)
			)
			( pinPair "@baseboard_fab2_lib.baseboard_fab2(sch_1):\PP5729\"
				( pinRef "@baseboard_fab2_lib.baseboard_fab2(sch_1):page116_i220:PCIE9_SSATA3_TXP" )
				( pinRef "@baseboard_fab2_lib.baseboard_fab2(sch_1):page174_i13:B" )
			)
			( pinPair "@baseboard_fab2_lib.baseboard_fab2(sch_1):\PP5702\"
				( pinRef "@baseboard_fab2_lib.baseboard_fab2(sch_1):page116_i220:PCIE10_SSATA4_TXN" )
				( pinRef "@baseboard_fab2_lib.baseboard_fab2(sch_1):page174_i14:B" )
			)
			( pinPair "@baseboard_fab2_lib.baseboard_fab2(sch_1):\PP5703\"
				( pinRef "@baseboard_fab2_lib.baseboard_fab2(sch_1):page174_i26:TXA2_DN" )
				( pinRef "@baseboard_fab2_lib.baseboard_fab2(sch_1):page174_i14:A" )
				( attribute "PROPAGATION_DELAY_MAX" "250.00 MIL"
					( Units "uMaxMinProp" "ns" 1.000000)
					( Origin gBackEnd )
				)
			)
			( pinPair "@baseboard_fab2_lib.baseboard_fab2(sch_1):\PP5704\"
				( pinRef "@baseboard_fab2_lib.baseboard_fab2(sch_1):page174_i26:TXA2_DP" )
				( pinRef "@baseboard_fab2_lib.baseboard_fab2(sch_1):page174_i19:A" )
				( attribute "PROPAGATION_DELAY_MAX" "250.00 MIL"
					( Units "uMaxMinProp" "ns" 1.000000)
					( Origin gBackEnd )
				)
			)
			( pinPair "@baseboard_fab2_lib.baseboard_fab2(sch_1):\PP5705\"
				( pinRef "@baseboard_fab2_lib.baseboard_fab2(sch_1):page116_i220:PCIE10_SSATA4_TXP" )
				( pinRef "@baseboard_fab2_lib.baseboard_fab2(sch_1):page174_i19:B" )
			)
			( pinPair "@baseboard_fab2_lib.baseboard_fab2(sch_1):\PP5710\"
				( pinRef "@baseboard_fab2_lib.baseboard_fab2(sch_1):page116_i220:PCIE11_SSATA5_GBE_TXN" )
				( pinRef "@baseboard_fab2_lib.baseboard_fab2(sch_1):page174_i18:B" )
			)
			( pinPair "@baseboard_fab2_lib.baseboard_fab2(sch_1):\PP5711\"
				( pinRef "@baseboard_fab2_lib.baseboard_fab2(sch_1):page174_i26:TXA3_DN" )
				( pinRef "@baseboard_fab2_lib.baseboard_fab2(sch_1):page174_i18:A" )
				( attribute "PROPAGATION_DELAY_MAX" "250.00 MIL"
					( Units "uMaxMinProp" "ns" 1.000000)
					( Origin gBackEnd )
				)
			)
			( pinPair "@baseboard_fab2_lib.baseboard_fab2(sch_1):\PP5712\"
				( pinRef "@baseboard_fab2_lib.baseboard_fab2(sch_1):page174_i26:TXA3_DP" )
				( pinRef "@baseboard_fab2_lib.baseboard_fab2(sch_1):page174_i20:A" )
				( attribute "PROPAGATION_DELAY_MAX" "250.00 MIL"
					( Units "uMaxMinProp" "ns" 1.000000)
					( Origin gBackEnd )
				)
			)
			( pinPair "@baseboard_fab2_lib.baseboard_fab2(sch_1):\PP5713\"
				( pinRef "@baseboard_fab2_lib.baseboard_fab2(sch_1):page116_i220:PCIE11_SSATA5_GBE_TXP" )
				( pinRef "@baseboard_fab2_lib.baseboard_fab2(sch_1):page174_i20:B" )
			)
			( pinPair "@baseboard_fab2_lib.baseboard_fab2(sch_1):\PP6143\"
				( pinRef "@baseboard_fab2_lib.baseboard_fab2(sch_1):page116_i220:PCIE6_SSATA0_RXN" )
				( pinRef "@baseboard_fab2_lib.baseboard_fab2(sch_1):page185_i90:A" )
			)
			( pinPair "@baseboard_fab2_lib.baseboard_fab2(sch_1):\PP6142\"
				( pinRef "@baseboard_fab2_lib.baseboard_fab2(sch_1):page116_i220:PCIE6_SSATA0_RXP" )
				( pinRef "@baseboard_fab2_lib.baseboard_fab2(sch_1):page185_i99:A" )
			)
			( pinPair "@baseboard_fab2_lib.baseboard_fab2(sch_1):\PP6141\"
				( pinRef "@baseboard_fab2_lib.baseboard_fab2(sch_1):page116_i220:PCIE6_SSATA0_TXN" )
				( pinRef "@baseboard_fab2_lib.baseboard_fab2(sch_1):page185_i97:A" )
			)
			( pinPair "@baseboard_fab2_lib.baseboard_fab2(sch_1):\PP6140\"
				( pinRef "@baseboard_fab2_lib.baseboard_fab2(sch_1):page116_i220:PCIE6_SSATA0_TXP" )
				( pinRef "@baseboard_fab2_lib.baseboard_fab2(sch_1):page185_i95:A" )
			)
			( pinPair "@baseboard_fab2_lib.baseboard_fab2(sch_1):\PP6092\"
				( pinRef "@baseboard_fab2_lib.baseboard_fab2(sch_1):page147_i1:RGMII2RXD2_RMII2CRSDV_GPIOV6" )
				( pinRef "@baseboard_fab2_lib.baseboard_fab2(sch_1):page121_i34:GPP_K3_LAN_NCSI_TX_EN" )
				( attribute "PROPAGATION_DELAY_MIN" "1000.00 MIL"
					( Units "uMaxMinProp" "ns" 1.000000)
					( Status sCSetFlattened )
					( Origin gBackEnd )
				)
				( attribute "PROPAGATION_DELAY_MAX" "8000.00 MIL"
					( Units "uMaxMinProp" "ns" 1.000000)
					( Status sCSetFlattened )
					( Origin gBackEnd )
				)
			)
			( pinPair "@baseboard_fab2_lib.baseboard_fab2(sch_1):\PP5810\"
				( pinRef "@baseboard_fab2_lib.baseboard_fab2(sch_1):page101_i34:RMII(1)" )
				( pinRef "@baseboard_fab2_lib.baseboard_fab2(sch_1):page147_i1:RGMII1RXCK_RMII1RCLK_GPIOU4" )
				( attribute "PROPAGATION_DELAY_MIN" "2000.00 MIL"
					( Units "uMaxMinProp" "ns" 1.000000)
					( Origin gBackEnd )
				)
			)
			( pinPair "@baseboard_fab2_lib.baseboard_fab2(sch_1):\PP5800\"
				( pinRef "@baseboard_fab2_lib.baseboard_fab2(sch_1):page101_i34:RMII(2)" )
				( pinRef "@baseboard_fab2_lib.baseboard_fab2(sch_1):page147_i1:RGMII2RXCK_RMII2RCLK_GPIOV2" )
				( attribute "PROPAGATION_DELAY_MIN" "2000.00 MIL"
					( Units "uMaxMinProp" "ns" 1.000000)
					( Origin gBackEnd )
				)
			)
			( pinPair "@baseboard_fab2_lib.baseboard_fab2(sch_1):\PP6123\"
				( pinRef "@baseboard_fab2_lib.baseboard_fab2(sch_1):page144_i347:DP_USB11_DP_USB11_HDP2" )
				( pinRef "@baseboard_fab2_lib.baseboard_fab2(sch_1):page115_i74:USB2P_4" )
				( attribute "PROPAGATION_DELAY_MIN" "3000.00 MIL"
					( Units "uMaxMinProp" "ns" 1.000000)
					( Origin gBackEnd )
				)
				( attribute "PROPAGATION_DELAY_MAX" "24000.00 MIL"
					( Units "uMaxMinProp" "ns" 1.000000)
					( Origin gBackEnd )
				)
			)
			( pinPair "@baseboard_fab2_lib.baseboard_fab2(sch_1):\PP6124\"
				( pinRef "@baseboard_fab2_lib.baseboard_fab2(sch_1):page144_i347:DN_USB11_DN_USB11_HDN2" )
				( pinRef "@baseboard_fab2_lib.baseboard_fab2(sch_1):page115_i74:USB2N_4" )
				( attribute "PROPAGATION_DELAY_MIN" "3000.00 MIL"
					( Units "uMaxMinProp" "ns" 1.000000)
					( Origin gBackEnd )
				)
				( attribute "PROPAGATION_DELAY_MAX" "24000.00 MIL"
					( Units "uMaxMinProp" "ns" 1.000000)
					( Origin gBackEnd )
				)
			)
			( pinPair "@baseboard_fab2_lib.baseboard_fab2(sch_1):\PP6121\"
				( pinRef "@baseboard_fab2_lib.baseboard_fab2(sch_1):page144_i347:DP_USB2_DP_USB2_HDP" )
				( pinRef "@baseboard_fab2_lib.baseboard_fab2(sch_1):page115_i74:USB2P_5" )
				( attribute "PROPAGATION_DELAY_MIN" "3000.00 MIL"
					( Units "uMaxMinProp" "ns" 1.000000)
					( Origin gBackEnd )
				)
				( attribute "PROPAGATION_DELAY_MAX" "24000.00 MIL"
					( Units "uMaxMinProp" "ns" 1.000000)
					( Origin gBackEnd )
				)
			)
			( pinPair "@baseboard_fab2_lib.baseboard_fab2(sch_1):\PP6122\"
				( pinRef "@baseboard_fab2_lib.baseboard_fab2(sch_1):page144_i347:DN_USB2_DN_USB2_HDN" )
				( pinRef "@baseboard_fab2_lib.baseboard_fab2(sch_1):page115_i74:USB2N_5" )
				( attribute "PROPAGATION_DELAY_MIN" "3000.00 MIL"
					( Units "uMaxMinProp" "ns" 1.000000)
					( Origin gBackEnd )
				)
				( attribute "PROPAGATION_DELAY_MAX" "24000.00 MIL"
					( Units "uMaxMinProp" "ns" 1.000000)
					( Origin gBackEnd )
				)
			)
			( pinPair "@baseboard_fab2_lib.baseboard_fab2(sch_1):\PP5794\"
				( pinRef "@baseboard_fab2_lib.baseboard_fab2(sch_1):page176_i69:DN" )
				( pinRef "@baseboard_fab2_lib.baseboard_fab2(sch_1):page176_i30:B2" )
				( attribute "PROPAGATION_DELAY_MAX" "1000.00 MIL"
					( Units "uMaxMinProp" "ns" 1.000000)
					( Origin gBackEnd )
				)
			)
			( pinPair "@baseboard_fab2_lib.baseboard_fab2(sch_1):\PP5795\"
				( pinRef "@baseboard_fab2_lib.baseboard_fab2(sch_1):page176_i69:DP" )
				( pinRef "@baseboard_fab2_lib.baseboard_fab2(sch_1):page176_i30:B1" )
				( attribute "PROPAGATION_DELAY_MAX" "1000.00 MIL"
					( Units "uMaxMinProp" "ns" 1.000000)
					( Origin gBackEnd )
				)
			)
			( pinPair "@baseboard_fab2_lib.baseboard_fab2(sch_1):\PP5403\"
				( pinRef "@baseboard_fab2_lib.baseboard_fab2(sch_1):page22_i204:FIVR_FAULT" )
				( pinRef "@baseboard_fab2_lib.baseboard_fab2(sch_1):page92_i32:B1" )
				( attribute "PROPAGATION_DELAY_MAX" "13000.00 MIL"
					( Units "uMaxMinProp" "ns" 1.000000)
					( Status sCSetFlattened )
					( Origin gBackEnd )
				)
			)
			( pinPair "@baseboard_fab2_lib.baseboard_fab2(sch_1):\PP5652\"
				( pinRef "@baseboard_fab2_lib.baseboard_fab2(sch_1):page21_i259:PM_FAST_WAKE_N" )
				( pinRef "@baseboard_fab2_lib.baseboard_fab2(sch_1):page97_i42:B" )
				( attribute "PROPAGATION_DELAY_MAX" "2500.00 MIL"
					( Units "uMaxMinProp" "ns" 1.000000)
					( Origin gBackEnd )
				)
			)
			( pinPair "@baseboard_fab2_lib.baseboard_fab2(sch_1):\PP5653\"
				( pinRef "@baseboard_fab2_lib.baseboard_fab2(sch_1):page55_i172:PM_FAST_WAKE_N" )
				( pinRef "@baseboard_fab2_lib.baseboard_fab2(sch_1):page97_i44:B" )
				( attribute "PROPAGATION_DELAY_MAX" "2500.00 MIL"
					( Units "uMaxMinProp" "ns" 1.000000)
					( Origin gBackEnd )
				)
			)
			( pinPair "@baseboard_fab2_lib.baseboard_fab2(sch_1):\PP40\"
				( pinRef "@baseboard_fab2_lib.baseboard_fab2(sch_1):page118_i73:PM_SYNC" )
				( pinRef "@baseboard_fab2_lib.baseboard_fab2(sch_1):page118_i66:A" )
				( attribute "PROPAGATION_DELAY_MAX" "2100.00 MIL"
					( Units "uMaxMinProp" "ns" 1.000000)
					( Status sCSetFlattened )
					( Origin gBackEnd )
				)
			)
			( pinPair "@baseboard_fab2_lib.baseboard_fab2(sch_1):\PP41\"
				( pinRef "@baseboard_fab2_lib.baseboard_fab2(sch_1):page21_i259:PMSYNC" )
				( pinRef "@baseboard_fab2_lib.baseboard_fab2(sch_1):page21_i244:A" )
				( attribute "PROPAGATION_DELAY_MAX" "2500.00 MIL"
					( Units "uMaxMinProp" "ns" 1.000000)
					( Status sCSetFlattened )
					( Origin gBackEnd )
				)
			)
			( pinPair "@baseboard_fab2_lib.baseboard_fab2(sch_1):\PP42\"
				( pinRef "@baseboard_fab2_lib.baseboard_fab2(sch_1):page55_i172:PMSYNC" )
				( pinRef "@baseboard_fab2_lib.baseboard_fab2(sch_1):page55_i170:A" )
				( attribute "PROPAGATION_DELAY_MAX" "2500.00 MIL"
					( Units "uMaxMinProp" "ns" 1.000000)
					( Status sCSetFlattened )
					( Origin gBackEnd )
				)
			)
			( pinPair "@baseboard_fab2_lib.baseboard_fab2(sch_1):\PP16\"
				( pinRef "@baseboard_fab2_lib.baseboard_fab2(sch_1):page92_i32:B0" )
				( pinRef "@baseboard_fab2_lib.baseboard_fab2(sch_1):h_cpu_msmi_g_n:\<user>\" )
				( attribute "PROPAGATION_DELAY_MAX" "500.00 MIL"
					( Units "uMaxMinProp" "ns" 1.000000)
					( Status sCSetFlattened )
					( Origin gBackEnd )
				)
			)
			( pinPair "@baseboard_fab2_lib.baseboard_fab2(sch_1):\PP17\"
				( pinRef "@baseboard_fab2_lib.baseboard_fab2(sch_1):page55_i172:MSMI_N" )
				( pinRef "@baseboard_fab2_lib.baseboard_fab2(sch_1):page92_i65:B" )
				( attribute "PROPAGATION_DELAY_MAX" "2500.00 MIL"
					( Units "uMaxMinProp" "ns" 1.000000)
					( Status sCSetFlattened )
					( Origin gBackEnd )
				)
			)
			( pinPair "@baseboard_fab2_lib.baseboard_fab2(sch_1):\PP18\"
				( pinRef "@baseboard_fab2_lib.baseboard_fab2(sch_1):page92_i64:B" )
				( pinRef "@baseboard_fab2_lib.baseboard_fab2(sch_1):page21_i259:MSMI_N" )
				( attribute "PROPAGATION_DELAY_MAX" "2500.00 MIL"
					( Units "uMaxMinProp" "ns" 1.000000)
					( Status sCSetFlattened )
					( Origin gBackEnd )
				)
			)
			( pinPair "@baseboard_fab2_lib.baseboard_fab2(sch_1):\PP6113\"
				( pinRef "@baseboard_fab2_lib.baseboard_fab2(sch_1):page92_i65:B" )
				( pinRef "@baseboard_fab2_lib.baseboard_fab2(sch_1):h_cpu_msmi_g_n:\<user>\" )
				( attribute "PROPAGATION_DELAY_MAX" "10000.00 MIL"
					( Units "uMaxMinProp" "ns" 1.000000)
					( Status sCSetFlattened )
					( Origin gBackEnd )
				)
			)
			( pinPair "@baseboard_fab2_lib.baseboard_fab2(sch_1):\PP6114\"
				( pinRef "@baseboard_fab2_lib.baseboard_fab2(sch_1):page92_i64:B" )
				( pinRef "@baseboard_fab2_lib.baseboard_fab2(sch_1):h_cpu_msmi_g_n:\<user>\" )
				( attribute "PROPAGATION_DELAY_MAX" "10000.00 MIL"
					( Units "uMaxMinProp" "ns" 1.000000)
					( Status sCSetFlattened )
					( Origin gBackEnd )
				)
			)
			( pinPair "@baseboard_fab2_lib.baseboard_fab2(sch_1):\PP13\"
				( pinRef "@baseboard_fab2_lib.baseboard_fab2(sch_1):page92_i1:B2" )
				( pinRef "@baseboard_fab2_lib.baseboard_fab2(sch_1):h_cpu_caterr_g_n:\<user>\" )
				( attribute "PROPAGATION_DELAY_MAX" "500.00 MIL"
					( Units "uMaxMinProp" "ns" 1.000000)
					( Status sCSetFlattened )
					( Origin gBackEnd )
				)
			)
			( pinPair "@baseboard_fab2_lib.baseboard_fab2(sch_1):\PP14\"
				( pinRef "@baseboard_fab2_lib.baseboard_fab2(sch_1):page92_i101:B" )
				( pinRef "@baseboard_fab2_lib.baseboard_fab2(sch_1):page21_i259:CATERR_N" )
				( attribute "PROPAGATION_DELAY_MAX" "2500.00 MIL"
					( Units "uMaxMinProp" "ns" 1.000000)
					( Status sCSetFlattened )
					( Origin gBackEnd )
				)
			)
			( pinPair "@baseboard_fab2_lib.baseboard_fab2(sch_1):\PP15\"
				( pinRef "@baseboard_fab2_lib.baseboard_fab2(sch_1):page55_i172:CATERR_N" )
				( pinRef "@baseboard_fab2_lib.baseboard_fab2(sch_1):page92_i100:B" )
				( attribute "PROPAGATION_DELAY_MAX" "2500.00 MIL"
					( Units "uMaxMinProp" "ns" 1.000000)
					( Status sCSetFlattened )
					( Origin gBackEnd )
				)
			)
			( pinPair "@baseboard_fab2_lib.baseboard_fab2(sch_1):\PP6106\"
				( pinRef "@baseboard_fab2_lib.baseboard_fab2(sch_1):page92_i100:B" )
				( pinRef "@baseboard_fab2_lib.baseboard_fab2(sch_1):h_cpu_caterr_g_n:\<user>\" )
				( attribute "PROPAGATION_DELAY_MAX" "10000.00 MIL"
					( Units "uMaxMinProp" "ns" 1.000000)
					( Status sCSetFlattened )
					( Origin gBackEnd )
				)
			)
			( pinPair "@baseboard_fab2_lib.baseboard_fab2(sch_1):\PP6107\"
				( pinRef "@baseboard_fab2_lib.baseboard_fab2(sch_1):page92_i101:B" )
				( pinRef "@baseboard_fab2_lib.baseboard_fab2(sch_1):h_cpu_caterr_g_n:\<user>\" )
				( attribute "PROPAGATION_DELAY_MAX" "10000.00 MIL"
					( Units "uMaxMinProp" "ns" 1.000000)
					( Status sCSetFlattened )
					( Origin gBackEnd )
				)
			)
			( pinPair "@baseboard_fab2_lib.baseboard_fab2(sch_1):\PP68\"
				( pinRef "@baseboard_fab2_lib.baseboard_fab2(sch_1):page129_i76:B" )
				( pinRef "@baseboard_fab2_lib.baseboard_fab2(sch_1):page117_i9:DMI_RXN(0)" )
				( attribute "RELATIVE_PROPAGATION_DELAY_SCOPE" "L"
					( Parent
						( matchGroupRef "@baseboard_fab2_lib.baseboard_fab2(sch_1):\MG_DMI_L1\" )
					)
					( Status sCSetFlattened )
					( Origin gBackEnd )
				)
				( attribute "RELATIVE_PROPAGATION_DELAY" ",5.00 MIL"
					( Parent
						( matchGroupRef "@baseboard_fab2_lib.baseboard_fab2(sch_1):\MG_DMI_L1\" )
					)
					( Units "uMatchProp" "ns" 1.000000)
					( Status sCSetFlattened )
					( Origin gBackEnd )
				)
			)
			( pinPair "@baseboard_fab2_lib.baseboard_fab2(sch_1):\PP69\"
				( pinRef "@baseboard_fab2_lib.baseboard_fab2(sch_1):page29_i61:DMI_TX_DN(0)" )
				( pinRef "@baseboard_fab2_lib.baseboard_fab2(sch_1):page129_i76:A" )
				( attribute "RELATIVE_PROPAGATION_DELAY_SCOPE" "L"
					( Parent
						( matchGroupRef "@baseboard_fab2_lib.baseboard_fab2(sch_1):\MG_DMI_L0\" )
					)
					( Status sCSetFlattened )
					( Origin gBackEnd )
				)
				( attribute "RELATIVE_PROPAGATION_DELAY" ",5.00 MIL"
					( Parent
						( matchGroupRef "@baseboard_fab2_lib.baseboard_fab2(sch_1):\MG_DMI_L0\" )
					)
					( Units "uMatchProp" "ns" 1.000000)
					( Status sCSetFlattened )
					( Origin gBackEnd )
				)
			)
			( pinPair "@baseboard_fab2_lib.baseboard_fab2(sch_1):\PP6082\"
				( pinRef "@baseboard_fab2_lib.baseboard_fab2(sch_1):page29_i61:DMI_TX_DN(0)" )
				( pinRef "@baseboard_fab2_lib.baseboard_fab2(sch_1):page117_i9:DMI_RXN(0)" )
				( attribute "PROPAGATION_DELAY_MAX" "15000.00 MIL"
					( Units "uMaxMinProp" "ns" 1.000000)
					( Status sCSetFlattened )
					( Origin gBackEnd )
				)
			)
			( pinPair "@baseboard_fab2_lib.baseboard_fab2(sch_1):\PP70\"
				( pinRef "@baseboard_fab2_lib.baseboard_fab2(sch_1):page29_i61:DMI_TX_DP(0)" )
				( pinRef "@baseboard_fab2_lib.baseboard_fab2(sch_1):page129_i71:A" )
				( attribute "RELATIVE_PROPAGATION_DELAY_SCOPE" "L"
					( Parent
						( matchGroupRef "@baseboard_fab2_lib.baseboard_fab2(sch_1):\MG_DMI_L0\" )
					)
					( Status sCSetFlattened )
					( Origin gBackEnd )
				)
				( attribute "RELATIVE_PROPAGATION_DELAY" ",5.00 MIL"
					( Parent
						( matchGroupRef "@baseboard_fab2_lib.baseboard_fab2(sch_1):\MG_DMI_L0\" )
					)
					( Units "uMatchProp" "ns" 1.000000)
					( Status sCSetFlattened )
					( Origin gBackEnd )
				)
			)
			( pinPair "@baseboard_fab2_lib.baseboard_fab2(sch_1):\PP71\"
				( pinRef "@baseboard_fab2_lib.baseboard_fab2(sch_1):page129_i71:B" )
				( pinRef "@baseboard_fab2_lib.baseboard_fab2(sch_1):page117_i9:DMI_RXP(0)" )
				( attribute "RELATIVE_PROPAGATION_DELAY_SCOPE" "L"
					( Parent
						( matchGroupRef "@baseboard_fab2_lib.baseboard_fab2(sch_1):\MG_DMI_L1\" )
					)
					( Status sCSetFlattened )
					( Origin gBackEnd )
				)
				( attribute "RELATIVE_PROPAGATION_DELAY" ",5.00 MIL"
					( Parent
						( matchGroupRef "@baseboard_fab2_lib.baseboard_fab2(sch_1):\MG_DMI_L1\" )
					)
					( Units "uMatchProp" "ns" 1.000000)
					( Status sCSetFlattened )
					( Origin gBackEnd )
				)
			)
			( pinPair "@baseboard_fab2_lib.baseboard_fab2(sch_1):\PP6080\"
				( pinRef "@baseboard_fab2_lib.baseboard_fab2(sch_1):page29_i61:DMI_TX_DP(0)" )
				( pinRef "@baseboard_fab2_lib.baseboard_fab2(sch_1):page117_i9:DMI_RXP(0)" )
				( attribute "PROPAGATION_DELAY_MAX" "15000.00 MIL"
					( Units "uMaxMinProp" "ns" 1.000000)
					( Status sCSetFlattened )
					( Origin gBackEnd )
				)
			)
			( pinPair "@baseboard_fab2_lib.baseboard_fab2(sch_1):\PP72\"
				( pinRef "@baseboard_fab2_lib.baseboard_fab2(sch_1):page129_i77:B" )
				( pinRef "@baseboard_fab2_lib.baseboard_fab2(sch_1):page117_i9:DMI_RXN(1)" )
				( attribute "RELATIVE_PROPAGATION_DELAY_SCOPE" "L"
					( Parent
						( matchGroupRef "@baseboard_fab2_lib.baseboard_fab2(sch_1):\MG_DMI_L1\" )
					)
					( Status sCSetFlattened )
					( Origin gBackEnd )
				)
				( attribute "RELATIVE_PROPAGATION_DELAY" ",5.00 MIL"
					( Parent
						( matchGroupRef "@baseboard_fab2_lib.baseboard_fab2(sch_1):\MG_DMI_L1\" )
					)
					( Units "uMatchProp" "ns" 1.000000)
					( Status sCSetFlattened )
					( Origin gBackEnd )
				)
			)
			( pinPair "@baseboard_fab2_lib.baseboard_fab2(sch_1):\PP73\"
				( pinRef "@baseboard_fab2_lib.baseboard_fab2(sch_1):page29_i61:DMI_TX_DN(1)" )
				( pinRef "@baseboard_fab2_lib.baseboard_fab2(sch_1):page129_i77:A" )
				( attribute "RELATIVE_PROPAGATION_DELAY_SCOPE" "L"
					( Parent
						( matchGroupRef "@baseboard_fab2_lib.baseboard_fab2(sch_1):\MG_DMI_L0\" )
					)
					( Status sCSetFlattened )
					( Origin gBackEnd )
				)
				( attribute "RELATIVE_PROPAGATION_DELAY" ",5.00 MIL"
					( Parent
						( matchGroupRef "@baseboard_fab2_lib.baseboard_fab2(sch_1):\MG_DMI_L0\" )
					)
					( Units "uMatchProp" "ns" 1.000000)
					( Status sCSetFlattened )
					( Origin gBackEnd )
				)
			)
			( pinPair "@baseboard_fab2_lib.baseboard_fab2(sch_1):\PP6079\"
				( pinRef "@baseboard_fab2_lib.baseboard_fab2(sch_1):page29_i61:DMI_TX_DN(1)" )
				( pinRef "@baseboard_fab2_lib.baseboard_fab2(sch_1):page117_i9:DMI_RXN(1)" )
				( attribute "PROPAGATION_DELAY_MAX" "15000.00 MIL"
					( Units "uMaxMinProp" "ns" 1.000000)
					( Status sCSetFlattened )
					( Origin gBackEnd )
				)
			)
			( pinPair "@baseboard_fab2_lib.baseboard_fab2(sch_1):\PP74\"
				( pinRef "@baseboard_fab2_lib.baseboard_fab2(sch_1):page29_i61:DMI_TX_DP(1)" )
				( pinRef "@baseboard_fab2_lib.baseboard_fab2(sch_1):page129_i70:A" )
				( attribute "RELATIVE_PROPAGATION_DELAY_SCOPE" "L"
					( Parent
						( matchGroupRef "@baseboard_fab2_lib.baseboard_fab2(sch_1):\MG_DMI_L0\" )
					)
					( Status sCSetFlattened )
					( Origin gBackEnd )
				)
				( attribute "RELATIVE_PROPAGATION_DELAY" ",5.00 MIL"
					( Parent
						( matchGroupRef "@baseboard_fab2_lib.baseboard_fab2(sch_1):\MG_DMI_L0\" )
					)
					( Units "uMatchProp" "ns" 1.000000)
					( Status sCSetFlattened )
					( Origin gBackEnd )
				)
			)
			( pinPair "@baseboard_fab2_lib.baseboard_fab2(sch_1):\PP75\"
				( pinRef "@baseboard_fab2_lib.baseboard_fab2(sch_1):page129_i70:B" )
				( pinRef "@baseboard_fab2_lib.baseboard_fab2(sch_1):page117_i9:DMI_RXP(1)" )
				( attribute "RELATIVE_PROPAGATION_DELAY_SCOPE" "L"
					( Parent
						( matchGroupRef "@baseboard_fab2_lib.baseboard_fab2(sch_1):\MG_DMI_L1\" )
					)
					( Status sCSetFlattened )
					( Origin gBackEnd )
				)
				( attribute "RELATIVE_PROPAGATION_DELAY" ",5.00 MIL"
					( Parent
						( matchGroupRef "@baseboard_fab2_lib.baseboard_fab2(sch_1):\MG_DMI_L1\" )
					)
					( Units "uMatchProp" "ns" 1.000000)
					( Status sCSetFlattened )
					( Origin gBackEnd )
				)
			)
			( pinPair "@baseboard_fab2_lib.baseboard_fab2(sch_1):\PP6078\"
				( pinRef "@baseboard_fab2_lib.baseboard_fab2(sch_1):page29_i61:DMI_TX_DP(1)" )
				( pinRef "@baseboard_fab2_lib.baseboard_fab2(sch_1):page117_i9:DMI_RXP(1)" )
				( attribute "PROPAGATION_DELAY_MAX" "15000.00 MIL"
					( Units "uMaxMinProp" "ns" 1.000000)
					( Status sCSetFlattened )
					( Origin gBackEnd )
				)
			)
			( pinPair "@baseboard_fab2_lib.baseboard_fab2(sch_1):\PP76\"
				( pinRef "@baseboard_fab2_lib.baseboard_fab2(sch_1):page129_i78:B" )
				( pinRef "@baseboard_fab2_lib.baseboard_fab2(sch_1):page117_i9:DMI_RXN(2)" )
				( attribute "RELATIVE_PROPAGATION_DELAY_SCOPE" "L"
					( Parent
						( matchGroupRef "@baseboard_fab2_lib.baseboard_fab2(sch_1):\MG_DMI_L1\" )
					)
					( Status sCSetFlattened )
					( Origin gBackEnd )
				)
				( attribute "RELATIVE_PROPAGATION_DELAY" ",5.00 MIL"
					( Parent
						( matchGroupRef "@baseboard_fab2_lib.baseboard_fab2(sch_1):\MG_DMI_L1\" )
					)
					( Units "uMatchProp" "ns" 1.000000)
					( Status sCSetFlattened )
					( Origin gBackEnd )
				)
			)
			( pinPair "@baseboard_fab2_lib.baseboard_fab2(sch_1):\PP77\"
				( pinRef "@baseboard_fab2_lib.baseboard_fab2(sch_1):page29_i61:DMI_TX_DN(2)" )
				( pinRef "@baseboard_fab2_lib.baseboard_fab2(sch_1):page129_i78:A" )
				( attribute "RELATIVE_PROPAGATION_DELAY_SCOPE" "L"
					( Parent
						( matchGroupRef "@baseboard_fab2_lib.baseboard_fab2(sch_1):\MG_DMI_L0\" )
					)
					( Status sCSetFlattened )
					( Origin gBackEnd )
				)
				( attribute "RELATIVE_PROPAGATION_DELAY" ",5.00 MIL"
					( Parent
						( matchGroupRef "@baseboard_fab2_lib.baseboard_fab2(sch_1):\MG_DMI_L0\" )
					)
					( Units "uMatchProp" "ns" 1.000000)
					( Status sCSetFlattened )
					( Origin gBackEnd )
				)
			)
			( pinPair "@baseboard_fab2_lib.baseboard_fab2(sch_1):\PP6076\"
				( pinRef "@baseboard_fab2_lib.baseboard_fab2(sch_1):page29_i61:DMI_TX_DN(2)" )
				( pinRef "@baseboard_fab2_lib.baseboard_fab2(sch_1):page117_i9:DMI_RXN(2)" )
				( attribute "PROPAGATION_DELAY_MAX" "15000.00 MIL"
					( Units "uMaxMinProp" "ns" 1.000000)
					( Status sCSetFlattened )
					( Origin gBackEnd )
				)
			)
			( pinPair "@baseboard_fab2_lib.baseboard_fab2(sch_1):\PP78\"
				( pinRef "@baseboard_fab2_lib.baseboard_fab2(sch_1):page29_i61:DMI_TX_DP(2)" )
				( pinRef "@baseboard_fab2_lib.baseboard_fab2(sch_1):page129_i69:A" )
				( attribute "RELATIVE_PROPAGATION_DELAY_SCOPE" "L"
					( Parent
						( matchGroupRef "@baseboard_fab2_lib.baseboard_fab2(sch_1):\MG_DMI_L0\" )
					)
					( Status sCSetFlattened )
					( Origin gBackEnd )
				)
				( attribute "RELATIVE_PROPAGATION_DELAY" ",5.00 MIL"
					( Parent
						( matchGroupRef "@baseboard_fab2_lib.baseboard_fab2(sch_1):\MG_DMI_L0\" )
					)
					( Units "uMatchProp" "ns" 1.000000)
					( Status sCSetFlattened )
					( Origin gBackEnd )
				)
			)
			( pinPair "@baseboard_fab2_lib.baseboard_fab2(sch_1):\PP79\"
				( pinRef "@baseboard_fab2_lib.baseboard_fab2(sch_1):page129_i69:B" )
				( pinRef "@baseboard_fab2_lib.baseboard_fab2(sch_1):page117_i9:DMI_RXP(2)" )
				( attribute "RELATIVE_PROPAGATION_DELAY_SCOPE" "L"
					( Parent
						( matchGroupRef "@baseboard_fab2_lib.baseboard_fab2(sch_1):\MG_DMI_L1\" )
					)
					( Status sCSetFlattened )
					( Origin gBackEnd )
				)
				( attribute "RELATIVE_PROPAGATION_DELAY" ",5.00 MIL"
					( Parent
						( matchGroupRef "@baseboard_fab2_lib.baseboard_fab2(sch_1):\MG_DMI_L1\" )
					)
					( Units "uMatchProp" "ns" 1.000000)
					( Status sCSetFlattened )
					( Origin gBackEnd )
				)
			)
			( pinPair "@baseboard_fab2_lib.baseboard_fab2(sch_1):\PP6066\"
				( pinRef "@baseboard_fab2_lib.baseboard_fab2(sch_1):page29_i61:DMI_TX_DP(2)" )
				( pinRef "@baseboard_fab2_lib.baseboard_fab2(sch_1):page117_i9:DMI_RXP(2)" )
				( attribute "PROPAGATION_DELAY_MAX" "15000.00 MIL"
					( Units "uMaxMinProp" "ns" 1.000000)
					( Status sCSetFlattened )
					( Origin gBackEnd )
				)
			)
			( pinPair "@baseboard_fab2_lib.baseboard_fab2(sch_1):\PP80\"
				( pinRef "@baseboard_fab2_lib.baseboard_fab2(sch_1):page129_i79:B" )
				( pinRef "@baseboard_fab2_lib.baseboard_fab2(sch_1):page117_i9:DMI_RXN(3)" )
				( attribute "RELATIVE_PROPAGATION_DELAY_SCOPE" "L"
					( Parent
						( matchGroupRef "@baseboard_fab2_lib.baseboard_fab2(sch_1):\MG_DMI_L1\" )
					)
					( Status sCSetFlattened )
					( Origin gBackEnd )
				)
				( attribute "RELATIVE_PROPAGATION_DELAY" ",5.00 MIL"
					( Parent
						( matchGroupRef "@baseboard_fab2_lib.baseboard_fab2(sch_1):\MG_DMI_L1\" )
					)
					( Units "uMatchProp" "ns" 1.000000)
					( Status sCSetFlattened )
					( Origin gBackEnd )
				)
			)
			( pinPair "@baseboard_fab2_lib.baseboard_fab2(sch_1):\PP81\"
				( pinRef "@baseboard_fab2_lib.baseboard_fab2(sch_1):page29_i61:DMI_TX_DN(3)" )
				( pinRef "@baseboard_fab2_lib.baseboard_fab2(sch_1):page129_i79:A" )
				( attribute "RELATIVE_PROPAGATION_DELAY_SCOPE" "L"
					( Parent
						( matchGroupRef "@baseboard_fab2_lib.baseboard_fab2(sch_1):\MG_DMI_L0\" )
					)
					( Status sCSetFlattened )
					( Origin gBackEnd )
				)
				( attribute "RELATIVE_PROPAGATION_DELAY" ",5.00 MIL"
					( Parent
						( matchGroupRef "@baseboard_fab2_lib.baseboard_fab2(sch_1):\MG_DMI_L0\" )
					)
					( Units "uMatchProp" "ns" 1.000000)
					( Status sCSetFlattened )
					( Origin gBackEnd )
				)
			)
			( pinPair "@baseboard_fab2_lib.baseboard_fab2(sch_1):\PP6033\"
				( pinRef "@baseboard_fab2_lib.baseboard_fab2(sch_1):page29_i61:DMI_TX_DN(3)" )
				( pinRef "@baseboard_fab2_lib.baseboard_fab2(sch_1):page117_i9:DMI_RXN(3)" )
				( attribute "PROPAGATION_DELAY_MAX" "15000.00 MIL"
					( Units "uMaxMinProp" "ns" 1.000000)
					( Status sCSetFlattened )
					( Origin gBackEnd )
				)
			)
			( pinPair "@baseboard_fab2_lib.baseboard_fab2(sch_1):\PP82\"
				( pinRef "@baseboard_fab2_lib.baseboard_fab2(sch_1):page29_i61:DMI_TX_DP(3)" )
				( pinRef "@baseboard_fab2_lib.baseboard_fab2(sch_1):page129_i35:A" )
				( attribute "RELATIVE_PROPAGATION_DELAY_SCOPE" "L"
					( Parent
						( matchGroupRef "@baseboard_fab2_lib.baseboard_fab2(sch_1):\MG_DMI_L0\" )
					)
					( Status sCSetFlattened )
					( Origin gBackEnd )
				)
				( attribute "RELATIVE_PROPAGATION_DELAY" ",5.00 MIL"
					( Parent
						( matchGroupRef "@baseboard_fab2_lib.baseboard_fab2(sch_1):\MG_DMI_L0\" )
					)
					( Units "uMatchProp" "ns" 1.000000)
					( Status sCSetFlattened )
					( Origin gBackEnd )
				)
			)
			( pinPair "@baseboard_fab2_lib.baseboard_fab2(sch_1):\PP83\"
				( pinRef "@baseboard_fab2_lib.baseboard_fab2(sch_1):page129_i35:B" )
				( pinRef "@baseboard_fab2_lib.baseboard_fab2(sch_1):page117_i9:DMI_RXP(3)" )
				( attribute "RELATIVE_PROPAGATION_DELAY_SCOPE" "L"
					( Parent
						( matchGroupRef "@baseboard_fab2_lib.baseboard_fab2(sch_1):\MG_DMI_L1\" )
					)
					( Status sCSetFlattened )
					( Origin gBackEnd )
				)
				( attribute "RELATIVE_PROPAGATION_DELAY" ",5.00 MIL"
					( Parent
						( matchGroupRef "@baseboard_fab2_lib.baseboard_fab2(sch_1):\MG_DMI_L1\" )
					)
					( Units "uMatchProp" "ns" 1.000000)
					( Status sCSetFlattened )
					( Origin gBackEnd )
				)
			)
			( pinPair "@baseboard_fab2_lib.baseboard_fab2(sch_1):\PP6065\"
				( pinRef "@baseboard_fab2_lib.baseboard_fab2(sch_1):page29_i61:DMI_TX_DP(3)" )
				( pinRef "@baseboard_fab2_lib.baseboard_fab2(sch_1):page117_i9:DMI_RXP(3)" )
				( attribute "PROPAGATION_DELAY_MAX" "15000.00 MIL"
					( Units "uMaxMinProp" "ns" 1.000000)
					( Status sCSetFlattened )
					( Origin gBackEnd )
				)
			)
			( pinPair "@baseboard_fab2_lib.baseboard_fab2(sch_1):\PP84\"
				( pinRef "@baseboard_fab2_lib.baseboard_fab2(sch_1):page116_i220:USB3_8_PCIE1_TXN" )
				( pinRef "@baseboard_fab2_lib.baseboard_fab2(sch_1):page185_i62:B" )
				( attribute "RELATIVE_PROPAGATION_DELAY_SCOPE" "L"
					( Parent
						( matchGroupRef "@baseboard_fab2_lib.baseboard_fab2(sch_1):\MG_PCIE_L0\" )
					)
					( Status sCSetFlattened )
					( Origin gBackEnd )
				)
				( attribute "RELATIVE_PROPAGATION_DELAY" ",5.00 MIL"
					( Parent
						( matchGroupRef "@baseboard_fab2_lib.baseboard_fab2(sch_1):\MG_PCIE_L0\" )
					)
					( Units "uMatchProp" "ns" 1.000000)
					( Status sCSetFlattened )
					( Origin gBackEnd )
				)
			)
			( pinPair "@baseboard_fab2_lib.baseboard_fab2(sch_1):\PP85\"
				( pinRef "@baseboard_fab2_lib.baseboard_fab2(sch_1):page185_i53:PETN1" )
				( pinRef "@baseboard_fab2_lib.baseboard_fab2(sch_1):page185_i62:A" )
				( attribute "RELATIVE_PROPAGATION_DELAY_SCOPE" "L"
					( Parent
						( matchGroupRef "@baseboard_fab2_lib.baseboard_fab2(sch_1):\MG_PCIE_L1\" )
					)
					( Status sCSetFlattened )
					( Origin gBackEnd )
				)
				( attribute "RELATIVE_PROPAGATION_DELAY" ",5.00 MIL"
					( Parent
						( matchGroupRef "@baseboard_fab2_lib.baseboard_fab2(sch_1):\MG_PCIE_L1\" )
					)
					( Units "uMatchProp" "ns" 1.000000)
					( Status sCSetFlattened )
					( Origin gBackEnd )
				)
			)
			( pinPair "@baseboard_fab2_lib.baseboard_fab2(sch_1):\PP6064\"
				( pinRef "@baseboard_fab2_lib.baseboard_fab2(sch_1):page185_i53:PETN1" )
				( pinRef "@baseboard_fab2_lib.baseboard_fab2(sch_1):page116_i220:USB3_8_PCIE1_TXN" )
				( attribute "PROPAGATION_DELAY_MIN" "3000.00 MIL"
					( Units "uMaxMinProp" "ns" 1.000000)
					( Status sCSetFlattened )
					( Origin gBackEnd )
				)
				( attribute "PROPAGATION_DELAY_MAX" "16000.00 MIL"
					( Units "uMaxMinProp" "ns" 1.000000)
					( Status sCSetFlattened )
					( Origin gBackEnd )
				)
			)
			( pinPair "@baseboard_fab2_lib.baseboard_fab2(sch_1):\PP86\"
				( pinRef "@baseboard_fab2_lib.baseboard_fab2(sch_1):page116_i220:USB3_8_PCIE1_TXP" )
				( pinRef "@baseboard_fab2_lib.baseboard_fab2(sch_1):page185_i63:B" )
				( attribute "RELATIVE_PROPAGATION_DELAY_SCOPE" "L"
					( Parent
						( matchGroupRef "@baseboard_fab2_lib.baseboard_fab2(sch_1):\MG_PCIE_L0\" )
					)
					( Status sCSetFlattened )
					( Origin gBackEnd )
				)
				( attribute "RELATIVE_PROPAGATION_DELAY" ",5.00 MIL"
					( Parent
						( matchGroupRef "@baseboard_fab2_lib.baseboard_fab2(sch_1):\MG_PCIE_L0\" )
					)
					( Units "uMatchProp" "ns" 1.000000)
					( Status sCSetFlattened )
					( Origin gBackEnd )
				)
			)
			( pinPair "@baseboard_fab2_lib.baseboard_fab2(sch_1):\PP87\"
				( pinRef "@baseboard_fab2_lib.baseboard_fab2(sch_1):page185_i53:PETP1" )
				( pinRef "@baseboard_fab2_lib.baseboard_fab2(sch_1):page185_i63:A" )
				( attribute "RELATIVE_PROPAGATION_DELAY_SCOPE" "L"
					( Parent
						( matchGroupRef "@baseboard_fab2_lib.baseboard_fab2(sch_1):\MG_PCIE_L1\" )
					)
					( Status sCSetFlattened )
					( Origin gBackEnd )
				)
				( attribute "RELATIVE_PROPAGATION_DELAY" ",5.00 MIL"
					( Parent
						( matchGroupRef "@baseboard_fab2_lib.baseboard_fab2(sch_1):\MG_PCIE_L1\" )
					)
					( Units "uMatchProp" "ns" 1.000000)
					( Status sCSetFlattened )
					( Origin gBackEnd )
				)
			)
			( pinPair "@baseboard_fab2_lib.baseboard_fab2(sch_1):\PP6067\"
				( pinRef "@baseboard_fab2_lib.baseboard_fab2(sch_1):page185_i53:PETP1" )
				( pinRef "@baseboard_fab2_lib.baseboard_fab2(sch_1):page116_i220:USB3_8_PCIE1_TXP" )
				( attribute "PROPAGATION_DELAY_MIN" "3000.00 MIL"
					( Units "uMaxMinProp" "ns" 1.000000)
					( Status sCSetFlattened )
					( Origin gBackEnd )
				)
				( attribute "PROPAGATION_DELAY_MAX" "16000.00 MIL"
					( Units "uMaxMinProp" "ns" 1.000000)
					( Status sCSetFlattened )
					( Origin gBackEnd )
				)
			)
			( pinPair "@baseboard_fab2_lib.baseboard_fab2(sch_1):\PP88\"
				( pinRef "@baseboard_fab2_lib.baseboard_fab2(sch_1):page116_i220:USB3_9_PCIE2_TXN" )
				( pinRef "@baseboard_fab2_lib.baseboard_fab2(sch_1):page185_i65:B" )
				( attribute "RELATIVE_PROPAGATION_DELAY_SCOPE" "L"
					( Parent
						( matchGroupRef "@baseboard_fab2_lib.baseboard_fab2(sch_1):\MG_PCIE_L0\" )
					)
					( Status sCSetFlattened )
					( Origin gBackEnd )
				)
				( attribute "RELATIVE_PROPAGATION_DELAY" ",5.00 MIL"
					( Parent
						( matchGroupRef "@baseboard_fab2_lib.baseboard_fab2(sch_1):\MG_PCIE_L0\" )
					)
					( Units "uMatchProp" "ns" 1.000000)
					( Status sCSetFlattened )
					( Origin gBackEnd )
				)
			)
			( pinPair "@baseboard_fab2_lib.baseboard_fab2(sch_1):\PP89\"
				( pinRef "@baseboard_fab2_lib.baseboard_fab2(sch_1):page185_i53:PETN2" )
				( pinRef "@baseboard_fab2_lib.baseboard_fab2(sch_1):page185_i65:A" )
				( attribute "RELATIVE_PROPAGATION_DELAY_SCOPE" "L"
					( Parent
						( matchGroupRef "@baseboard_fab2_lib.baseboard_fab2(sch_1):\MG_PCIE_L1\" )
					)
					( Status sCSetFlattened )
					( Origin gBackEnd )
				)
				( attribute "RELATIVE_PROPAGATION_DELAY" ",5.00 MIL"
					( Parent
						( matchGroupRef "@baseboard_fab2_lib.baseboard_fab2(sch_1):\MG_PCIE_L1\" )
					)
					( Units "uMatchProp" "ns" 1.000000)
					( Status sCSetFlattened )
					( Origin gBackEnd )
				)
			)
			( pinPair "@baseboard_fab2_lib.baseboard_fab2(sch_1):\PP6049\"
				( pinRef "@baseboard_fab2_lib.baseboard_fab2(sch_1):page185_i53:PETN2" )
				( pinRef "@baseboard_fab2_lib.baseboard_fab2(sch_1):page116_i220:USB3_9_PCIE2_TXN" )
				( attribute "PROPAGATION_DELAY_MIN" "3000.00 MIL"
					( Units "uMaxMinProp" "ns" 1.000000)
					( Status sCSetFlattened )
					( Origin gBackEnd )
				)
				( attribute "PROPAGATION_DELAY_MAX" "16000.00 MIL"
					( Units "uMaxMinProp" "ns" 1.000000)
					( Status sCSetFlattened )
					( Origin gBackEnd )
				)
			)
			( pinPair "@baseboard_fab2_lib.baseboard_fab2(sch_1):\PP90\"
				( pinRef "@baseboard_fab2_lib.baseboard_fab2(sch_1):page116_i220:USB3_9_PCIE2_TXP" )
				( pinRef "@baseboard_fab2_lib.baseboard_fab2(sch_1):page185_i64:B" )
				( attribute "RELATIVE_PROPAGATION_DELAY_SCOPE" "L"
					( Parent
						( matchGroupRef "@baseboard_fab2_lib.baseboard_fab2(sch_1):\MG_PCIE_L0\" )
					)
					( Status sCSetFlattened )
					( Origin gBackEnd )
				)
				( attribute "RELATIVE_PROPAGATION_DELAY" ",5.00 MIL"
					( Parent
						( matchGroupRef "@baseboard_fab2_lib.baseboard_fab2(sch_1):\MG_PCIE_L0\" )
					)
					( Units "uMatchProp" "ns" 1.000000)
					( Status sCSetFlattened )
					( Origin gBackEnd )
				)
			)
			( pinPair "@baseboard_fab2_lib.baseboard_fab2(sch_1):\PP91\"
				( pinRef "@baseboard_fab2_lib.baseboard_fab2(sch_1):page185_i53:PETP2" )
				( pinRef "@baseboard_fab2_lib.baseboard_fab2(sch_1):page185_i64:A" )
				( attribute "RELATIVE_PROPAGATION_DELAY_SCOPE" "L"
					( Parent
						( matchGroupRef "@baseboard_fab2_lib.baseboard_fab2(sch_1):\MG_PCIE_L1\" )
					)
					( Status sCSetFlattened )
					( Origin gBackEnd )
				)
				( attribute "RELATIVE_PROPAGATION_DELAY" ",5.00 MIL"
					( Parent
						( matchGroupRef "@baseboard_fab2_lib.baseboard_fab2(sch_1):\MG_PCIE_L1\" )
					)
					( Units "uMatchProp" "ns" 1.000000)
					( Status sCSetFlattened )
					( Origin gBackEnd )
				)
			)
			( pinPair "@baseboard_fab2_lib.baseboard_fab2(sch_1):\PP6074\"
				( pinRef "@baseboard_fab2_lib.baseboard_fab2(sch_1):page185_i53:PETP2" )
				( pinRef "@baseboard_fab2_lib.baseboard_fab2(sch_1):page116_i220:USB3_9_PCIE2_TXP" )
				( attribute "PROPAGATION_DELAY_MIN" "3000.00 MIL"
					( Units "uMaxMinProp" "ns" 1.000000)
					( Status sCSetFlattened )
					( Origin gBackEnd )
				)
				( attribute "PROPAGATION_DELAY_MAX" "16000.00 MIL"
					( Units "uMaxMinProp" "ns" 1.000000)
					( Status sCSetFlattened )
					( Origin gBackEnd )
				)
			)
			( pinPair "@baseboard_fab2_lib.baseboard_fab2(sch_1):\PP92\"
				( pinRef "@baseboard_fab2_lib.baseboard_fab2(sch_1):page116_i220:USB3_10_PCIE3_GBE_TXN" )
				( pinRef "@baseboard_fab2_lib.baseboard_fab2(sch_1):page185_i67:B" )
				( attribute "RELATIVE_PROPAGATION_DELAY_SCOPE" "L"
					( Parent
						( matchGroupRef "@baseboard_fab2_lib.baseboard_fab2(sch_1):\MG_PCIE_L0\" )
					)
					( Status sCSetFlattened )
					( Origin gBackEnd )
				)
				( attribute "RELATIVE_PROPAGATION_DELAY" ",5.00 MIL"
					( Parent
						( matchGroupRef "@baseboard_fab2_lib.baseboard_fab2(sch_1):\MG_PCIE_L0\" )
					)
					( Units "uMatchProp" "ns" 1.000000)
					( Status sCSetFlattened )
					( Origin gBackEnd )
				)
			)
			( pinPair "@baseboard_fab2_lib.baseboard_fab2(sch_1):\PP93\"
				( pinRef "@baseboard_fab2_lib.baseboard_fab2(sch_1):page185_i53:PETN3" )
				( pinRef "@baseboard_fab2_lib.baseboard_fab2(sch_1):page185_i67:A" )
				( attribute "RELATIVE_PROPAGATION_DELAY_SCOPE" "L"
					( Parent
						( matchGroupRef "@baseboard_fab2_lib.baseboard_fab2(sch_1):\MG_PCIE_L1\" )
					)
					( Status sCSetFlattened )
					( Origin gBackEnd )
				)
				( attribute "RELATIVE_PROPAGATION_DELAY" ",5.00 MIL"
					( Parent
						( matchGroupRef "@baseboard_fab2_lib.baseboard_fab2(sch_1):\MG_PCIE_L1\" )
					)
					( Units "uMatchProp" "ns" 1.000000)
					( Status sCSetFlattened )
					( Origin gBackEnd )
				)
			)
			( pinPair "@baseboard_fab2_lib.baseboard_fab2(sch_1):\PP6075\"
				( pinRef "@baseboard_fab2_lib.baseboard_fab2(sch_1):page185_i53:PETN3" )
				( pinRef "@baseboard_fab2_lib.baseboard_fab2(sch_1):page116_i220:USB3_10_PCIE3_GBE_TXN" )
				( attribute "PROPAGATION_DELAY_MIN" "3000.00 MIL"
					( Units "uMaxMinProp" "ns" 1.000000)
					( Status sCSetFlattened )
					( Origin gBackEnd )
				)
				( attribute "PROPAGATION_DELAY_MAX" "16000.00 MIL"
					( Units "uMaxMinProp" "ns" 1.000000)
					( Status sCSetFlattened )
					( Origin gBackEnd )
				)
			)
			( pinPair "@baseboard_fab2_lib.baseboard_fab2(sch_1):\PP94\"
				( pinRef "@baseboard_fab2_lib.baseboard_fab2(sch_1):page116_i220:USB3_10_PCIE3_GBE_TXP" )
				( pinRef "@baseboard_fab2_lib.baseboard_fab2(sch_1):page185_i66:B" )
				( attribute "RELATIVE_PROPAGATION_DELAY_SCOPE" "L"
					( Parent
						( matchGroupRef "@baseboard_fab2_lib.baseboard_fab2(sch_1):\MG_PCIE_L0\" )
					)
					( Status sCSetFlattened )
					( Origin gBackEnd )
				)
				( attribute "RELATIVE_PROPAGATION_DELAY" ",5.00 MIL"
					( Parent
						( matchGroupRef "@baseboard_fab2_lib.baseboard_fab2(sch_1):\MG_PCIE_L0\" )
					)
					( Units "uMatchProp" "ns" 1.000000)
					( Status sCSetFlattened )
					( Origin gBackEnd )
				)
			)
			( pinPair "@baseboard_fab2_lib.baseboard_fab2(sch_1):\PP95\"
				( pinRef "@baseboard_fab2_lib.baseboard_fab2(sch_1):page185_i53:PETP3" )
				( pinRef "@baseboard_fab2_lib.baseboard_fab2(sch_1):page185_i66:A" )
				( attribute "RELATIVE_PROPAGATION_DELAY_SCOPE" "L"
					( Parent
						( matchGroupRef "@baseboard_fab2_lib.baseboard_fab2(sch_1):\MG_PCIE_L1\" )
					)
					( Status sCSetFlattened )
					( Origin gBackEnd )
				)
				( attribute "RELATIVE_PROPAGATION_DELAY" ",5.00 MIL"
					( Parent
						( matchGroupRef "@baseboard_fab2_lib.baseboard_fab2(sch_1):\MG_PCIE_L1\" )
					)
					( Units "uMatchProp" "ns" 1.000000)
					( Status sCSetFlattened )
					( Origin gBackEnd )
				)
			)
			( pinPair "@baseboard_fab2_lib.baseboard_fab2(sch_1):\PP6073\"
				( pinRef "@baseboard_fab2_lib.baseboard_fab2(sch_1):page185_i53:PETP3" )
				( pinRef "@baseboard_fab2_lib.baseboard_fab2(sch_1):page116_i220:USB3_10_PCIE3_GBE_TXP" )
				( attribute "PROPAGATION_DELAY_MIN" "3000.00 MIL"
					( Units "uMaxMinProp" "ns" 1.000000)
					( Status sCSetFlattened )
					( Origin gBackEnd )
				)
				( attribute "PROPAGATION_DELAY_MAX" "16000.00 MIL"
					( Units "uMaxMinProp" "ns" 1.000000)
					( Status sCSetFlattened )
					( Origin gBackEnd )
				)
			)
			( pinPair "@baseboard_fab2_lib.baseboard_fab2(sch_1):\PP5686\"
				( pinRef "@baseboard_fab2_lib.baseboard_fab2(sch_1):page116_i220:USB3_7_PCIE0_TXN" )
				( pinRef "@baseboard_fab2_lib.baseboard_fab2(sch_1):page185_i98:A" )
			)
			( pinPair "@baseboard_fab2_lib.baseboard_fab2(sch_1):\PP5687\"
				( pinRef "@baseboard_fab2_lib.baseboard_fab2(sch_1):page185_i53:PETN0_SATA_AN" )
				( pinRef "@baseboard_fab2_lib.baseboard_fab2(sch_1):page185_i98:B" )
				( attribute "PROPAGATION_DELAY_MAX" "250.00 MIL"
					( Units "uMaxMinProp" "ns" 1.000000)
					( Origin gBackEnd )
				)
			)
			( pinPair "@baseboard_fab2_lib.baseboard_fab2(sch_1):\PP5688\"
				( pinRef "@baseboard_fab2_lib.baseboard_fab2(sch_1):page185_i53:PETN0_SATA_AN" )
				( pinRef "@baseboard_fab2_lib.baseboard_fab2(sch_1):page185_i97:B" )
			)
			( pinPair "@baseboard_fab2_lib.baseboard_fab2(sch_1):\PP5689\"
				( pinRef "@baseboard_fab2_lib.baseboard_fab2(sch_1):page116_i220:USB3_7_PCIE0_TXP" )
				( pinRef "@baseboard_fab2_lib.baseboard_fab2(sch_1):page185_i96:A" )
			)
			( pinPair "@baseboard_fab2_lib.baseboard_fab2(sch_1):\PP5690\"
				( pinRef "@baseboard_fab2_lib.baseboard_fab2(sch_1):page185_i53:PETP0_SATA_AP" )
				( pinRef "@baseboard_fab2_lib.baseboard_fab2(sch_1):page185_i96:B" )
				( attribute "PROPAGATION_DELAY_MAX" "250.00 MIL"
					( Units "uMaxMinProp" "ns" 1.000000)
					( Origin gBackEnd )
				)
			)
			( pinPair "@baseboard_fab2_lib.baseboard_fab2(sch_1):\PP5691\"
				( pinRef "@baseboard_fab2_lib.baseboard_fab2(sch_1):page185_i53:PETP0_SATA_AP" )
				( pinRef "@baseboard_fab2_lib.baseboard_fab2(sch_1):page185_i95:B" )
			)
			( pinPair "@baseboard_fab2_lib.baseboard_fab2(sch_1):\PP5367\"
				( pinRef "@baseboard_fab2_lib.baseboard_fab2(sch_1):page116_i220:USB3_8_PCIE1_RXP" )
				( pinRef "@baseboard_fab2_lib.baseboard_fab2(sch_1):page185_i53:PERP1" )
				( attribute "PROPAGATION_DELAY_MIN" "3000.00 MIL"
					( Units "uMaxMinProp" "ns" 1.000000)
					( Status sCSetFlattened )
					( Origin gBackEnd )
				)
				( attribute "PROPAGATION_DELAY_MAX" "16000.00 MIL"
					( Units "uMaxMinProp" "ns" 1.000000)
					( Status sCSetFlattened )
					( Origin gBackEnd )
				)
			)
			( pinPair "@baseboard_fab2_lib.baseboard_fab2(sch_1):\PP5370\"
				( pinRef "@baseboard_fab2_lib.baseboard_fab2(sch_1):page116_i220:USB3_8_PCIE1_RXN" )
				( pinRef "@baseboard_fab2_lib.baseboard_fab2(sch_1):page185_i53:PERN1" )
				( attribute "PROPAGATION_DELAY_MIN" "3000.00 MIL"
					( Units "uMaxMinProp" "ns" 1.000000)
					( Status sCSetFlattened )
					( Origin gBackEnd )
				)
				( attribute "PROPAGATION_DELAY_MAX" "16000.00 MIL"
					( Units "uMaxMinProp" "ns" 1.000000)
					( Status sCSetFlattened )
					( Origin gBackEnd )
				)
			)
			( pinPair "@baseboard_fab2_lib.baseboard_fab2(sch_1):\PP5368\"
				( pinRef "@baseboard_fab2_lib.baseboard_fab2(sch_1):page116_i220:USB3_9_PCIE2_RXP" )
				( pinRef "@baseboard_fab2_lib.baseboard_fab2(sch_1):page185_i53:PERP2" )
				( attribute "PROPAGATION_DELAY_MIN" "3000.00 MIL"
					( Units "uMaxMinProp" "ns" 1.000000)
					( Status sCSetFlattened )
					( Origin gBackEnd )
				)
				( attribute "PROPAGATION_DELAY_MAX" "16000.00 MIL"
					( Units "uMaxMinProp" "ns" 1.000000)
					( Status sCSetFlattened )
					( Origin gBackEnd )
				)
			)
			( pinPair "@baseboard_fab2_lib.baseboard_fab2(sch_1):\PP5371\"
				( pinRef "@baseboard_fab2_lib.baseboard_fab2(sch_1):page116_i220:USB3_9_PCIE2_RXN" )
				( pinRef "@baseboard_fab2_lib.baseboard_fab2(sch_1):page185_i53:PERN2" )
				( attribute "PROPAGATION_DELAY_MIN" "3000.00 MIL"
					( Units "uMaxMinProp" "ns" 1.000000)
					( Status sCSetFlattened )
					( Origin gBackEnd )
				)
				( attribute "PROPAGATION_DELAY_MAX" "16000.00 MIL"
					( Units "uMaxMinProp" "ns" 1.000000)
					( Status sCSetFlattened )
					( Origin gBackEnd )
				)
			)
			( pinPair "@baseboard_fab2_lib.baseboard_fab2(sch_1):\PP5369\"
				( pinRef "@baseboard_fab2_lib.baseboard_fab2(sch_1):page116_i220:USB3_10_PCIE3_GBE_RXP" )
				( pinRef "@baseboard_fab2_lib.baseboard_fab2(sch_1):page185_i53:PERP3" )
				( attribute "PROPAGATION_DELAY_MIN" "3000.00 MIL"
					( Units "uMaxMinProp" "ns" 1.000000)
					( Status sCSetFlattened )
					( Origin gBackEnd )
				)
				( attribute "PROPAGATION_DELAY_MAX" "16000.00 MIL"
					( Units "uMaxMinProp" "ns" 1.000000)
					( Status sCSetFlattened )
					( Origin gBackEnd )
				)
			)
			( pinPair "@baseboard_fab2_lib.baseboard_fab2(sch_1):\PP5372\"
				( pinRef "@baseboard_fab2_lib.baseboard_fab2(sch_1):page116_i220:USB3_10_PCIE3_GBE_RXN" )
				( pinRef "@baseboard_fab2_lib.baseboard_fab2(sch_1):page185_i53:PERN3" )
				( attribute "PROPAGATION_DELAY_MIN" "3000.00 MIL"
					( Units "uMaxMinProp" "ns" 1.000000)
					( Status sCSetFlattened )
					( Origin gBackEnd )
				)
				( attribute "PROPAGATION_DELAY_MAX" "16000.00 MIL"
					( Units "uMaxMinProp" "ns" 1.000000)
					( Status sCSetFlattened )
					( Origin gBackEnd )
				)
			)
			( pinPair "@baseboard_fab2_lib.baseboard_fab2(sch_1):\PP5684\"
				( pinRef "@baseboard_fab2_lib.baseboard_fab2(sch_1):page116_i220:USB3_7_PCIE0_RXN" )
				( pinRef "@baseboard_fab2_lib.baseboard_fab2(sch_1):page185_i106:A" )
			)
			( pinPair "@baseboard_fab2_lib.baseboard_fab2(sch_1):\PP5685\"
				( pinRef "@baseboard_fab2_lib.baseboard_fab2(sch_1):page116_i220:USB3_7_PCIE0_RXP" )
				( pinRef "@baseboard_fab2_lib.baseboard_fab2(sch_1):page185_i105:A" )
			)
			( pinPair "@baseboard_fab2_lib.baseboard_fab2(sch_1):\PP5499\"
				( pinRef "@baseboard_fab2_lib.baseboard_fab2(sch_1):page118_i73:PECI" )
				( pinRef "@baseboard_fab2_lib.baseboard_fab2(sch_1):page166_i15:A" )
				( attribute "PROPAGATION_DELAY_MAX" "2100.00 MIL"
					( Units "uMaxMinProp" "ns" 1.000000)
					( Origin gBackEnd )
				)
			)
			( pinPair "@baseboard_fab2_lib.baseboard_fab2(sch_1):\PP5696\"
				( pinRef "@baseboard_fab2_lib.baseboard_fab2(sch_1):page176_i69:STDA_SSTXN" )
				( pinRef "@baseboard_fab2_lib.baseboard_fab2(sch_1):page176_i62:\2\" )
				( attribute "PROPAGATION_DELAY_MAX" "500.00 MIL"
					( Units "uMaxMinProp" "ns" 1.000000)
					( Origin gBackEnd )
				)
			)
			( pinPair "@baseboard_fab2_lib.baseboard_fab2(sch_1):\PP5697\"
				( pinRef "@baseboard_fab2_lib.baseboard_fab2(sch_1):page176_i69:STDA_SSTXP" )
				( pinRef "@baseboard_fab2_lib.baseboard_fab2(sch_1):page176_i62:\3\" )
				( attribute "PROPAGATION_DELAY_MAX" "500.00 MIL"
					( Units "uMaxMinProp" "ns" 1.000000)
					( Origin gBackEnd )
				)
			)
			( pinPair "@baseboard_fab2_lib.baseboard_fab2(sch_1):\PP3143\"
				( pinRef "@baseboard_fab2_lib.baseboard_fab2(sch_1):page68_i125:UPI1_TX_DN(0)" )
				( pinRef "@baseboard_fab2_lib.baseboard_fab2(sch_1):page34_i86:UPI1_RX_DP(19)" )
				( attribute "RELATIVE_PROPAGATION_DELAY_SCOPE" "G"
					( Parent
						( matchGroupRef "@crescent_city_bb_fab1_lib.crescent_city_bb_fab1(sch_1):\MG_KTI_CPU1_CPU0_P1P1\" )
					)
					( Status sCSetFlattened )
					( Origin gBackEnd )
				)
				( attribute "RELATIVE_PROPAGATION_DELAY" "-1055.00 MIL,1055.00 MIL"
					( Parent
						( matchGroupRef "@crescent_city_bb_fab1_lib.crescent_city_bb_fab1(sch_1):\MG_KTI_CPU1_CPU0_P1P1\" )
					)
					( Units "uMatchProp" "ns" 1.000000)
					( Status sCSetFlattened )
					( Origin gBackEnd )
				)
				( attribute "RELATIVE_PROPAGATION_DELAY_SCOPE" "G"
					( Parent
						( matchGroupRef "@baseboard_fab2_lib.baseboard_fab2(sch_1):\MG_KTI_BUNDLE_NG_KTI_CPU1_CPU0_P1P1_0-1\" )
					)
					( Status sCSetFlattened )
					( Origin gBackEnd )
				)
				( attribute "RELATIVE_PROPAGATION_DELAY" ",500.00 MIL"
					( Parent
						( matchGroupRef "@baseboard_fab2_lib.baseboard_fab2(sch_1):\MG_KTI_BUNDLE_NG_KTI_CPU1_CPU0_P1P1_0-1\" )
					)
					( Units "uMatchProp" "ns" 1.000000)
					( Status sCSetFlattened )
					( Origin gBackEnd )
				)
			)
			( pinPair "@baseboard_fab2_lib.baseboard_fab2(sch_1):\PP3144\"
				( pinRef "@baseboard_fab2_lib.baseboard_fab2(sch_1):page68_i125:UPI1_TX_DP(0)" )
				( pinRef "@baseboard_fab2_lib.baseboard_fab2(sch_1):page34_i86:UPI1_RX_DN(19)" )
				( attribute "RELATIVE_PROPAGATION_DELAY_SCOPE" "G"
					( Parent
						( matchGroupRef "@crescent_city_bb_fab1_lib.crescent_city_bb_fab1(sch_1):\MG_KTI_CPU1_CPU0_P1P1\" )
					)
					( Status sCSetFlattened )
					( Origin gBackEnd )
				)
				( attribute "RELATIVE_PROPAGATION_DELAY" "-1055.00 MIL,1055.00 MIL"
					( Parent
						( matchGroupRef "@crescent_city_bb_fab1_lib.crescent_city_bb_fab1(sch_1):\MG_KTI_CPU1_CPU0_P1P1\" )
					)
					( Units "uMatchProp" "ns" 1.000000)
					( Status sCSetFlattened )
					( Origin gBackEnd )
				)
				( attribute "RELATIVE_PROPAGATION_DELAY_SCOPE" "G"
					( Parent
						( matchGroupRef "@baseboard_fab2_lib.baseboard_fab2(sch_1):\MG_KTI_BUNDLE_NG_KTI_CPU1_CPU0_P1P1_0-1\" )
					)
					( Status sCSetFlattened )
					( Origin gBackEnd )
				)
				( attribute "RELATIVE_PROPAGATION_DELAY" ",500.00 MIL"
					( Parent
						( matchGroupRef "@baseboard_fab2_lib.baseboard_fab2(sch_1):\MG_KTI_BUNDLE_NG_KTI_CPU1_CPU0_P1P1_0-1\" )
					)
					( Units "uMatchProp" "ns" 1.000000)
					( Status sCSetFlattened )
					( Origin gBackEnd )
				)
			)
			( pinPair "@baseboard_fab2_lib.baseboard_fab2(sch_1):\PP3145\"
				( pinRef "@baseboard_fab2_lib.baseboard_fab2(sch_1):page68_i125:UPI1_TX_DN(1)" )
				( pinRef "@baseboard_fab2_lib.baseboard_fab2(sch_1):page34_i86:UPI1_RX_DP(18)" )
				( attribute "RELATIVE_PROPAGATION_DELAY_SCOPE" "G"
					( Parent
						( matchGroupRef "@crescent_city_bb_fab1_lib.crescent_city_bb_fab1(sch_1):\MG_KTI_CPU1_CPU0_P1P1\" )
					)
					( Status sCSetFlattened )
					( Origin gBackEnd )
				)
				( attribute "RELATIVE_PROPAGATION_DELAY" "-1055.00 MIL,1055.00 MIL"
					( Parent
						( matchGroupRef "@crescent_city_bb_fab1_lib.crescent_city_bb_fab1(sch_1):\MG_KTI_CPU1_CPU0_P1P1\" )
					)
					( Units "uMatchProp" "ns" 1.000000)
					( Status sCSetFlattened )
					( Origin gBackEnd )
				)
				( attribute "RELATIVE_PROPAGATION_DELAY_SCOPE" "G"
					( Parent
						( matchGroupRef "@baseboard_fab2_lib.baseboard_fab2(sch_1):\MG_KTI_BUNDLE_NG_KTI_CPU1_CPU0_P1P1_0-1\" )
					)
					( Status sCSetFlattened )
					( Origin gBackEnd )
				)
				( attribute "RELATIVE_PROPAGATION_DELAY" ",500.00 MIL"
					( Parent
						( matchGroupRef "@baseboard_fab2_lib.baseboard_fab2(sch_1):\MG_KTI_BUNDLE_NG_KTI_CPU1_CPU0_P1P1_0-1\" )
					)
					( Units "uMatchProp" "ns" 1.000000)
					( Status sCSetFlattened )
					( Origin gBackEnd )
				)
			)
			( pinPair "@baseboard_fab2_lib.baseboard_fab2(sch_1):\PP3146\"
				( pinRef "@baseboard_fab2_lib.baseboard_fab2(sch_1):page68_i125:UPI1_TX_DP(1)" )
				( pinRef "@baseboard_fab2_lib.baseboard_fab2(sch_1):page34_i86:UPI1_RX_DN(18)" )
				( attribute "RELATIVE_PROPAGATION_DELAY_SCOPE" "G"
					( Parent
						( matchGroupRef "@crescent_city_bb_fab1_lib.crescent_city_bb_fab1(sch_1):\MG_KTI_CPU1_CPU0_P1P1\" )
					)
					( Status sCSetFlattened )
					( Origin gBackEnd )
				)
				( attribute "RELATIVE_PROPAGATION_DELAY" "-1055.00 MIL,1055.00 MIL"
					( Parent
						( matchGroupRef "@crescent_city_bb_fab1_lib.crescent_city_bb_fab1(sch_1):\MG_KTI_CPU1_CPU0_P1P1\" )
					)
					( Units "uMatchProp" "ns" 1.000000)
					( Status sCSetFlattened )
					( Origin gBackEnd )
				)
				( attribute "RELATIVE_PROPAGATION_DELAY_SCOPE" "G"
					( Parent
						( matchGroupRef "@baseboard_fab2_lib.baseboard_fab2(sch_1):\MG_KTI_BUNDLE_NG_KTI_CPU1_CPU0_P1P1_0-1\" )
					)
					( Status sCSetFlattened )
					( Origin gBackEnd )
				)
				( attribute "RELATIVE_PROPAGATION_DELAY" ",500.00 MIL"
					( Parent
						( matchGroupRef "@baseboard_fab2_lib.baseboard_fab2(sch_1):\MG_KTI_BUNDLE_NG_KTI_CPU1_CPU0_P1P1_0-1\" )
					)
					( Units "uMatchProp" "ns" 1.000000)
					( Status sCSetFlattened )
					( Origin gBackEnd )
				)
			)
			( pinPair "@baseboard_fab2_lib.baseboard_fab2(sch_1):\PP3139\"
				( pinRef "@baseboard_fab2_lib.baseboard_fab2(sch_1):page68_i125:UPI1_TX_DP(2)" )
				( pinRef "@baseboard_fab2_lib.baseboard_fab2(sch_1):page34_i86:UPI1_RX_DP(17)" )
				( attribute "RELATIVE_PROPAGATION_DELAY_SCOPE" "G"
					( Parent
						( matchGroupRef "@crescent_city_bb_fab1_lib.crescent_city_bb_fab1(sch_1):\MG_KTI_CPU1_CPU0_P1P1\" )
					)
					( Status sCSetFlattened )
					( Origin gBackEnd )
				)
				( attribute "RELATIVE_PROPAGATION_DELAY" "-1055.00 MIL,1055.00 MIL"
					( Parent
						( matchGroupRef "@crescent_city_bb_fab1_lib.crescent_city_bb_fab1(sch_1):\MG_KTI_CPU1_CPU0_P1P1\" )
					)
					( Units "uMatchProp" "ns" 1.000000)
					( Status sCSetFlattened )
					( Origin gBackEnd )
				)
				( attribute "RELATIVE_PROPAGATION_DELAY_SCOPE" "G"
					( Parent
						( matchGroupRef "@baseboard_fab2_lib.baseboard_fab2(sch_1):\MG_KTI_BUNDLE_NG_KTI_CPU1_CPU0_P1P1_2-3\" )
					)
					( Status sCSetFlattened )
					( Origin gBackEnd )
				)
				( attribute "RELATIVE_PROPAGATION_DELAY" ",500.00 MIL"
					( Parent
						( matchGroupRef "@baseboard_fab2_lib.baseboard_fab2(sch_1):\MG_KTI_BUNDLE_NG_KTI_CPU1_CPU0_P1P1_2-3\" )
					)
					( Units "uMatchProp" "ns" 1.000000)
					( Status sCSetFlattened )
					( Origin gBackEnd )
				)
			)
			( pinPair "@baseboard_fab2_lib.baseboard_fab2(sch_1):\PP3140\"
				( pinRef "@baseboard_fab2_lib.baseboard_fab2(sch_1):page68_i125:UPI1_TX_DN(2)" )
				( pinRef "@baseboard_fab2_lib.baseboard_fab2(sch_1):page34_i86:UPI1_RX_DN(17)" )
				( attribute "RELATIVE_PROPAGATION_DELAY_SCOPE" "G"
					( Parent
						( matchGroupRef "@crescent_city_bb_fab1_lib.crescent_city_bb_fab1(sch_1):\MG_KTI_CPU1_CPU0_P1P1\" )
					)
					( Status sCSetFlattened )
					( Origin gBackEnd )
				)
				( attribute "RELATIVE_PROPAGATION_DELAY" "-1055.00 MIL,1055.00 MIL"
					( Parent
						( matchGroupRef "@crescent_city_bb_fab1_lib.crescent_city_bb_fab1(sch_1):\MG_KTI_CPU1_CPU0_P1P1\" )
					)
					( Units "uMatchProp" "ns" 1.000000)
					( Status sCSetFlattened )
					( Origin gBackEnd )
				)
				( attribute "RELATIVE_PROPAGATION_DELAY_SCOPE" "G"
					( Parent
						( matchGroupRef "@baseboard_fab2_lib.baseboard_fab2(sch_1):\MG_KTI_BUNDLE_NG_KTI_CPU1_CPU0_P1P1_2-3\" )
					)
					( Status sCSetFlattened )
					( Origin gBackEnd )
				)
				( attribute "RELATIVE_PROPAGATION_DELAY" ",500.00 MIL"
					( Parent
						( matchGroupRef "@baseboard_fab2_lib.baseboard_fab2(sch_1):\MG_KTI_BUNDLE_NG_KTI_CPU1_CPU0_P1P1_2-3\" )
					)
					( Units "uMatchProp" "ns" 1.000000)
					( Status sCSetFlattened )
					( Origin gBackEnd )
				)
			)
			( pinPair "@baseboard_fab2_lib.baseboard_fab2(sch_1):\PP3141\"
				( pinRef "@baseboard_fab2_lib.baseboard_fab2(sch_1):page68_i125:UPI1_TX_DP(3)" )
				( pinRef "@baseboard_fab2_lib.baseboard_fab2(sch_1):page34_i86:UPI1_RX_DP(16)" )
				( attribute "RELATIVE_PROPAGATION_DELAY_SCOPE" "G"
					( Parent
						( matchGroupRef "@crescent_city_bb_fab1_lib.crescent_city_bb_fab1(sch_1):\MG_KTI_CPU1_CPU0_P1P1\" )
					)
					( Status sCSetFlattened )
					( Origin gBackEnd )
				)
				( attribute "RELATIVE_PROPAGATION_DELAY" "-1055.00 MIL,1055.00 MIL"
					( Parent
						( matchGroupRef "@crescent_city_bb_fab1_lib.crescent_city_bb_fab1(sch_1):\MG_KTI_CPU1_CPU0_P1P1\" )
					)
					( Units "uMatchProp" "ns" 1.000000)
					( Status sCSetFlattened )
					( Origin gBackEnd )
				)
				( attribute "RELATIVE_PROPAGATION_DELAY_SCOPE" "G"
					( Parent
						( matchGroupRef "@baseboard_fab2_lib.baseboard_fab2(sch_1):\MG_KTI_BUNDLE_NG_KTI_CPU1_CPU0_P1P1_2-3\" )
					)
					( Status sCSetFlattened )
					( Origin gBackEnd )
				)
				( attribute "RELATIVE_PROPAGATION_DELAY" ",500.00 MIL"
					( Parent
						( matchGroupRef "@baseboard_fab2_lib.baseboard_fab2(sch_1):\MG_KTI_BUNDLE_NG_KTI_CPU1_CPU0_P1P1_2-3\" )
					)
					( Units "uMatchProp" "ns" 1.000000)
					( Status sCSetFlattened )
					( Origin gBackEnd )
				)
			)
			( pinPair "@baseboard_fab2_lib.baseboard_fab2(sch_1):\PP3142\"
				( pinRef "@baseboard_fab2_lib.baseboard_fab2(sch_1):page68_i125:UPI1_TX_DN(3)" )
				( pinRef "@baseboard_fab2_lib.baseboard_fab2(sch_1):page34_i86:UPI1_RX_DN(16)" )
				( attribute "RELATIVE_PROPAGATION_DELAY_SCOPE" "G"
					( Parent
						( matchGroupRef "@crescent_city_bb_fab1_lib.crescent_city_bb_fab1(sch_1):\MG_KTI_CPU1_CPU0_P1P1\" )
					)
					( Status sCSetFlattened )
					( Origin gBackEnd )
				)
				( attribute "RELATIVE_PROPAGATION_DELAY" "-1055.00 MIL,1055.00 MIL"
					( Parent
						( matchGroupRef "@crescent_city_bb_fab1_lib.crescent_city_bb_fab1(sch_1):\MG_KTI_CPU1_CPU0_P1P1\" )
					)
					( Units "uMatchProp" "ns" 1.000000)
					( Status sCSetFlattened )
					( Origin gBackEnd )
				)
				( attribute "RELATIVE_PROPAGATION_DELAY_SCOPE" "G"
					( Parent
						( matchGroupRef "@baseboard_fab2_lib.baseboard_fab2(sch_1):\MG_KTI_BUNDLE_NG_KTI_CPU1_CPU0_P1P1_2-3\" )
					)
					( Status sCSetFlattened )
					( Origin gBackEnd )
				)
				( attribute "RELATIVE_PROPAGATION_DELAY" ",500.00 MIL"
					( Parent
						( matchGroupRef "@baseboard_fab2_lib.baseboard_fab2(sch_1):\MG_KTI_BUNDLE_NG_KTI_CPU1_CPU0_P1P1_2-3\" )
					)
					( Units "uMatchProp" "ns" 1.000000)
					( Status sCSetFlattened )
					( Origin gBackEnd )
				)
			)
			( pinPair "@baseboard_fab2_lib.baseboard_fab2(sch_1):\PP3135\"
				( pinRef "@baseboard_fab2_lib.baseboard_fab2(sch_1):page68_i125:UPI1_TX_DP(4)" )
				( pinRef "@baseboard_fab2_lib.baseboard_fab2(sch_1):page34_i86:UPI1_RX_DP(15)" )
				( attribute "RELATIVE_PROPAGATION_DELAY_SCOPE" "G"
					( Parent
						( matchGroupRef "@crescent_city_bb_fab1_lib.crescent_city_bb_fab1(sch_1):\MG_KTI_CPU1_CPU0_P1P1\" )
					)
					( Status sCSetFlattened )
					( Origin gBackEnd )
				)
				( attribute "RELATIVE_PROPAGATION_DELAY" "-1055.00 MIL,1055.00 MIL"
					( Parent
						( matchGroupRef "@crescent_city_bb_fab1_lib.crescent_city_bb_fab1(sch_1):\MG_KTI_CPU1_CPU0_P1P1\" )
					)
					( Units "uMatchProp" "ns" 1.000000)
					( Status sCSetFlattened )
					( Origin gBackEnd )
				)
				( attribute "RELATIVE_PROPAGATION_DELAY_SCOPE" "G"
					( Parent
						( matchGroupRef "@baseboard_fab2_lib.baseboard_fab2(sch_1):\MG_KTI_BUNDLE_NG_KTI_CPU1_CPU0_P1P1_4-5\" )
					)
					( Status sCSetFlattened )
					( Origin gBackEnd )
				)
				( attribute "RELATIVE_PROPAGATION_DELAY" ",500.00 MIL"
					( Parent
						( matchGroupRef "@baseboard_fab2_lib.baseboard_fab2(sch_1):\MG_KTI_BUNDLE_NG_KTI_CPU1_CPU0_P1P1_4-5\" )
					)
					( Units "uMatchProp" "ns" 1.000000)
					( Status sCSetFlattened )
					( Origin gBackEnd )
				)
			)
			( pinPair "@baseboard_fab2_lib.baseboard_fab2(sch_1):\PP3136\"
				( pinRef "@baseboard_fab2_lib.baseboard_fab2(sch_1):page68_i125:UPI1_TX_DN(4)" )
				( pinRef "@baseboard_fab2_lib.baseboard_fab2(sch_1):page34_i86:UPI1_RX_DN(15)" )
				( attribute "RELATIVE_PROPAGATION_DELAY_SCOPE" "G"
					( Parent
						( matchGroupRef "@crescent_city_bb_fab1_lib.crescent_city_bb_fab1(sch_1):\MG_KTI_CPU1_CPU0_P1P1\" )
					)
					( Status sCSetFlattened )
					( Origin gBackEnd )
				)
				( attribute "RELATIVE_PROPAGATION_DELAY" "-1055.00 MIL,1055.00 MIL"
					( Parent
						( matchGroupRef "@crescent_city_bb_fab1_lib.crescent_city_bb_fab1(sch_1):\MG_KTI_CPU1_CPU0_P1P1\" )
					)
					( Units "uMatchProp" "ns" 1.000000)
					( Status sCSetFlattened )
					( Origin gBackEnd )
				)
				( attribute "RELATIVE_PROPAGATION_DELAY_SCOPE" "G"
					( Parent
						( matchGroupRef "@baseboard_fab2_lib.baseboard_fab2(sch_1):\MG_KTI_BUNDLE_NG_KTI_CPU1_CPU0_P1P1_4-5\" )
					)
					( Status sCSetFlattened )
					( Origin gBackEnd )
				)
				( attribute "RELATIVE_PROPAGATION_DELAY" ",500.00 MIL"
					( Parent
						( matchGroupRef "@baseboard_fab2_lib.baseboard_fab2(sch_1):\MG_KTI_BUNDLE_NG_KTI_CPU1_CPU0_P1P1_4-5\" )
					)
					( Units "uMatchProp" "ns" 1.000000)
					( Status sCSetFlattened )
					( Origin gBackEnd )
				)
			)
			( pinPair "@baseboard_fab2_lib.baseboard_fab2(sch_1):\PP3137\"
				( pinRef "@baseboard_fab2_lib.baseboard_fab2(sch_1):page68_i125:UPI1_TX_DP(5)" )
				( pinRef "@baseboard_fab2_lib.baseboard_fab2(sch_1):page34_i86:UPI1_RX_DP(14)" )
				( attribute "RELATIVE_PROPAGATION_DELAY_SCOPE" "G"
					( Parent
						( matchGroupRef "@crescent_city_bb_fab1_lib.crescent_city_bb_fab1(sch_1):\MG_KTI_CPU1_CPU0_P1P1\" )
					)
					( Status sCSetFlattened )
					( Origin gBackEnd )
				)
				( attribute "RELATIVE_PROPAGATION_DELAY" "-1055.00 MIL,1055.00 MIL"
					( Parent
						( matchGroupRef "@crescent_city_bb_fab1_lib.crescent_city_bb_fab1(sch_1):\MG_KTI_CPU1_CPU0_P1P1\" )
					)
					( Units "uMatchProp" "ns" 1.000000)
					( Status sCSetFlattened )
					( Origin gBackEnd )
				)
				( attribute "RELATIVE_PROPAGATION_DELAY_SCOPE" "G"
					( Parent
						( matchGroupRef "@baseboard_fab2_lib.baseboard_fab2(sch_1):\MG_KTI_BUNDLE_NG_KTI_CPU1_CPU0_P1P1_4-5\" )
					)
					( Status sCSetFlattened )
					( Origin gBackEnd )
				)
				( attribute "RELATIVE_PROPAGATION_DELAY" ",500.00 MIL"
					( Parent
						( matchGroupRef "@baseboard_fab2_lib.baseboard_fab2(sch_1):\MG_KTI_BUNDLE_NG_KTI_CPU1_CPU0_P1P1_4-5\" )
					)
					( Units "uMatchProp" "ns" 1.000000)
					( Status sCSetFlattened )
					( Origin gBackEnd )
				)
			)
			( pinPair "@baseboard_fab2_lib.baseboard_fab2(sch_1):\PP3138\"
				( pinRef "@baseboard_fab2_lib.baseboard_fab2(sch_1):page68_i125:UPI1_TX_DN(5)" )
				( pinRef "@baseboard_fab2_lib.baseboard_fab2(sch_1):page34_i86:UPI1_RX_DN(14)" )
				( attribute "RELATIVE_PROPAGATION_DELAY_SCOPE" "G"
					( Parent
						( matchGroupRef "@crescent_city_bb_fab1_lib.crescent_city_bb_fab1(sch_1):\MG_KTI_CPU1_CPU0_P1P1\" )
					)
					( Status sCSetFlattened )
					( Origin gBackEnd )
				)
				( attribute "RELATIVE_PROPAGATION_DELAY" "-1055.00 MIL,1055.00 MIL"
					( Parent
						( matchGroupRef "@crescent_city_bb_fab1_lib.crescent_city_bb_fab1(sch_1):\MG_KTI_CPU1_CPU0_P1P1\" )
					)
					( Units "uMatchProp" "ns" 1.000000)
					( Status sCSetFlattened )
					( Origin gBackEnd )
				)
				( attribute "RELATIVE_PROPAGATION_DELAY_SCOPE" "G"
					( Parent
						( matchGroupRef "@baseboard_fab2_lib.baseboard_fab2(sch_1):\MG_KTI_BUNDLE_NG_KTI_CPU1_CPU0_P1P1_4-5\" )
					)
					( Status sCSetFlattened )
					( Origin gBackEnd )
				)
				( attribute "RELATIVE_PROPAGATION_DELAY" ",500.00 MIL"
					( Parent
						( matchGroupRef "@baseboard_fab2_lib.baseboard_fab2(sch_1):\MG_KTI_BUNDLE_NG_KTI_CPU1_CPU0_P1P1_4-5\" )
					)
					( Units "uMatchProp" "ns" 1.000000)
					( Status sCSetFlattened )
					( Origin gBackEnd )
				)
			)
			( pinPair "@baseboard_fab2_lib.baseboard_fab2(sch_1):\PP3131\"
				( pinRef "@baseboard_fab2_lib.baseboard_fab2(sch_1):page34_i86:UPI1_RX_DP(13)" )
				( pinRef "@baseboard_fab2_lib.baseboard_fab2(sch_1):page68_i125:UPI1_TX_DN(6)" )
				( attribute "RELATIVE_PROPAGATION_DELAY_SCOPE" "G"
					( Parent
						( matchGroupRef "@crescent_city_bb_fab1_lib.crescent_city_bb_fab1(sch_1):\MG_KTI_CPU1_CPU0_P1P1\" )
					)
					( Status sCSetFlattened )
					( Origin gBackEnd )
				)
				( attribute "RELATIVE_PROPAGATION_DELAY" "-1055.00 MIL,1055.00 MIL"
					( Parent
						( matchGroupRef "@crescent_city_bb_fab1_lib.crescent_city_bb_fab1(sch_1):\MG_KTI_CPU1_CPU0_P1P1\" )
					)
					( Units "uMatchProp" "ns" 1.000000)
					( Status sCSetFlattened )
					( Origin gBackEnd )
				)
				( attribute "RELATIVE_PROPAGATION_DELAY_SCOPE" "G"
					( Parent
						( matchGroupRef "@baseboard_fab2_lib.baseboard_fab2(sch_1):\MG_KTI_BUNDLE_NG_KTI_CPU1_CPU0_P1P1_6-7\" )
					)
					( Status sCSetFlattened )
					( Origin gBackEnd )
				)
				( attribute "RELATIVE_PROPAGATION_DELAY" ",500.00 MIL"
					( Parent
						( matchGroupRef "@baseboard_fab2_lib.baseboard_fab2(sch_1):\MG_KTI_BUNDLE_NG_KTI_CPU1_CPU0_P1P1_6-7\" )
					)
					( Units "uMatchProp" "ns" 1.000000)
					( Status sCSetFlattened )
					( Origin gBackEnd )
				)
			)
			( pinPair "@baseboard_fab2_lib.baseboard_fab2(sch_1):\PP3132\"
				( pinRef "@baseboard_fab2_lib.baseboard_fab2(sch_1):page34_i86:UPI1_RX_DN(13)" )
				( pinRef "@baseboard_fab2_lib.baseboard_fab2(sch_1):page68_i125:UPI1_TX_DP(6)" )
				( attribute "RELATIVE_PROPAGATION_DELAY_SCOPE" "G"
					( Parent
						( matchGroupRef "@crescent_city_bb_fab1_lib.crescent_city_bb_fab1(sch_1):\MG_KTI_CPU1_CPU0_P1P1\" )
					)
					( Status sCSetFlattened )
					( Origin gBackEnd )
				)
				( attribute "RELATIVE_PROPAGATION_DELAY" "-1055.00 MIL,1055.00 MIL"
					( Parent
						( matchGroupRef "@crescent_city_bb_fab1_lib.crescent_city_bb_fab1(sch_1):\MG_KTI_CPU1_CPU0_P1P1\" )
					)
					( Units "uMatchProp" "ns" 1.000000)
					( Status sCSetFlattened )
					( Origin gBackEnd )
				)
				( attribute "RELATIVE_PROPAGATION_DELAY_SCOPE" "G"
					( Parent
						( matchGroupRef "@baseboard_fab2_lib.baseboard_fab2(sch_1):\MG_KTI_BUNDLE_NG_KTI_CPU1_CPU0_P1P1_6-7\" )
					)
					( Status sCSetFlattened )
					( Origin gBackEnd )
				)
				( attribute "RELATIVE_PROPAGATION_DELAY" ",500.00 MIL"
					( Parent
						( matchGroupRef "@baseboard_fab2_lib.baseboard_fab2(sch_1):\MG_KTI_BUNDLE_NG_KTI_CPU1_CPU0_P1P1_6-7\" )
					)
					( Units "uMatchProp" "ns" 1.000000)
					( Status sCSetFlattened )
					( Origin gBackEnd )
				)
			)
			( pinPair "@baseboard_fab2_lib.baseboard_fab2(sch_1):\PP3133\"
				( pinRef "@baseboard_fab2_lib.baseboard_fab2(sch_1):page34_i86:UPI1_RX_DP(12)" )
				( pinRef "@baseboard_fab2_lib.baseboard_fab2(sch_1):page68_i125:UPI1_TX_DN(7)" )
				( attribute "RELATIVE_PROPAGATION_DELAY_SCOPE" "G"
					( Parent
						( matchGroupRef "@crescent_city_bb_fab1_lib.crescent_city_bb_fab1(sch_1):\MG_KTI_CPU1_CPU0_P1P1\" )
					)
					( Status sCSetFlattened )
					( Origin gBackEnd )
				)
				( attribute "RELATIVE_PROPAGATION_DELAY" "-1055.00 MIL,1055.00 MIL"
					( Parent
						( matchGroupRef "@crescent_city_bb_fab1_lib.crescent_city_bb_fab1(sch_1):\MG_KTI_CPU1_CPU0_P1P1\" )
					)
					( Units "uMatchProp" "ns" 1.000000)
					( Status sCSetFlattened )
					( Origin gBackEnd )
				)
				( attribute "RELATIVE_PROPAGATION_DELAY_SCOPE" "G"
					( Parent
						( matchGroupRef "@baseboard_fab2_lib.baseboard_fab2(sch_1):\MG_KTI_BUNDLE_NG_KTI_CPU1_CPU0_P1P1_6-7\" )
					)
					( Status sCSetFlattened )
					( Origin gBackEnd )
				)
				( attribute "RELATIVE_PROPAGATION_DELAY" ",500.00 MIL"
					( Parent
						( matchGroupRef "@baseboard_fab2_lib.baseboard_fab2(sch_1):\MG_KTI_BUNDLE_NG_KTI_CPU1_CPU0_P1P1_6-7\" )
					)
					( Units "uMatchProp" "ns" 1.000000)
					( Status sCSetFlattened )
					( Origin gBackEnd )
				)
			)
			( pinPair "@baseboard_fab2_lib.baseboard_fab2(sch_1):\PP3134\"
				( pinRef "@baseboard_fab2_lib.baseboard_fab2(sch_1):page34_i86:UPI1_RX_DN(12)" )
				( pinRef "@baseboard_fab2_lib.baseboard_fab2(sch_1):page68_i125:UPI1_TX_DP(7)" )
				( attribute "RELATIVE_PROPAGATION_DELAY_SCOPE" "G"
					( Parent
						( matchGroupRef "@crescent_city_bb_fab1_lib.crescent_city_bb_fab1(sch_1):\MG_KTI_CPU1_CPU0_P1P1\" )
					)
					( Status sCSetFlattened )
					( Origin gBackEnd )
				)
				( attribute "RELATIVE_PROPAGATION_DELAY" "-1055.00 MIL,1055.00 MIL"
					( Parent
						( matchGroupRef "@crescent_city_bb_fab1_lib.crescent_city_bb_fab1(sch_1):\MG_KTI_CPU1_CPU0_P1P1\" )
					)
					( Units "uMatchProp" "ns" 1.000000)
					( Status sCSetFlattened )
					( Origin gBackEnd )
				)
				( attribute "RELATIVE_PROPAGATION_DELAY_SCOPE" "G"
					( Parent
						( matchGroupRef "@baseboard_fab2_lib.baseboard_fab2(sch_1):\MG_KTI_BUNDLE_NG_KTI_CPU1_CPU0_P1P1_6-7\" )
					)
					( Status sCSetFlattened )
					( Origin gBackEnd )
				)
				( attribute "RELATIVE_PROPAGATION_DELAY" ",500.00 MIL"
					( Parent
						( matchGroupRef "@baseboard_fab2_lib.baseboard_fab2(sch_1):\MG_KTI_BUNDLE_NG_KTI_CPU1_CPU0_P1P1_6-7\" )
					)
					( Units "uMatchProp" "ns" 1.000000)
					( Status sCSetFlattened )
					( Origin gBackEnd )
				)
			)
			( pinPair "@baseboard_fab2_lib.baseboard_fab2(sch_1):\PP3127\"
				( pinRef "@baseboard_fab2_lib.baseboard_fab2(sch_1):page34_i86:UPI1_RX_DP(11)" )
				( pinRef "@baseboard_fab2_lib.baseboard_fab2(sch_1):page68_i125:UPI1_TX_DN(8)" )
				( attribute "RELATIVE_PROPAGATION_DELAY_SCOPE" "G"
					( Parent
						( matchGroupRef "@crescent_city_bb_fab1_lib.crescent_city_bb_fab1(sch_1):\MG_KTI_CPU1_CPU0_P1P1\" )
					)
					( Status sCSetFlattened )
					( Origin gBackEnd )
				)
				( attribute "RELATIVE_PROPAGATION_DELAY" "-1055.00 MIL,1055.00 MIL"
					( Parent
						( matchGroupRef "@crescent_city_bb_fab1_lib.crescent_city_bb_fab1(sch_1):\MG_KTI_CPU1_CPU0_P1P1\" )
					)
					( Units "uMatchProp" "ns" 1.000000)
					( Status sCSetFlattened )
					( Origin gBackEnd )
				)
				( attribute "RELATIVE_PROPAGATION_DELAY_SCOPE" "G"
					( Parent
						( matchGroupRef "@baseboard_fab2_lib.baseboard_fab2(sch_1):\MG_KTI_BUNDLE_NG_KTI_CPU1_CPU0_P1P1_8-9\" )
					)
					( Status sCSetFlattened )
					( Origin gBackEnd )
				)
				( attribute "RELATIVE_PROPAGATION_DELAY" ",500.00 MIL"
					( Parent
						( matchGroupRef "@baseboard_fab2_lib.baseboard_fab2(sch_1):\MG_KTI_BUNDLE_NG_KTI_CPU1_CPU0_P1P1_8-9\" )
					)
					( Units "uMatchProp" "ns" 1.000000)
					( Status sCSetFlattened )
					( Origin gBackEnd )
				)
			)
			( pinPair "@baseboard_fab2_lib.baseboard_fab2(sch_1):\PP3128\"
				( pinRef "@baseboard_fab2_lib.baseboard_fab2(sch_1):page34_i86:UPI1_RX_DN(11)" )
				( pinRef "@baseboard_fab2_lib.baseboard_fab2(sch_1):page68_i125:UPI1_TX_DP(8)" )
				( attribute "RELATIVE_PROPAGATION_DELAY_SCOPE" "G"
					( Parent
						( matchGroupRef "@crescent_city_bb_fab1_lib.crescent_city_bb_fab1(sch_1):\MG_KTI_CPU1_CPU0_P1P1\" )
					)
					( Status sCSetFlattened )
					( Origin gBackEnd )
				)
				( attribute "RELATIVE_PROPAGATION_DELAY" "-1055.00 MIL,1055.00 MIL"
					( Parent
						( matchGroupRef "@crescent_city_bb_fab1_lib.crescent_city_bb_fab1(sch_1):\MG_KTI_CPU1_CPU0_P1P1\" )
					)
					( Units "uMatchProp" "ns" 1.000000)
					( Status sCSetFlattened )
					( Origin gBackEnd )
				)
				( attribute "RELATIVE_PROPAGATION_DELAY_SCOPE" "G"
					( Parent
						( matchGroupRef "@baseboard_fab2_lib.baseboard_fab2(sch_1):\MG_KTI_BUNDLE_NG_KTI_CPU1_CPU0_P1P1_8-9\" )
					)
					( Status sCSetFlattened )
					( Origin gBackEnd )
				)
				( attribute "RELATIVE_PROPAGATION_DELAY" ",500.00 MIL"
					( Parent
						( matchGroupRef "@baseboard_fab2_lib.baseboard_fab2(sch_1):\MG_KTI_BUNDLE_NG_KTI_CPU1_CPU0_P1P1_8-9\" )
					)
					( Units "uMatchProp" "ns" 1.000000)
					( Status sCSetFlattened )
					( Origin gBackEnd )
				)
			)
			( pinPair "@baseboard_fab2_lib.baseboard_fab2(sch_1):\PP3129\"
				( pinRef "@baseboard_fab2_lib.baseboard_fab2(sch_1):page34_i86:UPI1_RX_DP(10)" )
				( pinRef "@baseboard_fab2_lib.baseboard_fab2(sch_1):page68_i125:UPI1_TX_DP(9)" )
				( attribute "RELATIVE_PROPAGATION_DELAY_SCOPE" "G"
					( Parent
						( matchGroupRef "@crescent_city_bb_fab1_lib.crescent_city_bb_fab1(sch_1):\MG_KTI_CPU1_CPU0_P1P1\" )
					)
					( Status sCSetFlattened )
					( Origin gBackEnd )
				)
				( attribute "RELATIVE_PROPAGATION_DELAY" "-1055.00 MIL,1055.00 MIL"
					( Parent
						( matchGroupRef "@crescent_city_bb_fab1_lib.crescent_city_bb_fab1(sch_1):\MG_KTI_CPU1_CPU0_P1P1\" )
					)
					( Units "uMatchProp" "ns" 1.000000)
					( Status sCSetFlattened )
					( Origin gBackEnd )
				)
				( attribute "RELATIVE_PROPAGATION_DELAY_SCOPE" "G"
					( Parent
						( matchGroupRef "@baseboard_fab2_lib.baseboard_fab2(sch_1):\MG_KTI_BUNDLE_NG_KTI_CPU1_CPU0_P1P1_8-9\" )
					)
					( Status sCSetFlattened )
					( Origin gBackEnd )
				)
				( attribute "RELATIVE_PROPAGATION_DELAY" ",500.00 MIL"
					( Parent
						( matchGroupRef "@baseboard_fab2_lib.baseboard_fab2(sch_1):\MG_KTI_BUNDLE_NG_KTI_CPU1_CPU0_P1P1_8-9\" )
					)
					( Units "uMatchProp" "ns" 1.000000)
					( Status sCSetFlattened )
					( Origin gBackEnd )
				)
			)
			( pinPair "@baseboard_fab2_lib.baseboard_fab2(sch_1):\PP3130\"
				( pinRef "@baseboard_fab2_lib.baseboard_fab2(sch_1):page34_i86:UPI1_RX_DN(10)" )
				( pinRef "@baseboard_fab2_lib.baseboard_fab2(sch_1):page68_i125:UPI1_TX_DN(9)" )
				( attribute "RELATIVE_PROPAGATION_DELAY_SCOPE" "G"
					( Parent
						( matchGroupRef "@crescent_city_bb_fab1_lib.crescent_city_bb_fab1(sch_1):\MG_KTI_CPU1_CPU0_P1P1\" )
					)
					( Status sCSetFlattened )
					( Origin gBackEnd )
				)
				( attribute "RELATIVE_PROPAGATION_DELAY" "-1055.00 MIL,1055.00 MIL"
					( Parent
						( matchGroupRef "@crescent_city_bb_fab1_lib.crescent_city_bb_fab1(sch_1):\MG_KTI_CPU1_CPU0_P1P1\" )
					)
					( Units "uMatchProp" "ns" 1.000000)
					( Status sCSetFlattened )
					( Origin gBackEnd )
				)
				( attribute "RELATIVE_PROPAGATION_DELAY_SCOPE" "G"
					( Parent
						( matchGroupRef "@baseboard_fab2_lib.baseboard_fab2(sch_1):\MG_KTI_BUNDLE_NG_KTI_CPU1_CPU0_P1P1_8-9\" )
					)
					( Status sCSetFlattened )
					( Origin gBackEnd )
				)
				( attribute "RELATIVE_PROPAGATION_DELAY" ",500.00 MIL"
					( Parent
						( matchGroupRef "@baseboard_fab2_lib.baseboard_fab2(sch_1):\MG_KTI_BUNDLE_NG_KTI_CPU1_CPU0_P1P1_8-9\" )
					)
					( Units "uMatchProp" "ns" 1.000000)
					( Status sCSetFlattened )
					( Origin gBackEnd )
				)
			)
			( pinPair "@baseboard_fab2_lib.baseboard_fab2(sch_1):\PP3123\"
				( pinRef "@baseboard_fab2_lib.baseboard_fab2(sch_1):page68_i125:UPI1_TX_DP(10)" )
				( pinRef "@baseboard_fab2_lib.baseboard_fab2(sch_1):page34_i86:UPI1_RX_DP(9)" )
				( attribute "RELATIVE_PROPAGATION_DELAY_SCOPE" "G"
					( Parent
						( matchGroupRef "@crescent_city_bb_fab1_lib.crescent_city_bb_fab1(sch_1):\MG_KTI_CPU1_CPU0_P1P1\" )
					)
					( Status sCSetFlattened )
					( Origin gBackEnd )
				)
				( attribute "RELATIVE_PROPAGATION_DELAY" "-1055.00 MIL,1055.00 MIL"
					( Parent
						( matchGroupRef "@crescent_city_bb_fab1_lib.crescent_city_bb_fab1(sch_1):\MG_KTI_CPU1_CPU0_P1P1\" )
					)
					( Units "uMatchProp" "ns" 1.000000)
					( Status sCSetFlattened )
					( Origin gBackEnd )
				)
				( attribute "RELATIVE_PROPAGATION_DELAY_SCOPE" "G"
					( Parent
						( matchGroupRef "@baseboard_fab2_lib.baseboard_fab2(sch_1):\MG_KTI_BUNDLE_NG_KTI_CPU1_CPU0_P1P1_10-11\" )
					)
					( Status sCSetFlattened )
					( Origin gBackEnd )
				)
				( attribute "RELATIVE_PROPAGATION_DELAY" ",500.00 MIL"
					( Parent
						( matchGroupRef "@baseboard_fab2_lib.baseboard_fab2(sch_1):\MG_KTI_BUNDLE_NG_KTI_CPU1_CPU0_P1P1_10-11\" )
					)
					( Units "uMatchProp" "ns" 1.000000)
					( Status sCSetFlattened )
					( Origin gBackEnd )
				)
			)
			( pinPair "@baseboard_fab2_lib.baseboard_fab2(sch_1):\PP3124\"
				( pinRef "@baseboard_fab2_lib.baseboard_fab2(sch_1):page68_i125:UPI1_TX_DN(10)" )
				( pinRef "@baseboard_fab2_lib.baseboard_fab2(sch_1):page34_i86:UPI1_RX_DN(9)" )
				( attribute "RELATIVE_PROPAGATION_DELAY_SCOPE" "G"
					( Parent
						( matchGroupRef "@crescent_city_bb_fab1_lib.crescent_city_bb_fab1(sch_1):\MG_KTI_CPU1_CPU0_P1P1\" )
					)
					( Status sCSetFlattened )
					( Origin gBackEnd )
				)
				( attribute "RELATIVE_PROPAGATION_DELAY" "-1055.00 MIL,1055.00 MIL"
					( Parent
						( matchGroupRef "@crescent_city_bb_fab1_lib.crescent_city_bb_fab1(sch_1):\MG_KTI_CPU1_CPU0_P1P1\" )
					)
					( Units "uMatchProp" "ns" 1.000000)
					( Status sCSetFlattened )
					( Origin gBackEnd )
				)
				( attribute "RELATIVE_PROPAGATION_DELAY_SCOPE" "G"
					( Parent
						( matchGroupRef "@baseboard_fab2_lib.baseboard_fab2(sch_1):\MG_KTI_BUNDLE_NG_KTI_CPU1_CPU0_P1P1_10-11\" )
					)
					( Status sCSetFlattened )
					( Origin gBackEnd )
				)
				( attribute "RELATIVE_PROPAGATION_DELAY" ",500.00 MIL"
					( Parent
						( matchGroupRef "@baseboard_fab2_lib.baseboard_fab2(sch_1):\MG_KTI_BUNDLE_NG_KTI_CPU1_CPU0_P1P1_10-11\" )
					)
					( Units "uMatchProp" "ns" 1.000000)
					( Status sCSetFlattened )
					( Origin gBackEnd )
				)
			)
			( pinPair "@baseboard_fab2_lib.baseboard_fab2(sch_1):\PP3125\"
				( pinRef "@baseboard_fab2_lib.baseboard_fab2(sch_1):page68_i125:UPI1_TX_DN(11)" )
				( pinRef "@baseboard_fab2_lib.baseboard_fab2(sch_1):page34_i86:UPI1_RX_DP(8)" )
				( attribute "RELATIVE_PROPAGATION_DELAY_SCOPE" "G"
					( Parent
						( matchGroupRef "@crescent_city_bb_fab1_lib.crescent_city_bb_fab1(sch_1):\MG_KTI_CPU1_CPU0_P1P1\" )
					)
					( Status sCSetFlattened )
					( Origin gBackEnd )
				)
				( attribute "RELATIVE_PROPAGATION_DELAY" "-1055.00 MIL,1055.00 MIL"
					( Parent
						( matchGroupRef "@crescent_city_bb_fab1_lib.crescent_city_bb_fab1(sch_1):\MG_KTI_CPU1_CPU0_P1P1\" )
					)
					( Units "uMatchProp" "ns" 1.000000)
					( Status sCSetFlattened )
					( Origin gBackEnd )
				)
				( attribute "RELATIVE_PROPAGATION_DELAY_SCOPE" "G"
					( Parent
						( matchGroupRef "@baseboard_fab2_lib.baseboard_fab2(sch_1):\MG_KTI_BUNDLE_NG_KTI_CPU1_CPU0_P1P1_10-11\" )
					)
					( Status sCSetFlattened )
					( Origin gBackEnd )
				)
				( attribute "RELATIVE_PROPAGATION_DELAY" ",500.00 MIL"
					( Parent
						( matchGroupRef "@baseboard_fab2_lib.baseboard_fab2(sch_1):\MG_KTI_BUNDLE_NG_KTI_CPU1_CPU0_P1P1_10-11\" )
					)
					( Units "uMatchProp" "ns" 1.000000)
					( Status sCSetFlattened )
					( Origin gBackEnd )
				)
			)
			( pinPair "@baseboard_fab2_lib.baseboard_fab2(sch_1):\PP3126\"
				( pinRef "@baseboard_fab2_lib.baseboard_fab2(sch_1):page68_i125:UPI1_TX_DP(11)" )
				( pinRef "@baseboard_fab2_lib.baseboard_fab2(sch_1):page34_i86:UPI1_RX_DN(8)" )
				( attribute "RELATIVE_PROPAGATION_DELAY_SCOPE" "G"
					( Parent
						( matchGroupRef "@crescent_city_bb_fab1_lib.crescent_city_bb_fab1(sch_1):\MG_KTI_CPU1_CPU0_P1P1\" )
					)
					( Status sCSetFlattened )
					( Origin gBackEnd )
				)
				( attribute "RELATIVE_PROPAGATION_DELAY" "-1055.00 MIL,1055.00 MIL"
					( Parent
						( matchGroupRef "@crescent_city_bb_fab1_lib.crescent_city_bb_fab1(sch_1):\MG_KTI_CPU1_CPU0_P1P1\" )
					)
					( Units "uMatchProp" "ns" 1.000000)
					( Status sCSetFlattened )
					( Origin gBackEnd )
				)
				( attribute "RELATIVE_PROPAGATION_DELAY_SCOPE" "G"
					( Parent
						( matchGroupRef "@baseboard_fab2_lib.baseboard_fab2(sch_1):\MG_KTI_BUNDLE_NG_KTI_CPU1_CPU0_P1P1_10-11\" )
					)
					( Status sCSetFlattened )
					( Origin gBackEnd )
				)
				( attribute "RELATIVE_PROPAGATION_DELAY" ",500.00 MIL"
					( Parent
						( matchGroupRef "@baseboard_fab2_lib.baseboard_fab2(sch_1):\MG_KTI_BUNDLE_NG_KTI_CPU1_CPU0_P1P1_10-11\" )
					)
					( Units "uMatchProp" "ns" 1.000000)
					( Status sCSetFlattened )
					( Origin gBackEnd )
				)
			)
			( pinPair "@baseboard_fab2_lib.baseboard_fab2(sch_1):\PP3119\"
				( pinRef "@baseboard_fab2_lib.baseboard_fab2(sch_1):page68_i125:UPI1_TX_DP(12)" )
				( pinRef "@baseboard_fab2_lib.baseboard_fab2(sch_1):page34_i86:UPI1_RX_DP(7)" )
				( attribute "RELATIVE_PROPAGATION_DELAY_SCOPE" "G"
					( Parent
						( matchGroupRef "@crescent_city_bb_fab1_lib.crescent_city_bb_fab1(sch_1):\MG_KTI_CPU1_CPU0_P1P1\" )
					)
					( Status sCSetFlattened )
					( Origin gBackEnd )
				)
				( attribute "RELATIVE_PROPAGATION_DELAY" "-1055.00 MIL,1055.00 MIL"
					( Parent
						( matchGroupRef "@crescent_city_bb_fab1_lib.crescent_city_bb_fab1(sch_1):\MG_KTI_CPU1_CPU0_P1P1\" )
					)
					( Units "uMatchProp" "ns" 1.000000)
					( Status sCSetFlattened )
					( Origin gBackEnd )
				)
				( attribute "RELATIVE_PROPAGATION_DELAY_SCOPE" "G"
					( Parent
						( matchGroupRef "@baseboard_fab2_lib.baseboard_fab2(sch_1):\MG_KTI_BUNDLE_NG_KTI_CPU1_CPU0_P1P1_12-13\" )
					)
					( Status sCSetFlattened )
					( Origin gBackEnd )
				)
				( attribute "RELATIVE_PROPAGATION_DELAY" ",500.00 MIL"
					( Parent
						( matchGroupRef "@baseboard_fab2_lib.baseboard_fab2(sch_1):\MG_KTI_BUNDLE_NG_KTI_CPU1_CPU0_P1P1_12-13\" )
					)
					( Units "uMatchProp" "ns" 1.000000)
					( Status sCSetFlattened )
					( Origin gBackEnd )
				)
			)
			( pinPair "@baseboard_fab2_lib.baseboard_fab2(sch_1):\PP3120\"
				( pinRef "@baseboard_fab2_lib.baseboard_fab2(sch_1):page68_i125:UPI1_TX_DN(12)" )
				( pinRef "@baseboard_fab2_lib.baseboard_fab2(sch_1):page34_i86:UPI1_RX_DN(7)" )
				( attribute "RELATIVE_PROPAGATION_DELAY_SCOPE" "G"
					( Parent
						( matchGroupRef "@crescent_city_bb_fab1_lib.crescent_city_bb_fab1(sch_1):\MG_KTI_CPU1_CPU0_P1P1\" )
					)
					( Status sCSetFlattened )
					( Origin gBackEnd )
				)
				( attribute "RELATIVE_PROPAGATION_DELAY" "-1055.00 MIL,1055.00 MIL"
					( Parent
						( matchGroupRef "@crescent_city_bb_fab1_lib.crescent_city_bb_fab1(sch_1):\MG_KTI_CPU1_CPU0_P1P1\" )
					)
					( Units "uMatchProp" "ns" 1.000000)
					( Status sCSetFlattened )
					( Origin gBackEnd )
				)
				( attribute "RELATIVE_PROPAGATION_DELAY_SCOPE" "G"
					( Parent
						( matchGroupRef "@baseboard_fab2_lib.baseboard_fab2(sch_1):\MG_KTI_BUNDLE_NG_KTI_CPU1_CPU0_P1P1_12-13\" )
					)
					( Status sCSetFlattened )
					( Origin gBackEnd )
				)
				( attribute "RELATIVE_PROPAGATION_DELAY" ",500.00 MIL"
					( Parent
						( matchGroupRef "@baseboard_fab2_lib.baseboard_fab2(sch_1):\MG_KTI_BUNDLE_NG_KTI_CPU1_CPU0_P1P1_12-13\" )
					)
					( Units "uMatchProp" "ns" 1.000000)
					( Status sCSetFlattened )
					( Origin gBackEnd )
				)
			)
			( pinPair "@baseboard_fab2_lib.baseboard_fab2(sch_1):\PP3121\"
				( pinRef "@baseboard_fab2_lib.baseboard_fab2(sch_1):page68_i125:UPI1_TX_DP(13)" )
				( pinRef "@baseboard_fab2_lib.baseboard_fab2(sch_1):page34_i86:UPI1_RX_DP(6)" )
				( attribute "RELATIVE_PROPAGATION_DELAY_SCOPE" "G"
					( Parent
						( matchGroupRef "@crescent_city_bb_fab1_lib.crescent_city_bb_fab1(sch_1):\MG_KTI_CPU1_CPU0_P1P1\" )
					)
					( Status sCSetFlattened )
					( Origin gBackEnd )
				)
				( attribute "RELATIVE_PROPAGATION_DELAY" "-1055.00 MIL,1055.00 MIL"
					( Parent
						( matchGroupRef "@crescent_city_bb_fab1_lib.crescent_city_bb_fab1(sch_1):\MG_KTI_CPU1_CPU0_P1P1\" )
					)
					( Units "uMatchProp" "ns" 1.000000)
					( Status sCSetFlattened )
					( Origin gBackEnd )
				)
				( attribute "RELATIVE_PROPAGATION_DELAY_SCOPE" "G"
					( Parent
						( matchGroupRef "@baseboard_fab2_lib.baseboard_fab2(sch_1):\MG_KTI_BUNDLE_NG_KTI_CPU1_CPU0_P1P1_12-13\" )
					)
					( Status sCSetFlattened )
					( Origin gBackEnd )
				)
				( attribute "RELATIVE_PROPAGATION_DELAY" ",500.00 MIL"
					( Parent
						( matchGroupRef "@baseboard_fab2_lib.baseboard_fab2(sch_1):\MG_KTI_BUNDLE_NG_KTI_CPU1_CPU0_P1P1_12-13\" )
					)
					( Units "uMatchProp" "ns" 1.000000)
					( Status sCSetFlattened )
					( Origin gBackEnd )
				)
			)
			( pinPair "@baseboard_fab2_lib.baseboard_fab2(sch_1):\PP3122\"
				( pinRef "@baseboard_fab2_lib.baseboard_fab2(sch_1):page68_i125:UPI1_TX_DN(13)" )
				( pinRef "@baseboard_fab2_lib.baseboard_fab2(sch_1):page34_i86:UPI1_RX_DN(6)" )
				( attribute "RELATIVE_PROPAGATION_DELAY_SCOPE" "G"
					( Parent
						( matchGroupRef "@crescent_city_bb_fab1_lib.crescent_city_bb_fab1(sch_1):\MG_KTI_CPU1_CPU0_P1P1\" )
					)
					( Status sCSetFlattened )
					( Origin gBackEnd )
				)
				( attribute "RELATIVE_PROPAGATION_DELAY" "-1055.00 MIL,1055.00 MIL"
					( Parent
						( matchGroupRef "@crescent_city_bb_fab1_lib.crescent_city_bb_fab1(sch_1):\MG_KTI_CPU1_CPU0_P1P1\" )
					)
					( Units "uMatchProp" "ns" 1.000000)
					( Status sCSetFlattened )
					( Origin gBackEnd )
				)
				( attribute "RELATIVE_PROPAGATION_DELAY_SCOPE" "G"
					( Parent
						( matchGroupRef "@baseboard_fab2_lib.baseboard_fab2(sch_1):\MG_KTI_BUNDLE_NG_KTI_CPU1_CPU0_P1P1_12-13\" )
					)
					( Status sCSetFlattened )
					( Origin gBackEnd )
				)
				( attribute "RELATIVE_PROPAGATION_DELAY" ",500.00 MIL"
					( Parent
						( matchGroupRef "@baseboard_fab2_lib.baseboard_fab2(sch_1):\MG_KTI_BUNDLE_NG_KTI_CPU1_CPU0_P1P1_12-13\" )
					)
					( Units "uMatchProp" "ns" 1.000000)
					( Status sCSetFlattened )
					( Origin gBackEnd )
				)
			)
			( pinPair "@baseboard_fab2_lib.baseboard_fab2(sch_1):\PP3115\"
				( pinRef "@baseboard_fab2_lib.baseboard_fab2(sch_1):page68_i125:UPI1_TX_DP(14)" )
				( pinRef "@baseboard_fab2_lib.baseboard_fab2(sch_1):page34_i86:UPI1_RX_DP(5)" )
				( attribute "RELATIVE_PROPAGATION_DELAY_SCOPE" "G"
					( Parent
						( matchGroupRef "@crescent_city_bb_fab1_lib.crescent_city_bb_fab1(sch_1):\MG_KTI_CPU1_CPU0_P1P1\" )
					)
					( Status sCSetFlattened )
					( Origin gBackEnd )
				)
				( attribute "RELATIVE_PROPAGATION_DELAY" "-1055.00 MIL,1055.00 MIL"
					( Parent
						( matchGroupRef "@crescent_city_bb_fab1_lib.crescent_city_bb_fab1(sch_1):\MG_KTI_CPU1_CPU0_P1P1\" )
					)
					( Units "uMatchProp" "ns" 1.000000)
					( Status sCSetFlattened )
					( Origin gBackEnd )
				)
				( attribute "RELATIVE_PROPAGATION_DELAY_SCOPE" "G"
					( Parent
						( matchGroupRef "@baseboard_fab2_lib.baseboard_fab2(sch_1):\MG_KTI_BUNDLE_NG_KTI_CPU1_CPU0_P1P1_14-15\" )
					)
					( Status sCSetFlattened )
					( Origin gBackEnd )
				)
				( attribute "RELATIVE_PROPAGATION_DELAY" ",500.00 MIL"
					( Parent
						( matchGroupRef "@baseboard_fab2_lib.baseboard_fab2(sch_1):\MG_KTI_BUNDLE_NG_KTI_CPU1_CPU0_P1P1_14-15\" )
					)
					( Units "uMatchProp" "ns" 1.000000)
					( Status sCSetFlattened )
					( Origin gBackEnd )
				)
			)
			( pinPair "@baseboard_fab2_lib.baseboard_fab2(sch_1):\PP3116\"
				( pinRef "@baseboard_fab2_lib.baseboard_fab2(sch_1):page68_i125:UPI1_TX_DN(14)" )
				( pinRef "@baseboard_fab2_lib.baseboard_fab2(sch_1):page34_i86:UPI1_RX_DN(5)" )
				( attribute "RELATIVE_PROPAGATION_DELAY_SCOPE" "G"
					( Parent
						( matchGroupRef "@crescent_city_bb_fab1_lib.crescent_city_bb_fab1(sch_1):\MG_KTI_CPU1_CPU0_P1P1\" )
					)
					( Status sCSetFlattened )
					( Origin gBackEnd )
				)
				( attribute "RELATIVE_PROPAGATION_DELAY" "-1055.00 MIL,1055.00 MIL"
					( Parent
						( matchGroupRef "@crescent_city_bb_fab1_lib.crescent_city_bb_fab1(sch_1):\MG_KTI_CPU1_CPU0_P1P1\" )
					)
					( Units "uMatchProp" "ns" 1.000000)
					( Status sCSetFlattened )
					( Origin gBackEnd )
				)
				( attribute "RELATIVE_PROPAGATION_DELAY_SCOPE" "G"
					( Parent
						( matchGroupRef "@baseboard_fab2_lib.baseboard_fab2(sch_1):\MG_KTI_BUNDLE_NG_KTI_CPU1_CPU0_P1P1_14-15\" )
					)
					( Status sCSetFlattened )
					( Origin gBackEnd )
				)
				( attribute "RELATIVE_PROPAGATION_DELAY" ",500.00 MIL"
					( Parent
						( matchGroupRef "@baseboard_fab2_lib.baseboard_fab2(sch_1):\MG_KTI_BUNDLE_NG_KTI_CPU1_CPU0_P1P1_14-15\" )
					)
					( Units "uMatchProp" "ns" 1.000000)
					( Status sCSetFlattened )
					( Origin gBackEnd )
				)
			)
			( pinPair "@baseboard_fab2_lib.baseboard_fab2(sch_1):\PP3117\"
				( pinRef "@baseboard_fab2_lib.baseboard_fab2(sch_1):page68_i125:UPI1_TX_DP(15)" )
				( pinRef "@baseboard_fab2_lib.baseboard_fab2(sch_1):page34_i86:UPI1_RX_DP(4)" )
				( attribute "RELATIVE_PROPAGATION_DELAY_SCOPE" "G"
					( Parent
						( matchGroupRef "@crescent_city_bb_fab1_lib.crescent_city_bb_fab1(sch_1):\MG_KTI_CPU1_CPU0_P1P1\" )
					)
					( Status sCSetFlattened )
					( Origin gBackEnd )
				)
				( attribute "RELATIVE_PROPAGATION_DELAY" "-1055.00 MIL,1055.00 MIL"
					( Parent
						( matchGroupRef "@crescent_city_bb_fab1_lib.crescent_city_bb_fab1(sch_1):\MG_KTI_CPU1_CPU0_P1P1\" )
					)
					( Units "uMatchProp" "ns" 1.000000)
					( Status sCSetFlattened )
					( Origin gBackEnd )
				)
				( attribute "RELATIVE_PROPAGATION_DELAY_SCOPE" "G"
					( Parent
						( matchGroupRef "@baseboard_fab2_lib.baseboard_fab2(sch_1):\MG_KTI_BUNDLE_NG_KTI_CPU1_CPU0_P1P1_14-15\" )
					)
					( Status sCSetFlattened )
					( Origin gBackEnd )
				)
				( attribute "RELATIVE_PROPAGATION_DELAY" ",500.00 MIL"
					( Parent
						( matchGroupRef "@baseboard_fab2_lib.baseboard_fab2(sch_1):\MG_KTI_BUNDLE_NG_KTI_CPU1_CPU0_P1P1_14-15\" )
					)
					( Units "uMatchProp" "ns" 1.000000)
					( Status sCSetFlattened )
					( Origin gBackEnd )
				)
			)
			( pinPair "@baseboard_fab2_lib.baseboard_fab2(sch_1):\PP3118\"
				( pinRef "@baseboard_fab2_lib.baseboard_fab2(sch_1):page68_i125:UPI1_TX_DN(15)" )
				( pinRef "@baseboard_fab2_lib.baseboard_fab2(sch_1):page34_i86:UPI1_RX_DN(4)" )
				( attribute "RELATIVE_PROPAGATION_DELAY_SCOPE" "G"
					( Parent
						( matchGroupRef "@crescent_city_bb_fab1_lib.crescent_city_bb_fab1(sch_1):\MG_KTI_CPU1_CPU0_P1P1\" )
					)
					( Status sCSetFlattened )
					( Origin gBackEnd )
				)
				( attribute "RELATIVE_PROPAGATION_DELAY" "-1055.00 MIL,1055.00 MIL"
					( Parent
						( matchGroupRef "@crescent_city_bb_fab1_lib.crescent_city_bb_fab1(sch_1):\MG_KTI_CPU1_CPU0_P1P1\" )
					)
					( Units "uMatchProp" "ns" 1.000000)
					( Status sCSetFlattened )
					( Origin gBackEnd )
				)
				( attribute "RELATIVE_PROPAGATION_DELAY_SCOPE" "G"
					( Parent
						( matchGroupRef "@baseboard_fab2_lib.baseboard_fab2(sch_1):\MG_KTI_BUNDLE_NG_KTI_CPU1_CPU0_P1P1_14-15\" )
					)
					( Status sCSetFlattened )
					( Origin gBackEnd )
				)
				( attribute "RELATIVE_PROPAGATION_DELAY" ",500.00 MIL"
					( Parent
						( matchGroupRef "@baseboard_fab2_lib.baseboard_fab2(sch_1):\MG_KTI_BUNDLE_NG_KTI_CPU1_CPU0_P1P1_14-15\" )
					)
					( Units "uMatchProp" "ns" 1.000000)
					( Status sCSetFlattened )
					( Origin gBackEnd )
				)
			)
			( pinPair "@baseboard_fab2_lib.baseboard_fab2(sch_1):\PP3111\"
				( pinRef "@baseboard_fab2_lib.baseboard_fab2(sch_1):page68_i125:UPI1_TX_DP(16)" )
				( pinRef "@baseboard_fab2_lib.baseboard_fab2(sch_1):page34_i86:UPI1_RX_DP(3)" )
				( attribute "RELATIVE_PROPAGATION_DELAY_SCOPE" "G"
					( Parent
						( matchGroupRef "@crescent_city_bb_fab1_lib.crescent_city_bb_fab1(sch_1):\MG_KTI_CPU1_CPU0_P1P1\" )
					)
					( Status sCSetFlattened )
					( Origin gBackEnd )
				)
				( attribute "RELATIVE_PROPAGATION_DELAY" "-1055.00 MIL,1055.00 MIL"
					( Parent
						( matchGroupRef "@crescent_city_bb_fab1_lib.crescent_city_bb_fab1(sch_1):\MG_KTI_CPU1_CPU0_P1P1\" )
					)
					( Units "uMatchProp" "ns" 1.000000)
					( Status sCSetFlattened )
					( Origin gBackEnd )
				)
				( attribute "RELATIVE_PROPAGATION_DELAY_SCOPE" "G"
					( Parent
						( matchGroupRef "@baseboard_fab2_lib.baseboard_fab2(sch_1):\MG_KTI_BUNDLE_NG_KTI_CPU1_CPU0_P1P1_16-17\" )
					)
					( Status sCSetFlattened )
					( Origin gBackEnd )
				)
				( attribute "RELATIVE_PROPAGATION_DELAY" ",500.00 MIL"
					( Parent
						( matchGroupRef "@baseboard_fab2_lib.baseboard_fab2(sch_1):\MG_KTI_BUNDLE_NG_KTI_CPU1_CPU0_P1P1_16-17\" )
					)
					( Units "uMatchProp" "ns" 1.000000)
					( Status sCSetFlattened )
					( Origin gBackEnd )
				)
			)
			( pinPair "@baseboard_fab2_lib.baseboard_fab2(sch_1):\PP3112\"
				( pinRef "@baseboard_fab2_lib.baseboard_fab2(sch_1):page68_i125:UPI1_TX_DN(16)" )
				( pinRef "@baseboard_fab2_lib.baseboard_fab2(sch_1):page34_i86:UPI1_RX_DN(3)" )
				( attribute "RELATIVE_PROPAGATION_DELAY_SCOPE" "G"
					( Parent
						( matchGroupRef "@crescent_city_bb_fab1_lib.crescent_city_bb_fab1(sch_1):\MG_KTI_CPU1_CPU0_P1P1\" )
					)
					( Status sCSetFlattened )
					( Origin gBackEnd )
				)
				( attribute "RELATIVE_PROPAGATION_DELAY" "-1055.00 MIL,1055.00 MIL"
					( Parent
						( matchGroupRef "@crescent_city_bb_fab1_lib.crescent_city_bb_fab1(sch_1):\MG_KTI_CPU1_CPU0_P1P1\" )
					)
					( Units "uMatchProp" "ns" 1.000000)
					( Status sCSetFlattened )
					( Origin gBackEnd )
				)
				( attribute "RELATIVE_PROPAGATION_DELAY_SCOPE" "G"
					( Parent
						( matchGroupRef "@baseboard_fab2_lib.baseboard_fab2(sch_1):\MG_KTI_BUNDLE_NG_KTI_CPU1_CPU0_P1P1_16-17\" )
					)
					( Status sCSetFlattened )
					( Origin gBackEnd )
				)
				( attribute "RELATIVE_PROPAGATION_DELAY" ",500.00 MIL"
					( Parent
						( matchGroupRef "@baseboard_fab2_lib.baseboard_fab2(sch_1):\MG_KTI_BUNDLE_NG_KTI_CPU1_CPU0_P1P1_16-17\" )
					)
					( Units "uMatchProp" "ns" 1.000000)
					( Status sCSetFlattened )
					( Origin gBackEnd )
				)
			)
			( pinPair "@baseboard_fab2_lib.baseboard_fab2(sch_1):\PP3113\"
				( pinRef "@baseboard_fab2_lib.baseboard_fab2(sch_1):page68_i125:UPI1_TX_DP(17)" )
				( pinRef "@baseboard_fab2_lib.baseboard_fab2(sch_1):page34_i86:UPI1_RX_DP(2)" )
				( attribute "RELATIVE_PROPAGATION_DELAY_SCOPE" "G"
					( Parent
						( matchGroupRef "@crescent_city_bb_fab1_lib.crescent_city_bb_fab1(sch_1):\MG_KTI_CPU1_CPU0_P1P1\" )
					)
					( Status sCSetFlattened )
					( Origin gBackEnd )
				)
				( attribute "RELATIVE_PROPAGATION_DELAY" "-1055.00 MIL,1055.00 MIL"
					( Parent
						( matchGroupRef "@crescent_city_bb_fab1_lib.crescent_city_bb_fab1(sch_1):\MG_KTI_CPU1_CPU0_P1P1\" )
					)
					( Units "uMatchProp" "ns" 1.000000)
					( Status sCSetFlattened )
					( Origin gBackEnd )
				)
				( attribute "RELATIVE_PROPAGATION_DELAY_SCOPE" "G"
					( Parent
						( matchGroupRef "@baseboard_fab2_lib.baseboard_fab2(sch_1):\MG_KTI_BUNDLE_NG_KTI_CPU1_CPU0_P1P1_16-17\" )
					)
					( Status sCSetFlattened )
					( Origin gBackEnd )
				)
				( attribute "RELATIVE_PROPAGATION_DELAY" ",500.00 MIL"
					( Parent
						( matchGroupRef "@baseboard_fab2_lib.baseboard_fab2(sch_1):\MG_KTI_BUNDLE_NG_KTI_CPU1_CPU0_P1P1_16-17\" )
					)
					( Units "uMatchProp" "ns" 1.000000)
					( Status sCSetFlattened )
					( Origin gBackEnd )
				)
			)
			( pinPair "@baseboard_fab2_lib.baseboard_fab2(sch_1):\PP3114\"
				( pinRef "@baseboard_fab2_lib.baseboard_fab2(sch_1):page68_i125:UPI1_TX_DN(17)" )
				( pinRef "@baseboard_fab2_lib.baseboard_fab2(sch_1):page34_i86:UPI1_RX_DN(2)" )
				( attribute "RELATIVE_PROPAGATION_DELAY_SCOPE" "G"
					( Parent
						( matchGroupRef "@crescent_city_bb_fab1_lib.crescent_city_bb_fab1(sch_1):\MG_KTI_CPU1_CPU0_P1P1\" )
					)
					( Status sCSetFlattened )
					( Origin gBackEnd )
				)
				( attribute "RELATIVE_PROPAGATION_DELAY" "-1055.00 MIL,1055.00 MIL"
					( Parent
						( matchGroupRef "@crescent_city_bb_fab1_lib.crescent_city_bb_fab1(sch_1):\MG_KTI_CPU1_CPU0_P1P1\" )
					)
					( Units "uMatchProp" "ns" 1.000000)
					( Status sCSetFlattened )
					( Origin gBackEnd )
				)
				( attribute "RELATIVE_PROPAGATION_DELAY_SCOPE" "G"
					( Parent
						( matchGroupRef "@baseboard_fab2_lib.baseboard_fab2(sch_1):\MG_KTI_BUNDLE_NG_KTI_CPU1_CPU0_P1P1_16-17\" )
					)
					( Status sCSetFlattened )
					( Origin gBackEnd )
				)
				( attribute "RELATIVE_PROPAGATION_DELAY" ",500.00 MIL"
					( Parent
						( matchGroupRef "@baseboard_fab2_lib.baseboard_fab2(sch_1):\MG_KTI_BUNDLE_NG_KTI_CPU1_CPU0_P1P1_16-17\" )
					)
					( Units "uMatchProp" "ns" 1.000000)
					( Status sCSetFlattened )
					( Origin gBackEnd )
				)
			)
			( pinPair "@baseboard_fab2_lib.baseboard_fab2(sch_1):\PP3107\"
				( pinRef "@baseboard_fab2_lib.baseboard_fab2(sch_1):page34_i86:UPI1_RX_DP(1)" )
				( pinRef "@baseboard_fab2_lib.baseboard_fab2(sch_1):page68_i125:UPI1_TX_DN(18)" )
				( attribute "RELATIVE_PROPAGATION_DELAY_SCOPE" "G"
					( Parent
						( matchGroupRef "@crescent_city_bb_fab1_lib.crescent_city_bb_fab1(sch_1):\MG_KTI_CPU1_CPU0_P1P1\" )
					)
					( Status sCSetFlattened )
					( Origin gBackEnd )
				)
				( attribute "RELATIVE_PROPAGATION_DELAY" "-1055.00 MIL,1055.00 MIL"
					( Parent
						( matchGroupRef "@crescent_city_bb_fab1_lib.crescent_city_bb_fab1(sch_1):\MG_KTI_CPU1_CPU0_P1P1\" )
					)
					( Units "uMatchProp" "ns" 1.000000)
					( Status sCSetFlattened )
					( Origin gBackEnd )
				)
				( attribute "RELATIVE_PROPAGATION_DELAY_SCOPE" "G"
					( Parent
						( matchGroupRef "@baseboard_fab2_lib.baseboard_fab2(sch_1):\MG_KTI_BUNDLE_NG_KTI_CPU1_CPU0_P1P1_18-19\" )
					)
					( Status sCSetFlattened )
					( Origin gBackEnd )
				)
				( attribute "RELATIVE_PROPAGATION_DELAY" ",500.00 MIL"
					( Parent
						( matchGroupRef "@baseboard_fab2_lib.baseboard_fab2(sch_1):\MG_KTI_BUNDLE_NG_KTI_CPU1_CPU0_P1P1_18-19\" )
					)
					( Units "uMatchProp" "ns" 1.000000)
					( Status sCSetFlattened )
					( Origin gBackEnd )
				)
			)
			( pinPair "@baseboard_fab2_lib.baseboard_fab2(sch_1):\PP3108\"
				( pinRef "@baseboard_fab2_lib.baseboard_fab2(sch_1):page34_i86:UPI1_RX_DN(1)" )
				( pinRef "@baseboard_fab2_lib.baseboard_fab2(sch_1):page68_i125:UPI1_TX_DP(18)" )
				( attribute "RELATIVE_PROPAGATION_DELAY_SCOPE" "G"
					( Parent
						( matchGroupRef "@crescent_city_bb_fab1_lib.crescent_city_bb_fab1(sch_1):\MG_KTI_CPU1_CPU0_P1P1\" )
					)
					( Status sCSetFlattened )
					( Origin gBackEnd )
				)
				( attribute "RELATIVE_PROPAGATION_DELAY" "-1055.00 MIL,1055.00 MIL"
					( Parent
						( matchGroupRef "@crescent_city_bb_fab1_lib.crescent_city_bb_fab1(sch_1):\MG_KTI_CPU1_CPU0_P1P1\" )
					)
					( Units "uMatchProp" "ns" 1.000000)
					( Status sCSetFlattened )
					( Origin gBackEnd )
				)
				( attribute "RELATIVE_PROPAGATION_DELAY_SCOPE" "G"
					( Parent
						( matchGroupRef "@baseboard_fab2_lib.baseboard_fab2(sch_1):\MG_KTI_BUNDLE_NG_KTI_CPU1_CPU0_P1P1_18-19\" )
					)
					( Status sCSetFlattened )
					( Origin gBackEnd )
				)
				( attribute "RELATIVE_PROPAGATION_DELAY" ",500.00 MIL"
					( Parent
						( matchGroupRef "@baseboard_fab2_lib.baseboard_fab2(sch_1):\MG_KTI_BUNDLE_NG_KTI_CPU1_CPU0_P1P1_18-19\" )
					)
					( Units "uMatchProp" "ns" 1.000000)
					( Status sCSetFlattened )
					( Origin gBackEnd )
				)
			)
			( pinPair "@baseboard_fab2_lib.baseboard_fab2(sch_1):\PP3109\"
				( pinRef "@baseboard_fab2_lib.baseboard_fab2(sch_1):page68_i125:UPI1_TX_DN(19)" )
				( pinRef "@baseboard_fab2_lib.baseboard_fab2(sch_1):page34_i86:UPI1_RX_DP(0)" )
				( attribute "RELATIVE_PROPAGATION_DELAY_SCOPE" "G"
					( Parent
						( matchGroupRef "@crescent_city_bb_fab1_lib.crescent_city_bb_fab1(sch_1):\MG_KTI_CPU1_CPU0_P1P1\" )
					)
					( Origin gBackEnd )
				)
				( attribute "RELATIVE_PROPAGATION_DELAY" "TARGET,TARGET"
					( Parent
						( matchGroupRef "@crescent_city_bb_fab1_lib.crescent_city_bb_fab1(sch_1):\MG_KTI_CPU1_CPU0_P1P1\" )
					)
					( Units "uMatchProp" "ns" 1.000000)
					( Origin gBackEnd )
				)
				( attribute "RELATIVE_PROPAGATION_DELAY_SCOPE" "G"
					( Parent
						( matchGroupRef "@baseboard_fab2_lib.baseboard_fab2(sch_1):\MG_KTI_BUNDLE_NG_KTI_CPU1_CPU0_P1P1_18-19\" )
					)
					( Status sCSetFlattened )
					( Origin gBackEnd )
				)
				( attribute "RELATIVE_PROPAGATION_DELAY" ",500.00 MIL"
					( Parent
						( matchGroupRef "@baseboard_fab2_lib.baseboard_fab2(sch_1):\MG_KTI_BUNDLE_NG_KTI_CPU1_CPU0_P1P1_18-19\" )
					)
					( Units "uMatchProp" "ns" 1.000000)
					( Status sCSetFlattened )
					( Origin gBackEnd )
				)
			)
			( pinPair "@baseboard_fab2_lib.baseboard_fab2(sch_1):\PP3110\"
				( pinRef "@baseboard_fab2_lib.baseboard_fab2(sch_1):page68_i125:UPI1_TX_DP(19)" )
				( pinRef "@baseboard_fab2_lib.baseboard_fab2(sch_1):page34_i86:UPI1_RX_DN(0)" )
				( attribute "RELATIVE_PROPAGATION_DELAY_SCOPE" "G"
					( Parent
						( matchGroupRef "@crescent_city_bb_fab1_lib.crescent_city_bb_fab1(sch_1):\MG_KTI_CPU1_CPU0_P1P1\" )
					)
					( Status sCSetFlattened )
					( Origin gBackEnd )
				)
				( attribute "RELATIVE_PROPAGATION_DELAY" "-1055.00 MIL,1055.00 MIL"
					( Parent
						( matchGroupRef "@crescent_city_bb_fab1_lib.crescent_city_bb_fab1(sch_1):\MG_KTI_CPU1_CPU0_P1P1\" )
					)
					( Units "uMatchProp" "ns" 1.000000)
					( Status sCSetFlattened )
					( Origin gBackEnd )
				)
				( attribute "RELATIVE_PROPAGATION_DELAY_SCOPE" "G"
					( Parent
						( matchGroupRef "@baseboard_fab2_lib.baseboard_fab2(sch_1):\MG_KTI_BUNDLE_NG_KTI_CPU1_CPU0_P1P1_18-19\" )
					)
					( Status sCSetFlattened )
					( Origin gBackEnd )
				)
				( attribute "RELATIVE_PROPAGATION_DELAY" ",500.00 MIL"
					( Parent
						( matchGroupRef "@baseboard_fab2_lib.baseboard_fab2(sch_1):\MG_KTI_BUNDLE_NG_KTI_CPU1_CPU0_P1P1_18-19\" )
					)
					( Units "uMatchProp" "ns" 1.000000)
					( Status sCSetFlattened )
					( Origin gBackEnd )
				)
			)
			( pinPair "@baseboard_fab2_lib.baseboard_fab2(sch_1):\PP3183\"
				( pinRef "@baseboard_fab2_lib.baseboard_fab2(sch_1):page67_i132:UPI0_TX_DN(0)" )
				( pinRef "@baseboard_fab2_lib.baseboard_fab2(sch_1):page33_i86:UPI0_RX_DP(19)" )
				( attribute "RELATIVE_PROPAGATION_DELAY_SCOPE" "G"
					( Parent
						( matchGroupRef "@crescent_city_bb_fab1_lib.crescent_city_bb_fab1(sch_1):\MG_KTI_CPU1_CPU0_P0P0\" )
					)
					( Status sCSetFlattened )
					( Origin gBackEnd )
				)
				( attribute "RELATIVE_PROPAGATION_DELAY" "-1315.00 MIL,1315.00 MIL"
					( Parent
						( matchGroupRef "@crescent_city_bb_fab1_lib.crescent_city_bb_fab1(sch_1):\MG_KTI_CPU1_CPU0_P0P0\" )
					)
					( Units "uMatchProp" "ns" 1.000000)
					( Status sCSetFlattened )
					( Origin gBackEnd )
				)
				( attribute "RELATIVE_PROPAGATION_DELAY_SCOPE" "G"
					( Parent
						( matchGroupRef "@baseboard_fab2_lib.baseboard_fab2(sch_1):\MG_KTI_BUNDLE_NG_KTI_CPU1_CPU0_P0P0_0-1\" )
					)
					( Status sCSetFlattened )
					( Origin gBackEnd )
				)
				( attribute "RELATIVE_PROPAGATION_DELAY" ",500.00 MIL"
					( Parent
						( matchGroupRef "@baseboard_fab2_lib.baseboard_fab2(sch_1):\MG_KTI_BUNDLE_NG_KTI_CPU1_CPU0_P0P0_0-1\" )
					)
					( Units "uMatchProp" "ns" 1.000000)
					( Status sCSetFlattened )
					( Origin gBackEnd )
				)
			)
			( pinPair "@baseboard_fab2_lib.baseboard_fab2(sch_1):\PP3184\"
				( pinRef "@baseboard_fab2_lib.baseboard_fab2(sch_1):page67_i132:UPI0_TX_DP(0)" )
				( pinRef "@baseboard_fab2_lib.baseboard_fab2(sch_1):page33_i86:UPI0_RX_DN(19)" )
				( attribute "RELATIVE_PROPAGATION_DELAY_SCOPE" "G"
					( Parent
						( matchGroupRef "@crescent_city_bb_fab1_lib.crescent_city_bb_fab1(sch_1):\MG_KTI_CPU1_CPU0_P0P0\" )
					)
					( Status sCSetFlattened )
					( Origin gBackEnd )
				)
				( attribute "RELATIVE_PROPAGATION_DELAY" "-1315.00 MIL,1315.00 MIL"
					( Parent
						( matchGroupRef "@crescent_city_bb_fab1_lib.crescent_city_bb_fab1(sch_1):\MG_KTI_CPU1_CPU0_P0P0\" )
					)
					( Units "uMatchProp" "ns" 1.000000)
					( Status sCSetFlattened )
					( Origin gBackEnd )
				)
				( attribute "RELATIVE_PROPAGATION_DELAY_SCOPE" "G"
					( Parent
						( matchGroupRef "@baseboard_fab2_lib.baseboard_fab2(sch_1):\MG_KTI_BUNDLE_NG_KTI_CPU1_CPU0_P0P0_0-1\" )
					)
					( Status sCSetFlattened )
					( Origin gBackEnd )
				)
				( attribute "RELATIVE_PROPAGATION_DELAY" ",500.00 MIL"
					( Parent
						( matchGroupRef "@baseboard_fab2_lib.baseboard_fab2(sch_1):\MG_KTI_BUNDLE_NG_KTI_CPU1_CPU0_P0P0_0-1\" )
					)
					( Units "uMatchProp" "ns" 1.000000)
					( Status sCSetFlattened )
					( Origin gBackEnd )
				)
			)
			( pinPair "@baseboard_fab2_lib.baseboard_fab2(sch_1):\PP3185\"
				( pinRef "@baseboard_fab2_lib.baseboard_fab2(sch_1):page67_i132:UPI0_TX_DN(1)" )
				( pinRef "@baseboard_fab2_lib.baseboard_fab2(sch_1):page33_i86:UPI0_RX_DP(18)" )
				( attribute "RELATIVE_PROPAGATION_DELAY_SCOPE" "G"
					( Parent
						( matchGroupRef "@crescent_city_bb_fab1_lib.crescent_city_bb_fab1(sch_1):\MG_KTI_CPU1_CPU0_P0P0\" )
					)
					( Status sCSetFlattened )
					( Origin gBackEnd )
				)
				( attribute "RELATIVE_PROPAGATION_DELAY" "-1315.00 MIL,1315.00 MIL"
					( Parent
						( matchGroupRef "@crescent_city_bb_fab1_lib.crescent_city_bb_fab1(sch_1):\MG_KTI_CPU1_CPU0_P0P0\" )
					)
					( Units "uMatchProp" "ns" 1.000000)
					( Status sCSetFlattened )
					( Origin gBackEnd )
				)
				( attribute "RELATIVE_PROPAGATION_DELAY_SCOPE" "G"
					( Parent
						( matchGroupRef "@baseboard_fab2_lib.baseboard_fab2(sch_1):\MG_KTI_BUNDLE_NG_KTI_CPU1_CPU0_P0P0_0-1\" )
					)
					( Status sCSetFlattened )
					( Origin gBackEnd )
				)
				( attribute "RELATIVE_PROPAGATION_DELAY" ",500.00 MIL"
					( Parent
						( matchGroupRef "@baseboard_fab2_lib.baseboard_fab2(sch_1):\MG_KTI_BUNDLE_NG_KTI_CPU1_CPU0_P0P0_0-1\" )
					)
					( Units "uMatchProp" "ns" 1.000000)
					( Status sCSetFlattened )
					( Origin gBackEnd )
				)
			)
			( pinPair "@baseboard_fab2_lib.baseboard_fab2(sch_1):\PP3186\"
				( pinRef "@baseboard_fab2_lib.baseboard_fab2(sch_1):page67_i132:UPI0_TX_DP(1)" )
				( pinRef "@baseboard_fab2_lib.baseboard_fab2(sch_1):page33_i86:UPI0_RX_DN(18)" )
				( attribute "RELATIVE_PROPAGATION_DELAY_SCOPE" "G"
					( Parent
						( matchGroupRef "@crescent_city_bb_fab1_lib.crescent_city_bb_fab1(sch_1):\MG_KTI_CPU1_CPU0_P0P0\" )
					)
					( Status sCSetFlattened )
					( Origin gBackEnd )
				)
				( attribute "RELATIVE_PROPAGATION_DELAY" "-1315.00 MIL,1315.00 MIL"
					( Parent
						( matchGroupRef "@crescent_city_bb_fab1_lib.crescent_city_bb_fab1(sch_1):\MG_KTI_CPU1_CPU0_P0P0\" )
					)
					( Units "uMatchProp" "ns" 1.000000)
					( Status sCSetFlattened )
					( Origin gBackEnd )
				)
				( attribute "RELATIVE_PROPAGATION_DELAY_SCOPE" "G"
					( Parent
						( matchGroupRef "@baseboard_fab2_lib.baseboard_fab2(sch_1):\MG_KTI_BUNDLE_NG_KTI_CPU1_CPU0_P0P0_0-1\" )
					)
					( Status sCSetFlattened )
					( Origin gBackEnd )
				)
				( attribute "RELATIVE_PROPAGATION_DELAY" ",500.00 MIL"
					( Parent
						( matchGroupRef "@baseboard_fab2_lib.baseboard_fab2(sch_1):\MG_KTI_BUNDLE_NG_KTI_CPU1_CPU0_P0P0_0-1\" )
					)
					( Units "uMatchProp" "ns" 1.000000)
					( Status sCSetFlattened )
					( Origin gBackEnd )
				)
			)
			( pinPair "@baseboard_fab2_lib.baseboard_fab2(sch_1):\PP3179\"
				( pinRef "@baseboard_fab2_lib.baseboard_fab2(sch_1):page67_i132:UPI0_TX_DP(2)" )
				( pinRef "@baseboard_fab2_lib.baseboard_fab2(sch_1):page33_i86:UPI0_RX_DP(17)" )
				( attribute "RELATIVE_PROPAGATION_DELAY_SCOPE" "G"
					( Parent
						( matchGroupRef "@crescent_city_bb_fab1_lib.crescent_city_bb_fab1(sch_1):\MG_KTI_CPU1_CPU0_P0P0\" )
					)
					( Status sCSetFlattened )
					( Origin gBackEnd )
				)
				( attribute "RELATIVE_PROPAGATION_DELAY" "-1315.00 MIL,1315.00 MIL"
					( Parent
						( matchGroupRef "@crescent_city_bb_fab1_lib.crescent_city_bb_fab1(sch_1):\MG_KTI_CPU1_CPU0_P0P0\" )
					)
					( Units "uMatchProp" "ns" 1.000000)
					( Status sCSetFlattened )
					( Origin gBackEnd )
				)
				( attribute "RELATIVE_PROPAGATION_DELAY_SCOPE" "G"
					( Parent
						( matchGroupRef "@baseboard_fab2_lib.baseboard_fab2(sch_1):\MG_KTI_BUNDLE_NG_KTI_CPU1_CPU0_P0P0_2-3\" )
					)
					( Status sCSetFlattened )
					( Origin gBackEnd )
				)
				( attribute "RELATIVE_PROPAGATION_DELAY" ",500.00 MIL"
					( Parent
						( matchGroupRef "@baseboard_fab2_lib.baseboard_fab2(sch_1):\MG_KTI_BUNDLE_NG_KTI_CPU1_CPU0_P0P0_2-3\" )
					)
					( Units "uMatchProp" "ns" 1.000000)
					( Status sCSetFlattened )
					( Origin gBackEnd )
				)
			)
			( pinPair "@baseboard_fab2_lib.baseboard_fab2(sch_1):\PP3180\"
				( pinRef "@baseboard_fab2_lib.baseboard_fab2(sch_1):page33_i86:UPI0_RX_DN(17)" )
				( pinRef "@baseboard_fab2_lib.baseboard_fab2(sch_1):page67_i132:UPI0_TX_DN(2)" )
				( attribute "RELATIVE_PROPAGATION_DELAY_SCOPE" "G"
					( Parent
						( matchGroupRef "@crescent_city_bb_fab1_lib.crescent_city_bb_fab1(sch_1):\MG_KTI_CPU1_CPU0_P0P0\" )
					)
					( Status sCSetFlattened )
					( Origin gBackEnd )
				)
				( attribute "RELATIVE_PROPAGATION_DELAY" "-1315.00 MIL,1315.00 MIL"
					( Parent
						( matchGroupRef "@crescent_city_bb_fab1_lib.crescent_city_bb_fab1(sch_1):\MG_KTI_CPU1_CPU0_P0P0\" )
					)
					( Units "uMatchProp" "ns" 1.000000)
					( Status sCSetFlattened )
					( Origin gBackEnd )
				)
				( attribute "RELATIVE_PROPAGATION_DELAY_SCOPE" "G"
					( Parent
						( matchGroupRef "@baseboard_fab2_lib.baseboard_fab2(sch_1):\MG_KTI_BUNDLE_NG_KTI_CPU1_CPU0_P0P0_2-3\" )
					)
					( Status sCSetFlattened )
					( Origin gBackEnd )
				)
				( attribute "RELATIVE_PROPAGATION_DELAY" ",500.00 MIL"
					( Parent
						( matchGroupRef "@baseboard_fab2_lib.baseboard_fab2(sch_1):\MG_KTI_BUNDLE_NG_KTI_CPU1_CPU0_P0P0_2-3\" )
					)
					( Units "uMatchProp" "ns" 1.000000)
					( Status sCSetFlattened )
					( Origin gBackEnd )
				)
			)
			( pinPair "@baseboard_fab2_lib.baseboard_fab2(sch_1):\PP3181\"
				( pinRef "@baseboard_fab2_lib.baseboard_fab2(sch_1):page33_i86:UPI0_RX_DP(16)" )
				( pinRef "@baseboard_fab2_lib.baseboard_fab2(sch_1):page67_i132:UPI0_TX_DP(3)" )
				( attribute "RELATIVE_PROPAGATION_DELAY_SCOPE" "G"
					( Parent
						( matchGroupRef "@crescent_city_bb_fab1_lib.crescent_city_bb_fab1(sch_1):\MG_KTI_CPU1_CPU0_P0P0\" )
					)
					( Status sCSetFlattened )
					( Origin gBackEnd )
				)
				( attribute "RELATIVE_PROPAGATION_DELAY" "-1315.00 MIL,1315.00 MIL"
					( Parent
						( matchGroupRef "@crescent_city_bb_fab1_lib.crescent_city_bb_fab1(sch_1):\MG_KTI_CPU1_CPU0_P0P0\" )
					)
					( Units "uMatchProp" "ns" 1.000000)
					( Status sCSetFlattened )
					( Origin gBackEnd )
				)
				( attribute "RELATIVE_PROPAGATION_DELAY_SCOPE" "G"
					( Parent
						( matchGroupRef "@baseboard_fab2_lib.baseboard_fab2(sch_1):\MG_KTI_BUNDLE_NG_KTI_CPU1_CPU0_P0P0_2-3\" )
					)
					( Status sCSetFlattened )
					( Origin gBackEnd )
				)
				( attribute "RELATIVE_PROPAGATION_DELAY" ",500.00 MIL"
					( Parent
						( matchGroupRef "@baseboard_fab2_lib.baseboard_fab2(sch_1):\MG_KTI_BUNDLE_NG_KTI_CPU1_CPU0_P0P0_2-3\" )
					)
					( Units "uMatchProp" "ns" 1.000000)
					( Status sCSetFlattened )
					( Origin gBackEnd )
				)
			)
			( pinPair "@baseboard_fab2_lib.baseboard_fab2(sch_1):\PP3182\"
				( pinRef "@baseboard_fab2_lib.baseboard_fab2(sch_1):page33_i86:UPI0_RX_DN(16)" )
				( pinRef "@baseboard_fab2_lib.baseboard_fab2(sch_1):page67_i132:UPI0_TX_DN(3)" )
				( attribute "RELATIVE_PROPAGATION_DELAY_SCOPE" "G"
					( Parent
						( matchGroupRef "@crescent_city_bb_fab1_lib.crescent_city_bb_fab1(sch_1):\MG_KTI_CPU1_CPU0_P0P0\" )
					)
					( Status sCSetFlattened )
					( Origin gBackEnd )
				)
				( attribute "RELATIVE_PROPAGATION_DELAY" "-1315.00 MIL,1315.00 MIL"
					( Parent
						( matchGroupRef "@crescent_city_bb_fab1_lib.crescent_city_bb_fab1(sch_1):\MG_KTI_CPU1_CPU0_P0P0\" )
					)
					( Units "uMatchProp" "ns" 1.000000)
					( Status sCSetFlattened )
					( Origin gBackEnd )
				)
				( attribute "RELATIVE_PROPAGATION_DELAY_SCOPE" "G"
					( Parent
						( matchGroupRef "@baseboard_fab2_lib.baseboard_fab2(sch_1):\MG_KTI_BUNDLE_NG_KTI_CPU1_CPU0_P0P0_2-3\" )
					)
					( Status sCSetFlattened )
					( Origin gBackEnd )
				)
				( attribute "RELATIVE_PROPAGATION_DELAY" ",500.00 MIL"
					( Parent
						( matchGroupRef "@baseboard_fab2_lib.baseboard_fab2(sch_1):\MG_KTI_BUNDLE_NG_KTI_CPU1_CPU0_P0P0_2-3\" )
					)
					( Units "uMatchProp" "ns" 1.000000)
					( Status sCSetFlattened )
					( Origin gBackEnd )
				)
			)
			( pinPair "@baseboard_fab2_lib.baseboard_fab2(sch_1):\PP3175\"
				( pinRef "@baseboard_fab2_lib.baseboard_fab2(sch_1):page67_i132:UPI0_TX_DP(4)" )
				( pinRef "@baseboard_fab2_lib.baseboard_fab2(sch_1):page33_i86:UPI0_RX_DP(15)" )
				( attribute "RELATIVE_PROPAGATION_DELAY_SCOPE" "G"
					( Parent
						( matchGroupRef "@crescent_city_bb_fab1_lib.crescent_city_bb_fab1(sch_1):\MG_KTI_CPU1_CPU0_P0P0\" )
					)
					( Status sCSetFlattened )
					( Origin gBackEnd )
				)
				( attribute "RELATIVE_PROPAGATION_DELAY" "-1315.00 MIL,1315.00 MIL"
					( Parent
						( matchGroupRef "@crescent_city_bb_fab1_lib.crescent_city_bb_fab1(sch_1):\MG_KTI_CPU1_CPU0_P0P0\" )
					)
					( Units "uMatchProp" "ns" 1.000000)
					( Status sCSetFlattened )
					( Origin gBackEnd )
				)
				( attribute "RELATIVE_PROPAGATION_DELAY_SCOPE" "G"
					( Parent
						( matchGroupRef "@baseboard_fab2_lib.baseboard_fab2(sch_1):\MG_KTI_BUNDLE_NG_KTI_CPU1_CPU0_P0P0_4-5\" )
					)
					( Status sCSetFlattened )
					( Origin gBackEnd )
				)
				( attribute "RELATIVE_PROPAGATION_DELAY" ",500.00 MIL"
					( Parent
						( matchGroupRef "@baseboard_fab2_lib.baseboard_fab2(sch_1):\MG_KTI_BUNDLE_NG_KTI_CPU1_CPU0_P0P0_4-5\" )
					)
					( Units "uMatchProp" "ns" 1.000000)
					( Status sCSetFlattened )
					( Origin gBackEnd )
				)
			)
			( pinPair "@baseboard_fab2_lib.baseboard_fab2(sch_1):\PP3176\"
				( pinRef "@baseboard_fab2_lib.baseboard_fab2(sch_1):page67_i132:UPI0_TX_DN(4)" )
				( pinRef "@baseboard_fab2_lib.baseboard_fab2(sch_1):page33_i86:UPI0_RX_DN(15)" )
				( attribute "RELATIVE_PROPAGATION_DELAY_SCOPE" "G"
					( Parent
						( matchGroupRef "@crescent_city_bb_fab1_lib.crescent_city_bb_fab1(sch_1):\MG_KTI_CPU1_CPU0_P0P0\" )
					)
					( Status sCSetFlattened )
					( Origin gBackEnd )
				)
				( attribute "RELATIVE_PROPAGATION_DELAY" "-1315.00 MIL,1315.00 MIL"
					( Parent
						( matchGroupRef "@crescent_city_bb_fab1_lib.crescent_city_bb_fab1(sch_1):\MG_KTI_CPU1_CPU0_P0P0\" )
					)
					( Units "uMatchProp" "ns" 1.000000)
					( Status sCSetFlattened )
					( Origin gBackEnd )
				)
				( attribute "RELATIVE_PROPAGATION_DELAY_SCOPE" "G"
					( Parent
						( matchGroupRef "@baseboard_fab2_lib.baseboard_fab2(sch_1):\MG_KTI_BUNDLE_NG_KTI_CPU1_CPU0_P0P0_4-5\" )
					)
					( Status sCSetFlattened )
					( Origin gBackEnd )
				)
				( attribute "RELATIVE_PROPAGATION_DELAY" ",500.00 MIL"
					( Parent
						( matchGroupRef "@baseboard_fab2_lib.baseboard_fab2(sch_1):\MG_KTI_BUNDLE_NG_KTI_CPU1_CPU0_P0P0_4-5\" )
					)
					( Units "uMatchProp" "ns" 1.000000)
					( Status sCSetFlattened )
					( Origin gBackEnd )
				)
			)
			( pinPair "@baseboard_fab2_lib.baseboard_fab2(sch_1):\PP3177\"
				( pinRef "@baseboard_fab2_lib.baseboard_fab2(sch_1):page33_i86:UPI0_RX_DP(14)" )
				( pinRef "@baseboard_fab2_lib.baseboard_fab2(sch_1):page67_i132:UPI0_TX_DN(5)" )
				( attribute "RELATIVE_PROPAGATION_DELAY_SCOPE" "G"
					( Parent
						( matchGroupRef "@crescent_city_bb_fab1_lib.crescent_city_bb_fab1(sch_1):\MG_KTI_CPU1_CPU0_P0P0\" )
					)
					( Status sCSetFlattened )
					( Origin gBackEnd )
				)
				( attribute "RELATIVE_PROPAGATION_DELAY" "-1315.00 MIL,1315.00 MIL"
					( Parent
						( matchGroupRef "@crescent_city_bb_fab1_lib.crescent_city_bb_fab1(sch_1):\MG_KTI_CPU1_CPU0_P0P0\" )
					)
					( Units "uMatchProp" "ns" 1.000000)
					( Status sCSetFlattened )
					( Origin gBackEnd )
				)
				( attribute "RELATIVE_PROPAGATION_DELAY_SCOPE" "G"
					( Parent
						( matchGroupRef "@baseboard_fab2_lib.baseboard_fab2(sch_1):\MG_KTI_BUNDLE_NG_KTI_CPU1_CPU0_P0P0_4-5\" )
					)
					( Status sCSetFlattened )
					( Origin gBackEnd )
				)
				( attribute "RELATIVE_PROPAGATION_DELAY" ",500.00 MIL"
					( Parent
						( matchGroupRef "@baseboard_fab2_lib.baseboard_fab2(sch_1):\MG_KTI_BUNDLE_NG_KTI_CPU1_CPU0_P0P0_4-5\" )
					)
					( Units "uMatchProp" "ns" 1.000000)
					( Status sCSetFlattened )
					( Origin gBackEnd )
				)
			)
			( pinPair "@baseboard_fab2_lib.baseboard_fab2(sch_1):\PP3178\"
				( pinRef "@baseboard_fab2_lib.baseboard_fab2(sch_1):page33_i86:UPI0_RX_DN(14)" )
				( pinRef "@baseboard_fab2_lib.baseboard_fab2(sch_1):page67_i132:UPI0_TX_DP(5)" )
				( attribute "RELATIVE_PROPAGATION_DELAY_SCOPE" "G"
					( Parent
						( matchGroupRef "@crescent_city_bb_fab1_lib.crescent_city_bb_fab1(sch_1):\MG_KTI_CPU1_CPU0_P0P0\" )
					)
					( Status sCSetFlattened )
					( Origin gBackEnd )
				)
				( attribute "RELATIVE_PROPAGATION_DELAY" "-1315.00 MIL,1315.00 MIL"
					( Parent
						( matchGroupRef "@crescent_city_bb_fab1_lib.crescent_city_bb_fab1(sch_1):\MG_KTI_CPU1_CPU0_P0P0\" )
					)
					( Units "uMatchProp" "ns" 1.000000)
					( Status sCSetFlattened )
					( Origin gBackEnd )
				)
				( attribute "RELATIVE_PROPAGATION_DELAY_SCOPE" "G"
					( Parent
						( matchGroupRef "@baseboard_fab2_lib.baseboard_fab2(sch_1):\MG_KTI_BUNDLE_NG_KTI_CPU1_CPU0_P0P0_4-5\" )
					)
					( Status sCSetFlattened )
					( Origin gBackEnd )
				)
				( attribute "RELATIVE_PROPAGATION_DELAY" ",500.00 MIL"
					( Parent
						( matchGroupRef "@baseboard_fab2_lib.baseboard_fab2(sch_1):\MG_KTI_BUNDLE_NG_KTI_CPU1_CPU0_P0P0_4-5\" )
					)
					( Units "uMatchProp" "ns" 1.000000)
					( Status sCSetFlattened )
					( Origin gBackEnd )
				)
			)
			( pinPair "@baseboard_fab2_lib.baseboard_fab2(sch_1):\PP3171\"
				( pinRef "@baseboard_fab2_lib.baseboard_fab2(sch_1):page67_i132:UPI0_TX_DP(6)" )
				( pinRef "@baseboard_fab2_lib.baseboard_fab2(sch_1):page33_i86:UPI0_RX_DP(13)" )
				( attribute "RELATIVE_PROPAGATION_DELAY_SCOPE" "G"
					( Parent
						( matchGroupRef "@crescent_city_bb_fab1_lib.crescent_city_bb_fab1(sch_1):\MG_KTI_CPU1_CPU0_P0P0\" )
					)
					( Status sCSetFlattened )
					( Origin gBackEnd )
				)
				( attribute "RELATIVE_PROPAGATION_DELAY" "-1315.00 MIL,1315.00 MIL"
					( Parent
						( matchGroupRef "@crescent_city_bb_fab1_lib.crescent_city_bb_fab1(sch_1):\MG_KTI_CPU1_CPU0_P0P0\" )
					)
					( Units "uMatchProp" "ns" 1.000000)
					( Status sCSetFlattened )
					( Origin gBackEnd )
				)
				( attribute "RELATIVE_PROPAGATION_DELAY_SCOPE" "G"
					( Parent
						( matchGroupRef "@baseboard_fab2_lib.baseboard_fab2(sch_1):\MG_KTI_BUNDLE_NG_KTI_CPU1_CPU0_P0P0_6-7\" )
					)
					( Status sCSetFlattened )
					( Origin gBackEnd )
				)
				( attribute "RELATIVE_PROPAGATION_DELAY" ",500.00 MIL"
					( Parent
						( matchGroupRef "@baseboard_fab2_lib.baseboard_fab2(sch_1):\MG_KTI_BUNDLE_NG_KTI_CPU1_CPU0_P0P0_6-7\" )
					)
					( Units "uMatchProp" "ns" 1.000000)
					( Status sCSetFlattened )
					( Origin gBackEnd )
				)
			)
			( pinPair "@baseboard_fab2_lib.baseboard_fab2(sch_1):\PP3172\"
				( pinRef "@baseboard_fab2_lib.baseboard_fab2(sch_1):page67_i132:UPI0_TX_DN(6)" )
				( pinRef "@baseboard_fab2_lib.baseboard_fab2(sch_1):page33_i86:UPI0_RX_DN(13)" )
				( attribute "RELATIVE_PROPAGATION_DELAY_SCOPE" "G"
					( Parent
						( matchGroupRef "@crescent_city_bb_fab1_lib.crescent_city_bb_fab1(sch_1):\MG_KTI_CPU1_CPU0_P0P0\" )
					)
					( Status sCSetFlattened )
					( Origin gBackEnd )
				)
				( attribute "RELATIVE_PROPAGATION_DELAY" "-1315.00 MIL,1315.00 MIL"
					( Parent
						( matchGroupRef "@crescent_city_bb_fab1_lib.crescent_city_bb_fab1(sch_1):\MG_KTI_CPU1_CPU0_P0P0\" )
					)
					( Units "uMatchProp" "ns" 1.000000)
					( Status sCSetFlattened )
					( Origin gBackEnd )
				)
				( attribute "RELATIVE_PROPAGATION_DELAY_SCOPE" "G"
					( Parent
						( matchGroupRef "@baseboard_fab2_lib.baseboard_fab2(sch_1):\MG_KTI_BUNDLE_NG_KTI_CPU1_CPU0_P0P0_6-7\" )
					)
					( Status sCSetFlattened )
					( Origin gBackEnd )
				)
				( attribute "RELATIVE_PROPAGATION_DELAY" ",500.00 MIL"
					( Parent
						( matchGroupRef "@baseboard_fab2_lib.baseboard_fab2(sch_1):\MG_KTI_BUNDLE_NG_KTI_CPU1_CPU0_P0P0_6-7\" )
					)
					( Units "uMatchProp" "ns" 1.000000)
					( Status sCSetFlattened )
					( Origin gBackEnd )
				)
			)
			( pinPair "@baseboard_fab2_lib.baseboard_fab2(sch_1):\PP3173\"
				( pinRef "@baseboard_fab2_lib.baseboard_fab2(sch_1):page67_i132:UPI0_TX_DP(7)" )
				( pinRef "@baseboard_fab2_lib.baseboard_fab2(sch_1):page33_i86:UPI0_RX_DP(12)" )
				( attribute "RELATIVE_PROPAGATION_DELAY_SCOPE" "G"
					( Parent
						( matchGroupRef "@crescent_city_bb_fab1_lib.crescent_city_bb_fab1(sch_1):\MG_KTI_CPU1_CPU0_P0P0\" )
					)
					( Status sCSetFlattened )
					( Origin gBackEnd )
				)
				( attribute "RELATIVE_PROPAGATION_DELAY" "-1315.00 MIL,1315.00 MIL"
					( Parent
						( matchGroupRef "@crescent_city_bb_fab1_lib.crescent_city_bb_fab1(sch_1):\MG_KTI_CPU1_CPU0_P0P0\" )
					)
					( Units "uMatchProp" "ns" 1.000000)
					( Status sCSetFlattened )
					( Origin gBackEnd )
				)
				( attribute "RELATIVE_PROPAGATION_DELAY_SCOPE" "G"
					( Parent
						( matchGroupRef "@baseboard_fab2_lib.baseboard_fab2(sch_1):\MG_KTI_BUNDLE_NG_KTI_CPU1_CPU0_P0P0_6-7\" )
					)
					( Status sCSetFlattened )
					( Origin gBackEnd )
				)
				( attribute "RELATIVE_PROPAGATION_DELAY" ",500.00 MIL"
					( Parent
						( matchGroupRef "@baseboard_fab2_lib.baseboard_fab2(sch_1):\MG_KTI_BUNDLE_NG_KTI_CPU1_CPU0_P0P0_6-7\" )
					)
					( Units "uMatchProp" "ns" 1.000000)
					( Status sCSetFlattened )
					( Origin gBackEnd )
				)
			)
			( pinPair "@baseboard_fab2_lib.baseboard_fab2(sch_1):\PP3174\"
				( pinRef "@baseboard_fab2_lib.baseboard_fab2(sch_1):page67_i132:UPI0_TX_DN(7)" )
				( pinRef "@baseboard_fab2_lib.baseboard_fab2(sch_1):page33_i86:UPI0_RX_DN(12)" )
				( attribute "RELATIVE_PROPAGATION_DELAY_SCOPE" "G"
					( Parent
						( matchGroupRef "@crescent_city_bb_fab1_lib.crescent_city_bb_fab1(sch_1):\MG_KTI_CPU1_CPU0_P0P0\" )
					)
					( Status sCSetFlattened )
					( Origin gBackEnd )
				)
				( attribute "RELATIVE_PROPAGATION_DELAY" "-1315.00 MIL,1315.00 MIL"
					( Parent
						( matchGroupRef "@crescent_city_bb_fab1_lib.crescent_city_bb_fab1(sch_1):\MG_KTI_CPU1_CPU0_P0P0\" )
					)
					( Units "uMatchProp" "ns" 1.000000)
					( Status sCSetFlattened )
					( Origin gBackEnd )
				)
				( attribute "RELATIVE_PROPAGATION_DELAY_SCOPE" "G"
					( Parent
						( matchGroupRef "@baseboard_fab2_lib.baseboard_fab2(sch_1):\MG_KTI_BUNDLE_NG_KTI_CPU1_CPU0_P0P0_6-7\" )
					)
					( Status sCSetFlattened )
					( Origin gBackEnd )
				)
				( attribute "RELATIVE_PROPAGATION_DELAY" ",500.00 MIL"
					( Parent
						( matchGroupRef "@baseboard_fab2_lib.baseboard_fab2(sch_1):\MG_KTI_BUNDLE_NG_KTI_CPU1_CPU0_P0P0_6-7\" )
					)
					( Units "uMatchProp" "ns" 1.000000)
					( Status sCSetFlattened )
					( Origin gBackEnd )
				)
			)
			( pinPair "@baseboard_fab2_lib.baseboard_fab2(sch_1):\PP3167\"
				( pinRef "@baseboard_fab2_lib.baseboard_fab2(sch_1):page67_i132:UPI0_TX_DN(8)" )
				( pinRef "@baseboard_fab2_lib.baseboard_fab2(sch_1):page33_i86:UPI0_RX_DP(11)" )
				( attribute "RELATIVE_PROPAGATION_DELAY_SCOPE" "G"
					( Parent
						( matchGroupRef "@crescent_city_bb_fab1_lib.crescent_city_bb_fab1(sch_1):\MG_KTI_CPU1_CPU0_P0P0\" )
					)
					( Status sCSetFlattened )
					( Origin gBackEnd )
				)
				( attribute "RELATIVE_PROPAGATION_DELAY" "-1315.00 MIL,1315.00 MIL"
					( Parent
						( matchGroupRef "@crescent_city_bb_fab1_lib.crescent_city_bb_fab1(sch_1):\MG_KTI_CPU1_CPU0_P0P0\" )
					)
					( Units "uMatchProp" "ns" 1.000000)
					( Status sCSetFlattened )
					( Origin gBackEnd )
				)
				( attribute "RELATIVE_PROPAGATION_DELAY_SCOPE" "G"
					( Parent
						( matchGroupRef "@baseboard_fab2_lib.baseboard_fab2(sch_1):\MG_KTI_BUNDLE_NG_KTI_CPU1_CPU0_P0P0_8-9\" )
					)
					( Status sCSetFlattened )
					( Origin gBackEnd )
				)
				( attribute "RELATIVE_PROPAGATION_DELAY" ",500.00 MIL"
					( Parent
						( matchGroupRef "@baseboard_fab2_lib.baseboard_fab2(sch_1):\MG_KTI_BUNDLE_NG_KTI_CPU1_CPU0_P0P0_8-9\" )
					)
					( Units "uMatchProp" "ns" 1.000000)
					( Status sCSetFlattened )
					( Origin gBackEnd )
				)
			)
			( pinPair "@baseboard_fab2_lib.baseboard_fab2(sch_1):\PP3168\"
				( pinRef "@baseboard_fab2_lib.baseboard_fab2(sch_1):page67_i132:UPI0_TX_DP(8)" )
				( pinRef "@baseboard_fab2_lib.baseboard_fab2(sch_1):page33_i86:UPI0_RX_DN(11)" )
				( attribute "RELATIVE_PROPAGATION_DELAY_SCOPE" "G"
					( Parent
						( matchGroupRef "@crescent_city_bb_fab1_lib.crescent_city_bb_fab1(sch_1):\MG_KTI_CPU1_CPU0_P0P0\" )
					)
					( Status sCSetFlattened )
					( Origin gBackEnd )
				)
				( attribute "RELATIVE_PROPAGATION_DELAY" "-1315.00 MIL,1315.00 MIL"
					( Parent
						( matchGroupRef "@crescent_city_bb_fab1_lib.crescent_city_bb_fab1(sch_1):\MG_KTI_CPU1_CPU0_P0P0\" )
					)
					( Units "uMatchProp" "ns" 1.000000)
					( Status sCSetFlattened )
					( Origin gBackEnd )
				)
				( attribute "RELATIVE_PROPAGATION_DELAY_SCOPE" "G"
					( Parent
						( matchGroupRef "@baseboard_fab2_lib.baseboard_fab2(sch_1):\MG_KTI_BUNDLE_NG_KTI_CPU1_CPU0_P0P0_8-9\" )
					)
					( Status sCSetFlattened )
					( Origin gBackEnd )
				)
				( attribute "RELATIVE_PROPAGATION_DELAY" ",500.00 MIL"
					( Parent
						( matchGroupRef "@baseboard_fab2_lib.baseboard_fab2(sch_1):\MG_KTI_BUNDLE_NG_KTI_CPU1_CPU0_P0P0_8-9\" )
					)
					( Units "uMatchProp" "ns" 1.000000)
					( Status sCSetFlattened )
					( Origin gBackEnd )
				)
			)
			( pinPair "@baseboard_fab2_lib.baseboard_fab2(sch_1):\PP3169\"
				( pinRef "@baseboard_fab2_lib.baseboard_fab2(sch_1):page33_i86:UPI0_RX_DP(10)" )
				( pinRef "@baseboard_fab2_lib.baseboard_fab2(sch_1):page67_i132:UPI0_TX_DP(9)" )
				( attribute "RELATIVE_PROPAGATION_DELAY_SCOPE" "G"
					( Parent
						( matchGroupRef "@crescent_city_bb_fab1_lib.crescent_city_bb_fab1(sch_1):\MG_KTI_CPU1_CPU0_P0P0\" )
					)
					( Status sCSetFlattened )
					( Origin gBackEnd )
				)
				( attribute "RELATIVE_PROPAGATION_DELAY" "-1315.00 MIL,1315.00 MIL"
					( Parent
						( matchGroupRef "@crescent_city_bb_fab1_lib.crescent_city_bb_fab1(sch_1):\MG_KTI_CPU1_CPU0_P0P0\" )
					)
					( Units "uMatchProp" "ns" 1.000000)
					( Status sCSetFlattened )
					( Origin gBackEnd )
				)
				( attribute "RELATIVE_PROPAGATION_DELAY_SCOPE" "G"
					( Parent
						( matchGroupRef "@baseboard_fab2_lib.baseboard_fab2(sch_1):\MG_KTI_BUNDLE_NG_KTI_CPU1_CPU0_P0P0_8-9\" )
					)
					( Status sCSetFlattened )
					( Origin gBackEnd )
				)
				( attribute "RELATIVE_PROPAGATION_DELAY" ",500.00 MIL"
					( Parent
						( matchGroupRef "@baseboard_fab2_lib.baseboard_fab2(sch_1):\MG_KTI_BUNDLE_NG_KTI_CPU1_CPU0_P0P0_8-9\" )
					)
					( Units "uMatchProp" "ns" 1.000000)
					( Status sCSetFlattened )
					( Origin gBackEnd )
				)
			)
			( pinPair "@baseboard_fab2_lib.baseboard_fab2(sch_1):\PP3170\"
				( pinRef "@baseboard_fab2_lib.baseboard_fab2(sch_1):page33_i86:UPI0_RX_DN(10)" )
				( pinRef "@baseboard_fab2_lib.baseboard_fab2(sch_1):page67_i132:UPI0_TX_DN(9)" )
				( attribute "RELATIVE_PROPAGATION_DELAY_SCOPE" "G"
					( Parent
						( matchGroupRef "@crescent_city_bb_fab1_lib.crescent_city_bb_fab1(sch_1):\MG_KTI_CPU1_CPU0_P0P0\" )
					)
					( Status sCSetFlattened )
					( Origin gBackEnd )
				)
				( attribute "RELATIVE_PROPAGATION_DELAY" "-1315.00 MIL,1315.00 MIL"
					( Parent
						( matchGroupRef "@crescent_city_bb_fab1_lib.crescent_city_bb_fab1(sch_1):\MG_KTI_CPU1_CPU0_P0P0\" )
					)
					( Units "uMatchProp" "ns" 1.000000)
					( Status sCSetFlattened )
					( Origin gBackEnd )
				)
				( attribute "RELATIVE_PROPAGATION_DELAY_SCOPE" "G"
					( Parent
						( matchGroupRef "@baseboard_fab2_lib.baseboard_fab2(sch_1):\MG_KTI_BUNDLE_NG_KTI_CPU1_CPU0_P0P0_8-9\" )
					)
					( Status sCSetFlattened )
					( Origin gBackEnd )
				)
				( attribute "RELATIVE_PROPAGATION_DELAY" ",500.00 MIL"
					( Parent
						( matchGroupRef "@baseboard_fab2_lib.baseboard_fab2(sch_1):\MG_KTI_BUNDLE_NG_KTI_CPU1_CPU0_P0P0_8-9\" )
					)
					( Units "uMatchProp" "ns" 1.000000)
					( Status sCSetFlattened )
					( Origin gBackEnd )
				)
			)
			( pinPair "@baseboard_fab2_lib.baseboard_fab2(sch_1):\PP3163\"
				( pinRef "@baseboard_fab2_lib.baseboard_fab2(sch_1):page67_i132:UPI0_TX_DN(10)" )
				( pinRef "@baseboard_fab2_lib.baseboard_fab2(sch_1):page33_i86:UPI0_RX_DP(9)" )
				( attribute "RELATIVE_PROPAGATION_DELAY_SCOPE" "G"
					( Parent
						( matchGroupRef "@crescent_city_bb_fab1_lib.crescent_city_bb_fab1(sch_1):\MG_KTI_CPU1_CPU0_P0P0\" )
					)
					( Status sCSetFlattened )
					( Origin gBackEnd )
				)
				( attribute "RELATIVE_PROPAGATION_DELAY" "-1315.00 MIL,1315.00 MIL"
					( Parent
						( matchGroupRef "@crescent_city_bb_fab1_lib.crescent_city_bb_fab1(sch_1):\MG_KTI_CPU1_CPU0_P0P0\" )
					)
					( Units "uMatchProp" "ns" 1.000000)
					( Status sCSetFlattened )
					( Origin gBackEnd )
				)
				( attribute "RELATIVE_PROPAGATION_DELAY_SCOPE" "G"
					( Parent
						( matchGroupRef "@baseboard_fab2_lib.baseboard_fab2(sch_1):\MG_KTI_BUNDLE_NG_KTI_CPU1_CPU0_P0P0_10-11\" )
					)
					( Status sCSetFlattened )
					( Origin gBackEnd )
				)
				( attribute "RELATIVE_PROPAGATION_DELAY" ",500.00 MIL"
					( Parent
						( matchGroupRef "@baseboard_fab2_lib.baseboard_fab2(sch_1):\MG_KTI_BUNDLE_NG_KTI_CPU1_CPU0_P0P0_10-11\" )
					)
					( Units "uMatchProp" "ns" 1.000000)
					( Status sCSetFlattened )
					( Origin gBackEnd )
				)
			)
			( pinPair "@baseboard_fab2_lib.baseboard_fab2(sch_1):\PP3164\"
				( pinRef "@baseboard_fab2_lib.baseboard_fab2(sch_1):page67_i132:UPI0_TX_DP(10)" )
				( pinRef "@baseboard_fab2_lib.baseboard_fab2(sch_1):page33_i86:UPI0_RX_DN(9)" )
				( attribute "RELATIVE_PROPAGATION_DELAY_SCOPE" "G"
					( Parent
						( matchGroupRef "@crescent_city_bb_fab1_lib.crescent_city_bb_fab1(sch_1):\MG_KTI_CPU1_CPU0_P0P0\" )
					)
					( Status sCSetFlattened )
					( Origin gBackEnd )
				)
				( attribute "RELATIVE_PROPAGATION_DELAY" "-1315.00 MIL,1315.00 MIL"
					( Parent
						( matchGroupRef "@crescent_city_bb_fab1_lib.crescent_city_bb_fab1(sch_1):\MG_KTI_CPU1_CPU0_P0P0\" )
					)
					( Units "uMatchProp" "ns" 1.000000)
					( Status sCSetFlattened )
					( Origin gBackEnd )
				)
				( attribute "RELATIVE_PROPAGATION_DELAY_SCOPE" "G"
					( Parent
						( matchGroupRef "@baseboard_fab2_lib.baseboard_fab2(sch_1):\MG_KTI_BUNDLE_NG_KTI_CPU1_CPU0_P0P0_10-11\" )
					)
					( Status sCSetFlattened )
					( Origin gBackEnd )
				)
				( attribute "RELATIVE_PROPAGATION_DELAY" ",500.00 MIL"
					( Parent
						( matchGroupRef "@baseboard_fab2_lib.baseboard_fab2(sch_1):\MG_KTI_BUNDLE_NG_KTI_CPU1_CPU0_P0P0_10-11\" )
					)
					( Units "uMatchProp" "ns" 1.000000)
					( Status sCSetFlattened )
					( Origin gBackEnd )
				)
			)
			( pinPair "@baseboard_fab2_lib.baseboard_fab2(sch_1):\PP3165\"
				( pinRef "@baseboard_fab2_lib.baseboard_fab2(sch_1):page67_i132:UPI0_TX_DN(11)" )
				( pinRef "@baseboard_fab2_lib.baseboard_fab2(sch_1):page33_i86:UPI0_RX_DP(8)" )
				( attribute "RELATIVE_PROPAGATION_DELAY_SCOPE" "G"
					( Parent
						( matchGroupRef "@crescent_city_bb_fab1_lib.crescent_city_bb_fab1(sch_1):\MG_KTI_CPU1_CPU0_P0P0\" )
					)
					( Status sCSetFlattened )
					( Origin gBackEnd )
				)
				( attribute "RELATIVE_PROPAGATION_DELAY" "-1315.00 MIL,1315.00 MIL"
					( Parent
						( matchGroupRef "@crescent_city_bb_fab1_lib.crescent_city_bb_fab1(sch_1):\MG_KTI_CPU1_CPU0_P0P0\" )
					)
					( Units "uMatchProp" "ns" 1.000000)
					( Status sCSetFlattened )
					( Origin gBackEnd )
				)
				( attribute "RELATIVE_PROPAGATION_DELAY_SCOPE" "G"
					( Parent
						( matchGroupRef "@baseboard_fab2_lib.baseboard_fab2(sch_1):\MG_KTI_BUNDLE_NG_KTI_CPU1_CPU0_P0P0_10-11\" )
					)
					( Status sCSetFlattened )
					( Origin gBackEnd )
				)
				( attribute "RELATIVE_PROPAGATION_DELAY" ",500.00 MIL"
					( Parent
						( matchGroupRef "@baseboard_fab2_lib.baseboard_fab2(sch_1):\MG_KTI_BUNDLE_NG_KTI_CPU1_CPU0_P0P0_10-11\" )
					)
					( Units "uMatchProp" "ns" 1.000000)
					( Status sCSetFlattened )
					( Origin gBackEnd )
				)
			)
			( pinPair "@baseboard_fab2_lib.baseboard_fab2(sch_1):\PP3166\"
				( pinRef "@baseboard_fab2_lib.baseboard_fab2(sch_1):page67_i132:UPI0_TX_DP(11)" )
				( pinRef "@baseboard_fab2_lib.baseboard_fab2(sch_1):page33_i86:UPI0_RX_DN(8)" )
				( attribute "RELATIVE_PROPAGATION_DELAY_SCOPE" "G"
					( Parent
						( matchGroupRef "@crescent_city_bb_fab1_lib.crescent_city_bb_fab1(sch_1):\MG_KTI_CPU1_CPU0_P0P0\" )
					)
					( Status sCSetFlattened )
					( Origin gBackEnd )
				)
				( attribute "RELATIVE_PROPAGATION_DELAY" "-1315.00 MIL,1315.00 MIL"
					( Parent
						( matchGroupRef "@crescent_city_bb_fab1_lib.crescent_city_bb_fab1(sch_1):\MG_KTI_CPU1_CPU0_P0P0\" )
					)
					( Units "uMatchProp" "ns" 1.000000)
					( Status sCSetFlattened )
					( Origin gBackEnd )
				)
				( attribute "RELATIVE_PROPAGATION_DELAY_SCOPE" "G"
					( Parent
						( matchGroupRef "@baseboard_fab2_lib.baseboard_fab2(sch_1):\MG_KTI_BUNDLE_NG_KTI_CPU1_CPU0_P0P0_10-11\" )
					)
					( Status sCSetFlattened )
					( Origin gBackEnd )
				)
				( attribute "RELATIVE_PROPAGATION_DELAY" ",500.00 MIL"
					( Parent
						( matchGroupRef "@baseboard_fab2_lib.baseboard_fab2(sch_1):\MG_KTI_BUNDLE_NG_KTI_CPU1_CPU0_P0P0_10-11\" )
					)
					( Units "uMatchProp" "ns" 1.000000)
					( Status sCSetFlattened )
					( Origin gBackEnd )
				)
			)
			( pinPair "@baseboard_fab2_lib.baseboard_fab2(sch_1):\PP3159\"
				( pinRef "@baseboard_fab2_lib.baseboard_fab2(sch_1):page67_i132:UPI0_TX_DN(12)" )
				( pinRef "@baseboard_fab2_lib.baseboard_fab2(sch_1):page33_i86:UPI0_RX_DP(7)" )
				( attribute "RELATIVE_PROPAGATION_DELAY_SCOPE" "G"
					( Parent
						( matchGroupRef "@crescent_city_bb_fab1_lib.crescent_city_bb_fab1(sch_1):\MG_KTI_CPU1_CPU0_P0P0\" )
					)
					( Status sCSetFlattened )
					( Origin gBackEnd )
				)
				( attribute "RELATIVE_PROPAGATION_DELAY" "-1315.00 MIL,1315.00 MIL"
					( Parent
						( matchGroupRef "@crescent_city_bb_fab1_lib.crescent_city_bb_fab1(sch_1):\MG_KTI_CPU1_CPU0_P0P0\" )
					)
					( Units "uMatchProp" "ns" 1.000000)
					( Status sCSetFlattened )
					( Origin gBackEnd )
				)
				( attribute "RELATIVE_PROPAGATION_DELAY_SCOPE" "G"
					( Parent
						( matchGroupRef "@baseboard_fab2_lib.baseboard_fab2(sch_1):\MG_KTI_BUNDLE_NG_KTI_CPU1_CPU0_P0P0_12-13\" )
					)
					( Status sCSetFlattened )
					( Origin gBackEnd )
				)
				( attribute "RELATIVE_PROPAGATION_DELAY" ",500.00 MIL"
					( Parent
						( matchGroupRef "@baseboard_fab2_lib.baseboard_fab2(sch_1):\MG_KTI_BUNDLE_NG_KTI_CPU1_CPU0_P0P0_12-13\" )
					)
					( Units "uMatchProp" "ns" 1.000000)
					( Status sCSetFlattened )
					( Origin gBackEnd )
				)
			)
			( pinPair "@baseboard_fab2_lib.baseboard_fab2(sch_1):\PP3160\"
				( pinRef "@baseboard_fab2_lib.baseboard_fab2(sch_1):page33_i86:UPI0_RX_DN(7)" )
				( pinRef "@baseboard_fab2_lib.baseboard_fab2(sch_1):page67_i132:UPI0_TX_DP(12)" )
				( attribute "RELATIVE_PROPAGATION_DELAY_SCOPE" "G"
					( Parent
						( matchGroupRef "@crescent_city_bb_fab1_lib.crescent_city_bb_fab1(sch_1):\MG_KTI_CPU1_CPU0_P0P0\" )
					)
					( Status sCSetFlattened )
					( Origin gBackEnd )
				)
				( attribute "RELATIVE_PROPAGATION_DELAY" "-1315.00 MIL,1315.00 MIL"
					( Parent
						( matchGroupRef "@crescent_city_bb_fab1_lib.crescent_city_bb_fab1(sch_1):\MG_KTI_CPU1_CPU0_P0P0\" )
					)
					( Units "uMatchProp" "ns" 1.000000)
					( Status sCSetFlattened )
					( Origin gBackEnd )
				)
				( attribute "RELATIVE_PROPAGATION_DELAY_SCOPE" "G"
					( Parent
						( matchGroupRef "@baseboard_fab2_lib.baseboard_fab2(sch_1):\MG_KTI_BUNDLE_NG_KTI_CPU1_CPU0_P0P0_12-13\" )
					)
					( Status sCSetFlattened )
					( Origin gBackEnd )
				)
				( attribute "RELATIVE_PROPAGATION_DELAY" ",500.00 MIL"
					( Parent
						( matchGroupRef "@baseboard_fab2_lib.baseboard_fab2(sch_1):\MG_KTI_BUNDLE_NG_KTI_CPU1_CPU0_P0P0_12-13\" )
					)
					( Units "uMatchProp" "ns" 1.000000)
					( Status sCSetFlattened )
					( Origin gBackEnd )
				)
			)
			( pinPair "@baseboard_fab2_lib.baseboard_fab2(sch_1):\PP3161\"
				( pinRef "@baseboard_fab2_lib.baseboard_fab2(sch_1):page67_i132:UPI0_TX_DN(13)" )
				( pinRef "@baseboard_fab2_lib.baseboard_fab2(sch_1):page33_i86:UPI0_RX_DP(6)" )
				( attribute "RELATIVE_PROPAGATION_DELAY_SCOPE" "G"
					( Parent
						( matchGroupRef "@crescent_city_bb_fab1_lib.crescent_city_bb_fab1(sch_1):\MG_KTI_CPU1_CPU0_P0P0\" )
					)
					( Status sCSetFlattened )
					( Origin gBackEnd )
				)
				( attribute "RELATIVE_PROPAGATION_DELAY" "-1315.00 MIL,1315.00 MIL"
					( Parent
						( matchGroupRef "@crescent_city_bb_fab1_lib.crescent_city_bb_fab1(sch_1):\MG_KTI_CPU1_CPU0_P0P0\" )
					)
					( Units "uMatchProp" "ns" 1.000000)
					( Status sCSetFlattened )
					( Origin gBackEnd )
				)
				( attribute "RELATIVE_PROPAGATION_DELAY_SCOPE" "G"
					( Parent
						( matchGroupRef "@baseboard_fab2_lib.baseboard_fab2(sch_1):\MG_KTI_BUNDLE_NG_KTI_CPU1_CPU0_P0P0_12-13\" )
					)
					( Status sCSetFlattened )
					( Origin gBackEnd )
				)
				( attribute "RELATIVE_PROPAGATION_DELAY" ",500.00 MIL"
					( Parent
						( matchGroupRef "@baseboard_fab2_lib.baseboard_fab2(sch_1):\MG_KTI_BUNDLE_NG_KTI_CPU1_CPU0_P0P0_12-13\" )
					)
					( Units "uMatchProp" "ns" 1.000000)
					( Status sCSetFlattened )
					( Origin gBackEnd )
				)
			)
			( pinPair "@baseboard_fab2_lib.baseboard_fab2(sch_1):\PP3162\"
				( pinRef "@baseboard_fab2_lib.baseboard_fab2(sch_1):page67_i132:UPI0_TX_DP(13)" )
				( pinRef "@baseboard_fab2_lib.baseboard_fab2(sch_1):page33_i86:UPI0_RX_DN(6)" )
				( attribute "RELATIVE_PROPAGATION_DELAY_SCOPE" "G"
					( Parent
						( matchGroupRef "@crescent_city_bb_fab1_lib.crescent_city_bb_fab1(sch_1):\MG_KTI_CPU1_CPU0_P0P0\" )
					)
					( Status sCSetFlattened )
					( Origin gBackEnd )
				)
				( attribute "RELATIVE_PROPAGATION_DELAY" "-1315.00 MIL,1315.00 MIL"
					( Parent
						( matchGroupRef "@crescent_city_bb_fab1_lib.crescent_city_bb_fab1(sch_1):\MG_KTI_CPU1_CPU0_P0P0\" )
					)
					( Units "uMatchProp" "ns" 1.000000)
					( Status sCSetFlattened )
					( Origin gBackEnd )
				)
				( attribute "RELATIVE_PROPAGATION_DELAY_SCOPE" "G"
					( Parent
						( matchGroupRef "@baseboard_fab2_lib.baseboard_fab2(sch_1):\MG_KTI_BUNDLE_NG_KTI_CPU1_CPU0_P0P0_12-13\" )
					)
					( Status sCSetFlattened )
					( Origin gBackEnd )
				)
				( attribute "RELATIVE_PROPAGATION_DELAY" ",500.00 MIL"
					( Parent
						( matchGroupRef "@baseboard_fab2_lib.baseboard_fab2(sch_1):\MG_KTI_BUNDLE_NG_KTI_CPU1_CPU0_P0P0_12-13\" )
					)
					( Units "uMatchProp" "ns" 1.000000)
					( Status sCSetFlattened )
					( Origin gBackEnd )
				)
			)
			( pinPair "@baseboard_fab2_lib.baseboard_fab2(sch_1):\PP3155\"
				( pinRef "@baseboard_fab2_lib.baseboard_fab2(sch_1):page33_i86:UPI0_RX_DP(5)" )
				( pinRef "@baseboard_fab2_lib.baseboard_fab2(sch_1):page67_i132:UPI0_TX_DN(14)" )
				( attribute "RELATIVE_PROPAGATION_DELAY_SCOPE" "G"
					( Parent
						( matchGroupRef "@crescent_city_bb_fab1_lib.crescent_city_bb_fab1(sch_1):\MG_KTI_CPU1_CPU0_P0P0\" )
					)
					( Status sCSetFlattened )
					( Origin gBackEnd )
				)
				( attribute "RELATIVE_PROPAGATION_DELAY" "-1315.00 MIL,1315.00 MIL"
					( Parent
						( matchGroupRef "@crescent_city_bb_fab1_lib.crescent_city_bb_fab1(sch_1):\MG_KTI_CPU1_CPU0_P0P0\" )
					)
					( Units "uMatchProp" "ns" 1.000000)
					( Status sCSetFlattened )
					( Origin gBackEnd )
				)
				( attribute "RELATIVE_PROPAGATION_DELAY_SCOPE" "G"
					( Parent
						( matchGroupRef "@baseboard_fab2_lib.baseboard_fab2(sch_1):\MG_KTI_BUNDLE_NG_KTI_CPU1_CPU0_P0P0_14-15\" )
					)
					( Status sCSetFlattened )
					( Origin gBackEnd )
				)
				( attribute "RELATIVE_PROPAGATION_DELAY" ",500.00 MIL"
					( Parent
						( matchGroupRef "@baseboard_fab2_lib.baseboard_fab2(sch_1):\MG_KTI_BUNDLE_NG_KTI_CPU1_CPU0_P0P0_14-15\" )
					)
					( Units "uMatchProp" "ns" 1.000000)
					( Status sCSetFlattened )
					( Origin gBackEnd )
				)
			)
			( pinPair "@baseboard_fab2_lib.baseboard_fab2(sch_1):\PP3156\"
				( pinRef "@baseboard_fab2_lib.baseboard_fab2(sch_1):page33_i86:UPI0_RX_DN(5)" )
				( pinRef "@baseboard_fab2_lib.baseboard_fab2(sch_1):page67_i132:UPI0_TX_DP(14)" )
				( attribute "RELATIVE_PROPAGATION_DELAY_SCOPE" "G"
					( Parent
						( matchGroupRef "@crescent_city_bb_fab1_lib.crescent_city_bb_fab1(sch_1):\MG_KTI_CPU1_CPU0_P0P0\" )
					)
					( Status sCSetFlattened )
					( Origin gBackEnd )
				)
				( attribute "RELATIVE_PROPAGATION_DELAY" "-1315.00 MIL,1315.00 MIL"
					( Parent
						( matchGroupRef "@crescent_city_bb_fab1_lib.crescent_city_bb_fab1(sch_1):\MG_KTI_CPU1_CPU0_P0P0\" )
					)
					( Units "uMatchProp" "ns" 1.000000)
					( Status sCSetFlattened )
					( Origin gBackEnd )
				)
				( attribute "RELATIVE_PROPAGATION_DELAY_SCOPE" "G"
					( Parent
						( matchGroupRef "@baseboard_fab2_lib.baseboard_fab2(sch_1):\MG_KTI_BUNDLE_NG_KTI_CPU1_CPU0_P0P0_14-15\" )
					)
					( Status sCSetFlattened )
					( Origin gBackEnd )
				)
				( attribute "RELATIVE_PROPAGATION_DELAY" ",500.00 MIL"
					( Parent
						( matchGroupRef "@baseboard_fab2_lib.baseboard_fab2(sch_1):\MG_KTI_BUNDLE_NG_KTI_CPU1_CPU0_P0P0_14-15\" )
					)
					( Units "uMatchProp" "ns" 1.000000)
					( Status sCSetFlattened )
					( Origin gBackEnd )
				)
			)
			( pinPair "@baseboard_fab2_lib.baseboard_fab2(sch_1):\PP3157\"
				( pinRef "@baseboard_fab2_lib.baseboard_fab2(sch_1):page67_i132:UPI0_TX_DN(15)" )
				( pinRef "@baseboard_fab2_lib.baseboard_fab2(sch_1):page33_i86:UPI0_RX_DP(4)" )
				( attribute "RELATIVE_PROPAGATION_DELAY_SCOPE" "G"
					( Parent
						( matchGroupRef "@crescent_city_bb_fab1_lib.crescent_city_bb_fab1(sch_1):\MG_KTI_CPU1_CPU0_P0P0\" )
					)
					( Status sCSetFlattened )
					( Origin gBackEnd )
				)
				( attribute "RELATIVE_PROPAGATION_DELAY" "-1315.00 MIL,1315.00 MIL"
					( Parent
						( matchGroupRef "@crescent_city_bb_fab1_lib.crescent_city_bb_fab1(sch_1):\MG_KTI_CPU1_CPU0_P0P0\" )
					)
					( Units "uMatchProp" "ns" 1.000000)
					( Status sCSetFlattened )
					( Origin gBackEnd )
				)
				( attribute "RELATIVE_PROPAGATION_DELAY_SCOPE" "G"
					( Parent
						( matchGroupRef "@baseboard_fab2_lib.baseboard_fab2(sch_1):\MG_KTI_BUNDLE_NG_KTI_CPU1_CPU0_P0P0_14-15\" )
					)
					( Status sCSetFlattened )
					( Origin gBackEnd )
				)
				( attribute "RELATIVE_PROPAGATION_DELAY" ",500.00 MIL"
					( Parent
						( matchGroupRef "@baseboard_fab2_lib.baseboard_fab2(sch_1):\MG_KTI_BUNDLE_NG_KTI_CPU1_CPU0_P0P0_14-15\" )
					)
					( Units "uMatchProp" "ns" 1.000000)
					( Status sCSetFlattened )
					( Origin gBackEnd )
				)
			)
			( pinPair "@baseboard_fab2_lib.baseboard_fab2(sch_1):\PP3158\"
				( pinRef "@baseboard_fab2_lib.baseboard_fab2(sch_1):page67_i132:UPI0_TX_DP(15)" )
				( pinRef "@baseboard_fab2_lib.baseboard_fab2(sch_1):page33_i86:UPI0_RX_DN(4)" )
				( attribute "RELATIVE_PROPAGATION_DELAY_SCOPE" "G"
					( Parent
						( matchGroupRef "@crescent_city_bb_fab1_lib.crescent_city_bb_fab1(sch_1):\MG_KTI_CPU1_CPU0_P0P0\" )
					)
					( Status sCSetFlattened )
					( Origin gBackEnd )
				)
				( attribute "RELATIVE_PROPAGATION_DELAY" "-1315.00 MIL,1315.00 MIL"
					( Parent
						( matchGroupRef "@crescent_city_bb_fab1_lib.crescent_city_bb_fab1(sch_1):\MG_KTI_CPU1_CPU0_P0P0\" )
					)
					( Units "uMatchProp" "ns" 1.000000)
					( Status sCSetFlattened )
					( Origin gBackEnd )
				)
				( attribute "RELATIVE_PROPAGATION_DELAY_SCOPE" "G"
					( Parent
						( matchGroupRef "@baseboard_fab2_lib.baseboard_fab2(sch_1):\MG_KTI_BUNDLE_NG_KTI_CPU1_CPU0_P0P0_14-15\" )
					)
					( Status sCSetFlattened )
					( Origin gBackEnd )
				)
				( attribute "RELATIVE_PROPAGATION_DELAY" ",500.00 MIL"
					( Parent
						( matchGroupRef "@baseboard_fab2_lib.baseboard_fab2(sch_1):\MG_KTI_BUNDLE_NG_KTI_CPU1_CPU0_P0P0_14-15\" )
					)
					( Units "uMatchProp" "ns" 1.000000)
					( Status sCSetFlattened )
					( Origin gBackEnd )
				)
			)
			( pinPair "@baseboard_fab2_lib.baseboard_fab2(sch_1):\PP3151\"
				( pinRef "@baseboard_fab2_lib.baseboard_fab2(sch_1):page33_i86:UPI0_RX_DP(3)" )
				( pinRef "@baseboard_fab2_lib.baseboard_fab2(sch_1):page67_i132:UPI0_TX_DN(16)" )
				( attribute "RELATIVE_PROPAGATION_DELAY_SCOPE" "G"
					( Parent
						( matchGroupRef "@crescent_city_bb_fab1_lib.crescent_city_bb_fab1(sch_1):\MG_KTI_CPU1_CPU0_P0P0\" )
					)
					( Status sCSetFlattened )
					( Origin gBackEnd )
				)
				( attribute "RELATIVE_PROPAGATION_DELAY" "-1315.00 MIL,1315.00 MIL"
					( Parent
						( matchGroupRef "@crescent_city_bb_fab1_lib.crescent_city_bb_fab1(sch_1):\MG_KTI_CPU1_CPU0_P0P0\" )
					)
					( Units "uMatchProp" "ns" 1.000000)
					( Status sCSetFlattened )
					( Origin gBackEnd )
				)
				( attribute "RELATIVE_PROPAGATION_DELAY_SCOPE" "G"
					( Parent
						( matchGroupRef "@baseboard_fab2_lib.baseboard_fab2(sch_1):\MG_KTI_BUNDLE_NG_KTI_CPU1_CPU0_P0P0_16-17\" )
					)
					( Status sCSetFlattened )
					( Origin gBackEnd )
				)
				( attribute "RELATIVE_PROPAGATION_DELAY" ",500.00 MIL"
					( Parent
						( matchGroupRef "@baseboard_fab2_lib.baseboard_fab2(sch_1):\MG_KTI_BUNDLE_NG_KTI_CPU1_CPU0_P0P0_16-17\" )
					)
					( Units "uMatchProp" "ns" 1.000000)
					( Status sCSetFlattened )
					( Origin gBackEnd )
				)
			)
			( pinPair "@baseboard_fab2_lib.baseboard_fab2(sch_1):\PP3152\"
				( pinRef "@baseboard_fab2_lib.baseboard_fab2(sch_1):page33_i86:UPI0_RX_DN(3)" )
				( pinRef "@baseboard_fab2_lib.baseboard_fab2(sch_1):page67_i132:UPI0_TX_DP(16)" )
				( attribute "RELATIVE_PROPAGATION_DELAY_SCOPE" "G"
					( Parent
						( matchGroupRef "@crescent_city_bb_fab1_lib.crescent_city_bb_fab1(sch_1):\MG_KTI_CPU1_CPU0_P0P0\" )
					)
					( Status sCSetFlattened )
					( Origin gBackEnd )
				)
				( attribute "RELATIVE_PROPAGATION_DELAY" "-1315.00 MIL,1315.00 MIL"
					( Parent
						( matchGroupRef "@crescent_city_bb_fab1_lib.crescent_city_bb_fab1(sch_1):\MG_KTI_CPU1_CPU0_P0P0\" )
					)
					( Units "uMatchProp" "ns" 1.000000)
					( Status sCSetFlattened )
					( Origin gBackEnd )
				)
				( attribute "RELATIVE_PROPAGATION_DELAY_SCOPE" "G"
					( Parent
						( matchGroupRef "@baseboard_fab2_lib.baseboard_fab2(sch_1):\MG_KTI_BUNDLE_NG_KTI_CPU1_CPU0_P0P0_16-17\" )
					)
					( Status sCSetFlattened )
					( Origin gBackEnd )
				)
				( attribute "RELATIVE_PROPAGATION_DELAY" ",500.00 MIL"
					( Parent
						( matchGroupRef "@baseboard_fab2_lib.baseboard_fab2(sch_1):\MG_KTI_BUNDLE_NG_KTI_CPU1_CPU0_P0P0_16-17\" )
					)
					( Units "uMatchProp" "ns" 1.000000)
					( Status sCSetFlattened )
					( Origin gBackEnd )
				)
			)
			( pinPair "@baseboard_fab2_lib.baseboard_fab2(sch_1):\PP3153\"
				( pinRef "@baseboard_fab2_lib.baseboard_fab2(sch_1):page33_i86:UPI0_RX_DP(2)" )
				( pinRef "@baseboard_fab2_lib.baseboard_fab2(sch_1):page67_i132:UPI0_TX_DP(17)" )
				( attribute "RELATIVE_PROPAGATION_DELAY_SCOPE" "G"
					( Parent
						( matchGroupRef "@crescent_city_bb_fab1_lib.crescent_city_bb_fab1(sch_1):\MG_KTI_CPU1_CPU0_P0P0\" )
					)
					( Status sCSetFlattened )
					( Origin gBackEnd )
				)
				( attribute "RELATIVE_PROPAGATION_DELAY" "-1315.00 MIL,1315.00 MIL"
					( Parent
						( matchGroupRef "@crescent_city_bb_fab1_lib.crescent_city_bb_fab1(sch_1):\MG_KTI_CPU1_CPU0_P0P0\" )
					)
					( Units "uMatchProp" "ns" 1.000000)
					( Status sCSetFlattened )
					( Origin gBackEnd )
				)
				( attribute "RELATIVE_PROPAGATION_DELAY_SCOPE" "G"
					( Parent
						( matchGroupRef "@baseboard_fab2_lib.baseboard_fab2(sch_1):\MG_KTI_BUNDLE_NG_KTI_CPU1_CPU0_P0P0_16-17\" )
					)
					( Status sCSetFlattened )
					( Origin gBackEnd )
				)
				( attribute "RELATIVE_PROPAGATION_DELAY" ",500.00 MIL"
					( Parent
						( matchGroupRef "@baseboard_fab2_lib.baseboard_fab2(sch_1):\MG_KTI_BUNDLE_NG_KTI_CPU1_CPU0_P0P0_16-17\" )
					)
					( Units "uMatchProp" "ns" 1.000000)
					( Status sCSetFlattened )
					( Origin gBackEnd )
				)
			)
			( pinPair "@baseboard_fab2_lib.baseboard_fab2(sch_1):\PP3154\"
				( pinRef "@baseboard_fab2_lib.baseboard_fab2(sch_1):page33_i86:UPI0_RX_DN(2)" )
				( pinRef "@baseboard_fab2_lib.baseboard_fab2(sch_1):page67_i132:UPI0_TX_DN(17)" )
				( attribute "RELATIVE_PROPAGATION_DELAY_SCOPE" "G"
					( Parent
						( matchGroupRef "@crescent_city_bb_fab1_lib.crescent_city_bb_fab1(sch_1):\MG_KTI_CPU1_CPU0_P0P0\" )
					)
					( Status sCSetFlattened )
					( Origin gBackEnd )
				)
				( attribute "RELATIVE_PROPAGATION_DELAY" "-1315.00 MIL,1315.00 MIL"
					( Parent
						( matchGroupRef "@crescent_city_bb_fab1_lib.crescent_city_bb_fab1(sch_1):\MG_KTI_CPU1_CPU0_P0P0\" )
					)
					( Units "uMatchProp" "ns" 1.000000)
					( Status sCSetFlattened )
					( Origin gBackEnd )
				)
				( attribute "RELATIVE_PROPAGATION_DELAY_SCOPE" "G"
					( Parent
						( matchGroupRef "@baseboard_fab2_lib.baseboard_fab2(sch_1):\MG_KTI_BUNDLE_NG_KTI_CPU1_CPU0_P0P0_16-17\" )
					)
					( Status sCSetFlattened )
					( Origin gBackEnd )
				)
				( attribute "RELATIVE_PROPAGATION_DELAY" ",500.00 MIL"
					( Parent
						( matchGroupRef "@baseboard_fab2_lib.baseboard_fab2(sch_1):\MG_KTI_BUNDLE_NG_KTI_CPU1_CPU0_P0P0_16-17\" )
					)
					( Units "uMatchProp" "ns" 1.000000)
					( Status sCSetFlattened )
					( Origin gBackEnd )
				)
			)
			( pinPair "@baseboard_fab2_lib.baseboard_fab2(sch_1):\PP3147\"
				( pinRef "@baseboard_fab2_lib.baseboard_fab2(sch_1):page33_i86:UPI0_RX_DP(1)" )
				( pinRef "@baseboard_fab2_lib.baseboard_fab2(sch_1):page67_i132:UPI0_TX_DP(18)" )
				( attribute "RELATIVE_PROPAGATION_DELAY_SCOPE" "G"
					( Parent
						( matchGroupRef "@crescent_city_bb_fab1_lib.crescent_city_bb_fab1(sch_1):\MG_KTI_CPU1_CPU0_P0P0\" )
					)
					( Status sCSetFlattened )
					( Origin gBackEnd )
				)
				( attribute "RELATIVE_PROPAGATION_DELAY" "-1315.00 MIL,1315.00 MIL"
					( Parent
						( matchGroupRef "@crescent_city_bb_fab1_lib.crescent_city_bb_fab1(sch_1):\MG_KTI_CPU1_CPU0_P0P0\" )
					)
					( Units "uMatchProp" "ns" 1.000000)
					( Status sCSetFlattened )
					( Origin gBackEnd )
				)
				( attribute "RELATIVE_PROPAGATION_DELAY_SCOPE" "G"
					( Parent
						( matchGroupRef "@baseboard_fab2_lib.baseboard_fab2(sch_1):\MG_KTI_BUNDLE_NG_KTI_CPU1_CPU0_P0P0_18-19\" )
					)
					( Status sCSetFlattened )
					( Origin gBackEnd )
				)
				( attribute "RELATIVE_PROPAGATION_DELAY" ",500.00 MIL"
					( Parent
						( matchGroupRef "@baseboard_fab2_lib.baseboard_fab2(sch_1):\MG_KTI_BUNDLE_NG_KTI_CPU1_CPU0_P0P0_18-19\" )
					)
					( Units "uMatchProp" "ns" 1.000000)
					( Status sCSetFlattened )
					( Origin gBackEnd )
				)
			)
			( pinPair "@baseboard_fab2_lib.baseboard_fab2(sch_1):\PP3148\"
				( pinRef "@baseboard_fab2_lib.baseboard_fab2(sch_1):page67_i132:UPI0_TX_DN(18)" )
				( pinRef "@baseboard_fab2_lib.baseboard_fab2(sch_1):page33_i86:UPI0_RX_DN(1)" )
				( attribute "RELATIVE_PROPAGATION_DELAY_SCOPE" "G"
					( Parent
						( matchGroupRef "@crescent_city_bb_fab1_lib.crescent_city_bb_fab1(sch_1):\MG_KTI_CPU1_CPU0_P0P0\" )
					)
					( Status sCSetFlattened )
					( Origin gBackEnd )
				)
				( attribute "RELATIVE_PROPAGATION_DELAY" "-1315.00 MIL,1315.00 MIL"
					( Parent
						( matchGroupRef "@crescent_city_bb_fab1_lib.crescent_city_bb_fab1(sch_1):\MG_KTI_CPU1_CPU0_P0P0\" )
					)
					( Units "uMatchProp" "ns" 1.000000)
					( Status sCSetFlattened )
					( Origin gBackEnd )
				)
				( attribute "RELATIVE_PROPAGATION_DELAY_SCOPE" "G"
					( Parent
						( matchGroupRef "@baseboard_fab2_lib.baseboard_fab2(sch_1):\MG_KTI_BUNDLE_NG_KTI_CPU1_CPU0_P0P0_18-19\" )
					)
					( Status sCSetFlattened )
					( Origin gBackEnd )
				)
				( attribute "RELATIVE_PROPAGATION_DELAY" ",500.00 MIL"
					( Parent
						( matchGroupRef "@baseboard_fab2_lib.baseboard_fab2(sch_1):\MG_KTI_BUNDLE_NG_KTI_CPU1_CPU0_P0P0_18-19\" )
					)
					( Units "uMatchProp" "ns" 1.000000)
					( Status sCSetFlattened )
					( Origin gBackEnd )
				)
			)
			( pinPair "@baseboard_fab2_lib.baseboard_fab2(sch_1):\PP3149\"
				( pinRef "@baseboard_fab2_lib.baseboard_fab2(sch_1):page67_i132:UPI0_TX_DN(19)" )
				( pinRef "@baseboard_fab2_lib.baseboard_fab2(sch_1):page33_i86:UPI0_RX_DP(0)" )
				( attribute "RELATIVE_PROPAGATION_DELAY_SCOPE" "G"
					( Parent
						( matchGroupRef "@crescent_city_bb_fab1_lib.crescent_city_bb_fab1(sch_1):\MG_KTI_CPU1_CPU0_P0P0\" )
					)
					( Status sCSetFlattened )
					( Origin gBackEnd )
				)
				( attribute "RELATIVE_PROPAGATION_DELAY" "-1315.00 MIL,1315.00 MIL"
					( Parent
						( matchGroupRef "@crescent_city_bb_fab1_lib.crescent_city_bb_fab1(sch_1):\MG_KTI_CPU1_CPU0_P0P0\" )
					)
					( Units "uMatchProp" "ns" 1.000000)
					( Status sCSetFlattened )
					( Origin gBackEnd )
				)
				( attribute "RELATIVE_PROPAGATION_DELAY_SCOPE" "G"
					( Parent
						( matchGroupRef "@baseboard_fab2_lib.baseboard_fab2(sch_1):\MG_KTI_BUNDLE_NG_KTI_CPU1_CPU0_P0P0_18-19\" )
					)
					( Status sCSetFlattened )
					( Origin gBackEnd )
				)
				( attribute "RELATIVE_PROPAGATION_DELAY" ",500.00 MIL"
					( Parent
						( matchGroupRef "@baseboard_fab2_lib.baseboard_fab2(sch_1):\MG_KTI_BUNDLE_NG_KTI_CPU1_CPU0_P0P0_18-19\" )
					)
					( Units "uMatchProp" "ns" 1.000000)
					( Status sCSetFlattened )
					( Origin gBackEnd )
				)
			)
			( pinPair "@baseboard_fab2_lib.baseboard_fab2(sch_1):\PP3150\"
				( pinRef "@baseboard_fab2_lib.baseboard_fab2(sch_1):page33_i86:UPI0_RX_DN(0)" )
				( pinRef "@baseboard_fab2_lib.baseboard_fab2(sch_1):page67_i132:UPI0_TX_DP(19)" )
				( attribute "RELATIVE_PROPAGATION_DELAY_SCOPE" "G"
					( Parent
						( matchGroupRef "@crescent_city_bb_fab1_lib.crescent_city_bb_fab1(sch_1):\MG_KTI_CPU1_CPU0_P0P0\" )
					)
					( Origin gBackEnd )
				)
				( attribute "RELATIVE_PROPAGATION_DELAY" "TARGET,TARGET"
					( Parent
						( matchGroupRef "@crescent_city_bb_fab1_lib.crescent_city_bb_fab1(sch_1):\MG_KTI_CPU1_CPU0_P0P0\" )
					)
					( Units "uMatchProp" "ns" 1.000000)
					( Origin gBackEnd )
				)
				( attribute "RELATIVE_PROPAGATION_DELAY_SCOPE" "G"
					( Parent
						( matchGroupRef "@baseboard_fab2_lib.baseboard_fab2(sch_1):\MG_KTI_BUNDLE_NG_KTI_CPU1_CPU0_P0P0_18-19\" )
					)
					( Status sCSetFlattened )
					( Origin gBackEnd )
				)
				( attribute "RELATIVE_PROPAGATION_DELAY" ",500.00 MIL"
					( Parent
						( matchGroupRef "@baseboard_fab2_lib.baseboard_fab2(sch_1):\MG_KTI_BUNDLE_NG_KTI_CPU1_CPU0_P0P0_18-19\" )
					)
					( Units "uMatchProp" "ns" 1.000000)
					( Status sCSetFlattened )
					( Origin gBackEnd )
				)
			)
			( pinPair "@baseboard_fab2_lib.baseboard_fab2(sch_1):\PP3223\"
				( pinRef "@baseboard_fab2_lib.baseboard_fab2(sch_1):page34_i86:UPI1_TX_DP(19)" )
				( pinRef "@baseboard_fab2_lib.baseboard_fab2(sch_1):page68_i125:UPI1_RX_DN(0)" )
				( attribute "RELATIVE_PROPAGATION_DELAY_SCOPE" "G"
					( Parent
						( matchGroupRef "@crescent_city_bb_fab1_lib.crescent_city_bb_fab1(sch_1):\MG_KTI_CPU0_CPU1_P1P1\" )
					)
					( Status sCSetFlattened )
					( Origin gBackEnd )
				)
				( attribute "RELATIVE_PROPAGATION_DELAY" "-1315.00 MIL,1315.00 MIL"
					( Parent
						( matchGroupRef "@crescent_city_bb_fab1_lib.crescent_city_bb_fab1(sch_1):\MG_KTI_CPU0_CPU1_P1P1\" )
					)
					( Units "uMatchProp" "ns" 1.000000)
					( Status sCSetFlattened )
					( Origin gBackEnd )
				)
				( attribute "RELATIVE_PROPAGATION_DELAY_SCOPE" "G"
					( Parent
						( matchGroupRef "@baseboard_fab2_lib.baseboard_fab2(sch_1):\MG_KTI_BUNDLE_NG_KTI_CPU0_CPU1_P1P1_0-1\" )
					)
					( Status sCSetFlattened )
					( Origin gBackEnd )
				)
				( attribute "RELATIVE_PROPAGATION_DELAY" ",500.00 MIL"
					( Parent
						( matchGroupRef "@baseboard_fab2_lib.baseboard_fab2(sch_1):\MG_KTI_BUNDLE_NG_KTI_CPU0_CPU1_P1P1_0-1\" )
					)
					( Units "uMatchProp" "ns" 1.000000)
					( Status sCSetFlattened )
					( Origin gBackEnd )
				)
			)
			( pinPair "@baseboard_fab2_lib.baseboard_fab2(sch_1):\PP3224\"
				( pinRef "@baseboard_fab2_lib.baseboard_fab2(sch_1):page34_i86:UPI1_TX_DN(19)" )
				( pinRef "@baseboard_fab2_lib.baseboard_fab2(sch_1):page68_i125:UPI1_RX_DP(0)" )
				( attribute "RELATIVE_PROPAGATION_DELAY_SCOPE" "G"
					( Parent
						( matchGroupRef "@crescent_city_bb_fab1_lib.crescent_city_bb_fab1(sch_1):\MG_KTI_CPU0_CPU1_P1P1\" )
					)
					( Status sCSetFlattened )
					( Origin gBackEnd )
				)
				( attribute "RELATIVE_PROPAGATION_DELAY" "-1315.00 MIL,1315.00 MIL"
					( Parent
						( matchGroupRef "@crescent_city_bb_fab1_lib.crescent_city_bb_fab1(sch_1):\MG_KTI_CPU0_CPU1_P1P1\" )
					)
					( Units "uMatchProp" "ns" 1.000000)
					( Status sCSetFlattened )
					( Origin gBackEnd )
				)
				( attribute "RELATIVE_PROPAGATION_DELAY_SCOPE" "G"
					( Parent
						( matchGroupRef "@baseboard_fab2_lib.baseboard_fab2(sch_1):\MG_KTI_BUNDLE_NG_KTI_CPU0_CPU1_P1P1_0-1\" )
					)
					( Status sCSetFlattened )
					( Origin gBackEnd )
				)
				( attribute "RELATIVE_PROPAGATION_DELAY" ",500.00 MIL"
					( Parent
						( matchGroupRef "@baseboard_fab2_lib.baseboard_fab2(sch_1):\MG_KTI_BUNDLE_NG_KTI_CPU0_CPU1_P1P1_0-1\" )
					)
					( Units "uMatchProp" "ns" 1.000000)
					( Status sCSetFlattened )
					( Origin gBackEnd )
				)
			)
			( pinPair "@baseboard_fab2_lib.baseboard_fab2(sch_1):\PP3225\"
				( pinRef "@baseboard_fab2_lib.baseboard_fab2(sch_1):page34_i86:UPI1_TX_DP(18)" )
				( pinRef "@baseboard_fab2_lib.baseboard_fab2(sch_1):page68_i125:UPI1_RX_DP(1)" )
				( attribute "RELATIVE_PROPAGATION_DELAY_SCOPE" "G"
					( Parent
						( matchGroupRef "@crescent_city_bb_fab1_lib.crescent_city_bb_fab1(sch_1):\MG_KTI_CPU0_CPU1_P1P1\" )
					)
					( Status sCSetFlattened )
					( Origin gBackEnd )
				)
				( attribute "RELATIVE_PROPAGATION_DELAY" "-1315.00 MIL,1315.00 MIL"
					( Parent
						( matchGroupRef "@crescent_city_bb_fab1_lib.crescent_city_bb_fab1(sch_1):\MG_KTI_CPU0_CPU1_P1P1\" )
					)
					( Units "uMatchProp" "ns" 1.000000)
					( Status sCSetFlattened )
					( Origin gBackEnd )
				)
				( attribute "RELATIVE_PROPAGATION_DELAY_SCOPE" "G"
					( Parent
						( matchGroupRef "@baseboard_fab2_lib.baseboard_fab2(sch_1):\MG_KTI_BUNDLE_NG_KTI_CPU0_CPU1_P1P1_0-1\" )
					)
					( Status sCSetFlattened )
					( Origin gBackEnd )
				)
				( attribute "RELATIVE_PROPAGATION_DELAY" ",500.00 MIL"
					( Parent
						( matchGroupRef "@baseboard_fab2_lib.baseboard_fab2(sch_1):\MG_KTI_BUNDLE_NG_KTI_CPU0_CPU1_P1P1_0-1\" )
					)
					( Units "uMatchProp" "ns" 1.000000)
					( Status sCSetFlattened )
					( Origin gBackEnd )
				)
			)
			( pinPair "@baseboard_fab2_lib.baseboard_fab2(sch_1):\PP3226\"
				( pinRef "@baseboard_fab2_lib.baseboard_fab2(sch_1):page34_i86:UPI1_TX_DN(18)" )
				( pinRef "@baseboard_fab2_lib.baseboard_fab2(sch_1):page68_i125:UPI1_RX_DN(1)" )
				( attribute "RELATIVE_PROPAGATION_DELAY_SCOPE" "G"
					( Parent
						( matchGroupRef "@crescent_city_bb_fab1_lib.crescent_city_bb_fab1(sch_1):\MG_KTI_CPU0_CPU1_P1P1\" )
					)
					( Status sCSetFlattened )
					( Origin gBackEnd )
				)
				( attribute "RELATIVE_PROPAGATION_DELAY" "-1315.00 MIL,1315.00 MIL"
					( Parent
						( matchGroupRef "@crescent_city_bb_fab1_lib.crescent_city_bb_fab1(sch_1):\MG_KTI_CPU0_CPU1_P1P1\" )
					)
					( Units "uMatchProp" "ns" 1.000000)
					( Status sCSetFlattened )
					( Origin gBackEnd )
				)
				( attribute "RELATIVE_PROPAGATION_DELAY_SCOPE" "G"
					( Parent
						( matchGroupRef "@baseboard_fab2_lib.baseboard_fab2(sch_1):\MG_KTI_BUNDLE_NG_KTI_CPU0_CPU1_P1P1_0-1\" )
					)
					( Status sCSetFlattened )
					( Origin gBackEnd )
				)
				( attribute "RELATIVE_PROPAGATION_DELAY" ",500.00 MIL"
					( Parent
						( matchGroupRef "@baseboard_fab2_lib.baseboard_fab2(sch_1):\MG_KTI_BUNDLE_NG_KTI_CPU0_CPU1_P1P1_0-1\" )
					)
					( Units "uMatchProp" "ns" 1.000000)
					( Status sCSetFlattened )
					( Origin gBackEnd )
				)
			)
			( pinPair "@baseboard_fab2_lib.baseboard_fab2(sch_1):\PP3219\"
				( pinRef "@baseboard_fab2_lib.baseboard_fab2(sch_1):page34_i86:UPI1_TX_DP(17)" )
				( pinRef "@baseboard_fab2_lib.baseboard_fab2(sch_1):page68_i125:UPI1_RX_DP(2)" )
				( attribute "RELATIVE_PROPAGATION_DELAY_SCOPE" "G"
					( Parent
						( matchGroupRef "@crescent_city_bb_fab1_lib.crescent_city_bb_fab1(sch_1):\MG_KTI_CPU0_CPU1_P1P1\" )
					)
					( Status sCSetFlattened )
					( Origin gBackEnd )
				)
				( attribute "RELATIVE_PROPAGATION_DELAY" "-1315.00 MIL,1315.00 MIL"
					( Parent
						( matchGroupRef "@crescent_city_bb_fab1_lib.crescent_city_bb_fab1(sch_1):\MG_KTI_CPU0_CPU1_P1P1\" )
					)
					( Units "uMatchProp" "ns" 1.000000)
					( Status sCSetFlattened )
					( Origin gBackEnd )
				)
				( attribute "RELATIVE_PROPAGATION_DELAY_SCOPE" "G"
					( Parent
						( matchGroupRef "@baseboard_fab2_lib.baseboard_fab2(sch_1):\MG_KTI_BUNDLE_NG_KTI_CPU0_CPU1_P1P1_2-3\" )
					)
					( Status sCSetFlattened )
					( Origin gBackEnd )
				)
				( attribute "RELATIVE_PROPAGATION_DELAY" ",500.00 MIL"
					( Parent
						( matchGroupRef "@baseboard_fab2_lib.baseboard_fab2(sch_1):\MG_KTI_BUNDLE_NG_KTI_CPU0_CPU1_P1P1_2-3\" )
					)
					( Units "uMatchProp" "ns" 1.000000)
					( Status sCSetFlattened )
					( Origin gBackEnd )
				)
			)
			( pinPair "@baseboard_fab2_lib.baseboard_fab2(sch_1):\PP3220\"
				( pinRef "@baseboard_fab2_lib.baseboard_fab2(sch_1):page34_i86:UPI1_TX_DN(17)" )
				( pinRef "@baseboard_fab2_lib.baseboard_fab2(sch_1):page68_i125:UPI1_RX_DN(2)" )
				( attribute "RELATIVE_PROPAGATION_DELAY_SCOPE" "G"
					( Parent
						( matchGroupRef "@crescent_city_bb_fab1_lib.crescent_city_bb_fab1(sch_1):\MG_KTI_CPU0_CPU1_P1P1\" )
					)
					( Status sCSetFlattened )
					( Origin gBackEnd )
				)
				( attribute "RELATIVE_PROPAGATION_DELAY" "-1315.00 MIL,1315.00 MIL"
					( Parent
						( matchGroupRef "@crescent_city_bb_fab1_lib.crescent_city_bb_fab1(sch_1):\MG_KTI_CPU0_CPU1_P1P1\" )
					)
					( Units "uMatchProp" "ns" 1.000000)
					( Status sCSetFlattened )
					( Origin gBackEnd )
				)
				( attribute "RELATIVE_PROPAGATION_DELAY_SCOPE" "G"
					( Parent
						( matchGroupRef "@baseboard_fab2_lib.baseboard_fab2(sch_1):\MG_KTI_BUNDLE_NG_KTI_CPU0_CPU1_P1P1_2-3\" )
					)
					( Status sCSetFlattened )
					( Origin gBackEnd )
				)
				( attribute "RELATIVE_PROPAGATION_DELAY" ",500.00 MIL"
					( Parent
						( matchGroupRef "@baseboard_fab2_lib.baseboard_fab2(sch_1):\MG_KTI_BUNDLE_NG_KTI_CPU0_CPU1_P1P1_2-3\" )
					)
					( Units "uMatchProp" "ns" 1.000000)
					( Status sCSetFlattened )
					( Origin gBackEnd )
				)
			)
			( pinPair "@baseboard_fab2_lib.baseboard_fab2(sch_1):\PP3221\"
				( pinRef "@baseboard_fab2_lib.baseboard_fab2(sch_1):page34_i86:UPI1_TX_DP(16)" )
				( pinRef "@baseboard_fab2_lib.baseboard_fab2(sch_1):page68_i125:UPI1_RX_DP(3)" )
				( attribute "RELATIVE_PROPAGATION_DELAY_SCOPE" "G"
					( Parent
						( matchGroupRef "@crescent_city_bb_fab1_lib.crescent_city_bb_fab1(sch_1):\MG_KTI_CPU0_CPU1_P1P1\" )
					)
					( Status sCSetFlattened )
					( Origin gBackEnd )
				)
				( attribute "RELATIVE_PROPAGATION_DELAY" "-1315.00 MIL,1315.00 MIL"
					( Parent
						( matchGroupRef "@crescent_city_bb_fab1_lib.crescent_city_bb_fab1(sch_1):\MG_KTI_CPU0_CPU1_P1P1\" )
					)
					( Units "uMatchProp" "ns" 1.000000)
					( Status sCSetFlattened )
					( Origin gBackEnd )
				)
				( attribute "RELATIVE_PROPAGATION_DELAY_SCOPE" "G"
					( Parent
						( matchGroupRef "@baseboard_fab2_lib.baseboard_fab2(sch_1):\MG_KTI_BUNDLE_NG_KTI_CPU0_CPU1_P1P1_2-3\" )
					)
					( Status sCSetFlattened )
					( Origin gBackEnd )
				)
				( attribute "RELATIVE_PROPAGATION_DELAY" ",500.00 MIL"
					( Parent
						( matchGroupRef "@baseboard_fab2_lib.baseboard_fab2(sch_1):\MG_KTI_BUNDLE_NG_KTI_CPU0_CPU1_P1P1_2-3\" )
					)
					( Units "uMatchProp" "ns" 1.000000)
					( Status sCSetFlattened )
					( Origin gBackEnd )
				)
			)
			( pinPair "@baseboard_fab2_lib.baseboard_fab2(sch_1):\PP3222\"
				( pinRef "@baseboard_fab2_lib.baseboard_fab2(sch_1):page34_i86:UPI1_TX_DN(16)" )
				( pinRef "@baseboard_fab2_lib.baseboard_fab2(sch_1):page68_i125:UPI1_RX_DN(3)" )
				( attribute "RELATIVE_PROPAGATION_DELAY_SCOPE" "G"
					( Parent
						( matchGroupRef "@crescent_city_bb_fab1_lib.crescent_city_bb_fab1(sch_1):\MG_KTI_CPU0_CPU1_P1P1\" )
					)
					( Status sCSetFlattened )
					( Origin gBackEnd )
				)
				( attribute "RELATIVE_PROPAGATION_DELAY" "-1315.00 MIL,1315.00 MIL"
					( Parent
						( matchGroupRef "@crescent_city_bb_fab1_lib.crescent_city_bb_fab1(sch_1):\MG_KTI_CPU0_CPU1_P1P1\" )
					)
					( Units "uMatchProp" "ns" 1.000000)
					( Status sCSetFlattened )
					( Origin gBackEnd )
				)
				( attribute "RELATIVE_PROPAGATION_DELAY_SCOPE" "G"
					( Parent
						( matchGroupRef "@baseboard_fab2_lib.baseboard_fab2(sch_1):\MG_KTI_BUNDLE_NG_KTI_CPU0_CPU1_P1P1_2-3\" )
					)
					( Status sCSetFlattened )
					( Origin gBackEnd )
				)
				( attribute "RELATIVE_PROPAGATION_DELAY" ",500.00 MIL"
					( Parent
						( matchGroupRef "@baseboard_fab2_lib.baseboard_fab2(sch_1):\MG_KTI_BUNDLE_NG_KTI_CPU0_CPU1_P1P1_2-3\" )
					)
					( Units "uMatchProp" "ns" 1.000000)
					( Status sCSetFlattened )
					( Origin gBackEnd )
				)
			)
			( pinPair "@baseboard_fab2_lib.baseboard_fab2(sch_1):\PP3215\"
				( pinRef "@baseboard_fab2_lib.baseboard_fab2(sch_1):page34_i86:UPI1_TX_DP(15)" )
				( pinRef "@baseboard_fab2_lib.baseboard_fab2(sch_1):page68_i125:UPI1_RX_DP(4)" )
				( attribute "RELATIVE_PROPAGATION_DELAY_SCOPE" "G"
					( Parent
						( matchGroupRef "@crescent_city_bb_fab1_lib.crescent_city_bb_fab1(sch_1):\MG_KTI_CPU0_CPU1_P1P1\" )
					)
					( Status sCSetFlattened )
					( Origin gBackEnd )
				)
				( attribute "RELATIVE_PROPAGATION_DELAY" "-1315.00 MIL,1315.00 MIL"
					( Parent
						( matchGroupRef "@crescent_city_bb_fab1_lib.crescent_city_bb_fab1(sch_1):\MG_KTI_CPU0_CPU1_P1P1\" )
					)
					( Units "uMatchProp" "ns" 1.000000)
					( Status sCSetFlattened )
					( Origin gBackEnd )
				)
				( attribute "RELATIVE_PROPAGATION_DELAY_SCOPE" "G"
					( Parent
						( matchGroupRef "@baseboard_fab2_lib.baseboard_fab2(sch_1):\MG_KTI_BUNDLE_NG_KTI_CPU0_CPU1_P1P1_4-5\" )
					)
					( Status sCSetFlattened )
					( Origin gBackEnd )
				)
				( attribute "RELATIVE_PROPAGATION_DELAY" ",500.00 MIL"
					( Parent
						( matchGroupRef "@baseboard_fab2_lib.baseboard_fab2(sch_1):\MG_KTI_BUNDLE_NG_KTI_CPU0_CPU1_P1P1_4-5\" )
					)
					( Units "uMatchProp" "ns" 1.000000)
					( Status sCSetFlattened )
					( Origin gBackEnd )
				)
			)
			( pinPair "@baseboard_fab2_lib.baseboard_fab2(sch_1):\PP3216\"
				( pinRef "@baseboard_fab2_lib.baseboard_fab2(sch_1):page34_i86:UPI1_TX_DN(15)" )
				( pinRef "@baseboard_fab2_lib.baseboard_fab2(sch_1):page68_i125:UPI1_RX_DN(4)" )
				( attribute "RELATIVE_PROPAGATION_DELAY_SCOPE" "G"
					( Parent
						( matchGroupRef "@crescent_city_bb_fab1_lib.crescent_city_bb_fab1(sch_1):\MG_KTI_CPU0_CPU1_P1P1\" )
					)
					( Status sCSetFlattened )
					( Origin gBackEnd )
				)
				( attribute "RELATIVE_PROPAGATION_DELAY" "-1315.00 MIL,1315.00 MIL"
					( Parent
						( matchGroupRef "@crescent_city_bb_fab1_lib.crescent_city_bb_fab1(sch_1):\MG_KTI_CPU0_CPU1_P1P1\" )
					)
					( Units "uMatchProp" "ns" 1.000000)
					( Status sCSetFlattened )
					( Origin gBackEnd )
				)
				( attribute "RELATIVE_PROPAGATION_DELAY_SCOPE" "G"
					( Parent
						( matchGroupRef "@baseboard_fab2_lib.baseboard_fab2(sch_1):\MG_KTI_BUNDLE_NG_KTI_CPU0_CPU1_P1P1_4-5\" )
					)
					( Status sCSetFlattened )
					( Origin gBackEnd )
				)
				( attribute "RELATIVE_PROPAGATION_DELAY" ",500.00 MIL"
					( Parent
						( matchGroupRef "@baseboard_fab2_lib.baseboard_fab2(sch_1):\MG_KTI_BUNDLE_NG_KTI_CPU0_CPU1_P1P1_4-5\" )
					)
					( Units "uMatchProp" "ns" 1.000000)
					( Status sCSetFlattened )
					( Origin gBackEnd )
				)
			)
			( pinPair "@baseboard_fab2_lib.baseboard_fab2(sch_1):\PP3217\"
				( pinRef "@baseboard_fab2_lib.baseboard_fab2(sch_1):page68_i125:UPI1_RX_DP(5)" )
				( pinRef "@baseboard_fab2_lib.baseboard_fab2(sch_1):page34_i86:UPI1_TX_DP(14)" )
				( attribute "RELATIVE_PROPAGATION_DELAY_SCOPE" "G"
					( Parent
						( matchGroupRef "@crescent_city_bb_fab1_lib.crescent_city_bb_fab1(sch_1):\MG_KTI_CPU0_CPU1_P1P1\" )
					)
					( Status sCSetFlattened )
					( Origin gBackEnd )
				)
				( attribute "RELATIVE_PROPAGATION_DELAY" "-1315.00 MIL,1315.00 MIL"
					( Parent
						( matchGroupRef "@crescent_city_bb_fab1_lib.crescent_city_bb_fab1(sch_1):\MG_KTI_CPU0_CPU1_P1P1\" )
					)
					( Units "uMatchProp" "ns" 1.000000)
					( Status sCSetFlattened )
					( Origin gBackEnd )
				)
				( attribute "RELATIVE_PROPAGATION_DELAY_SCOPE" "G"
					( Parent
						( matchGroupRef "@baseboard_fab2_lib.baseboard_fab2(sch_1):\MG_KTI_BUNDLE_NG_KTI_CPU0_CPU1_P1P1_4-5\" )
					)
					( Status sCSetFlattened )
					( Origin gBackEnd )
				)
				( attribute "RELATIVE_PROPAGATION_DELAY" ",500.00 MIL"
					( Parent
						( matchGroupRef "@baseboard_fab2_lib.baseboard_fab2(sch_1):\MG_KTI_BUNDLE_NG_KTI_CPU0_CPU1_P1P1_4-5\" )
					)
					( Units "uMatchProp" "ns" 1.000000)
					( Status sCSetFlattened )
					( Origin gBackEnd )
				)
			)
			( pinPair "@baseboard_fab2_lib.baseboard_fab2(sch_1):\PP3218\"
				( pinRef "@baseboard_fab2_lib.baseboard_fab2(sch_1):page68_i125:UPI1_RX_DN(5)" )
				( pinRef "@baseboard_fab2_lib.baseboard_fab2(sch_1):page34_i86:UPI1_TX_DN(14)" )
				( attribute "RELATIVE_PROPAGATION_DELAY_SCOPE" "G"
					( Parent
						( matchGroupRef "@crescent_city_bb_fab1_lib.crescent_city_bb_fab1(sch_1):\MG_KTI_CPU0_CPU1_P1P1\" )
					)
					( Status sCSetFlattened )
					( Origin gBackEnd )
				)
				( attribute "RELATIVE_PROPAGATION_DELAY" "-1315.00 MIL,1315.00 MIL"
					( Parent
						( matchGroupRef "@crescent_city_bb_fab1_lib.crescent_city_bb_fab1(sch_1):\MG_KTI_CPU0_CPU1_P1P1\" )
					)
					( Units "uMatchProp" "ns" 1.000000)
					( Status sCSetFlattened )
					( Origin gBackEnd )
				)
				( attribute "RELATIVE_PROPAGATION_DELAY_SCOPE" "G"
					( Parent
						( matchGroupRef "@baseboard_fab2_lib.baseboard_fab2(sch_1):\MG_KTI_BUNDLE_NG_KTI_CPU0_CPU1_P1P1_4-5\" )
					)
					( Status sCSetFlattened )
					( Origin gBackEnd )
				)
				( attribute "RELATIVE_PROPAGATION_DELAY" ",500.00 MIL"
					( Parent
						( matchGroupRef "@baseboard_fab2_lib.baseboard_fab2(sch_1):\MG_KTI_BUNDLE_NG_KTI_CPU0_CPU1_P1P1_4-5\" )
					)
					( Units "uMatchProp" "ns" 1.000000)
					( Status sCSetFlattened )
					( Origin gBackEnd )
				)
			)
			( pinPair "@baseboard_fab2_lib.baseboard_fab2(sch_1):\PP3211\"
				( pinRef "@baseboard_fab2_lib.baseboard_fab2(sch_1):page34_i86:UPI1_TX_DP(13)" )
				( pinRef "@baseboard_fab2_lib.baseboard_fab2(sch_1):page68_i125:UPI1_RX_DP(6)" )
				( attribute "RELATIVE_PROPAGATION_DELAY_SCOPE" "G"
					( Parent
						( matchGroupRef "@crescent_city_bb_fab1_lib.crescent_city_bb_fab1(sch_1):\MG_KTI_CPU0_CPU1_P1P1\" )
					)
					( Status sCSetFlattened )
					( Origin gBackEnd )
				)
				( attribute "RELATIVE_PROPAGATION_DELAY" "-1315.00 MIL,1315.00 MIL"
					( Parent
						( matchGroupRef "@crescent_city_bb_fab1_lib.crescent_city_bb_fab1(sch_1):\MG_KTI_CPU0_CPU1_P1P1\" )
					)
					( Units "uMatchProp" "ns" 1.000000)
					( Status sCSetFlattened )
					( Origin gBackEnd )
				)
				( attribute "RELATIVE_PROPAGATION_DELAY_SCOPE" "G"
					( Parent
						( matchGroupRef "@baseboard_fab2_lib.baseboard_fab2(sch_1):\MG_KTI_BUNDLE_NG_KTI_CPU0_CPU1_P1P1_6-7\" )
					)
					( Status sCSetFlattened )
					( Origin gBackEnd )
				)
				( attribute "RELATIVE_PROPAGATION_DELAY" ",500.00 MIL"
					( Parent
						( matchGroupRef "@baseboard_fab2_lib.baseboard_fab2(sch_1):\MG_KTI_BUNDLE_NG_KTI_CPU0_CPU1_P1P1_6-7\" )
					)
					( Units "uMatchProp" "ns" 1.000000)
					( Status sCSetFlattened )
					( Origin gBackEnd )
				)
			)
			( pinPair "@baseboard_fab2_lib.baseboard_fab2(sch_1):\PP3212\"
				( pinRef "@baseboard_fab2_lib.baseboard_fab2(sch_1):page34_i86:UPI1_TX_DN(13)" )
				( pinRef "@baseboard_fab2_lib.baseboard_fab2(sch_1):page68_i125:UPI1_RX_DN(6)" )
				( attribute "RELATIVE_PROPAGATION_DELAY_SCOPE" "G"
					( Parent
						( matchGroupRef "@crescent_city_bb_fab1_lib.crescent_city_bb_fab1(sch_1):\MG_KTI_CPU0_CPU1_P1P1\" )
					)
					( Status sCSetFlattened )
					( Origin gBackEnd )
				)
				( attribute "RELATIVE_PROPAGATION_DELAY" "-1315.00 MIL,1315.00 MIL"
					( Parent
						( matchGroupRef "@crescent_city_bb_fab1_lib.crescent_city_bb_fab1(sch_1):\MG_KTI_CPU0_CPU1_P1P1\" )
					)
					( Units "uMatchProp" "ns" 1.000000)
					( Status sCSetFlattened )
					( Origin gBackEnd )
				)
				( attribute "RELATIVE_PROPAGATION_DELAY_SCOPE" "G"
					( Parent
						( matchGroupRef "@baseboard_fab2_lib.baseboard_fab2(sch_1):\MG_KTI_BUNDLE_NG_KTI_CPU0_CPU1_P1P1_6-7\" )
					)
					( Status sCSetFlattened )
					( Origin gBackEnd )
				)
				( attribute "RELATIVE_PROPAGATION_DELAY" ",500.00 MIL"
					( Parent
						( matchGroupRef "@baseboard_fab2_lib.baseboard_fab2(sch_1):\MG_KTI_BUNDLE_NG_KTI_CPU0_CPU1_P1P1_6-7\" )
					)
					( Units "uMatchProp" "ns" 1.000000)
					( Status sCSetFlattened )
					( Origin gBackEnd )
				)
			)
			( pinPair "@baseboard_fab2_lib.baseboard_fab2(sch_1):\PP3213\"
				( pinRef "@baseboard_fab2_lib.baseboard_fab2(sch_1):page34_i86:UPI1_TX_DP(12)" )
				( pinRef "@baseboard_fab2_lib.baseboard_fab2(sch_1):page68_i125:UPI1_RX_DP(7)" )
				( attribute "RELATIVE_PROPAGATION_DELAY_SCOPE" "G"
					( Parent
						( matchGroupRef "@crescent_city_bb_fab1_lib.crescent_city_bb_fab1(sch_1):\MG_KTI_CPU0_CPU1_P1P1\" )
					)
					( Status sCSetFlattened )
					( Origin gBackEnd )
				)
				( attribute "RELATIVE_PROPAGATION_DELAY" "-1315.00 MIL,1315.00 MIL"
					( Parent
						( matchGroupRef "@crescent_city_bb_fab1_lib.crescent_city_bb_fab1(sch_1):\MG_KTI_CPU0_CPU1_P1P1\" )
					)
					( Units "uMatchProp" "ns" 1.000000)
					( Status sCSetFlattened )
					( Origin gBackEnd )
				)
				( attribute "RELATIVE_PROPAGATION_DELAY_SCOPE" "G"
					( Parent
						( matchGroupRef "@baseboard_fab2_lib.baseboard_fab2(sch_1):\MG_KTI_BUNDLE_NG_KTI_CPU0_CPU1_P1P1_6-7\" )
					)
					( Status sCSetFlattened )
					( Origin gBackEnd )
				)
				( attribute "RELATIVE_PROPAGATION_DELAY" ",500.00 MIL"
					( Parent
						( matchGroupRef "@baseboard_fab2_lib.baseboard_fab2(sch_1):\MG_KTI_BUNDLE_NG_KTI_CPU0_CPU1_P1P1_6-7\" )
					)
					( Units "uMatchProp" "ns" 1.000000)
					( Status sCSetFlattened )
					( Origin gBackEnd )
				)
			)
			( pinPair "@baseboard_fab2_lib.baseboard_fab2(sch_1):\PP3214\"
				( pinRef "@baseboard_fab2_lib.baseboard_fab2(sch_1):page34_i86:UPI1_TX_DN(12)" )
				( pinRef "@baseboard_fab2_lib.baseboard_fab2(sch_1):page68_i125:UPI1_RX_DN(7)" )
				( attribute "RELATIVE_PROPAGATION_DELAY_SCOPE" "G"
					( Parent
						( matchGroupRef "@crescent_city_bb_fab1_lib.crescent_city_bb_fab1(sch_1):\MG_KTI_CPU0_CPU1_P1P1\" )
					)
					( Status sCSetFlattened )
					( Origin gBackEnd )
				)
				( attribute "RELATIVE_PROPAGATION_DELAY" "-1315.00 MIL,1315.00 MIL"
					( Parent
						( matchGroupRef "@crescent_city_bb_fab1_lib.crescent_city_bb_fab1(sch_1):\MG_KTI_CPU0_CPU1_P1P1\" )
					)
					( Units "uMatchProp" "ns" 1.000000)
					( Status sCSetFlattened )
					( Origin gBackEnd )
				)
				( attribute "RELATIVE_PROPAGATION_DELAY_SCOPE" "G"
					( Parent
						( matchGroupRef "@baseboard_fab2_lib.baseboard_fab2(sch_1):\MG_KTI_BUNDLE_NG_KTI_CPU0_CPU1_P1P1_6-7\" )
					)
					( Status sCSetFlattened )
					( Origin gBackEnd )
				)
				( attribute "RELATIVE_PROPAGATION_DELAY" ",500.00 MIL"
					( Parent
						( matchGroupRef "@baseboard_fab2_lib.baseboard_fab2(sch_1):\MG_KTI_BUNDLE_NG_KTI_CPU0_CPU1_P1P1_6-7\" )
					)
					( Units "uMatchProp" "ns" 1.000000)
					( Status sCSetFlattened )
					( Origin gBackEnd )
				)
			)
			( pinPair "@baseboard_fab2_lib.baseboard_fab2(sch_1):\PP3207\"
				( pinRef "@baseboard_fab2_lib.baseboard_fab2(sch_1):page68_i125:UPI1_RX_DN(8)" )
				( pinRef "@baseboard_fab2_lib.baseboard_fab2(sch_1):page34_i86:UPI1_TX_DP(11)" )
				( attribute "RELATIVE_PROPAGATION_DELAY_SCOPE" "G"
					( Parent
						( matchGroupRef "@crescent_city_bb_fab1_lib.crescent_city_bb_fab1(sch_1):\MG_KTI_CPU0_CPU1_P1P1\" )
					)
					( Status sCSetFlattened )
					( Origin gBackEnd )
				)
				( attribute "RELATIVE_PROPAGATION_DELAY" "-1315.00 MIL,1315.00 MIL"
					( Parent
						( matchGroupRef "@crescent_city_bb_fab1_lib.crescent_city_bb_fab1(sch_1):\MG_KTI_CPU0_CPU1_P1P1\" )
					)
					( Units "uMatchProp" "ns" 1.000000)
					( Status sCSetFlattened )
					( Origin gBackEnd )
				)
				( attribute "RELATIVE_PROPAGATION_DELAY_SCOPE" "G"
					( Parent
						( matchGroupRef "@baseboard_fab2_lib.baseboard_fab2(sch_1):\MG_KTI_BUNDLE_NG_KTI_CPU0_CPU1_P1P1_8-9\" )
					)
					( Status sCSetFlattened )
					( Origin gBackEnd )
				)
				( attribute "RELATIVE_PROPAGATION_DELAY" ",500.00 MIL"
					( Parent
						( matchGroupRef "@baseboard_fab2_lib.baseboard_fab2(sch_1):\MG_KTI_BUNDLE_NG_KTI_CPU0_CPU1_P1P1_8-9\" )
					)
					( Units "uMatchProp" "ns" 1.000000)
					( Status sCSetFlattened )
					( Origin gBackEnd )
				)
			)
			( pinPair "@baseboard_fab2_lib.baseboard_fab2(sch_1):\PP3208\"
				( pinRef "@baseboard_fab2_lib.baseboard_fab2(sch_1):page68_i125:UPI1_RX_DP(8)" )
				( pinRef "@baseboard_fab2_lib.baseboard_fab2(sch_1):page34_i86:UPI1_TX_DN(11)" )
				( attribute "RELATIVE_PROPAGATION_DELAY_SCOPE" "G"
					( Parent
						( matchGroupRef "@crescent_city_bb_fab1_lib.crescent_city_bb_fab1(sch_1):\MG_KTI_CPU0_CPU1_P1P1\" )
					)
					( Status sCSetFlattened )
					( Origin gBackEnd )
				)
				( attribute "RELATIVE_PROPAGATION_DELAY" "-1315.00 MIL,1315.00 MIL"
					( Parent
						( matchGroupRef "@crescent_city_bb_fab1_lib.crescent_city_bb_fab1(sch_1):\MG_KTI_CPU0_CPU1_P1P1\" )
					)
					( Units "uMatchProp" "ns" 1.000000)
					( Status sCSetFlattened )
					( Origin gBackEnd )
				)
				( attribute "RELATIVE_PROPAGATION_DELAY_SCOPE" "G"
					( Parent
						( matchGroupRef "@baseboard_fab2_lib.baseboard_fab2(sch_1):\MG_KTI_BUNDLE_NG_KTI_CPU0_CPU1_P1P1_8-9\" )
					)
					( Status sCSetFlattened )
					( Origin gBackEnd )
				)
				( attribute "RELATIVE_PROPAGATION_DELAY" ",500.00 MIL"
					( Parent
						( matchGroupRef "@baseboard_fab2_lib.baseboard_fab2(sch_1):\MG_KTI_BUNDLE_NG_KTI_CPU0_CPU1_P1P1_8-9\" )
					)
					( Units "uMatchProp" "ns" 1.000000)
					( Status sCSetFlattened )
					( Origin gBackEnd )
				)
			)
			( pinPair "@baseboard_fab2_lib.baseboard_fab2(sch_1):\PP3209\"
				( pinRef "@baseboard_fab2_lib.baseboard_fab2(sch_1):page68_i125:UPI1_RX_DP(9)" )
				( pinRef "@baseboard_fab2_lib.baseboard_fab2(sch_1):page34_i86:UPI1_TX_DP(10)" )
				( attribute "RELATIVE_PROPAGATION_DELAY_SCOPE" "G"
					( Parent
						( matchGroupRef "@crescent_city_bb_fab1_lib.crescent_city_bb_fab1(sch_1):\MG_KTI_CPU0_CPU1_P1P1\" )
					)
					( Status sCSetFlattened )
					( Origin gBackEnd )
				)
				( attribute "RELATIVE_PROPAGATION_DELAY" "-1315.00 MIL,1315.00 MIL"
					( Parent
						( matchGroupRef "@crescent_city_bb_fab1_lib.crescent_city_bb_fab1(sch_1):\MG_KTI_CPU0_CPU1_P1P1\" )
					)
					( Units "uMatchProp" "ns" 1.000000)
					( Status sCSetFlattened )
					( Origin gBackEnd )
				)
				( attribute "RELATIVE_PROPAGATION_DELAY_SCOPE" "G"
					( Parent
						( matchGroupRef "@baseboard_fab2_lib.baseboard_fab2(sch_1):\MG_KTI_BUNDLE_NG_KTI_CPU0_CPU1_P1P1_8-9\" )
					)
					( Status sCSetFlattened )
					( Origin gBackEnd )
				)
				( attribute "RELATIVE_PROPAGATION_DELAY" ",500.00 MIL"
					( Parent
						( matchGroupRef "@baseboard_fab2_lib.baseboard_fab2(sch_1):\MG_KTI_BUNDLE_NG_KTI_CPU0_CPU1_P1P1_8-9\" )
					)
					( Units "uMatchProp" "ns" 1.000000)
					( Status sCSetFlattened )
					( Origin gBackEnd )
				)
			)
			( pinPair "@baseboard_fab2_lib.baseboard_fab2(sch_1):\PP3210\"
				( pinRef "@baseboard_fab2_lib.baseboard_fab2(sch_1):page68_i125:UPI1_RX_DN(9)" )
				( pinRef "@baseboard_fab2_lib.baseboard_fab2(sch_1):page34_i86:UPI1_TX_DN(10)" )
				( attribute "RELATIVE_PROPAGATION_DELAY_SCOPE" "G"
					( Parent
						( matchGroupRef "@crescent_city_bb_fab1_lib.crescent_city_bb_fab1(sch_1):\MG_KTI_CPU0_CPU1_P1P1\" )
					)
					( Status sCSetFlattened )
					( Origin gBackEnd )
				)
				( attribute "RELATIVE_PROPAGATION_DELAY" "-1315.00 MIL,1315.00 MIL"
					( Parent
						( matchGroupRef "@crescent_city_bb_fab1_lib.crescent_city_bb_fab1(sch_1):\MG_KTI_CPU0_CPU1_P1P1\" )
					)
					( Units "uMatchProp" "ns" 1.000000)
					( Status sCSetFlattened )
					( Origin gBackEnd )
				)
				( attribute "RELATIVE_PROPAGATION_DELAY_SCOPE" "G"
					( Parent
						( matchGroupRef "@baseboard_fab2_lib.baseboard_fab2(sch_1):\MG_KTI_BUNDLE_NG_KTI_CPU0_CPU1_P1P1_8-9\" )
					)
					( Status sCSetFlattened )
					( Origin gBackEnd )
				)
				( attribute "RELATIVE_PROPAGATION_DELAY" ",500.00 MIL"
					( Parent
						( matchGroupRef "@baseboard_fab2_lib.baseboard_fab2(sch_1):\MG_KTI_BUNDLE_NG_KTI_CPU0_CPU1_P1P1_8-9\" )
					)
					( Units "uMatchProp" "ns" 1.000000)
					( Status sCSetFlattened )
					( Origin gBackEnd )
				)
			)
			( pinPair "@baseboard_fab2_lib.baseboard_fab2(sch_1):\PP3203\"
				( pinRef "@baseboard_fab2_lib.baseboard_fab2(sch_1):page34_i86:UPI1_TX_DP(9)" )
				( pinRef "@baseboard_fab2_lib.baseboard_fab2(sch_1):page68_i125:UPI1_RX_DP(10)" )
				( attribute "RELATIVE_PROPAGATION_DELAY_SCOPE" "G"
					( Parent
						( matchGroupRef "@crescent_city_bb_fab1_lib.crescent_city_bb_fab1(sch_1):\MG_KTI_CPU0_CPU1_P1P1\" )
					)
					( Status sCSetFlattened )
					( Origin gBackEnd )
				)
				( attribute "RELATIVE_PROPAGATION_DELAY" "-1315.00 MIL,1315.00 MIL"
					( Parent
						( matchGroupRef "@crescent_city_bb_fab1_lib.crescent_city_bb_fab1(sch_1):\MG_KTI_CPU0_CPU1_P1P1\" )
					)
					( Units "uMatchProp" "ns" 1.000000)
					( Status sCSetFlattened )
					( Origin gBackEnd )
				)
				( attribute "RELATIVE_PROPAGATION_DELAY_SCOPE" "G"
					( Parent
						( matchGroupRef "@baseboard_fab2_lib.baseboard_fab2(sch_1):\MG_KTI_BUNDLE_NG_KTI_CPU0_CPU1_P1P1_10-11\" )
					)
					( Status sCSetFlattened )
					( Origin gBackEnd )
				)
				( attribute "RELATIVE_PROPAGATION_DELAY" ",500.00 MIL"
					( Parent
						( matchGroupRef "@baseboard_fab2_lib.baseboard_fab2(sch_1):\MG_KTI_BUNDLE_NG_KTI_CPU0_CPU1_P1P1_10-11\" )
					)
					( Units "uMatchProp" "ns" 1.000000)
					( Status sCSetFlattened )
					( Origin gBackEnd )
				)
			)
			( pinPair "@baseboard_fab2_lib.baseboard_fab2(sch_1):\PP3204\"
				( pinRef "@baseboard_fab2_lib.baseboard_fab2(sch_1):page34_i86:UPI1_TX_DN(9)" )
				( pinRef "@baseboard_fab2_lib.baseboard_fab2(sch_1):page68_i125:UPI1_RX_DN(10)" )
				( attribute "RELATIVE_PROPAGATION_DELAY_SCOPE" "G"
					( Parent
						( matchGroupRef "@crescent_city_bb_fab1_lib.crescent_city_bb_fab1(sch_1):\MG_KTI_CPU0_CPU1_P1P1\" )
					)
					( Status sCSetFlattened )
					( Origin gBackEnd )
				)
				( attribute "RELATIVE_PROPAGATION_DELAY" "-1315.00 MIL,1315.00 MIL"
					( Parent
						( matchGroupRef "@crescent_city_bb_fab1_lib.crescent_city_bb_fab1(sch_1):\MG_KTI_CPU0_CPU1_P1P1\" )
					)
					( Units "uMatchProp" "ns" 1.000000)
					( Status sCSetFlattened )
					( Origin gBackEnd )
				)
				( attribute "RELATIVE_PROPAGATION_DELAY_SCOPE" "G"
					( Parent
						( matchGroupRef "@baseboard_fab2_lib.baseboard_fab2(sch_1):\MG_KTI_BUNDLE_NG_KTI_CPU0_CPU1_P1P1_10-11\" )
					)
					( Status sCSetFlattened )
					( Origin gBackEnd )
				)
				( attribute "RELATIVE_PROPAGATION_DELAY" ",500.00 MIL"
					( Parent
						( matchGroupRef "@baseboard_fab2_lib.baseboard_fab2(sch_1):\MG_KTI_BUNDLE_NG_KTI_CPU0_CPU1_P1P1_10-11\" )
					)
					( Units "uMatchProp" "ns" 1.000000)
					( Status sCSetFlattened )
					( Origin gBackEnd )
				)
			)
			( pinPair "@baseboard_fab2_lib.baseboard_fab2(sch_1):\PP3205\"
				( pinRef "@baseboard_fab2_lib.baseboard_fab2(sch_1):page68_i125:UPI1_RX_DN(11)" )
				( pinRef "@baseboard_fab2_lib.baseboard_fab2(sch_1):page34_i86:UPI1_TX_DP(8)" )
				( attribute "RELATIVE_PROPAGATION_DELAY_SCOPE" "G"
					( Parent
						( matchGroupRef "@crescent_city_bb_fab1_lib.crescent_city_bb_fab1(sch_1):\MG_KTI_CPU0_CPU1_P1P1\" )
					)
					( Status sCSetFlattened )
					( Origin gBackEnd )
				)
				( attribute "RELATIVE_PROPAGATION_DELAY" "-1315.00 MIL,1315.00 MIL"
					( Parent
						( matchGroupRef "@crescent_city_bb_fab1_lib.crescent_city_bb_fab1(sch_1):\MG_KTI_CPU0_CPU1_P1P1\" )
					)
					( Units "uMatchProp" "ns" 1.000000)
					( Status sCSetFlattened )
					( Origin gBackEnd )
				)
				( attribute "RELATIVE_PROPAGATION_DELAY_SCOPE" "G"
					( Parent
						( matchGroupRef "@baseboard_fab2_lib.baseboard_fab2(sch_1):\MG_KTI_BUNDLE_NG_KTI_CPU0_CPU1_P1P1_10-11\" )
					)
					( Status sCSetFlattened )
					( Origin gBackEnd )
				)
				( attribute "RELATIVE_PROPAGATION_DELAY" ",500.00 MIL"
					( Parent
						( matchGroupRef "@baseboard_fab2_lib.baseboard_fab2(sch_1):\MG_KTI_BUNDLE_NG_KTI_CPU0_CPU1_P1P1_10-11\" )
					)
					( Units "uMatchProp" "ns" 1.000000)
					( Status sCSetFlattened )
					( Origin gBackEnd )
				)
			)
			( pinPair "@baseboard_fab2_lib.baseboard_fab2(sch_1):\PP3206\"
				( pinRef "@baseboard_fab2_lib.baseboard_fab2(sch_1):page68_i125:UPI1_RX_DP(11)" )
				( pinRef "@baseboard_fab2_lib.baseboard_fab2(sch_1):page34_i86:UPI1_TX_DN(8)" )
				( attribute "RELATIVE_PROPAGATION_DELAY_SCOPE" "G"
					( Parent
						( matchGroupRef "@crescent_city_bb_fab1_lib.crescent_city_bb_fab1(sch_1):\MG_KTI_CPU0_CPU1_P1P1\" )
					)
					( Status sCSetFlattened )
					( Origin gBackEnd )
				)
				( attribute "RELATIVE_PROPAGATION_DELAY" "-1315.00 MIL,1315.00 MIL"
					( Parent
						( matchGroupRef "@crescent_city_bb_fab1_lib.crescent_city_bb_fab1(sch_1):\MG_KTI_CPU0_CPU1_P1P1\" )
					)
					( Units "uMatchProp" "ns" 1.000000)
					( Status sCSetFlattened )
					( Origin gBackEnd )
				)
				( attribute "RELATIVE_PROPAGATION_DELAY_SCOPE" "G"
					( Parent
						( matchGroupRef "@baseboard_fab2_lib.baseboard_fab2(sch_1):\MG_KTI_BUNDLE_NG_KTI_CPU0_CPU1_P1P1_10-11\" )
					)
					( Status sCSetFlattened )
					( Origin gBackEnd )
				)
				( attribute "RELATIVE_PROPAGATION_DELAY" ",500.00 MIL"
					( Parent
						( matchGroupRef "@baseboard_fab2_lib.baseboard_fab2(sch_1):\MG_KTI_BUNDLE_NG_KTI_CPU0_CPU1_P1P1_10-11\" )
					)
					( Units "uMatchProp" "ns" 1.000000)
					( Status sCSetFlattened )
					( Origin gBackEnd )
				)
			)
			( pinPair "@baseboard_fab2_lib.baseboard_fab2(sch_1):\PP3199\"
				( pinRef "@baseboard_fab2_lib.baseboard_fab2(sch_1):page68_i125:UPI1_RX_DN(12)" )
				( pinRef "@baseboard_fab2_lib.baseboard_fab2(sch_1):page34_i86:UPI1_TX_DP(7)" )
				( attribute "RELATIVE_PROPAGATION_DELAY_SCOPE" "G"
					( Parent
						( matchGroupRef "@crescent_city_bb_fab1_lib.crescent_city_bb_fab1(sch_1):\MG_KTI_CPU0_CPU1_P1P1\" )
					)
					( Status sCSetFlattened )
					( Origin gBackEnd )
				)
				( attribute "RELATIVE_PROPAGATION_DELAY" "-1315.00 MIL,1315.00 MIL"
					( Parent
						( matchGroupRef "@crescent_city_bb_fab1_lib.crescent_city_bb_fab1(sch_1):\MG_KTI_CPU0_CPU1_P1P1\" )
					)
					( Units "uMatchProp" "ns" 1.000000)
					( Status sCSetFlattened )
					( Origin gBackEnd )
				)
				( attribute "RELATIVE_PROPAGATION_DELAY_SCOPE" "G"
					( Parent
						( matchGroupRef "@baseboard_fab2_lib.baseboard_fab2(sch_1):\MG_KTI_BUNDLE_NG_KTI_CPU0_CPU1_P1P1_12-13\" )
					)
					( Status sCSetFlattened )
					( Origin gBackEnd )
				)
				( attribute "RELATIVE_PROPAGATION_DELAY" ",500.00 MIL"
					( Parent
						( matchGroupRef "@baseboard_fab2_lib.baseboard_fab2(sch_1):\MG_KTI_BUNDLE_NG_KTI_CPU0_CPU1_P1P1_12-13\" )
					)
					( Units "uMatchProp" "ns" 1.000000)
					( Status sCSetFlattened )
					( Origin gBackEnd )
				)
			)
			( pinPair "@baseboard_fab2_lib.baseboard_fab2(sch_1):\PP3200\"
				( pinRef "@baseboard_fab2_lib.baseboard_fab2(sch_1):page68_i125:UPI1_RX_DP(12)" )
				( pinRef "@baseboard_fab2_lib.baseboard_fab2(sch_1):page34_i86:UPI1_TX_DN(7)" )
				( attribute "RELATIVE_PROPAGATION_DELAY_SCOPE" "G"
					( Parent
						( matchGroupRef "@crescent_city_bb_fab1_lib.crescent_city_bb_fab1(sch_1):\MG_KTI_CPU0_CPU1_P1P1\" )
					)
					( Status sCSetFlattened )
					( Origin gBackEnd )
				)
				( attribute "RELATIVE_PROPAGATION_DELAY" "-1315.00 MIL,1315.00 MIL"
					( Parent
						( matchGroupRef "@crescent_city_bb_fab1_lib.crescent_city_bb_fab1(sch_1):\MG_KTI_CPU0_CPU1_P1P1\" )
					)
					( Units "uMatchProp" "ns" 1.000000)
					( Status sCSetFlattened )
					( Origin gBackEnd )
				)
				( attribute "RELATIVE_PROPAGATION_DELAY_SCOPE" "G"
					( Parent
						( matchGroupRef "@baseboard_fab2_lib.baseboard_fab2(sch_1):\MG_KTI_BUNDLE_NG_KTI_CPU0_CPU1_P1P1_12-13\" )
					)
					( Status sCSetFlattened )
					( Origin gBackEnd )
				)
				( attribute "RELATIVE_PROPAGATION_DELAY" ",500.00 MIL"
					( Parent
						( matchGroupRef "@baseboard_fab2_lib.baseboard_fab2(sch_1):\MG_KTI_BUNDLE_NG_KTI_CPU0_CPU1_P1P1_12-13\" )
					)
					( Units "uMatchProp" "ns" 1.000000)
					( Status sCSetFlattened )
					( Origin gBackEnd )
				)
			)
			( pinPair "@baseboard_fab2_lib.baseboard_fab2(sch_1):\PP3201\"
				( pinRef "@baseboard_fab2_lib.baseboard_fab2(sch_1):page68_i125:UPI1_RX_DN(13)" )
				( pinRef "@baseboard_fab2_lib.baseboard_fab2(sch_1):page34_i86:UPI1_TX_DP(6)" )
				( attribute "RELATIVE_PROPAGATION_DELAY_SCOPE" "G"
					( Parent
						( matchGroupRef "@crescent_city_bb_fab1_lib.crescent_city_bb_fab1(sch_1):\MG_KTI_CPU0_CPU1_P1P1\" )
					)
					( Status sCSetFlattened )
					( Origin gBackEnd )
				)
				( attribute "RELATIVE_PROPAGATION_DELAY" "-1315.00 MIL,1315.00 MIL"
					( Parent
						( matchGroupRef "@crescent_city_bb_fab1_lib.crescent_city_bb_fab1(sch_1):\MG_KTI_CPU0_CPU1_P1P1\" )
					)
					( Units "uMatchProp" "ns" 1.000000)
					( Status sCSetFlattened )
					( Origin gBackEnd )
				)
				( attribute "RELATIVE_PROPAGATION_DELAY_SCOPE" "G"
					( Parent
						( matchGroupRef "@baseboard_fab2_lib.baseboard_fab2(sch_1):\MG_KTI_BUNDLE_NG_KTI_CPU0_CPU1_P1P1_12-13\" )
					)
					( Status sCSetFlattened )
					( Origin gBackEnd )
				)
				( attribute "RELATIVE_PROPAGATION_DELAY" ",500.00 MIL"
					( Parent
						( matchGroupRef "@baseboard_fab2_lib.baseboard_fab2(sch_1):\MG_KTI_BUNDLE_NG_KTI_CPU0_CPU1_P1P1_12-13\" )
					)
					( Units "uMatchProp" "ns" 1.000000)
					( Status sCSetFlattened )
					( Origin gBackEnd )
				)
			)
			( pinPair "@baseboard_fab2_lib.baseboard_fab2(sch_1):\PP3202\"
				( pinRef "@baseboard_fab2_lib.baseboard_fab2(sch_1):page68_i125:UPI1_RX_DP(13)" )
				( pinRef "@baseboard_fab2_lib.baseboard_fab2(sch_1):page34_i86:UPI1_TX_DN(6)" )
				( attribute "RELATIVE_PROPAGATION_DELAY_SCOPE" "G"
					( Parent
						( matchGroupRef "@crescent_city_bb_fab1_lib.crescent_city_bb_fab1(sch_1):\MG_KTI_CPU0_CPU1_P1P1\" )
					)
					( Status sCSetFlattened )
					( Origin gBackEnd )
				)
				( attribute "RELATIVE_PROPAGATION_DELAY" "-1315.00 MIL,1315.00 MIL"
					( Parent
						( matchGroupRef "@crescent_city_bb_fab1_lib.crescent_city_bb_fab1(sch_1):\MG_KTI_CPU0_CPU1_P1P1\" )
					)
					( Units "uMatchProp" "ns" 1.000000)
					( Status sCSetFlattened )
					( Origin gBackEnd )
				)
				( attribute "RELATIVE_PROPAGATION_DELAY_SCOPE" "G"
					( Parent
						( matchGroupRef "@baseboard_fab2_lib.baseboard_fab2(sch_1):\MG_KTI_BUNDLE_NG_KTI_CPU0_CPU1_P1P1_12-13\" )
					)
					( Status sCSetFlattened )
					( Origin gBackEnd )
				)
				( attribute "RELATIVE_PROPAGATION_DELAY" ",500.00 MIL"
					( Parent
						( matchGroupRef "@baseboard_fab2_lib.baseboard_fab2(sch_1):\MG_KTI_BUNDLE_NG_KTI_CPU0_CPU1_P1P1_12-13\" )
					)
					( Units "uMatchProp" "ns" 1.000000)
					( Status sCSetFlattened )
					( Origin gBackEnd )
				)
			)
			( pinPair "@baseboard_fab2_lib.baseboard_fab2(sch_1):\PP3195\"
				( pinRef "@baseboard_fab2_lib.baseboard_fab2(sch_1):page68_i125:UPI1_RX_DP(14)" )
				( pinRef "@baseboard_fab2_lib.baseboard_fab2(sch_1):page34_i86:UPI1_TX_DP(5)" )
				( attribute "RELATIVE_PROPAGATION_DELAY_SCOPE" "G"
					( Parent
						( matchGroupRef "@crescent_city_bb_fab1_lib.crescent_city_bb_fab1(sch_1):\MG_KTI_CPU0_CPU1_P1P1\" )
					)
					( Status sCSetFlattened )
					( Origin gBackEnd )
				)
				( attribute "RELATIVE_PROPAGATION_DELAY" "-1315.00 MIL,1315.00 MIL"
					( Parent
						( matchGroupRef "@crescent_city_bb_fab1_lib.crescent_city_bb_fab1(sch_1):\MG_KTI_CPU0_CPU1_P1P1\" )
					)
					( Units "uMatchProp" "ns" 1.000000)
					( Status sCSetFlattened )
					( Origin gBackEnd )
				)
				( attribute "RELATIVE_PROPAGATION_DELAY_SCOPE" "G"
					( Parent
						( matchGroupRef "@baseboard_fab2_lib.baseboard_fab2(sch_1):\MG_KTI_BUNDLE_NG_KTI_CPU0_CPU1_P1P1_14-15\" )
					)
					( Status sCSetFlattened )
					( Origin gBackEnd )
				)
				( attribute "RELATIVE_PROPAGATION_DELAY" ",500.00 MIL"
					( Parent
						( matchGroupRef "@baseboard_fab2_lib.baseboard_fab2(sch_1):\MG_KTI_BUNDLE_NG_KTI_CPU0_CPU1_P1P1_14-15\" )
					)
					( Units "uMatchProp" "ns" 1.000000)
					( Status sCSetFlattened )
					( Origin gBackEnd )
				)
			)
			( pinPair "@baseboard_fab2_lib.baseboard_fab2(sch_1):\PP3196\"
				( pinRef "@baseboard_fab2_lib.baseboard_fab2(sch_1):page68_i125:UPI1_RX_DN(14)" )
				( pinRef "@baseboard_fab2_lib.baseboard_fab2(sch_1):page34_i86:UPI1_TX_DN(5)" )
				( attribute "RELATIVE_PROPAGATION_DELAY_SCOPE" "G"
					( Parent
						( matchGroupRef "@crescent_city_bb_fab1_lib.crescent_city_bb_fab1(sch_1):\MG_KTI_CPU0_CPU1_P1P1\" )
					)
					( Status sCSetFlattened )
					( Origin gBackEnd )
				)
				( attribute "RELATIVE_PROPAGATION_DELAY" "-1315.00 MIL,1315.00 MIL"
					( Parent
						( matchGroupRef "@crescent_city_bb_fab1_lib.crescent_city_bb_fab1(sch_1):\MG_KTI_CPU0_CPU1_P1P1\" )
					)
					( Units "uMatchProp" "ns" 1.000000)
					( Status sCSetFlattened )
					( Origin gBackEnd )
				)
				( attribute "RELATIVE_PROPAGATION_DELAY_SCOPE" "G"
					( Parent
						( matchGroupRef "@baseboard_fab2_lib.baseboard_fab2(sch_1):\MG_KTI_BUNDLE_NG_KTI_CPU0_CPU1_P1P1_14-15\" )
					)
					( Status sCSetFlattened )
					( Origin gBackEnd )
				)
				( attribute "RELATIVE_PROPAGATION_DELAY" ",500.00 MIL"
					( Parent
						( matchGroupRef "@baseboard_fab2_lib.baseboard_fab2(sch_1):\MG_KTI_BUNDLE_NG_KTI_CPU0_CPU1_P1P1_14-15\" )
					)
					( Units "uMatchProp" "ns" 1.000000)
					( Status sCSetFlattened )
					( Origin gBackEnd )
				)
			)
			( pinPair "@baseboard_fab2_lib.baseboard_fab2(sch_1):\PP3197\"
				( pinRef "@baseboard_fab2_lib.baseboard_fab2(sch_1):page34_i86:UPI1_TX_DP(4)" )
				( pinRef "@baseboard_fab2_lib.baseboard_fab2(sch_1):page68_i125:UPI1_RX_DP(15)" )
				( attribute "RELATIVE_PROPAGATION_DELAY_SCOPE" "G"
					( Parent
						( matchGroupRef "@crescent_city_bb_fab1_lib.crescent_city_bb_fab1(sch_1):\MG_KTI_CPU0_CPU1_P1P1\" )
					)
					( Status sCSetFlattened )
					( Origin gBackEnd )
				)
				( attribute "RELATIVE_PROPAGATION_DELAY" "-1315.00 MIL,1315.00 MIL"
					( Parent
						( matchGroupRef "@crescent_city_bb_fab1_lib.crescent_city_bb_fab1(sch_1):\MG_KTI_CPU0_CPU1_P1P1\" )
					)
					( Units "uMatchProp" "ns" 1.000000)
					( Status sCSetFlattened )
					( Origin gBackEnd )
				)
				( attribute "RELATIVE_PROPAGATION_DELAY_SCOPE" "G"
					( Parent
						( matchGroupRef "@baseboard_fab2_lib.baseboard_fab2(sch_1):\MG_KTI_BUNDLE_NG_KTI_CPU0_CPU1_P1P1_14-15\" )
					)
					( Status sCSetFlattened )
					( Origin gBackEnd )
				)
				( attribute "RELATIVE_PROPAGATION_DELAY" ",500.00 MIL"
					( Parent
						( matchGroupRef "@baseboard_fab2_lib.baseboard_fab2(sch_1):\MG_KTI_BUNDLE_NG_KTI_CPU0_CPU1_P1P1_14-15\" )
					)
					( Units "uMatchProp" "ns" 1.000000)
					( Status sCSetFlattened )
					( Origin gBackEnd )
				)
			)
			( pinPair "@baseboard_fab2_lib.baseboard_fab2(sch_1):\PP3198\"
				( pinRef "@baseboard_fab2_lib.baseboard_fab2(sch_1):page34_i86:UPI1_TX_DN(4)" )
				( pinRef "@baseboard_fab2_lib.baseboard_fab2(sch_1):page68_i125:UPI1_RX_DN(15)" )
				( attribute "RELATIVE_PROPAGATION_DELAY_SCOPE" "G"
					( Parent
						( matchGroupRef "@crescent_city_bb_fab1_lib.crescent_city_bb_fab1(sch_1):\MG_KTI_CPU0_CPU1_P1P1\" )
					)
					( Status sCSetFlattened )
					( Origin gBackEnd )
				)
				( attribute "RELATIVE_PROPAGATION_DELAY" "-1315.00 MIL,1315.00 MIL"
					( Parent
						( matchGroupRef "@crescent_city_bb_fab1_lib.crescent_city_bb_fab1(sch_1):\MG_KTI_CPU0_CPU1_P1P1\" )
					)
					( Units "uMatchProp" "ns" 1.000000)
					( Status sCSetFlattened )
					( Origin gBackEnd )
				)
				( attribute "RELATIVE_PROPAGATION_DELAY_SCOPE" "G"
					( Parent
						( matchGroupRef "@baseboard_fab2_lib.baseboard_fab2(sch_1):\MG_KTI_BUNDLE_NG_KTI_CPU0_CPU1_P1P1_14-15\" )
					)
					( Status sCSetFlattened )
					( Origin gBackEnd )
				)
				( attribute "RELATIVE_PROPAGATION_DELAY" ",500.00 MIL"
					( Parent
						( matchGroupRef "@baseboard_fab2_lib.baseboard_fab2(sch_1):\MG_KTI_BUNDLE_NG_KTI_CPU0_CPU1_P1P1_14-15\" )
					)
					( Units "uMatchProp" "ns" 1.000000)
					( Status sCSetFlattened )
					( Origin gBackEnd )
				)
			)
			( pinPair "@baseboard_fab2_lib.baseboard_fab2(sch_1):\PP3191\"
				( pinRef "@baseboard_fab2_lib.baseboard_fab2(sch_1):page34_i86:UPI1_TX_DP(3)" )
				( pinRef "@baseboard_fab2_lib.baseboard_fab2(sch_1):page68_i125:UPI1_RX_DP(16)" )
				( attribute "RELATIVE_PROPAGATION_DELAY_SCOPE" "G"
					( Parent
						( matchGroupRef "@crescent_city_bb_fab1_lib.crescent_city_bb_fab1(sch_1):\MG_KTI_CPU0_CPU1_P1P1\" )
					)
					( Status sCSetFlattened )
					( Origin gBackEnd )
				)
				( attribute "RELATIVE_PROPAGATION_DELAY" "-1315.00 MIL,1315.00 MIL"
					( Parent
						( matchGroupRef "@crescent_city_bb_fab1_lib.crescent_city_bb_fab1(sch_1):\MG_KTI_CPU0_CPU1_P1P1\" )
					)
					( Units "uMatchProp" "ns" 1.000000)
					( Status sCSetFlattened )
					( Origin gBackEnd )
				)
				( attribute "RELATIVE_PROPAGATION_DELAY_SCOPE" "G"
					( Parent
						( matchGroupRef "@baseboard_fab2_lib.baseboard_fab2(sch_1):\MG_KTI_BUNDLE_NG_KTI_CPU0_CPU1_P1P1_16-17\" )
					)
					( Status sCSetFlattened )
					( Origin gBackEnd )
				)
				( attribute "RELATIVE_PROPAGATION_DELAY" ",500.00 MIL"
					( Parent
						( matchGroupRef "@baseboard_fab2_lib.baseboard_fab2(sch_1):\MG_KTI_BUNDLE_NG_KTI_CPU0_CPU1_P1P1_16-17\" )
					)
					( Units "uMatchProp" "ns" 1.000000)
					( Status sCSetFlattened )
					( Origin gBackEnd )
				)
			)
			( pinPair "@baseboard_fab2_lib.baseboard_fab2(sch_1):\PP3192\"
				( pinRef "@baseboard_fab2_lib.baseboard_fab2(sch_1):page34_i86:UPI1_TX_DN(3)" )
				( pinRef "@baseboard_fab2_lib.baseboard_fab2(sch_1):page68_i125:UPI1_RX_DN(16)" )
				( attribute "RELATIVE_PROPAGATION_DELAY_SCOPE" "G"
					( Parent
						( matchGroupRef "@crescent_city_bb_fab1_lib.crescent_city_bb_fab1(sch_1):\MG_KTI_CPU0_CPU1_P1P1\" )
					)
					( Status sCSetFlattened )
					( Origin gBackEnd )
				)
				( attribute "RELATIVE_PROPAGATION_DELAY" "-1315.00 MIL,1315.00 MIL"
					( Parent
						( matchGroupRef "@crescent_city_bb_fab1_lib.crescent_city_bb_fab1(sch_1):\MG_KTI_CPU0_CPU1_P1P1\" )
					)
					( Units "uMatchProp" "ns" 1.000000)
					( Status sCSetFlattened )
					( Origin gBackEnd )
				)
				( attribute "RELATIVE_PROPAGATION_DELAY_SCOPE" "G"
					( Parent
						( matchGroupRef "@baseboard_fab2_lib.baseboard_fab2(sch_1):\MG_KTI_BUNDLE_NG_KTI_CPU0_CPU1_P1P1_16-17\" )
					)
					( Status sCSetFlattened )
					( Origin gBackEnd )
				)
				( attribute "RELATIVE_PROPAGATION_DELAY" ",500.00 MIL"
					( Parent
						( matchGroupRef "@baseboard_fab2_lib.baseboard_fab2(sch_1):\MG_KTI_BUNDLE_NG_KTI_CPU0_CPU1_P1P1_16-17\" )
					)
					( Units "uMatchProp" "ns" 1.000000)
					( Status sCSetFlattened )
					( Origin gBackEnd )
				)
			)
			( pinPair "@baseboard_fab2_lib.baseboard_fab2(sch_1):\PP3193\"
				( pinRef "@baseboard_fab2_lib.baseboard_fab2(sch_1):page34_i86:UPI1_TX_DP(2)" )
				( pinRef "@baseboard_fab2_lib.baseboard_fab2(sch_1):page68_i125:UPI1_RX_DP(17)" )
				( attribute "RELATIVE_PROPAGATION_DELAY_SCOPE" "G"
					( Parent
						( matchGroupRef "@crescent_city_bb_fab1_lib.crescent_city_bb_fab1(sch_1):\MG_KTI_CPU0_CPU1_P1P1\" )
					)
					( Status sCSetFlattened )
					( Origin gBackEnd )
				)
				( attribute "RELATIVE_PROPAGATION_DELAY" "-1315.00 MIL,1315.00 MIL"
					( Parent
						( matchGroupRef "@crescent_city_bb_fab1_lib.crescent_city_bb_fab1(sch_1):\MG_KTI_CPU0_CPU1_P1P1\" )
					)
					( Units "uMatchProp" "ns" 1.000000)
					( Status sCSetFlattened )
					( Origin gBackEnd )
				)
				( attribute "RELATIVE_PROPAGATION_DELAY_SCOPE" "G"
					( Parent
						( matchGroupRef "@baseboard_fab2_lib.baseboard_fab2(sch_1):\MG_KTI_BUNDLE_NG_KTI_CPU0_CPU1_P1P1_16-17\" )
					)
					( Status sCSetFlattened )
					( Origin gBackEnd )
				)
				( attribute "RELATIVE_PROPAGATION_DELAY" ",500.00 MIL"
					( Parent
						( matchGroupRef "@baseboard_fab2_lib.baseboard_fab2(sch_1):\MG_KTI_BUNDLE_NG_KTI_CPU0_CPU1_P1P1_16-17\" )
					)
					( Units "uMatchProp" "ns" 1.000000)
					( Status sCSetFlattened )
					( Origin gBackEnd )
				)
			)
			( pinPair "@baseboard_fab2_lib.baseboard_fab2(sch_1):\PP3194\"
				( pinRef "@baseboard_fab2_lib.baseboard_fab2(sch_1):page34_i86:UPI1_TX_DN(2)" )
				( pinRef "@baseboard_fab2_lib.baseboard_fab2(sch_1):page68_i125:UPI1_RX_DN(17)" )
				( attribute "RELATIVE_PROPAGATION_DELAY_SCOPE" "G"
					( Parent
						( matchGroupRef "@crescent_city_bb_fab1_lib.crescent_city_bb_fab1(sch_1):\MG_KTI_CPU0_CPU1_P1P1\" )
					)
					( Status sCSetFlattened )
					( Origin gBackEnd )
				)
				( attribute "RELATIVE_PROPAGATION_DELAY" "-1315.00 MIL,1315.00 MIL"
					( Parent
						( matchGroupRef "@crescent_city_bb_fab1_lib.crescent_city_bb_fab1(sch_1):\MG_KTI_CPU0_CPU1_P1P1\" )
					)
					( Units "uMatchProp" "ns" 1.000000)
					( Status sCSetFlattened )
					( Origin gBackEnd )
				)
				( attribute "RELATIVE_PROPAGATION_DELAY_SCOPE" "G"
					( Parent
						( matchGroupRef "@baseboard_fab2_lib.baseboard_fab2(sch_1):\MG_KTI_BUNDLE_NG_KTI_CPU0_CPU1_P1P1_16-17\" )
					)
					( Status sCSetFlattened )
					( Origin gBackEnd )
				)
				( attribute "RELATIVE_PROPAGATION_DELAY" ",500.00 MIL"
					( Parent
						( matchGroupRef "@baseboard_fab2_lib.baseboard_fab2(sch_1):\MG_KTI_BUNDLE_NG_KTI_CPU0_CPU1_P1P1_16-17\" )
					)
					( Units "uMatchProp" "ns" 1.000000)
					( Status sCSetFlattened )
					( Origin gBackEnd )
				)
			)
			( pinPair "@baseboard_fab2_lib.baseboard_fab2(sch_1):\PP3187\"
				( pinRef "@baseboard_fab2_lib.baseboard_fab2(sch_1):page34_i86:UPI1_TX_DP(1)" )
				( pinRef "@baseboard_fab2_lib.baseboard_fab2(sch_1):page68_i125:UPI1_RX_DN(18)" )
				( attribute "RELATIVE_PROPAGATION_DELAY_SCOPE" "G"
					( Parent
						( matchGroupRef "@crescent_city_bb_fab1_lib.crescent_city_bb_fab1(sch_1):\MG_KTI_CPU0_CPU1_P1P1\" )
					)
					( Status sCSetFlattened )
					( Origin gBackEnd )
				)
				( attribute "RELATIVE_PROPAGATION_DELAY" "-1315.00 MIL,1315.00 MIL"
					( Parent
						( matchGroupRef "@crescent_city_bb_fab1_lib.crescent_city_bb_fab1(sch_1):\MG_KTI_CPU0_CPU1_P1P1\" )
					)
					( Units "uMatchProp" "ns" 1.000000)
					( Status sCSetFlattened )
					( Origin gBackEnd )
				)
				( attribute "RELATIVE_PROPAGATION_DELAY_SCOPE" "G"
					( Parent
						( matchGroupRef "@baseboard_fab2_lib.baseboard_fab2(sch_1):\MG_KTI_BUNDLE_NG_KTI_CPU0_CPU1_P1P1_18-19\" )
					)
					( Status sCSetFlattened )
					( Origin gBackEnd )
				)
				( attribute "RELATIVE_PROPAGATION_DELAY" ",500.00 MIL"
					( Parent
						( matchGroupRef "@baseboard_fab2_lib.baseboard_fab2(sch_1):\MG_KTI_BUNDLE_NG_KTI_CPU0_CPU1_P1P1_18-19\" )
					)
					( Units "uMatchProp" "ns" 1.000000)
					( Status sCSetFlattened )
					( Origin gBackEnd )
				)
			)
			( pinPair "@baseboard_fab2_lib.baseboard_fab2(sch_1):\PP3188\"
				( pinRef "@baseboard_fab2_lib.baseboard_fab2(sch_1):page34_i86:UPI1_TX_DN(1)" )
				( pinRef "@baseboard_fab2_lib.baseboard_fab2(sch_1):page68_i125:UPI1_RX_DP(18)" )
				( attribute "RELATIVE_PROPAGATION_DELAY_SCOPE" "G"
					( Parent
						( matchGroupRef "@crescent_city_bb_fab1_lib.crescent_city_bb_fab1(sch_1):\MG_KTI_CPU0_CPU1_P1P1\" )
					)
					( Status sCSetFlattened )
					( Origin gBackEnd )
				)
				( attribute "RELATIVE_PROPAGATION_DELAY" "-1315.00 MIL,1315.00 MIL"
					( Parent
						( matchGroupRef "@crescent_city_bb_fab1_lib.crescent_city_bb_fab1(sch_1):\MG_KTI_CPU0_CPU1_P1P1\" )
					)
					( Units "uMatchProp" "ns" 1.000000)
					( Status sCSetFlattened )
					( Origin gBackEnd )
				)
				( attribute "RELATIVE_PROPAGATION_DELAY_SCOPE" "G"
					( Parent
						( matchGroupRef "@baseboard_fab2_lib.baseboard_fab2(sch_1):\MG_KTI_BUNDLE_NG_KTI_CPU0_CPU1_P1P1_18-19\" )
					)
					( Status sCSetFlattened )
					( Origin gBackEnd )
				)
				( attribute "RELATIVE_PROPAGATION_DELAY" ",500.00 MIL"
					( Parent
						( matchGroupRef "@baseboard_fab2_lib.baseboard_fab2(sch_1):\MG_KTI_BUNDLE_NG_KTI_CPU0_CPU1_P1P1_18-19\" )
					)
					( Units "uMatchProp" "ns" 1.000000)
					( Status sCSetFlattened )
					( Origin gBackEnd )
				)
			)
			( pinPair "@baseboard_fab2_lib.baseboard_fab2(sch_1):\PP3189\"
				( pinRef "@baseboard_fab2_lib.baseboard_fab2(sch_1):page34_i86:UPI1_TX_DP(0)" )
				( pinRef "@baseboard_fab2_lib.baseboard_fab2(sch_1):page68_i125:UPI1_RX_DN(19)" )
				( attribute "RELATIVE_PROPAGATION_DELAY_SCOPE" "G"
					( Parent
						( matchGroupRef "@crescent_city_bb_fab1_lib.crescent_city_bb_fab1(sch_1):\MG_KTI_CPU0_CPU1_P1P1\" )
					)
					( Status sCSetFlattened )
					( Origin gBackEnd )
				)
				( attribute "RELATIVE_PROPAGATION_DELAY" "-1315.00 MIL,1315.00 MIL"
					( Parent
						( matchGroupRef "@crescent_city_bb_fab1_lib.crescent_city_bb_fab1(sch_1):\MG_KTI_CPU0_CPU1_P1P1\" )
					)
					( Units "uMatchProp" "ns" 1.000000)
					( Status sCSetFlattened )
					( Origin gBackEnd )
				)
				( attribute "RELATIVE_PROPAGATION_DELAY_SCOPE" "G"
					( Parent
						( matchGroupRef "@baseboard_fab2_lib.baseboard_fab2(sch_1):\MG_KTI_BUNDLE_NG_KTI_CPU0_CPU1_P1P1_18-19\" )
					)
					( Status sCSetFlattened )
					( Origin gBackEnd )
				)
				( attribute "RELATIVE_PROPAGATION_DELAY" ",500.00 MIL"
					( Parent
						( matchGroupRef "@baseboard_fab2_lib.baseboard_fab2(sch_1):\MG_KTI_BUNDLE_NG_KTI_CPU0_CPU1_P1P1_18-19\" )
					)
					( Units "uMatchProp" "ns" 1.000000)
					( Status sCSetFlattened )
					( Origin gBackEnd )
				)
			)
			( pinPair "@baseboard_fab2_lib.baseboard_fab2(sch_1):\PP3190\"
				( pinRef "@baseboard_fab2_lib.baseboard_fab2(sch_1):page34_i86:UPI1_TX_DN(0)" )
				( pinRef "@baseboard_fab2_lib.baseboard_fab2(sch_1):page68_i125:UPI1_RX_DP(19)" )
				( attribute "RELATIVE_PROPAGATION_DELAY_SCOPE" "G"
					( Parent
						( matchGroupRef "@crescent_city_bb_fab1_lib.crescent_city_bb_fab1(sch_1):\MG_KTI_CPU0_CPU1_P1P1\" )
					)
					( Origin gBackEnd )
				)
				( attribute "RELATIVE_PROPAGATION_DELAY" "TARGET,TARGET"
					( Parent
						( matchGroupRef "@crescent_city_bb_fab1_lib.crescent_city_bb_fab1(sch_1):\MG_KTI_CPU0_CPU1_P1P1\" )
					)
					( Units "uMatchProp" "ns" 1.000000)
					( Origin gBackEnd )
				)
				( attribute "RELATIVE_PROPAGATION_DELAY_SCOPE" "G"
					( Parent
						( matchGroupRef "@baseboard_fab2_lib.baseboard_fab2(sch_1):\MG_KTI_BUNDLE_NG_KTI_CPU0_CPU1_P1P1_18-19\" )
					)
					( Status sCSetFlattened )
					( Origin gBackEnd )
				)
				( attribute "RELATIVE_PROPAGATION_DELAY" ",500.00 MIL"
					( Parent
						( matchGroupRef "@baseboard_fab2_lib.baseboard_fab2(sch_1):\MG_KTI_BUNDLE_NG_KTI_CPU0_CPU1_P1P1_18-19\" )
					)
					( Units "uMatchProp" "ns" 1.000000)
					( Status sCSetFlattened )
					( Origin gBackEnd )
				)
			)
			( pinPair "@baseboard_fab2_lib.baseboard_fab2(sch_1):\PP3263\"
				( pinRef "@baseboard_fab2_lib.baseboard_fab2(sch_1):page33_i86:UPI0_TX_DP(19)" )
				( pinRef "@baseboard_fab2_lib.baseboard_fab2(sch_1):page67_i132:UPI0_RX_DN(0)" )
				( attribute "RELATIVE_PROPAGATION_DELAY_SCOPE" "G"
					( Parent
						( matchGroupRef "@baseboard_fab2_lib.baseboard_fab2(sch_1):\MG_KTI_CPU0_CPU1_P0P0\" )
					)
					( Status sCSetFlattened )
					( Origin gBackEnd )
				)
				( attribute "RELATIVE_PROPAGATION_DELAY" "-1055.00 MIL,1055.00 MIL"
					( Parent
						( matchGroupRef "@baseboard_fab2_lib.baseboard_fab2(sch_1):\MG_KTI_CPU0_CPU1_P0P0\" )
					)
					( Units "uMatchProp" "ns" 1.000000)
					( Status sCSetFlattened )
					( Origin gBackEnd )
				)
				( attribute "RELATIVE_PROPAGATION_DELAY_SCOPE" "G"
					( Parent
						( matchGroupRef "@baseboard_fab2_lib.baseboard_fab2(sch_1):\MG_KTI_BUNDLE_NG_KTI_CPU0_CPU1_P0P0_0-1\" )
					)
					( Status sCSetFlattened )
					( Origin gBackEnd )
				)
				( attribute "RELATIVE_PROPAGATION_DELAY" ",500.00 MIL"
					( Parent
						( matchGroupRef "@baseboard_fab2_lib.baseboard_fab2(sch_1):\MG_KTI_BUNDLE_NG_KTI_CPU0_CPU1_P0P0_0-1\" )
					)
					( Units "uMatchProp" "ns" 1.000000)
					( Status sCSetFlattened )
					( Origin gBackEnd )
				)
			)
			( pinPair "@baseboard_fab2_lib.baseboard_fab2(sch_1):\PP3264\"
				( pinRef "@baseboard_fab2_lib.baseboard_fab2(sch_1):page33_i86:UPI0_TX_DN(19)" )
				( pinRef "@baseboard_fab2_lib.baseboard_fab2(sch_1):page67_i132:UPI0_RX_DP(0)" )
				( attribute "RELATIVE_PROPAGATION_DELAY_SCOPE" "G"
					( Parent
						( matchGroupRef "@baseboard_fab2_lib.baseboard_fab2(sch_1):\MG_KTI_CPU0_CPU1_P0P0\" )
					)
					( Status sCSetFlattened )
					( Origin gBackEnd )
				)
				( attribute "RELATIVE_PROPAGATION_DELAY" "-1055.00 MIL,1055.00 MIL"
					( Parent
						( matchGroupRef "@baseboard_fab2_lib.baseboard_fab2(sch_1):\MG_KTI_CPU0_CPU1_P0P0\" )
					)
					( Units "uMatchProp" "ns" 1.000000)
					( Status sCSetFlattened )
					( Origin gBackEnd )
				)
				( attribute "RELATIVE_PROPAGATION_DELAY_SCOPE" "G"
					( Parent
						( matchGroupRef "@baseboard_fab2_lib.baseboard_fab2(sch_1):\MG_KTI_BUNDLE_NG_KTI_CPU0_CPU1_P0P0_0-1\" )
					)
					( Status sCSetFlattened )
					( Origin gBackEnd )
				)
				( attribute "RELATIVE_PROPAGATION_DELAY" ",500.00 MIL"
					( Parent
						( matchGroupRef "@baseboard_fab2_lib.baseboard_fab2(sch_1):\MG_KTI_BUNDLE_NG_KTI_CPU0_CPU1_P0P0_0-1\" )
					)
					( Units "uMatchProp" "ns" 1.000000)
					( Status sCSetFlattened )
					( Origin gBackEnd )
				)
			)
			( pinPair "@baseboard_fab2_lib.baseboard_fab2(sch_1):\PP3265\"
				( pinRef "@baseboard_fab2_lib.baseboard_fab2(sch_1):page33_i86:UPI0_TX_DP(18)" )
				( pinRef "@baseboard_fab2_lib.baseboard_fab2(sch_1):page67_i132:UPI0_RX_DP(1)" )
				( attribute "RELATIVE_PROPAGATION_DELAY_SCOPE" "G"
					( Parent
						( matchGroupRef "@baseboard_fab2_lib.baseboard_fab2(sch_1):\MG_KTI_CPU0_CPU1_P0P0\" )
					)
					( Status sCSetFlattened )
					( Origin gBackEnd )
				)
				( attribute "RELATIVE_PROPAGATION_DELAY" "-1055.00 MIL,1055.00 MIL"
					( Parent
						( matchGroupRef "@baseboard_fab2_lib.baseboard_fab2(sch_1):\MG_KTI_CPU0_CPU1_P0P0\" )
					)
					( Units "uMatchProp" "ns" 1.000000)
					( Status sCSetFlattened )
					( Origin gBackEnd )
				)
				( attribute "RELATIVE_PROPAGATION_DELAY_SCOPE" "G"
					( Parent
						( matchGroupRef "@baseboard_fab2_lib.baseboard_fab2(sch_1):\MG_KTI_BUNDLE_NG_KTI_CPU0_CPU1_P0P0_0-1\" )
					)
					( Status sCSetFlattened )
					( Origin gBackEnd )
				)
				( attribute "RELATIVE_PROPAGATION_DELAY" ",500.00 MIL"
					( Parent
						( matchGroupRef "@baseboard_fab2_lib.baseboard_fab2(sch_1):\MG_KTI_BUNDLE_NG_KTI_CPU0_CPU1_P0P0_0-1\" )
					)
					( Units "uMatchProp" "ns" 1.000000)
					( Status sCSetFlattened )
					( Origin gBackEnd )
				)
			)
			( pinPair "@baseboard_fab2_lib.baseboard_fab2(sch_1):\PP3266\"
				( pinRef "@baseboard_fab2_lib.baseboard_fab2(sch_1):page33_i86:UPI0_TX_DN(18)" )
				( pinRef "@baseboard_fab2_lib.baseboard_fab2(sch_1):page67_i132:UPI0_RX_DN(1)" )
				( attribute "RELATIVE_PROPAGATION_DELAY_SCOPE" "G"
					( Parent
						( matchGroupRef "@baseboard_fab2_lib.baseboard_fab2(sch_1):\MG_KTI_CPU0_CPU1_P0P0\" )
					)
					( Status sCSetFlattened )
					( Origin gBackEnd )
				)
				( attribute "RELATIVE_PROPAGATION_DELAY" "-1055.00 MIL,1055.00 MIL"
					( Parent
						( matchGroupRef "@baseboard_fab2_lib.baseboard_fab2(sch_1):\MG_KTI_CPU0_CPU1_P0P0\" )
					)
					( Units "uMatchProp" "ns" 1.000000)
					( Status sCSetFlattened )
					( Origin gBackEnd )
				)
				( attribute "RELATIVE_PROPAGATION_DELAY_SCOPE" "G"
					( Parent
						( matchGroupRef "@baseboard_fab2_lib.baseboard_fab2(sch_1):\MG_KTI_BUNDLE_NG_KTI_CPU0_CPU1_P0P0_0-1\" )
					)
					( Status sCSetFlattened )
					( Origin gBackEnd )
				)
				( attribute "RELATIVE_PROPAGATION_DELAY" ",500.00 MIL"
					( Parent
						( matchGroupRef "@baseboard_fab2_lib.baseboard_fab2(sch_1):\MG_KTI_BUNDLE_NG_KTI_CPU0_CPU1_P0P0_0-1\" )
					)
					( Units "uMatchProp" "ns" 1.000000)
					( Status sCSetFlattened )
					( Origin gBackEnd )
				)
			)
			( pinPair "@baseboard_fab2_lib.baseboard_fab2(sch_1):\PP3259\"
				( pinRef "@baseboard_fab2_lib.baseboard_fab2(sch_1):page33_i86:UPI0_TX_DP(17)" )
				( pinRef "@baseboard_fab2_lib.baseboard_fab2(sch_1):page67_i132:UPI0_RX_DP(2)" )
				( attribute "RELATIVE_PROPAGATION_DELAY_SCOPE" "G"
					( Parent
						( matchGroupRef "@baseboard_fab2_lib.baseboard_fab2(sch_1):\MG_KTI_CPU0_CPU1_P0P0\" )
					)
					( Status sCSetFlattened )
					( Origin gBackEnd )
				)
				( attribute "RELATIVE_PROPAGATION_DELAY" "-1055.00 MIL,1055.00 MIL"
					( Parent
						( matchGroupRef "@baseboard_fab2_lib.baseboard_fab2(sch_1):\MG_KTI_CPU0_CPU1_P0P0\" )
					)
					( Units "uMatchProp" "ns" 1.000000)
					( Status sCSetFlattened )
					( Origin gBackEnd )
				)
				( attribute "RELATIVE_PROPAGATION_DELAY_SCOPE" "G"
					( Parent
						( matchGroupRef "@baseboard_fab2_lib.baseboard_fab2(sch_1):\MG_KTI_BUNDLE_NG_KTI_CPU0_CPU1_P0P0_2-3\" )
					)
					( Status sCSetFlattened )
					( Origin gBackEnd )
				)
				( attribute "RELATIVE_PROPAGATION_DELAY" ",500.00 MIL"
					( Parent
						( matchGroupRef "@baseboard_fab2_lib.baseboard_fab2(sch_1):\MG_KTI_BUNDLE_NG_KTI_CPU0_CPU1_P0P0_2-3\" )
					)
					( Units "uMatchProp" "ns" 1.000000)
					( Status sCSetFlattened )
					( Origin gBackEnd )
				)
			)
			( pinPair "@baseboard_fab2_lib.baseboard_fab2(sch_1):\PP3260\"
				( pinRef "@baseboard_fab2_lib.baseboard_fab2(sch_1):page33_i86:UPI0_TX_DN(17)" )
				( pinRef "@baseboard_fab2_lib.baseboard_fab2(sch_1):page67_i132:UPI0_RX_DN(2)" )
				( attribute "RELATIVE_PROPAGATION_DELAY_SCOPE" "G"
					( Parent
						( matchGroupRef "@baseboard_fab2_lib.baseboard_fab2(sch_1):\MG_KTI_CPU0_CPU1_P0P0\" )
					)
					( Status sCSetFlattened )
					( Origin gBackEnd )
				)
				( attribute "RELATIVE_PROPAGATION_DELAY" "-1055.00 MIL,1055.00 MIL"
					( Parent
						( matchGroupRef "@baseboard_fab2_lib.baseboard_fab2(sch_1):\MG_KTI_CPU0_CPU1_P0P0\" )
					)
					( Units "uMatchProp" "ns" 1.000000)
					( Status sCSetFlattened )
					( Origin gBackEnd )
				)
				( attribute "RELATIVE_PROPAGATION_DELAY_SCOPE" "G"
					( Parent
						( matchGroupRef "@baseboard_fab2_lib.baseboard_fab2(sch_1):\MG_KTI_BUNDLE_NG_KTI_CPU0_CPU1_P0P0_2-3\" )
					)
					( Status sCSetFlattened )
					( Origin gBackEnd )
				)
				( attribute "RELATIVE_PROPAGATION_DELAY" ",500.00 MIL"
					( Parent
						( matchGroupRef "@baseboard_fab2_lib.baseboard_fab2(sch_1):\MG_KTI_BUNDLE_NG_KTI_CPU0_CPU1_P0P0_2-3\" )
					)
					( Units "uMatchProp" "ns" 1.000000)
					( Status sCSetFlattened )
					( Origin gBackEnd )
				)
			)
			( pinPair "@baseboard_fab2_lib.baseboard_fab2(sch_1):\PP3261\"
				( pinRef "@baseboard_fab2_lib.baseboard_fab2(sch_1):page33_i86:UPI0_TX_DP(16)" )
				( pinRef "@baseboard_fab2_lib.baseboard_fab2(sch_1):page67_i132:UPI0_RX_DN(3)" )
				( attribute "RELATIVE_PROPAGATION_DELAY_SCOPE" "G"
					( Parent
						( matchGroupRef "@baseboard_fab2_lib.baseboard_fab2(sch_1):\MG_KTI_CPU0_CPU1_P0P0\" )
					)
					( Status sCSetFlattened )
					( Origin gBackEnd )
				)
				( attribute "RELATIVE_PROPAGATION_DELAY" "-1055.00 MIL,1055.00 MIL"
					( Parent
						( matchGroupRef "@baseboard_fab2_lib.baseboard_fab2(sch_1):\MG_KTI_CPU0_CPU1_P0P0\" )
					)
					( Units "uMatchProp" "ns" 1.000000)
					( Status sCSetFlattened )
					( Origin gBackEnd )
				)
				( attribute "RELATIVE_PROPAGATION_DELAY_SCOPE" "G"
					( Parent
						( matchGroupRef "@baseboard_fab2_lib.baseboard_fab2(sch_1):\MG_KTI_BUNDLE_NG_KTI_CPU0_CPU1_P0P0_2-3\" )
					)
					( Status sCSetFlattened )
					( Origin gBackEnd )
				)
				( attribute "RELATIVE_PROPAGATION_DELAY" ",500.00 MIL"
					( Parent
						( matchGroupRef "@baseboard_fab2_lib.baseboard_fab2(sch_1):\MG_KTI_BUNDLE_NG_KTI_CPU0_CPU1_P0P0_2-3\" )
					)
					( Units "uMatchProp" "ns" 1.000000)
					( Status sCSetFlattened )
					( Origin gBackEnd )
				)
			)
			( pinPair "@baseboard_fab2_lib.baseboard_fab2(sch_1):\PP3262\"
				( pinRef "@baseboard_fab2_lib.baseboard_fab2(sch_1):page33_i86:UPI0_TX_DN(16)" )
				( pinRef "@baseboard_fab2_lib.baseboard_fab2(sch_1):page67_i132:UPI0_RX_DP(3)" )
				( attribute "RELATIVE_PROPAGATION_DELAY_SCOPE" "G"
					( Parent
						( matchGroupRef "@baseboard_fab2_lib.baseboard_fab2(sch_1):\MG_KTI_CPU0_CPU1_P0P0\" )
					)
					( Status sCSetFlattened )
					( Origin gBackEnd )
				)
				( attribute "RELATIVE_PROPAGATION_DELAY" "-1055.00 MIL,1055.00 MIL"
					( Parent
						( matchGroupRef "@baseboard_fab2_lib.baseboard_fab2(sch_1):\MG_KTI_CPU0_CPU1_P0P0\" )
					)
					( Units "uMatchProp" "ns" 1.000000)
					( Status sCSetFlattened )
					( Origin gBackEnd )
				)
				( attribute "RELATIVE_PROPAGATION_DELAY_SCOPE" "G"
					( Parent
						( matchGroupRef "@baseboard_fab2_lib.baseboard_fab2(sch_1):\MG_KTI_BUNDLE_NG_KTI_CPU0_CPU1_P0P0_2-3\" )
					)
					( Status sCSetFlattened )
					( Origin gBackEnd )
				)
				( attribute "RELATIVE_PROPAGATION_DELAY" ",500.00 MIL"
					( Parent
						( matchGroupRef "@baseboard_fab2_lib.baseboard_fab2(sch_1):\MG_KTI_BUNDLE_NG_KTI_CPU0_CPU1_P0P0_2-3\" )
					)
					( Units "uMatchProp" "ns" 1.000000)
					( Status sCSetFlattened )
					( Origin gBackEnd )
				)
			)
			( pinPair "@baseboard_fab2_lib.baseboard_fab2(sch_1):\PP3255\"
				( pinRef "@baseboard_fab2_lib.baseboard_fab2(sch_1):page33_i86:UPI0_TX_DP(15)" )
				( pinRef "@baseboard_fab2_lib.baseboard_fab2(sch_1):page67_i132:UPI0_RX_DN(4)" )
				( attribute "RELATIVE_PROPAGATION_DELAY_SCOPE" "G"
					( Parent
						( matchGroupRef "@baseboard_fab2_lib.baseboard_fab2(sch_1):\MG_KTI_CPU0_CPU1_P0P0\" )
					)
					( Status sCSetFlattened )
					( Origin gBackEnd )
				)
				( attribute "RELATIVE_PROPAGATION_DELAY" "-1055.00 MIL,1055.00 MIL"
					( Parent
						( matchGroupRef "@baseboard_fab2_lib.baseboard_fab2(sch_1):\MG_KTI_CPU0_CPU1_P0P0\" )
					)
					( Units "uMatchProp" "ns" 1.000000)
					( Status sCSetFlattened )
					( Origin gBackEnd )
				)
				( attribute "RELATIVE_PROPAGATION_DELAY_SCOPE" "G"
					( Parent
						( matchGroupRef "@baseboard_fab2_lib.baseboard_fab2(sch_1):\MG_KTI_BUNDLE_NG_KTI_CPU0_CPU1_P0P0_4-5\" )
					)
					( Status sCSetFlattened )
					( Origin gBackEnd )
				)
				( attribute "RELATIVE_PROPAGATION_DELAY" ",500.00 MIL"
					( Parent
						( matchGroupRef "@baseboard_fab2_lib.baseboard_fab2(sch_1):\MG_KTI_BUNDLE_NG_KTI_CPU0_CPU1_P0P0_4-5\" )
					)
					( Units "uMatchProp" "ns" 1.000000)
					( Status sCSetFlattened )
					( Origin gBackEnd )
				)
			)
			( pinPair "@baseboard_fab2_lib.baseboard_fab2(sch_1):\PP3256\"
				( pinRef "@baseboard_fab2_lib.baseboard_fab2(sch_1):page33_i86:UPI0_TX_DN(15)" )
				( pinRef "@baseboard_fab2_lib.baseboard_fab2(sch_1):page67_i132:UPI0_RX_DP(4)" )
				( attribute "RELATIVE_PROPAGATION_DELAY_SCOPE" "G"
					( Parent
						( matchGroupRef "@baseboard_fab2_lib.baseboard_fab2(sch_1):\MG_KTI_CPU0_CPU1_P0P0\" )
					)
					( Status sCSetFlattened )
					( Origin gBackEnd )
				)
				( attribute "RELATIVE_PROPAGATION_DELAY" "-1055.00 MIL,1055.00 MIL"
					( Parent
						( matchGroupRef "@baseboard_fab2_lib.baseboard_fab2(sch_1):\MG_KTI_CPU0_CPU1_P0P0\" )
					)
					( Units "uMatchProp" "ns" 1.000000)
					( Status sCSetFlattened )
					( Origin gBackEnd )
				)
				( attribute "RELATIVE_PROPAGATION_DELAY_SCOPE" "G"
					( Parent
						( matchGroupRef "@baseboard_fab2_lib.baseboard_fab2(sch_1):\MG_KTI_BUNDLE_NG_KTI_CPU0_CPU1_P0P0_4-5\" )
					)
					( Status sCSetFlattened )
					( Origin gBackEnd )
				)
				( attribute "RELATIVE_PROPAGATION_DELAY" ",500.00 MIL"
					( Parent
						( matchGroupRef "@baseboard_fab2_lib.baseboard_fab2(sch_1):\MG_KTI_BUNDLE_NG_KTI_CPU0_CPU1_P0P0_4-5\" )
					)
					( Units "uMatchProp" "ns" 1.000000)
					( Status sCSetFlattened )
					( Origin gBackEnd )
				)
			)
			( pinPair "@baseboard_fab2_lib.baseboard_fab2(sch_1):\PP3257\"
				( pinRef "@baseboard_fab2_lib.baseboard_fab2(sch_1):page33_i86:UPI0_TX_DP(14)" )
				( pinRef "@baseboard_fab2_lib.baseboard_fab2(sch_1):page67_i132:UPI0_RX_DN(5)" )
				( attribute "RELATIVE_PROPAGATION_DELAY_SCOPE" "G"
					( Parent
						( matchGroupRef "@baseboard_fab2_lib.baseboard_fab2(sch_1):\MG_KTI_CPU0_CPU1_P0P0\" )
					)
					( Status sCSetFlattened )
					( Origin gBackEnd )
				)
				( attribute "RELATIVE_PROPAGATION_DELAY" "-1055.00 MIL,1055.00 MIL"
					( Parent
						( matchGroupRef "@baseboard_fab2_lib.baseboard_fab2(sch_1):\MG_KTI_CPU0_CPU1_P0P0\" )
					)
					( Units "uMatchProp" "ns" 1.000000)
					( Status sCSetFlattened )
					( Origin gBackEnd )
				)
				( attribute "RELATIVE_PROPAGATION_DELAY_SCOPE" "G"
					( Parent
						( matchGroupRef "@baseboard_fab2_lib.baseboard_fab2(sch_1):\MG_KTI_BUNDLE_NG_KTI_CPU0_CPU1_P0P0_4-5\" )
					)
					( Status sCSetFlattened )
					( Origin gBackEnd )
				)
				( attribute "RELATIVE_PROPAGATION_DELAY" ",500.00 MIL"
					( Parent
						( matchGroupRef "@baseboard_fab2_lib.baseboard_fab2(sch_1):\MG_KTI_BUNDLE_NG_KTI_CPU0_CPU1_P0P0_4-5\" )
					)
					( Units "uMatchProp" "ns" 1.000000)
					( Status sCSetFlattened )
					( Origin gBackEnd )
				)
			)
			( pinPair "@baseboard_fab2_lib.baseboard_fab2(sch_1):\PP3258\"
				( pinRef "@baseboard_fab2_lib.baseboard_fab2(sch_1):page33_i86:UPI0_TX_DN(14)" )
				( pinRef "@baseboard_fab2_lib.baseboard_fab2(sch_1):page67_i132:UPI0_RX_DP(5)" )
				( attribute "RELATIVE_PROPAGATION_DELAY_SCOPE" "G"
					( Parent
						( matchGroupRef "@baseboard_fab2_lib.baseboard_fab2(sch_1):\MG_KTI_CPU0_CPU1_P0P0\" )
					)
					( Status sCSetFlattened )
					( Origin gBackEnd )
				)
				( attribute "RELATIVE_PROPAGATION_DELAY" "-1055.00 MIL,1055.00 MIL"
					( Parent
						( matchGroupRef "@baseboard_fab2_lib.baseboard_fab2(sch_1):\MG_KTI_CPU0_CPU1_P0P0\" )
					)
					( Units "uMatchProp" "ns" 1.000000)
					( Status sCSetFlattened )
					( Origin gBackEnd )
				)
				( attribute "RELATIVE_PROPAGATION_DELAY_SCOPE" "G"
					( Parent
						( matchGroupRef "@baseboard_fab2_lib.baseboard_fab2(sch_1):\MG_KTI_BUNDLE_NG_KTI_CPU0_CPU1_P0P0_4-5\" )
					)
					( Status sCSetFlattened )
					( Origin gBackEnd )
				)
				( attribute "RELATIVE_PROPAGATION_DELAY" ",500.00 MIL"
					( Parent
						( matchGroupRef "@baseboard_fab2_lib.baseboard_fab2(sch_1):\MG_KTI_BUNDLE_NG_KTI_CPU0_CPU1_P0P0_4-5\" )
					)
					( Units "uMatchProp" "ns" 1.000000)
					( Status sCSetFlattened )
					( Origin gBackEnd )
				)
			)
			( pinPair "@baseboard_fab2_lib.baseboard_fab2(sch_1):\PP3251\"
				( pinRef "@baseboard_fab2_lib.baseboard_fab2(sch_1):page33_i86:UPI0_TX_DP(13)" )
				( pinRef "@baseboard_fab2_lib.baseboard_fab2(sch_1):page67_i132:UPI0_RX_DN(6)" )
				( attribute "RELATIVE_PROPAGATION_DELAY_SCOPE" "G"
					( Parent
						( matchGroupRef "@baseboard_fab2_lib.baseboard_fab2(sch_1):\MG_KTI_CPU0_CPU1_P0P0\" )
					)
					( Status sCSetFlattened )
					( Origin gBackEnd )
				)
				( attribute "RELATIVE_PROPAGATION_DELAY" "-1055.00 MIL,1055.00 MIL"
					( Parent
						( matchGroupRef "@baseboard_fab2_lib.baseboard_fab2(sch_1):\MG_KTI_CPU0_CPU1_P0P0\" )
					)
					( Units "uMatchProp" "ns" 1.000000)
					( Status sCSetFlattened )
					( Origin gBackEnd )
				)
				( attribute "RELATIVE_PROPAGATION_DELAY_SCOPE" "G"
					( Parent
						( matchGroupRef "@baseboard_fab2_lib.baseboard_fab2(sch_1):\MG_KTI_BUNDLE_NG_KTI_CPU0_CPU1_P0P0_6-7\" )
					)
					( Status sCSetFlattened )
					( Origin gBackEnd )
				)
				( attribute "RELATIVE_PROPAGATION_DELAY" ",500.00 MIL"
					( Parent
						( matchGroupRef "@baseboard_fab2_lib.baseboard_fab2(sch_1):\MG_KTI_BUNDLE_NG_KTI_CPU0_CPU1_P0P0_6-7\" )
					)
					( Units "uMatchProp" "ns" 1.000000)
					( Status sCSetFlattened )
					( Origin gBackEnd )
				)
			)
			( pinPair "@baseboard_fab2_lib.baseboard_fab2(sch_1):\PP3252\"
				( pinRef "@baseboard_fab2_lib.baseboard_fab2(sch_1):page33_i86:UPI0_TX_DN(13)" )
				( pinRef "@baseboard_fab2_lib.baseboard_fab2(sch_1):page67_i132:UPI0_RX_DP(6)" )
				( attribute "RELATIVE_PROPAGATION_DELAY_SCOPE" "G"
					( Parent
						( matchGroupRef "@baseboard_fab2_lib.baseboard_fab2(sch_1):\MG_KTI_CPU0_CPU1_P0P0\" )
					)
					( Status sCSetFlattened )
					( Origin gBackEnd )
				)
				( attribute "RELATIVE_PROPAGATION_DELAY" "-1055.00 MIL,1055.00 MIL"
					( Parent
						( matchGroupRef "@baseboard_fab2_lib.baseboard_fab2(sch_1):\MG_KTI_CPU0_CPU1_P0P0\" )
					)
					( Units "uMatchProp" "ns" 1.000000)
					( Status sCSetFlattened )
					( Origin gBackEnd )
				)
				( attribute "RELATIVE_PROPAGATION_DELAY_SCOPE" "G"
					( Parent
						( matchGroupRef "@baseboard_fab2_lib.baseboard_fab2(sch_1):\MG_KTI_BUNDLE_NG_KTI_CPU0_CPU1_P0P0_6-7\" )
					)
					( Status sCSetFlattened )
					( Origin gBackEnd )
				)
				( attribute "RELATIVE_PROPAGATION_DELAY" ",500.00 MIL"
					( Parent
						( matchGroupRef "@baseboard_fab2_lib.baseboard_fab2(sch_1):\MG_KTI_BUNDLE_NG_KTI_CPU0_CPU1_P0P0_6-7\" )
					)
					( Units "uMatchProp" "ns" 1.000000)
					( Status sCSetFlattened )
					( Origin gBackEnd )
				)
			)
			( pinPair "@baseboard_fab2_lib.baseboard_fab2(sch_1):\PP3253\"
				( pinRef "@baseboard_fab2_lib.baseboard_fab2(sch_1):page67_i132:UPI0_RX_DN(7)" )
				( pinRef "@baseboard_fab2_lib.baseboard_fab2(sch_1):page33_i86:UPI0_TX_DP(12)" )
				( attribute "RELATIVE_PROPAGATION_DELAY_SCOPE" "G"
					( Parent
						( matchGroupRef "@baseboard_fab2_lib.baseboard_fab2(sch_1):\MG_KTI_CPU0_CPU1_P0P0\" )
					)
					( Status sCSetFlattened )
					( Origin gBackEnd )
				)
				( attribute "RELATIVE_PROPAGATION_DELAY" "-1055.00 MIL,1055.00 MIL"
					( Parent
						( matchGroupRef "@baseboard_fab2_lib.baseboard_fab2(sch_1):\MG_KTI_CPU0_CPU1_P0P0\" )
					)
					( Units "uMatchProp" "ns" 1.000000)
					( Status sCSetFlattened )
					( Origin gBackEnd )
				)
				( attribute "RELATIVE_PROPAGATION_DELAY_SCOPE" "G"
					( Parent
						( matchGroupRef "@baseboard_fab2_lib.baseboard_fab2(sch_1):\MG_KTI_BUNDLE_NG_KTI_CPU0_CPU1_P0P0_6-7\" )
					)
					( Status sCSetFlattened )
					( Origin gBackEnd )
				)
				( attribute "RELATIVE_PROPAGATION_DELAY" ",500.00 MIL"
					( Parent
						( matchGroupRef "@baseboard_fab2_lib.baseboard_fab2(sch_1):\MG_KTI_BUNDLE_NG_KTI_CPU0_CPU1_P0P0_6-7\" )
					)
					( Units "uMatchProp" "ns" 1.000000)
					( Status sCSetFlattened )
					( Origin gBackEnd )
				)
			)
			( pinPair "@baseboard_fab2_lib.baseboard_fab2(sch_1):\PP3254\"
				( pinRef "@baseboard_fab2_lib.baseboard_fab2(sch_1):page67_i132:UPI0_RX_DP(7)" )
				( pinRef "@baseboard_fab2_lib.baseboard_fab2(sch_1):page33_i86:UPI0_TX_DN(12)" )
				( attribute "RELATIVE_PROPAGATION_DELAY_SCOPE" "G"
					( Parent
						( matchGroupRef "@baseboard_fab2_lib.baseboard_fab2(sch_1):\MG_KTI_CPU0_CPU1_P0P0\" )
					)
					( Status sCSetFlattened )
					( Origin gBackEnd )
				)
				( attribute "RELATIVE_PROPAGATION_DELAY" "-1055.00 MIL,1055.00 MIL"
					( Parent
						( matchGroupRef "@baseboard_fab2_lib.baseboard_fab2(sch_1):\MG_KTI_CPU0_CPU1_P0P0\" )
					)
					( Units "uMatchProp" "ns" 1.000000)
					( Status sCSetFlattened )
					( Origin gBackEnd )
				)
				( attribute "RELATIVE_PROPAGATION_DELAY_SCOPE" "G"
					( Parent
						( matchGroupRef "@baseboard_fab2_lib.baseboard_fab2(sch_1):\MG_KTI_BUNDLE_NG_KTI_CPU0_CPU1_P0P0_6-7\" )
					)
					( Status sCSetFlattened )
					( Origin gBackEnd )
				)
				( attribute "RELATIVE_PROPAGATION_DELAY" ",500.00 MIL"
					( Parent
						( matchGroupRef "@baseboard_fab2_lib.baseboard_fab2(sch_1):\MG_KTI_BUNDLE_NG_KTI_CPU0_CPU1_P0P0_6-7\" )
					)
					( Units "uMatchProp" "ns" 1.000000)
					( Status sCSetFlattened )
					( Origin gBackEnd )
				)
			)
			( pinPair "@baseboard_fab2_lib.baseboard_fab2(sch_1):\PP3247\"
				( pinRef "@baseboard_fab2_lib.baseboard_fab2(sch_1):page33_i86:UPI0_TX_DP(11)" )
				( pinRef "@baseboard_fab2_lib.baseboard_fab2(sch_1):page67_i132:UPI0_RX_DN(8)" )
				( attribute "RELATIVE_PROPAGATION_DELAY_SCOPE" "G"
					( Parent
						( matchGroupRef "@baseboard_fab2_lib.baseboard_fab2(sch_1):\MG_KTI_CPU0_CPU1_P0P0\" )
					)
					( Status sCSetFlattened )
					( Origin gBackEnd )
				)
				( attribute "RELATIVE_PROPAGATION_DELAY" "-1055.00 MIL,1055.00 MIL"
					( Parent
						( matchGroupRef "@baseboard_fab2_lib.baseboard_fab2(sch_1):\MG_KTI_CPU0_CPU1_P0P0\" )
					)
					( Units "uMatchProp" "ns" 1.000000)
					( Status sCSetFlattened )
					( Origin gBackEnd )
				)
				( attribute "RELATIVE_PROPAGATION_DELAY_SCOPE" "G"
					( Parent
						( matchGroupRef "@baseboard_fab2_lib.baseboard_fab2(sch_1):\MG_KTI_BUNDLE_NG_KTI_CPU0_CPU1_P0P0_8-9\" )
					)
					( Status sCSetFlattened )
					( Origin gBackEnd )
				)
				( attribute "RELATIVE_PROPAGATION_DELAY" ",500.00 MIL"
					( Parent
						( matchGroupRef "@baseboard_fab2_lib.baseboard_fab2(sch_1):\MG_KTI_BUNDLE_NG_KTI_CPU0_CPU1_P0P0_8-9\" )
					)
					( Units "uMatchProp" "ns" 1.000000)
					( Status sCSetFlattened )
					( Origin gBackEnd )
				)
			)
			( pinPair "@baseboard_fab2_lib.baseboard_fab2(sch_1):\PP3248\"
				( pinRef "@baseboard_fab2_lib.baseboard_fab2(sch_1):page33_i86:UPI0_TX_DN(11)" )
				( pinRef "@baseboard_fab2_lib.baseboard_fab2(sch_1):page67_i132:UPI0_RX_DP(8)" )
				( attribute "RELATIVE_PROPAGATION_DELAY_SCOPE" "G"
					( Parent
						( matchGroupRef "@baseboard_fab2_lib.baseboard_fab2(sch_1):\MG_KTI_CPU0_CPU1_P0P0\" )
					)
					( Status sCSetFlattened )
					( Origin gBackEnd )
				)
				( attribute "RELATIVE_PROPAGATION_DELAY" "-1055.00 MIL,1055.00 MIL"
					( Parent
						( matchGroupRef "@baseboard_fab2_lib.baseboard_fab2(sch_1):\MG_KTI_CPU0_CPU1_P0P0\" )
					)
					( Units "uMatchProp" "ns" 1.000000)
					( Status sCSetFlattened )
					( Origin gBackEnd )
				)
				( attribute "RELATIVE_PROPAGATION_DELAY_SCOPE" "G"
					( Parent
						( matchGroupRef "@baseboard_fab2_lib.baseboard_fab2(sch_1):\MG_KTI_BUNDLE_NG_KTI_CPU0_CPU1_P0P0_8-9\" )
					)
					( Status sCSetFlattened )
					( Origin gBackEnd )
				)
				( attribute "RELATIVE_PROPAGATION_DELAY" ",500.00 MIL"
					( Parent
						( matchGroupRef "@baseboard_fab2_lib.baseboard_fab2(sch_1):\MG_KTI_BUNDLE_NG_KTI_CPU0_CPU1_P0P0_8-9\" )
					)
					( Units "uMatchProp" "ns" 1.000000)
					( Status sCSetFlattened )
					( Origin gBackEnd )
				)
			)
			( pinPair "@baseboard_fab2_lib.baseboard_fab2(sch_1):\PP3249\"
				( pinRef "@baseboard_fab2_lib.baseboard_fab2(sch_1):page33_i86:UPI0_TX_DP(10)" )
				( pinRef "@baseboard_fab2_lib.baseboard_fab2(sch_1):page67_i132:UPI0_RX_DN(9)" )
				( attribute "RELATIVE_PROPAGATION_DELAY_SCOPE" "G"
					( Parent
						( matchGroupRef "@baseboard_fab2_lib.baseboard_fab2(sch_1):\MG_KTI_CPU0_CPU1_P0P0\" )
					)
					( Status sCSetFlattened )
					( Origin gBackEnd )
				)
				( attribute "RELATIVE_PROPAGATION_DELAY" "-1055.00 MIL,1055.00 MIL"
					( Parent
						( matchGroupRef "@baseboard_fab2_lib.baseboard_fab2(sch_1):\MG_KTI_CPU0_CPU1_P0P0\" )
					)
					( Units "uMatchProp" "ns" 1.000000)
					( Status sCSetFlattened )
					( Origin gBackEnd )
				)
				( attribute "RELATIVE_PROPAGATION_DELAY_SCOPE" "G"
					( Parent
						( matchGroupRef "@baseboard_fab2_lib.baseboard_fab2(sch_1):\MG_KTI_BUNDLE_NG_KTI_CPU0_CPU1_P0P0_8-9\" )
					)
					( Status sCSetFlattened )
					( Origin gBackEnd )
				)
				( attribute "RELATIVE_PROPAGATION_DELAY" ",500.00 MIL"
					( Parent
						( matchGroupRef "@baseboard_fab2_lib.baseboard_fab2(sch_1):\MG_KTI_BUNDLE_NG_KTI_CPU0_CPU1_P0P0_8-9\" )
					)
					( Units "uMatchProp" "ns" 1.000000)
					( Status sCSetFlattened )
					( Origin gBackEnd )
				)
			)
			( pinPair "@baseboard_fab2_lib.baseboard_fab2(sch_1):\PP3250\"
				( pinRef "@baseboard_fab2_lib.baseboard_fab2(sch_1):page33_i86:UPI0_TX_DN(10)" )
				( pinRef "@baseboard_fab2_lib.baseboard_fab2(sch_1):page67_i132:UPI0_RX_DP(9)" )
				( attribute "RELATIVE_PROPAGATION_DELAY_SCOPE" "G"
					( Parent
						( matchGroupRef "@baseboard_fab2_lib.baseboard_fab2(sch_1):\MG_KTI_CPU0_CPU1_P0P0\" )
					)
					( Status sCSetFlattened )
					( Origin gBackEnd )
				)
				( attribute "RELATIVE_PROPAGATION_DELAY" "-1055.00 MIL,1055.00 MIL"
					( Parent
						( matchGroupRef "@baseboard_fab2_lib.baseboard_fab2(sch_1):\MG_KTI_CPU0_CPU1_P0P0\" )
					)
					( Units "uMatchProp" "ns" 1.000000)
					( Status sCSetFlattened )
					( Origin gBackEnd )
				)
				( attribute "RELATIVE_PROPAGATION_DELAY_SCOPE" "G"
					( Parent
						( matchGroupRef "@baseboard_fab2_lib.baseboard_fab2(sch_1):\MG_KTI_BUNDLE_NG_KTI_CPU0_CPU1_P0P0_8-9\" )
					)
					( Status sCSetFlattened )
					( Origin gBackEnd )
				)
				( attribute "RELATIVE_PROPAGATION_DELAY" ",500.00 MIL"
					( Parent
						( matchGroupRef "@baseboard_fab2_lib.baseboard_fab2(sch_1):\MG_KTI_BUNDLE_NG_KTI_CPU0_CPU1_P0P0_8-9\" )
					)
					( Units "uMatchProp" "ns" 1.000000)
					( Status sCSetFlattened )
					( Origin gBackEnd )
				)
			)
			( pinPair "@baseboard_fab2_lib.baseboard_fab2(sch_1):\PP3243\"
				( pinRef "@baseboard_fab2_lib.baseboard_fab2(sch_1):page33_i86:UPI0_TX_DP(9)" )
				( pinRef "@baseboard_fab2_lib.baseboard_fab2(sch_1):page67_i132:UPI0_RX_DP(10)" )
				( attribute "RELATIVE_PROPAGATION_DELAY_SCOPE" "G"
					( Parent
						( matchGroupRef "@baseboard_fab2_lib.baseboard_fab2(sch_1):\MG_KTI_CPU0_CPU1_P0P0\" )
					)
					( Status sCSetFlattened )
					( Origin gBackEnd )
				)
				( attribute "RELATIVE_PROPAGATION_DELAY" "-1055.00 MIL,1055.00 MIL"
					( Parent
						( matchGroupRef "@baseboard_fab2_lib.baseboard_fab2(sch_1):\MG_KTI_CPU0_CPU1_P0P0\" )
					)
					( Units "uMatchProp" "ns" 1.000000)
					( Status sCSetFlattened )
					( Origin gBackEnd )
				)
				( attribute "RELATIVE_PROPAGATION_DELAY_SCOPE" "G"
					( Parent
						( matchGroupRef "@baseboard_fab2_lib.baseboard_fab2(sch_1):\MG_KTI_BUNDLE_NG_KTI_CPU0_CPU1_P0P0_10-11\" )
					)
					( Status sCSetFlattened )
					( Origin gBackEnd )
				)
				( attribute "RELATIVE_PROPAGATION_DELAY" ",500.00 MIL"
					( Parent
						( matchGroupRef "@baseboard_fab2_lib.baseboard_fab2(sch_1):\MG_KTI_BUNDLE_NG_KTI_CPU0_CPU1_P0P0_10-11\" )
					)
					( Units "uMatchProp" "ns" 1.000000)
					( Status sCSetFlattened )
					( Origin gBackEnd )
				)
			)
			( pinPair "@baseboard_fab2_lib.baseboard_fab2(sch_1):\PP3244\"
				( pinRef "@baseboard_fab2_lib.baseboard_fab2(sch_1):page33_i86:UPI0_TX_DN(9)" )
				( pinRef "@baseboard_fab2_lib.baseboard_fab2(sch_1):page67_i132:UPI0_RX_DN(10)" )
				( attribute "RELATIVE_PROPAGATION_DELAY_SCOPE" "G"
					( Parent
						( matchGroupRef "@baseboard_fab2_lib.baseboard_fab2(sch_1):\MG_KTI_CPU0_CPU1_P0P0\" )
					)
					( Status sCSetFlattened )
					( Origin gBackEnd )
				)
				( attribute "RELATIVE_PROPAGATION_DELAY" "-1055.00 MIL,1055.00 MIL"
					( Parent
						( matchGroupRef "@baseboard_fab2_lib.baseboard_fab2(sch_1):\MG_KTI_CPU0_CPU1_P0P0\" )
					)
					( Units "uMatchProp" "ns" 1.000000)
					( Status sCSetFlattened )
					( Origin gBackEnd )
				)
				( attribute "RELATIVE_PROPAGATION_DELAY_SCOPE" "G"
					( Parent
						( matchGroupRef "@baseboard_fab2_lib.baseboard_fab2(sch_1):\MG_KTI_BUNDLE_NG_KTI_CPU0_CPU1_P0P0_10-11\" )
					)
					( Status sCSetFlattened )
					( Origin gBackEnd )
				)
				( attribute "RELATIVE_PROPAGATION_DELAY" ",500.00 MIL"
					( Parent
						( matchGroupRef "@baseboard_fab2_lib.baseboard_fab2(sch_1):\MG_KTI_BUNDLE_NG_KTI_CPU0_CPU1_P0P0_10-11\" )
					)
					( Units "uMatchProp" "ns" 1.000000)
					( Status sCSetFlattened )
					( Origin gBackEnd )
				)
			)
			( pinPair "@baseboard_fab2_lib.baseboard_fab2(sch_1):\PP3245\"
				( pinRef "@baseboard_fab2_lib.baseboard_fab2(sch_1):page33_i86:UPI0_TX_DP(8)" )
				( pinRef "@baseboard_fab2_lib.baseboard_fab2(sch_1):page67_i132:UPI0_RX_DN(11)" )
				( attribute "RELATIVE_PROPAGATION_DELAY_SCOPE" "G"
					( Parent
						( matchGroupRef "@baseboard_fab2_lib.baseboard_fab2(sch_1):\MG_KTI_CPU0_CPU1_P0P0\" )
					)
					( Status sCSetFlattened )
					( Origin gBackEnd )
				)
				( attribute "RELATIVE_PROPAGATION_DELAY" "-1055.00 MIL,1055.00 MIL"
					( Parent
						( matchGroupRef "@baseboard_fab2_lib.baseboard_fab2(sch_1):\MG_KTI_CPU0_CPU1_P0P0\" )
					)
					( Units "uMatchProp" "ns" 1.000000)
					( Status sCSetFlattened )
					( Origin gBackEnd )
				)
				( attribute "RELATIVE_PROPAGATION_DELAY_SCOPE" "G"
					( Parent
						( matchGroupRef "@baseboard_fab2_lib.baseboard_fab2(sch_1):\MG_KTI_BUNDLE_NG_KTI_CPU0_CPU1_P0P0_10-11\" )
					)
					( Status sCSetFlattened )
					( Origin gBackEnd )
				)
				( attribute "RELATIVE_PROPAGATION_DELAY" ",500.00 MIL"
					( Parent
						( matchGroupRef "@baseboard_fab2_lib.baseboard_fab2(sch_1):\MG_KTI_BUNDLE_NG_KTI_CPU0_CPU1_P0P0_10-11\" )
					)
					( Units "uMatchProp" "ns" 1.000000)
					( Status sCSetFlattened )
					( Origin gBackEnd )
				)
			)
			( pinPair "@baseboard_fab2_lib.baseboard_fab2(sch_1):\PP3246\"
				( pinRef "@baseboard_fab2_lib.baseboard_fab2(sch_1):page33_i86:UPI0_TX_DN(8)" )
				( pinRef "@baseboard_fab2_lib.baseboard_fab2(sch_1):page67_i132:UPI0_RX_DP(11)" )
				( attribute "RELATIVE_PROPAGATION_DELAY_SCOPE" "G"
					( Parent
						( matchGroupRef "@baseboard_fab2_lib.baseboard_fab2(sch_1):\MG_KTI_CPU0_CPU1_P0P0\" )
					)
					( Status sCSetFlattened )
					( Origin gBackEnd )
				)
				( attribute "RELATIVE_PROPAGATION_DELAY" "-1055.00 MIL,1055.00 MIL"
					( Parent
						( matchGroupRef "@baseboard_fab2_lib.baseboard_fab2(sch_1):\MG_KTI_CPU0_CPU1_P0P0\" )
					)
					( Units "uMatchProp" "ns" 1.000000)
					( Status sCSetFlattened )
					( Origin gBackEnd )
				)
				( attribute "RELATIVE_PROPAGATION_DELAY_SCOPE" "G"
					( Parent
						( matchGroupRef "@baseboard_fab2_lib.baseboard_fab2(sch_1):\MG_KTI_BUNDLE_NG_KTI_CPU0_CPU1_P0P0_10-11\" )
					)
					( Status sCSetFlattened )
					( Origin gBackEnd )
				)
				( attribute "RELATIVE_PROPAGATION_DELAY" ",500.00 MIL"
					( Parent
						( matchGroupRef "@baseboard_fab2_lib.baseboard_fab2(sch_1):\MG_KTI_BUNDLE_NG_KTI_CPU0_CPU1_P0P0_10-11\" )
					)
					( Units "uMatchProp" "ns" 1.000000)
					( Status sCSetFlattened )
					( Origin gBackEnd )
				)
			)
			( pinPair "@baseboard_fab2_lib.baseboard_fab2(sch_1):\PP3239\"
				( pinRef "@baseboard_fab2_lib.baseboard_fab2(sch_1):page33_i86:UPI0_TX_DP(7)" )
				( pinRef "@baseboard_fab2_lib.baseboard_fab2(sch_1):page67_i132:UPI0_RX_DP(12)" )
				( attribute "RELATIVE_PROPAGATION_DELAY_SCOPE" "G"
					( Parent
						( matchGroupRef "@baseboard_fab2_lib.baseboard_fab2(sch_1):\MG_KTI_CPU0_CPU1_P0P0\" )
					)
					( Status sCSetFlattened )
					( Origin gBackEnd )
				)
				( attribute "RELATIVE_PROPAGATION_DELAY" "-1055.00 MIL,1055.00 MIL"
					( Parent
						( matchGroupRef "@baseboard_fab2_lib.baseboard_fab2(sch_1):\MG_KTI_CPU0_CPU1_P0P0\" )
					)
					( Units "uMatchProp" "ns" 1.000000)
					( Status sCSetFlattened )
					( Origin gBackEnd )
				)
				( attribute "RELATIVE_PROPAGATION_DELAY_SCOPE" "G"
					( Parent
						( matchGroupRef "@baseboard_fab2_lib.baseboard_fab2(sch_1):\MG_KTI_BUNDLE_NG_KTI_CPU0_CPU1_P0P0_12-13\" )
					)
					( Status sCSetFlattened )
					( Origin gBackEnd )
				)
				( attribute "RELATIVE_PROPAGATION_DELAY" ",500.00 MIL"
					( Parent
						( matchGroupRef "@baseboard_fab2_lib.baseboard_fab2(sch_1):\MG_KTI_BUNDLE_NG_KTI_CPU0_CPU1_P0P0_12-13\" )
					)
					( Units "uMatchProp" "ns" 1.000000)
					( Status sCSetFlattened )
					( Origin gBackEnd )
				)
			)
			( pinPair "@baseboard_fab2_lib.baseboard_fab2(sch_1):\PP3240\"
				( pinRef "@baseboard_fab2_lib.baseboard_fab2(sch_1):page33_i86:UPI0_TX_DN(7)" )
				( pinRef "@baseboard_fab2_lib.baseboard_fab2(sch_1):page67_i132:UPI0_RX_DN(12)" )
				( attribute "RELATIVE_PROPAGATION_DELAY_SCOPE" "G"
					( Parent
						( matchGroupRef "@baseboard_fab2_lib.baseboard_fab2(sch_1):\MG_KTI_CPU0_CPU1_P0P0\" )
					)
					( Status sCSetFlattened )
					( Origin gBackEnd )
				)
				( attribute "RELATIVE_PROPAGATION_DELAY" "-1055.00 MIL,1055.00 MIL"
					( Parent
						( matchGroupRef "@baseboard_fab2_lib.baseboard_fab2(sch_1):\MG_KTI_CPU0_CPU1_P0P0\" )
					)
					( Units "uMatchProp" "ns" 1.000000)
					( Status sCSetFlattened )
					( Origin gBackEnd )
				)
				( attribute "RELATIVE_PROPAGATION_DELAY_SCOPE" "G"
					( Parent
						( matchGroupRef "@baseboard_fab2_lib.baseboard_fab2(sch_1):\MG_KTI_BUNDLE_NG_KTI_CPU0_CPU1_P0P0_12-13\" )
					)
					( Status sCSetFlattened )
					( Origin gBackEnd )
				)
				( attribute "RELATIVE_PROPAGATION_DELAY" ",500.00 MIL"
					( Parent
						( matchGroupRef "@baseboard_fab2_lib.baseboard_fab2(sch_1):\MG_KTI_BUNDLE_NG_KTI_CPU0_CPU1_P0P0_12-13\" )
					)
					( Units "uMatchProp" "ns" 1.000000)
					( Status sCSetFlattened )
					( Origin gBackEnd )
				)
			)
			( pinPair "@baseboard_fab2_lib.baseboard_fab2(sch_1):\PP3241\"
				( pinRef "@baseboard_fab2_lib.baseboard_fab2(sch_1):page33_i86:UPI0_TX_DP(6)" )
				( pinRef "@baseboard_fab2_lib.baseboard_fab2(sch_1):page67_i132:UPI0_RX_DP(13)" )
				( attribute "RELATIVE_PROPAGATION_DELAY_SCOPE" "G"
					( Parent
						( matchGroupRef "@baseboard_fab2_lib.baseboard_fab2(sch_1):\MG_KTI_CPU0_CPU1_P0P0\" )
					)
					( Status sCSetFlattened )
					( Origin gBackEnd )
				)
				( attribute "RELATIVE_PROPAGATION_DELAY" "-1055.00 MIL,1055.00 MIL"
					( Parent
						( matchGroupRef "@baseboard_fab2_lib.baseboard_fab2(sch_1):\MG_KTI_CPU0_CPU1_P0P0\" )
					)
					( Units "uMatchProp" "ns" 1.000000)
					( Status sCSetFlattened )
					( Origin gBackEnd )
				)
				( attribute "RELATIVE_PROPAGATION_DELAY_SCOPE" "G"
					( Parent
						( matchGroupRef "@baseboard_fab2_lib.baseboard_fab2(sch_1):\MG_KTI_BUNDLE_NG_KTI_CPU0_CPU1_P0P0_12-13\" )
					)
					( Status sCSetFlattened )
					( Origin gBackEnd )
				)
				( attribute "RELATIVE_PROPAGATION_DELAY" ",500.00 MIL"
					( Parent
						( matchGroupRef "@baseboard_fab2_lib.baseboard_fab2(sch_1):\MG_KTI_BUNDLE_NG_KTI_CPU0_CPU1_P0P0_12-13\" )
					)
					( Units "uMatchProp" "ns" 1.000000)
					( Status sCSetFlattened )
					( Origin gBackEnd )
				)
			)
			( pinPair "@baseboard_fab2_lib.baseboard_fab2(sch_1):\PP3242\"
				( pinRef "@baseboard_fab2_lib.baseboard_fab2(sch_1):page33_i86:UPI0_TX_DN(6)" )
				( pinRef "@baseboard_fab2_lib.baseboard_fab2(sch_1):page67_i132:UPI0_RX_DN(13)" )
				( attribute "RELATIVE_PROPAGATION_DELAY_SCOPE" "G"
					( Parent
						( matchGroupRef "@baseboard_fab2_lib.baseboard_fab2(sch_1):\MG_KTI_CPU0_CPU1_P0P0\" )
					)
					( Status sCSetFlattened )
					( Origin gBackEnd )
				)
				( attribute "RELATIVE_PROPAGATION_DELAY" "-1055.00 MIL,1055.00 MIL"
					( Parent
						( matchGroupRef "@baseboard_fab2_lib.baseboard_fab2(sch_1):\MG_KTI_CPU0_CPU1_P0P0\" )
					)
					( Units "uMatchProp" "ns" 1.000000)
					( Status sCSetFlattened )
					( Origin gBackEnd )
				)
				( attribute "RELATIVE_PROPAGATION_DELAY_SCOPE" "G"
					( Parent
						( matchGroupRef "@baseboard_fab2_lib.baseboard_fab2(sch_1):\MG_KTI_BUNDLE_NG_KTI_CPU0_CPU1_P0P0_12-13\" )
					)
					( Status sCSetFlattened )
					( Origin gBackEnd )
				)
				( attribute "RELATIVE_PROPAGATION_DELAY" ",500.00 MIL"
					( Parent
						( matchGroupRef "@baseboard_fab2_lib.baseboard_fab2(sch_1):\MG_KTI_BUNDLE_NG_KTI_CPU0_CPU1_P0P0_12-13\" )
					)
					( Units "uMatchProp" "ns" 1.000000)
					( Status sCSetFlattened )
					( Origin gBackEnd )
				)
			)
			( pinPair "@baseboard_fab2_lib.baseboard_fab2(sch_1):\PP3235\"
				( pinRef "@baseboard_fab2_lib.baseboard_fab2(sch_1):page67_i132:UPI0_RX_DN(14)" )
				( pinRef "@baseboard_fab2_lib.baseboard_fab2(sch_1):page33_i86:UPI0_TX_DP(5)" )
				( attribute "RELATIVE_PROPAGATION_DELAY_SCOPE" "G"
					( Parent
						( matchGroupRef "@baseboard_fab2_lib.baseboard_fab2(sch_1):\MG_KTI_CPU0_CPU1_P0P0\" )
					)
					( Status sCSetFlattened )
					( Origin gBackEnd )
				)
				( attribute "RELATIVE_PROPAGATION_DELAY" "-1055.00 MIL,1055.00 MIL"
					( Parent
						( matchGroupRef "@baseboard_fab2_lib.baseboard_fab2(sch_1):\MG_KTI_CPU0_CPU1_P0P0\" )
					)
					( Units "uMatchProp" "ns" 1.000000)
					( Status sCSetFlattened )
					( Origin gBackEnd )
				)
				( attribute "RELATIVE_PROPAGATION_DELAY_SCOPE" "G"
					( Parent
						( matchGroupRef "@baseboard_fab2_lib.baseboard_fab2(sch_1):\MG_KTI_BUNDLE_NG_KTI_CPU0_CPU1_P0P0_14-15\" )
					)
					( Status sCSetFlattened )
					( Origin gBackEnd )
				)
				( attribute "RELATIVE_PROPAGATION_DELAY" ",500.00 MIL"
					( Parent
						( matchGroupRef "@baseboard_fab2_lib.baseboard_fab2(sch_1):\MG_KTI_BUNDLE_NG_KTI_CPU0_CPU1_P0P0_14-15\" )
					)
					( Units "uMatchProp" "ns" 1.000000)
					( Status sCSetFlattened )
					( Origin gBackEnd )
				)
			)
			( pinPair "@baseboard_fab2_lib.baseboard_fab2(sch_1):\PP3236\"
				( pinRef "@baseboard_fab2_lib.baseboard_fab2(sch_1):page67_i132:UPI0_RX_DP(14)" )
				( pinRef "@baseboard_fab2_lib.baseboard_fab2(sch_1):page33_i86:UPI0_TX_DN(5)" )
				( attribute "RELATIVE_PROPAGATION_DELAY_SCOPE" "G"
					( Parent
						( matchGroupRef "@baseboard_fab2_lib.baseboard_fab2(sch_1):\MG_KTI_CPU0_CPU1_P0P0\" )
					)
					( Status sCSetFlattened )
					( Origin gBackEnd )
				)
				( attribute "RELATIVE_PROPAGATION_DELAY" "-1055.00 MIL,1055.00 MIL"
					( Parent
						( matchGroupRef "@baseboard_fab2_lib.baseboard_fab2(sch_1):\MG_KTI_CPU0_CPU1_P0P0\" )
					)
					( Units "uMatchProp" "ns" 1.000000)
					( Status sCSetFlattened )
					( Origin gBackEnd )
				)
				( attribute "RELATIVE_PROPAGATION_DELAY_SCOPE" "G"
					( Parent
						( matchGroupRef "@baseboard_fab2_lib.baseboard_fab2(sch_1):\MG_KTI_BUNDLE_NG_KTI_CPU0_CPU1_P0P0_14-15\" )
					)
					( Status sCSetFlattened )
					( Origin gBackEnd )
				)
				( attribute "RELATIVE_PROPAGATION_DELAY" ",500.00 MIL"
					( Parent
						( matchGroupRef "@baseboard_fab2_lib.baseboard_fab2(sch_1):\MG_KTI_BUNDLE_NG_KTI_CPU0_CPU1_P0P0_14-15\" )
					)
					( Units "uMatchProp" "ns" 1.000000)
					( Status sCSetFlattened )
					( Origin gBackEnd )
				)
			)
			( pinPair "@baseboard_fab2_lib.baseboard_fab2(sch_1):\PP3237\"
				( pinRef "@baseboard_fab2_lib.baseboard_fab2(sch_1):page67_i132:UPI0_RX_DP(15)" )
				( pinRef "@baseboard_fab2_lib.baseboard_fab2(sch_1):page33_i86:UPI0_TX_DP(4)" )
				( attribute "RELATIVE_PROPAGATION_DELAY_SCOPE" "G"
					( Parent
						( matchGroupRef "@baseboard_fab2_lib.baseboard_fab2(sch_1):\MG_KTI_CPU0_CPU1_P0P0\" )
					)
					( Status sCSetFlattened )
					( Origin gBackEnd )
				)
				( attribute "RELATIVE_PROPAGATION_DELAY" "-1055.00 MIL,1055.00 MIL"
					( Parent
						( matchGroupRef "@baseboard_fab2_lib.baseboard_fab2(sch_1):\MG_KTI_CPU0_CPU1_P0P0\" )
					)
					( Units "uMatchProp" "ns" 1.000000)
					( Status sCSetFlattened )
					( Origin gBackEnd )
				)
				( attribute "RELATIVE_PROPAGATION_DELAY_SCOPE" "G"
					( Parent
						( matchGroupRef "@baseboard_fab2_lib.baseboard_fab2(sch_1):\MG_KTI_BUNDLE_NG_KTI_CPU0_CPU1_P0P0_14-15\" )
					)
					( Status sCSetFlattened )
					( Origin gBackEnd )
				)
				( attribute "RELATIVE_PROPAGATION_DELAY" ",500.00 MIL"
					( Parent
						( matchGroupRef "@baseboard_fab2_lib.baseboard_fab2(sch_1):\MG_KTI_BUNDLE_NG_KTI_CPU0_CPU1_P0P0_14-15\" )
					)
					( Units "uMatchProp" "ns" 1.000000)
					( Status sCSetFlattened )
					( Origin gBackEnd )
				)
			)
			( pinPair "@baseboard_fab2_lib.baseboard_fab2(sch_1):\PP3238\"
				( pinRef "@baseboard_fab2_lib.baseboard_fab2(sch_1):page33_i86:UPI0_TX_DN(4)" )
				( pinRef "@baseboard_fab2_lib.baseboard_fab2(sch_1):page67_i132:UPI0_RX_DN(15)" )
				( attribute "RELATIVE_PROPAGATION_DELAY_SCOPE" "G"
					( Parent
						( matchGroupRef "@baseboard_fab2_lib.baseboard_fab2(sch_1):\MG_KTI_CPU0_CPU1_P0P0\" )
					)
					( Status sCSetFlattened )
					( Origin gBackEnd )
				)
				( attribute "RELATIVE_PROPAGATION_DELAY" "-1055.00 MIL,1055.00 MIL"
					( Parent
						( matchGroupRef "@baseboard_fab2_lib.baseboard_fab2(sch_1):\MG_KTI_CPU0_CPU1_P0P0\" )
					)
					( Units "uMatchProp" "ns" 1.000000)
					( Status sCSetFlattened )
					( Origin gBackEnd )
				)
				( attribute "RELATIVE_PROPAGATION_DELAY_SCOPE" "G"
					( Parent
						( matchGroupRef "@baseboard_fab2_lib.baseboard_fab2(sch_1):\MG_KTI_BUNDLE_NG_KTI_CPU0_CPU1_P0P0_14-15\" )
					)
					( Status sCSetFlattened )
					( Origin gBackEnd )
				)
				( attribute "RELATIVE_PROPAGATION_DELAY" ",500.00 MIL"
					( Parent
						( matchGroupRef "@baseboard_fab2_lib.baseboard_fab2(sch_1):\MG_KTI_BUNDLE_NG_KTI_CPU0_CPU1_P0P0_14-15\" )
					)
					( Units "uMatchProp" "ns" 1.000000)
					( Status sCSetFlattened )
					( Origin gBackEnd )
				)
			)
			( pinPair "@baseboard_fab2_lib.baseboard_fab2(sch_1):\PP3231\"
				( pinRef "@baseboard_fab2_lib.baseboard_fab2(sch_1):page33_i86:UPI0_TX_DP(3)" )
				( pinRef "@baseboard_fab2_lib.baseboard_fab2(sch_1):page67_i132:UPI0_RX_DP(16)" )
				( attribute "RELATIVE_PROPAGATION_DELAY_SCOPE" "G"
					( Parent
						( matchGroupRef "@baseboard_fab2_lib.baseboard_fab2(sch_1):\MG_KTI_CPU0_CPU1_P0P0\" )
					)
					( Status sCSetFlattened )
					( Origin gBackEnd )
				)
				( attribute "RELATIVE_PROPAGATION_DELAY" "-1055.00 MIL,1055.00 MIL"
					( Parent
						( matchGroupRef "@baseboard_fab2_lib.baseboard_fab2(sch_1):\MG_KTI_CPU0_CPU1_P0P0\" )
					)
					( Units "uMatchProp" "ns" 1.000000)
					( Status sCSetFlattened )
					( Origin gBackEnd )
				)
				( attribute "RELATIVE_PROPAGATION_DELAY_SCOPE" "G"
					( Parent
						( matchGroupRef "@baseboard_fab2_lib.baseboard_fab2(sch_1):\MG_KTI_BUNDLE_NG_KTI_CPU0_CPU1_P0P0_16-17\" )
					)
					( Status sCSetFlattened )
					( Origin gBackEnd )
				)
				( attribute "RELATIVE_PROPAGATION_DELAY" ",500.00 MIL"
					( Parent
						( matchGroupRef "@baseboard_fab2_lib.baseboard_fab2(sch_1):\MG_KTI_BUNDLE_NG_KTI_CPU0_CPU1_P0P0_16-17\" )
					)
					( Units "uMatchProp" "ns" 1.000000)
					( Status sCSetFlattened )
					( Origin gBackEnd )
				)
			)
			( pinPair "@baseboard_fab2_lib.baseboard_fab2(sch_1):\PP3232\"
				( pinRef "@baseboard_fab2_lib.baseboard_fab2(sch_1):page33_i86:UPI0_TX_DN(3)" )
				( pinRef "@baseboard_fab2_lib.baseboard_fab2(sch_1):page67_i132:UPI0_RX_DN(16)" )
				( attribute "RELATIVE_PROPAGATION_DELAY_SCOPE" "G"
					( Parent
						( matchGroupRef "@baseboard_fab2_lib.baseboard_fab2(sch_1):\MG_KTI_CPU0_CPU1_P0P0\" )
					)
					( Status sCSetFlattened )
					( Origin gBackEnd )
				)
				( attribute "RELATIVE_PROPAGATION_DELAY" "-1055.00 MIL,1055.00 MIL"
					( Parent
						( matchGroupRef "@baseboard_fab2_lib.baseboard_fab2(sch_1):\MG_KTI_CPU0_CPU1_P0P0\" )
					)
					( Units "uMatchProp" "ns" 1.000000)
					( Status sCSetFlattened )
					( Origin gBackEnd )
				)
				( attribute "RELATIVE_PROPAGATION_DELAY_SCOPE" "G"
					( Parent
						( matchGroupRef "@baseboard_fab2_lib.baseboard_fab2(sch_1):\MG_KTI_BUNDLE_NG_KTI_CPU0_CPU1_P0P0_16-17\" )
					)
					( Status sCSetFlattened )
					( Origin gBackEnd )
				)
				( attribute "RELATIVE_PROPAGATION_DELAY" ",500.00 MIL"
					( Parent
						( matchGroupRef "@baseboard_fab2_lib.baseboard_fab2(sch_1):\MG_KTI_BUNDLE_NG_KTI_CPU0_CPU1_P0P0_16-17\" )
					)
					( Units "uMatchProp" "ns" 1.000000)
					( Status sCSetFlattened )
					( Origin gBackEnd )
				)
			)
			( pinPair "@baseboard_fab2_lib.baseboard_fab2(sch_1):\PP3233\"
				( pinRef "@baseboard_fab2_lib.baseboard_fab2(sch_1):page33_i86:UPI0_TX_DP(2)" )
				( pinRef "@baseboard_fab2_lib.baseboard_fab2(sch_1):page67_i132:UPI0_RX_DP(17)" )
				( attribute "RELATIVE_PROPAGATION_DELAY_SCOPE" "G"
					( Parent
						( matchGroupRef "@baseboard_fab2_lib.baseboard_fab2(sch_1):\MG_KTI_CPU0_CPU1_P0P0\" )
					)
					( Status sCSetFlattened )
					( Origin gBackEnd )
				)
				( attribute "RELATIVE_PROPAGATION_DELAY" "-1055.00 MIL,1055.00 MIL"
					( Parent
						( matchGroupRef "@baseboard_fab2_lib.baseboard_fab2(sch_1):\MG_KTI_CPU0_CPU1_P0P0\" )
					)
					( Units "uMatchProp" "ns" 1.000000)
					( Status sCSetFlattened )
					( Origin gBackEnd )
				)
				( attribute "RELATIVE_PROPAGATION_DELAY_SCOPE" "G"
					( Parent
						( matchGroupRef "@baseboard_fab2_lib.baseboard_fab2(sch_1):\MG_KTI_BUNDLE_NG_KTI_CPU0_CPU1_P0P0_16-17\" )
					)
					( Status sCSetFlattened )
					( Origin gBackEnd )
				)
				( attribute "RELATIVE_PROPAGATION_DELAY" ",500.00 MIL"
					( Parent
						( matchGroupRef "@baseboard_fab2_lib.baseboard_fab2(sch_1):\MG_KTI_BUNDLE_NG_KTI_CPU0_CPU1_P0P0_16-17\" )
					)
					( Units "uMatchProp" "ns" 1.000000)
					( Status sCSetFlattened )
					( Origin gBackEnd )
				)
			)
			( pinPair "@baseboard_fab2_lib.baseboard_fab2(sch_1):\PP3234\"
				( pinRef "@baseboard_fab2_lib.baseboard_fab2(sch_1):page33_i86:UPI0_TX_DN(2)" )
				( pinRef "@baseboard_fab2_lib.baseboard_fab2(sch_1):page67_i132:UPI0_RX_DN(17)" )
				( attribute "RELATIVE_PROPAGATION_DELAY_SCOPE" "G"
					( Parent
						( matchGroupRef "@baseboard_fab2_lib.baseboard_fab2(sch_1):\MG_KTI_CPU0_CPU1_P0P0\" )
					)
					( Status sCSetFlattened )
					( Origin gBackEnd )
				)
				( attribute "RELATIVE_PROPAGATION_DELAY" "-1055.00 MIL,1055.00 MIL"
					( Parent
						( matchGroupRef "@baseboard_fab2_lib.baseboard_fab2(sch_1):\MG_KTI_CPU0_CPU1_P0P0\" )
					)
					( Units "uMatchProp" "ns" 1.000000)
					( Status sCSetFlattened )
					( Origin gBackEnd )
				)
				( attribute "RELATIVE_PROPAGATION_DELAY_SCOPE" "G"
					( Parent
						( matchGroupRef "@baseboard_fab2_lib.baseboard_fab2(sch_1):\MG_KTI_BUNDLE_NG_KTI_CPU0_CPU1_P0P0_16-17\" )
					)
					( Status sCSetFlattened )
					( Origin gBackEnd )
				)
				( attribute "RELATIVE_PROPAGATION_DELAY" ",500.00 MIL"
					( Parent
						( matchGroupRef "@baseboard_fab2_lib.baseboard_fab2(sch_1):\MG_KTI_BUNDLE_NG_KTI_CPU0_CPU1_P0P0_16-17\" )
					)
					( Units "uMatchProp" "ns" 1.000000)
					( Status sCSetFlattened )
					( Origin gBackEnd )
				)
			)
			( pinPair "@baseboard_fab2_lib.baseboard_fab2(sch_1):\PP3227\"
				( pinRef "@baseboard_fab2_lib.baseboard_fab2(sch_1):page33_i86:UPI0_TX_DP(1)" )
				( pinRef "@baseboard_fab2_lib.baseboard_fab2(sch_1):page67_i132:UPI0_RX_DN(18)" )
				( attribute "RELATIVE_PROPAGATION_DELAY_SCOPE" "G"
					( Parent
						( matchGroupRef "@baseboard_fab2_lib.baseboard_fab2(sch_1):\MG_KTI_CPU0_CPU1_P0P0\" )
					)
					( Status sCSetFlattened )
					( Origin gBackEnd )
				)
				( attribute "RELATIVE_PROPAGATION_DELAY" "-1055.00 MIL,1055.00 MIL"
					( Parent
						( matchGroupRef "@baseboard_fab2_lib.baseboard_fab2(sch_1):\MG_KTI_CPU0_CPU1_P0P0\" )
					)
					( Units "uMatchProp" "ns" 1.000000)
					( Status sCSetFlattened )
					( Origin gBackEnd )
				)
				( attribute "RELATIVE_PROPAGATION_DELAY_SCOPE" "G"
					( Parent
						( matchGroupRef "@baseboard_fab2_lib.baseboard_fab2(sch_1):\MG_KTI_BUNDLE_NG_KTI_CPU0_CPU1_P0P0_18-19\" )
					)
					( Status sCSetFlattened )
					( Origin gBackEnd )
				)
				( attribute "RELATIVE_PROPAGATION_DELAY" ",500.00 MIL"
					( Parent
						( matchGroupRef "@baseboard_fab2_lib.baseboard_fab2(sch_1):\MG_KTI_BUNDLE_NG_KTI_CPU0_CPU1_P0P0_18-19\" )
					)
					( Units "uMatchProp" "ns" 1.000000)
					( Status sCSetFlattened )
					( Origin gBackEnd )
				)
			)
			( pinPair "@baseboard_fab2_lib.baseboard_fab2(sch_1):\PP3228\"
				( pinRef "@baseboard_fab2_lib.baseboard_fab2(sch_1):page33_i86:UPI0_TX_DN(1)" )
				( pinRef "@baseboard_fab2_lib.baseboard_fab2(sch_1):page67_i132:UPI0_RX_DP(18)" )
				( attribute "RELATIVE_PROPAGATION_DELAY_SCOPE" "G"
					( Parent
						( matchGroupRef "@baseboard_fab2_lib.baseboard_fab2(sch_1):\MG_KTI_CPU0_CPU1_P0P0\" )
					)
					( Status sCSetFlattened )
					( Origin gBackEnd )
				)
				( attribute "RELATIVE_PROPAGATION_DELAY" "-1055.00 MIL,1055.00 MIL"
					( Parent
						( matchGroupRef "@baseboard_fab2_lib.baseboard_fab2(sch_1):\MG_KTI_CPU0_CPU1_P0P0\" )
					)
					( Units "uMatchProp" "ns" 1.000000)
					( Status sCSetFlattened )
					( Origin gBackEnd )
				)
				( attribute "RELATIVE_PROPAGATION_DELAY_SCOPE" "G"
					( Parent
						( matchGroupRef "@baseboard_fab2_lib.baseboard_fab2(sch_1):\MG_KTI_BUNDLE_NG_KTI_CPU0_CPU1_P0P0_18-19\" )
					)
					( Status sCSetFlattened )
					( Origin gBackEnd )
				)
				( attribute "RELATIVE_PROPAGATION_DELAY" ",500.00 MIL"
					( Parent
						( matchGroupRef "@baseboard_fab2_lib.baseboard_fab2(sch_1):\MG_KTI_BUNDLE_NG_KTI_CPU0_CPU1_P0P0_18-19\" )
					)
					( Units "uMatchProp" "ns" 1.000000)
					( Status sCSetFlattened )
					( Origin gBackEnd )
				)
			)
			( pinPair "@baseboard_fab2_lib.baseboard_fab2(sch_1):\PP3229\"
				( pinRef "@baseboard_fab2_lib.baseboard_fab2(sch_1):page67_i132:UPI0_RX_DN(19)" )
				( pinRef "@baseboard_fab2_lib.baseboard_fab2(sch_1):page33_i86:UPI0_TX_DP(0)" )
				( attribute "RELATIVE_PROPAGATION_DELAY_SCOPE" "G"
					( Parent
						( matchGroupRef "@baseboard_fab2_lib.baseboard_fab2(sch_1):\MG_KTI_CPU0_CPU1_P0P0\" )
					)
					( Status sCSetFlattened )
					( Origin gBackEnd )
				)
				( attribute "RELATIVE_PROPAGATION_DELAY" "-1055.00 MIL,1055.00 MIL"
					( Parent
						( matchGroupRef "@baseboard_fab2_lib.baseboard_fab2(sch_1):\MG_KTI_CPU0_CPU1_P0P0\" )
					)
					( Units "uMatchProp" "ns" 1.000000)
					( Status sCSetFlattened )
					( Origin gBackEnd )
				)
				( attribute "RELATIVE_PROPAGATION_DELAY_SCOPE" "G"
					( Parent
						( matchGroupRef "@baseboard_fab2_lib.baseboard_fab2(sch_1):\MG_KTI_BUNDLE_NG_KTI_CPU0_CPU1_P0P0_18-19\" )
					)
					( Status sCSetFlattened )
					( Origin gBackEnd )
				)
				( attribute "RELATIVE_PROPAGATION_DELAY" ",500.00 MIL"
					( Parent
						( matchGroupRef "@baseboard_fab2_lib.baseboard_fab2(sch_1):\MG_KTI_BUNDLE_NG_KTI_CPU0_CPU1_P0P0_18-19\" )
					)
					( Units "uMatchProp" "ns" 1.000000)
					( Status sCSetFlattened )
					( Origin gBackEnd )
				)
			)
			( pinPair "@baseboard_fab2_lib.baseboard_fab2(sch_1):\PP3230\"
				( pinRef "@baseboard_fab2_lib.baseboard_fab2(sch_1):page67_i132:UPI0_RX_DP(19)" )
				( pinRef "@baseboard_fab2_lib.baseboard_fab2(sch_1):page33_i86:UPI0_TX_DN(0)" )
				( attribute "RELATIVE_PROPAGATION_DELAY_SCOPE" "G"
					( Parent
						( matchGroupRef "@baseboard_fab2_lib.baseboard_fab2(sch_1):\MG_KTI_CPU0_CPU1_P0P0\" )
					)
					( Status sCSetFlattened )
					( Origin gBackEnd )
				)
				( attribute "RELATIVE_PROPAGATION_DELAY" "-1055.00 MIL,1055.00 MIL"
					( Parent
						( matchGroupRef "@baseboard_fab2_lib.baseboard_fab2(sch_1):\MG_KTI_CPU0_CPU1_P0P0\" )
					)
					( Units "uMatchProp" "ns" 1.000000)
					( Status sCSetFlattened )
					( Origin gBackEnd )
				)
				( attribute "RELATIVE_PROPAGATION_DELAY_SCOPE" "G"
					( Parent
						( matchGroupRef "@baseboard_fab2_lib.baseboard_fab2(sch_1):\MG_KTI_BUNDLE_NG_KTI_CPU0_CPU1_P0P0_18-19\" )
					)
					( Status sCSetFlattened )
					( Origin gBackEnd )
				)
				( attribute "RELATIVE_PROPAGATION_DELAY" ",500.00 MIL"
					( Parent
						( matchGroupRef "@baseboard_fab2_lib.baseboard_fab2(sch_1):\MG_KTI_BUNDLE_NG_KTI_CPU0_CPU1_P0P0_18-19\" )
					)
					( Units "uMatchProp" "ns" 1.000000)
					( Status sCSetFlattened )
					( Origin gBackEnd )
				)
			)
			( pinPair "@baseboard_fab2_lib.baseboard_fab2(sch_1):\PP3329\"
				( pinRef "@baseboard_fab2_lib.baseboard_fab2(sch_1):page62_i172:DDR5_CID(2)" )
				( pinRef "@baseboard_fab2_lib.baseboard_fab2(sch_1):page87_i186:C(2)" )
				( attribute "RELATIVE_PROPAGATION_DELAY_SCOPE" "G"
					( Parent
						( matchGroupRef "@baseboard_fab2_lib.baseboard_fab2(sch_1):\MG_DDR_FAR_DIMM_CMD_NG_DDR_M_DLL_1\" )
					)
					( Status sCSetFlattened )
					( Origin gBackEnd )
				)
				( attribute "RELATIVE_PROPAGATION_DELAY" "0.00 MIL,25.00 MIL"
					( Parent
						( matchGroupRef "@baseboard_fab2_lib.baseboard_fab2(sch_1):\MG_DDR_FAR_DIMM_CMD_NG_DDR_M_DLL_1\" )
					)
					( Units "uMatchProp" "ns" 1.000000)
					( Status sCSetFlattened )
					( Origin gBackEnd )
				)
				( attribute "RELATIVE_PROPAGATION_DELAY_SCOPE" "G"
					( Parent
						( matchGroupRef "@crescent_city_bb_fab1_lib.crescent_city_bb_fab1(sch_1):\MG_DDR_FAR_DIMM-CLK0_CLS_DDR_M_CAC-CLKS\" )
					)
					( Status sCSetFlattened )
					( Origin gBackEnd )
				)
				( attribute "RELATIVE_PROPAGATION_DELAY" "0.00 MIL,700.00 MIL"
					( Parent
						( matchGroupRef "@crescent_city_bb_fab1_lib.crescent_city_bb_fab1(sch_1):\MG_DDR_FAR_DIMM-CLK0_CLS_DDR_M_CAC-CLKS\" )
					)
					( Units "uMatchProp" "ns" 1.000000)
					( Status sCSetFlattened )
					( Origin gBackEnd )
				)
			)
			( pinPair "@baseboard_fab2_lib.baseboard_fab2(sch_1):\PP3330\"
				( pinRef "@baseboard_fab2_lib.baseboard_fab2(sch_1):page88_i111:C(2)" )
				( pinRef "@baseboard_fab2_lib.baseboard_fab2(sch_1):page62_i172:DDR5_CID(2)" )
				( attribute "RELATIVE_PROPAGATION_DELAY_SCOPE" "G"
					( Parent
						( matchGroupRef "@crescent_city_bb_fab1_lib.crescent_city_bb_fab1(sch_1):\MG_DDR_NEAR_DIMM-CLK1_CLS_DDR_M_CAC-CLKS\" )
					)
					( Status sCSetFlattened )
					( Origin gBackEnd )
				)
				( attribute "RELATIVE_PROPAGATION_DELAY" "0.00 MIL,700.00 MIL"
					( Parent
						( matchGroupRef "@crescent_city_bb_fab1_lib.crescent_city_bb_fab1(sch_1):\MG_DDR_NEAR_DIMM-CLK1_CLS_DDR_M_CAC-CLKS\" )
					)
					( Units "uMatchProp" "ns" 1.000000)
					( Status sCSetFlattened )
					( Origin gBackEnd )
				)
				( attribute "RELATIVE_PROPAGATION_DELAY_SCOPE" "G"
					( Parent
						( matchGroupRef "@baseboard_fab2_lib.baseboard_fab2(sch_1):\MG_DDR_CMD_NEAR_DIMM_NG_DDR_M_DLL_1\" )
					)
					( Status sCSetFlattened )
					( Origin gBackEnd )
				)
				( attribute "RELATIVE_PROPAGATION_DELAY" "0.00 MIL,25.00 MIL"
					( Parent
						( matchGroupRef "@baseboard_fab2_lib.baseboard_fab2(sch_1):\MG_DDR_CMD_NEAR_DIMM_NG_DDR_M_DLL_1\" )
					)
					( Units "uMatchProp" "ns" 1.000000)
					( Status sCSetFlattened )
					( Origin gBackEnd )
				)
			)
			( pinPair "@baseboard_fab2_lib.baseboard_fab2(sch_1):\PP3331\"
				( pinRef "@baseboard_fab2_lib.baseboard_fab2(sch_1):page62_i172:DDR5_MA(17)" )
				( pinRef "@baseboard_fab2_lib.baseboard_fab2(sch_1):page87_i186:A17" )
				( attribute "RELATIVE_PROPAGATION_DELAY_SCOPE" "G"
					( Parent
						( matchGroupRef "@baseboard_fab2_lib.baseboard_fab2(sch_1):\MG_DDR_FAR_DIMM_CMD_NG_DDR_M_DLL_1\" )
					)
					( Status sCSetFlattened )
					( Origin gBackEnd )
				)
				( attribute "RELATIVE_PROPAGATION_DELAY" "0.00 MIL,25.00 MIL"
					( Parent
						( matchGroupRef "@baseboard_fab2_lib.baseboard_fab2(sch_1):\MG_DDR_FAR_DIMM_CMD_NG_DDR_M_DLL_1\" )
					)
					( Units "uMatchProp" "ns" 1.000000)
					( Status sCSetFlattened )
					( Origin gBackEnd )
				)
				( attribute "RELATIVE_PROPAGATION_DELAY_SCOPE" "G"
					( Parent
						( matchGroupRef "@crescent_city_bb_fab1_lib.crescent_city_bb_fab1(sch_1):\MG_DDR_FAR_DIMM-CLK0_CLS_DDR_M_CAC-CLKS\" )
					)
					( Status sCSetFlattened )
					( Origin gBackEnd )
				)
				( attribute "RELATIVE_PROPAGATION_DELAY" "0.00 MIL,700.00 MIL"
					( Parent
						( matchGroupRef "@crescent_city_bb_fab1_lib.crescent_city_bb_fab1(sch_1):\MG_DDR_FAR_DIMM-CLK0_CLS_DDR_M_CAC-CLKS\" )
					)
					( Units "uMatchProp" "ns" 1.000000)
					( Status sCSetFlattened )
					( Origin gBackEnd )
				)
			)
			( pinPair "@baseboard_fab2_lib.baseboard_fab2(sch_1):\PP3332\"
				( pinRef "@baseboard_fab2_lib.baseboard_fab2(sch_1):page88_i111:A17" )
				( pinRef "@baseboard_fab2_lib.baseboard_fab2(sch_1):page62_i172:DDR5_MA(17)" )
				( attribute "RELATIVE_PROPAGATION_DELAY_SCOPE" "G"
					( Parent
						( matchGroupRef "@crescent_city_bb_fab1_lib.crescent_city_bb_fab1(sch_1):\MG_DDR_NEAR_DIMM-CLK1_CLS_DDR_M_CAC-CLKS\" )
					)
					( Status sCSetFlattened )
					( Origin gBackEnd )
				)
				( attribute "RELATIVE_PROPAGATION_DELAY" "0.00 MIL,700.00 MIL"
					( Parent
						( matchGroupRef "@crescent_city_bb_fab1_lib.crescent_city_bb_fab1(sch_1):\MG_DDR_NEAR_DIMM-CLK1_CLS_DDR_M_CAC-CLKS\" )
					)
					( Units "uMatchProp" "ns" 1.000000)
					( Status sCSetFlattened )
					( Origin gBackEnd )
				)
				( attribute "RELATIVE_PROPAGATION_DELAY_SCOPE" "G"
					( Parent
						( matchGroupRef "@baseboard_fab2_lib.baseboard_fab2(sch_1):\MG_DDR_CMD_NEAR_DIMM_NG_DDR_M_DLL_1\" )
					)
					( Status sCSetFlattened )
					( Origin gBackEnd )
				)
				( attribute "RELATIVE_PROPAGATION_DELAY" "0.00 MIL,25.00 MIL"
					( Parent
						( matchGroupRef "@baseboard_fab2_lib.baseboard_fab2(sch_1):\MG_DDR_CMD_NEAR_DIMM_NG_DDR_M_DLL_1\" )
					)
					( Units "uMatchProp" "ns" 1.000000)
					( Status sCSetFlattened )
					( Origin gBackEnd )
				)
			)
			( pinPair "@baseboard_fab2_lib.baseboard_fab2(sch_1):\PP3325\"
				( pinRef "@baseboard_fab2_lib.baseboard_fab2(sch_1):page62_i172:DDR5_MA(13)" )
				( pinRef "@baseboard_fab2_lib.baseboard_fab2(sch_1):page87_i186:A13" )
				( attribute "RELATIVE_PROPAGATION_DELAY_SCOPE" "G"
					( Parent
						( matchGroupRef "@crescent_city_bb_fab1_lib.crescent_city_bb_fab1(sch_1):\MG_DDR_FAR_DIMM-CLK0_CLS_DDR_M_CAC-CLKS\" )
					)
					( Status sCSetFlattened )
					( Origin gBackEnd )
				)
				( attribute "RELATIVE_PROPAGATION_DELAY" "0.00 MIL,700.00 MIL"
					( Parent
						( matchGroupRef "@crescent_city_bb_fab1_lib.crescent_city_bb_fab1(sch_1):\MG_DDR_FAR_DIMM-CLK0_CLS_DDR_M_CAC-CLKS\" )
					)
					( Units "uMatchProp" "ns" 1.000000)
					( Status sCSetFlattened )
					( Origin gBackEnd )
				)
				( attribute "RELATIVE_PROPAGATION_DELAY_SCOPE" "G"
					( Parent
						( matchGroupRef "@baseboard_fab2_lib.baseboard_fab2(sch_1):\MG_DDR_FAR_DIMM_CMD_NG_DDR_M_DLL_2\" )
					)
					( Status sCSetFlattened )
					( Origin gBackEnd )
				)
				( attribute "RELATIVE_PROPAGATION_DELAY" "0.00 MIL,25.00 MIL"
					( Parent
						( matchGroupRef "@baseboard_fab2_lib.baseboard_fab2(sch_1):\MG_DDR_FAR_DIMM_CMD_NG_DDR_M_DLL_2\" )
					)
					( Units "uMatchProp" "ns" 1.000000)
					( Status sCSetFlattened )
					( Origin gBackEnd )
				)
			)
			( pinPair "@baseboard_fab2_lib.baseboard_fab2(sch_1):\PP3326\"
				( pinRef "@baseboard_fab2_lib.baseboard_fab2(sch_1):page88_i111:A13" )
				( pinRef "@baseboard_fab2_lib.baseboard_fab2(sch_1):page62_i172:DDR5_MA(13)" )
				( attribute "RELATIVE_PROPAGATION_DELAY_SCOPE" "G"
					( Parent
						( matchGroupRef "@crescent_city_bb_fab1_lib.crescent_city_bb_fab1(sch_1):\MG_DDR_NEAR_DIMM-CLK1_CLS_DDR_M_CAC-CLKS\" )
					)
					( Status sCSetFlattened )
					( Origin gBackEnd )
				)
				( attribute "RELATIVE_PROPAGATION_DELAY" "0.00 MIL,700.00 MIL"
					( Parent
						( matchGroupRef "@crescent_city_bb_fab1_lib.crescent_city_bb_fab1(sch_1):\MG_DDR_NEAR_DIMM-CLK1_CLS_DDR_M_CAC-CLKS\" )
					)
					( Units "uMatchProp" "ns" 1.000000)
					( Status sCSetFlattened )
					( Origin gBackEnd )
				)
				( attribute "RELATIVE_PROPAGATION_DELAY_SCOPE" "G"
					( Parent
						( matchGroupRef "@baseboard_fab2_lib.baseboard_fab2(sch_1):\MG_DDR_CMD_NEAR_DIMM_NG_DDR_M_DLL_2\" )
					)
					( Status sCSetFlattened )
					( Origin gBackEnd )
				)
				( attribute "RELATIVE_PROPAGATION_DELAY" "0.00 MIL,25.00 MIL"
					( Parent
						( matchGroupRef "@baseboard_fab2_lib.baseboard_fab2(sch_1):\MG_DDR_CMD_NEAR_DIMM_NG_DDR_M_DLL_2\" )
					)
					( Units "uMatchProp" "ns" 1.000000)
					( Status sCSetFlattened )
					( Origin gBackEnd )
				)
			)
			( pinPair "@baseboard_fab2_lib.baseboard_fab2(sch_1):\PP3327\"
				( pinRef "@baseboard_fab2_lib.baseboard_fab2(sch_1):page62_i172:DDR5_MA(15)" )
				( pinRef "@baseboard_fab2_lib.baseboard_fab2(sch_1):page87_i186:A15_CAS_N" )
				( attribute "RELATIVE_PROPAGATION_DELAY_SCOPE" "G"
					( Parent
						( matchGroupRef "@crescent_city_bb_fab1_lib.crescent_city_bb_fab1(sch_1):\MG_DDR_FAR_DIMM-CLK0_CLS_DDR_M_CAC-CLKS\" )
					)
					( Status sCSetFlattened )
					( Origin gBackEnd )
				)
				( attribute "RELATIVE_PROPAGATION_DELAY" "0.00 MIL,700.00 MIL"
					( Parent
						( matchGroupRef "@crescent_city_bb_fab1_lib.crescent_city_bb_fab1(sch_1):\MG_DDR_FAR_DIMM-CLK0_CLS_DDR_M_CAC-CLKS\" )
					)
					( Units "uMatchProp" "ns" 1.000000)
					( Status sCSetFlattened )
					( Origin gBackEnd )
				)
				( attribute "RELATIVE_PROPAGATION_DELAY_SCOPE" "G"
					( Parent
						( matchGroupRef "@baseboard_fab2_lib.baseboard_fab2(sch_1):\MG_DDR_FAR_DIMM_CMD_NG_DDR_M_DLL_2\" )
					)
					( Status sCSetFlattened )
					( Origin gBackEnd )
				)
				( attribute "RELATIVE_PROPAGATION_DELAY" "0.00 MIL,25.00 MIL"
					( Parent
						( matchGroupRef "@baseboard_fab2_lib.baseboard_fab2(sch_1):\MG_DDR_FAR_DIMM_CMD_NG_DDR_M_DLL_2\" )
					)
					( Units "uMatchProp" "ns" 1.000000)
					( Status sCSetFlattened )
					( Origin gBackEnd )
				)
			)
			( pinPair "@baseboard_fab2_lib.baseboard_fab2(sch_1):\PP3328\"
				( pinRef "@baseboard_fab2_lib.baseboard_fab2(sch_1):page88_i111:A15_CAS_N" )
				( pinRef "@baseboard_fab2_lib.baseboard_fab2(sch_1):page62_i172:DDR5_MA(15)" )
				( attribute "RELATIVE_PROPAGATION_DELAY_SCOPE" "G"
					( Parent
						( matchGroupRef "@crescent_city_bb_fab1_lib.crescent_city_bb_fab1(sch_1):\MG_DDR_NEAR_DIMM-CLK1_CLS_DDR_M_CAC-CLKS\" )
					)
					( Status sCSetFlattened )
					( Origin gBackEnd )
				)
				( attribute "RELATIVE_PROPAGATION_DELAY" "0.00 MIL,700.00 MIL"
					( Parent
						( matchGroupRef "@crescent_city_bb_fab1_lib.crescent_city_bb_fab1(sch_1):\MG_DDR_NEAR_DIMM-CLK1_CLS_DDR_M_CAC-CLKS\" )
					)
					( Units "uMatchProp" "ns" 1.000000)
					( Status sCSetFlattened )
					( Origin gBackEnd )
				)
				( attribute "RELATIVE_PROPAGATION_DELAY_SCOPE" "G"
					( Parent
						( matchGroupRef "@baseboard_fab2_lib.baseboard_fab2(sch_1):\MG_DDR_CMD_NEAR_DIMM_NG_DDR_M_DLL_2\" )
					)
					( Status sCSetFlattened )
					( Origin gBackEnd )
				)
				( attribute "RELATIVE_PROPAGATION_DELAY" "0.00 MIL,25.00 MIL"
					( Parent
						( matchGroupRef "@baseboard_fab2_lib.baseboard_fab2(sch_1):\MG_DDR_CMD_NEAR_DIMM_NG_DDR_M_DLL_2\" )
					)
					( Units "uMatchProp" "ns" 1.000000)
					( Status sCSetFlattened )
					( Origin gBackEnd )
				)
			)
			( pinPair "@baseboard_fab2_lib.baseboard_fab2(sch_1):\PP3321\"
				( pinRef "@baseboard_fab2_lib.baseboard_fab2(sch_1):page62_i172:DDR5_MA(14)" )
				( pinRef "@baseboard_fab2_lib.baseboard_fab2(sch_1):page87_i186:A14_WE_N" )
				( attribute "RELATIVE_PROPAGATION_DELAY_SCOPE" "G"
					( Parent
						( matchGroupRef "@crescent_city_bb_fab1_lib.crescent_city_bb_fab1(sch_1):\MG_DDR_FAR_DIMM-CLK0_CLS_DDR_M_CAC-CLKS\" )
					)
					( Status sCSetFlattened )
					( Origin gBackEnd )
				)
				( attribute "RELATIVE_PROPAGATION_DELAY" "0.00 MIL,700.00 MIL"
					( Parent
						( matchGroupRef "@crescent_city_bb_fab1_lib.crescent_city_bb_fab1(sch_1):\MG_DDR_FAR_DIMM-CLK0_CLS_DDR_M_CAC-CLKS\" )
					)
					( Units "uMatchProp" "ns" 1.000000)
					( Status sCSetFlattened )
					( Origin gBackEnd )
				)
				( attribute "RELATIVE_PROPAGATION_DELAY_SCOPE" "G"
					( Parent
						( matchGroupRef "@baseboard_fab2_lib.baseboard_fab2(sch_1):\MG_DDR_FAR_DIMM_CMD_NG_DDR_M_DLL_3\" )
					)
					( Status sCSetFlattened )
					( Origin gBackEnd )
				)
				( attribute "RELATIVE_PROPAGATION_DELAY" "0.00 MIL,25.00 MIL"
					( Parent
						( matchGroupRef "@baseboard_fab2_lib.baseboard_fab2(sch_1):\MG_DDR_FAR_DIMM_CMD_NG_DDR_M_DLL_3\" )
					)
					( Units "uMatchProp" "ns" 1.000000)
					( Status sCSetFlattened )
					( Origin gBackEnd )
				)
			)
			( pinPair "@baseboard_fab2_lib.baseboard_fab2(sch_1):\PP3322\"
				( pinRef "@baseboard_fab2_lib.baseboard_fab2(sch_1):page88_i111:A14_WE_N" )
				( pinRef "@baseboard_fab2_lib.baseboard_fab2(sch_1):page62_i172:DDR5_MA(14)" )
				( attribute "RELATIVE_PROPAGATION_DELAY_SCOPE" "G"
					( Parent
						( matchGroupRef "@crescent_city_bb_fab1_lib.crescent_city_bb_fab1(sch_1):\MG_DDR_NEAR_DIMM-CLK1_CLS_DDR_M_CAC-CLKS\" )
					)
					( Status sCSetFlattened )
					( Origin gBackEnd )
				)
				( attribute "RELATIVE_PROPAGATION_DELAY" "0.00 MIL,700.00 MIL"
					( Parent
						( matchGroupRef "@crescent_city_bb_fab1_lib.crescent_city_bb_fab1(sch_1):\MG_DDR_NEAR_DIMM-CLK1_CLS_DDR_M_CAC-CLKS\" )
					)
					( Units "uMatchProp" "ns" 1.000000)
					( Status sCSetFlattened )
					( Origin gBackEnd )
				)
				( attribute "RELATIVE_PROPAGATION_DELAY_SCOPE" "G"
					( Parent
						( matchGroupRef "@baseboard_fab2_lib.baseboard_fab2(sch_1):\MG_DDR_CMD_NEAR_DIMM_NG_DDR_M_DLL_3\" )
					)
					( Status sCSetFlattened )
					( Origin gBackEnd )
				)
				( attribute "RELATIVE_PROPAGATION_DELAY" "0.00 MIL,25.00 MIL"
					( Parent
						( matchGroupRef "@baseboard_fab2_lib.baseboard_fab2(sch_1):\MG_DDR_CMD_NEAR_DIMM_NG_DDR_M_DLL_3\" )
					)
					( Units "uMatchProp" "ns" 1.000000)
					( Status sCSetFlattened )
					( Origin gBackEnd )
				)
			)
			( pinPair "@baseboard_fab2_lib.baseboard_fab2(sch_1):\PP3323\"
				( pinRef "@baseboard_fab2_lib.baseboard_fab2(sch_1):page62_i172:DDR5_MA(16)" )
				( pinRef "@baseboard_fab2_lib.baseboard_fab2(sch_1):page87_i186:A16_RAS_N" )
				( attribute "RELATIVE_PROPAGATION_DELAY_SCOPE" "G"
					( Parent
						( matchGroupRef "@crescent_city_bb_fab1_lib.crescent_city_bb_fab1(sch_1):\MG_DDR_FAR_DIMM-CLK0_CLS_DDR_M_CAC-CLKS\" )
					)
					( Status sCSetFlattened )
					( Origin gBackEnd )
				)
				( attribute "RELATIVE_PROPAGATION_DELAY" "0.00 MIL,700.00 MIL"
					( Parent
						( matchGroupRef "@crescent_city_bb_fab1_lib.crescent_city_bb_fab1(sch_1):\MG_DDR_FAR_DIMM-CLK0_CLS_DDR_M_CAC-CLKS\" )
					)
					( Units "uMatchProp" "ns" 1.000000)
					( Status sCSetFlattened )
					( Origin gBackEnd )
				)
				( attribute "RELATIVE_PROPAGATION_DELAY_SCOPE" "G"
					( Parent
						( matchGroupRef "@baseboard_fab2_lib.baseboard_fab2(sch_1):\MG_DDR_FAR_DIMM_CMD_NG_DDR_M_DLL_3\" )
					)
					( Status sCSetFlattened )
					( Origin gBackEnd )
				)
				( attribute "RELATIVE_PROPAGATION_DELAY" "0.00 MIL,25.00 MIL"
					( Parent
						( matchGroupRef "@baseboard_fab2_lib.baseboard_fab2(sch_1):\MG_DDR_FAR_DIMM_CMD_NG_DDR_M_DLL_3\" )
					)
					( Units "uMatchProp" "ns" 1.000000)
					( Status sCSetFlattened )
					( Origin gBackEnd )
				)
			)
			( pinPair "@baseboard_fab2_lib.baseboard_fab2(sch_1):\PP3324\"
				( pinRef "@baseboard_fab2_lib.baseboard_fab2(sch_1):page88_i111:A16_RAS_N" )
				( pinRef "@baseboard_fab2_lib.baseboard_fab2(sch_1):page62_i172:DDR5_MA(16)" )
				( attribute "RELATIVE_PROPAGATION_DELAY_SCOPE" "G"
					( Parent
						( matchGroupRef "@crescent_city_bb_fab1_lib.crescent_city_bb_fab1(sch_1):\MG_DDR_NEAR_DIMM-CLK1_CLS_DDR_M_CAC-CLKS\" )
					)
					( Status sCSetFlattened )
					( Origin gBackEnd )
				)
				( attribute "RELATIVE_PROPAGATION_DELAY" "0.00 MIL,700.00 MIL"
					( Parent
						( matchGroupRef "@crescent_city_bb_fab1_lib.crescent_city_bb_fab1(sch_1):\MG_DDR_NEAR_DIMM-CLK1_CLS_DDR_M_CAC-CLKS\" )
					)
					( Units "uMatchProp" "ns" 1.000000)
					( Status sCSetFlattened )
					( Origin gBackEnd )
				)
				( attribute "RELATIVE_PROPAGATION_DELAY_SCOPE" "G"
					( Parent
						( matchGroupRef "@baseboard_fab2_lib.baseboard_fab2(sch_1):\MG_DDR_CMD_NEAR_DIMM_NG_DDR_M_DLL_3\" )
					)
					( Status sCSetFlattened )
					( Origin gBackEnd )
				)
				( attribute "RELATIVE_PROPAGATION_DELAY" "0.00 MIL,25.00 MIL"
					( Parent
						( matchGroupRef "@baseboard_fab2_lib.baseboard_fab2(sch_1):\MG_DDR_CMD_NEAR_DIMM_NG_DDR_M_DLL_3\" )
					)
					( Units "uMatchProp" "ns" 1.000000)
					( Status sCSetFlattened )
					( Origin gBackEnd )
				)
			)
			( pinPair "@baseboard_fab2_lib.baseboard_fab2(sch_1):\PP3317\"
				( pinRef "@baseboard_fab2_lib.baseboard_fab2(sch_1):page62_i172:DDR5_BA(1)" )
				( pinRef "@baseboard_fab2_lib.baseboard_fab2(sch_1):page87_i186:BA(1)" )
				( attribute "RELATIVE_PROPAGATION_DELAY_SCOPE" "G"
					( Parent
						( matchGroupRef "@crescent_city_bb_fab1_lib.crescent_city_bb_fab1(sch_1):\MG_DDR_FAR_DIMM-CLK0_CLS_DDR_M_CAC-CLKS\" )
					)
					( Status sCSetFlattened )
					( Origin gBackEnd )
				)
				( attribute "RELATIVE_PROPAGATION_DELAY" "0.00 MIL,700.00 MIL"
					( Parent
						( matchGroupRef "@crescent_city_bb_fab1_lib.crescent_city_bb_fab1(sch_1):\MG_DDR_FAR_DIMM-CLK0_CLS_DDR_M_CAC-CLKS\" )
					)
					( Units "uMatchProp" "ns" 1.000000)
					( Status sCSetFlattened )
					( Origin gBackEnd )
				)
				( attribute "RELATIVE_PROPAGATION_DELAY_SCOPE" "G"
					( Parent
						( matchGroupRef "@baseboard_fab2_lib.baseboard_fab2(sch_1):\MG_DDR_FAR_DIMM_CMD_NG_DDR_M_DLL_4\" )
					)
					( Status sCSetFlattened )
					( Origin gBackEnd )
				)
				( attribute "RELATIVE_PROPAGATION_DELAY" "0.00 MIL,25.00 MIL"
					( Parent
						( matchGroupRef "@baseboard_fab2_lib.baseboard_fab2(sch_1):\MG_DDR_FAR_DIMM_CMD_NG_DDR_M_DLL_4\" )
					)
					( Units "uMatchProp" "ns" 1.000000)
					( Status sCSetFlattened )
					( Origin gBackEnd )
				)
			)
			( pinPair "@baseboard_fab2_lib.baseboard_fab2(sch_1):\PP3318\"
				( pinRef "@baseboard_fab2_lib.baseboard_fab2(sch_1):page88_i111:BA(1)" )
				( pinRef "@baseboard_fab2_lib.baseboard_fab2(sch_1):page62_i172:DDR5_BA(1)" )
				( attribute "RELATIVE_PROPAGATION_DELAY_SCOPE" "G"
					( Parent
						( matchGroupRef "@crescent_city_bb_fab1_lib.crescent_city_bb_fab1(sch_1):\MG_DDR_NEAR_DIMM-CLK1_CLS_DDR_M_CAC-CLKS\" )
					)
					( Status sCSetFlattened )
					( Origin gBackEnd )
				)
				( attribute "RELATIVE_PROPAGATION_DELAY" "0.00 MIL,700.00 MIL"
					( Parent
						( matchGroupRef "@crescent_city_bb_fab1_lib.crescent_city_bb_fab1(sch_1):\MG_DDR_NEAR_DIMM-CLK1_CLS_DDR_M_CAC-CLKS\" )
					)
					( Units "uMatchProp" "ns" 1.000000)
					( Status sCSetFlattened )
					( Origin gBackEnd )
				)
				( attribute "RELATIVE_PROPAGATION_DELAY_SCOPE" "G"
					( Parent
						( matchGroupRef "@baseboard_fab2_lib.baseboard_fab2(sch_1):\MG_DDR_CMD_NEAR_DIMM_NG_DDR_M_DLL_4\" )
					)
					( Status sCSetFlattened )
					( Origin gBackEnd )
				)
				( attribute "RELATIVE_PROPAGATION_DELAY" "0.00 MIL,25.00 MIL"
					( Parent
						( matchGroupRef "@baseboard_fab2_lib.baseboard_fab2(sch_1):\MG_DDR_CMD_NEAR_DIMM_NG_DDR_M_DLL_4\" )
					)
					( Units "uMatchProp" "ns" 1.000000)
					( Status sCSetFlattened )
					( Origin gBackEnd )
				)
			)
			( pinPair "@baseboard_fab2_lib.baseboard_fab2(sch_1):\PP3319\"
				( pinRef "@baseboard_fab2_lib.baseboard_fab2(sch_1):page62_i172:DDR5_MA(10)" )
				( pinRef "@baseboard_fab2_lib.baseboard_fab2(sch_1):page87_i186:A10" )
				( attribute "RELATIVE_PROPAGATION_DELAY_SCOPE" "G"
					( Parent
						( matchGroupRef "@crescent_city_bb_fab1_lib.crescent_city_bb_fab1(sch_1):\MG_DDR_FAR_DIMM-CLK0_CLS_DDR_M_CAC-CLKS\" )
					)
					( Status sCSetFlattened )
					( Origin gBackEnd )
				)
				( attribute "RELATIVE_PROPAGATION_DELAY" "0.00 MIL,700.00 MIL"
					( Parent
						( matchGroupRef "@crescent_city_bb_fab1_lib.crescent_city_bb_fab1(sch_1):\MG_DDR_FAR_DIMM-CLK0_CLS_DDR_M_CAC-CLKS\" )
					)
					( Units "uMatchProp" "ns" 1.000000)
					( Status sCSetFlattened )
					( Origin gBackEnd )
				)
				( attribute "RELATIVE_PROPAGATION_DELAY_SCOPE" "G"
					( Parent
						( matchGroupRef "@baseboard_fab2_lib.baseboard_fab2(sch_1):\MG_DDR_FAR_DIMM_CMD_NG_DDR_M_DLL_4\" )
					)
					( Status sCSetFlattened )
					( Origin gBackEnd )
				)
				( attribute "RELATIVE_PROPAGATION_DELAY" "0.00 MIL,25.00 MIL"
					( Parent
						( matchGroupRef "@baseboard_fab2_lib.baseboard_fab2(sch_1):\MG_DDR_FAR_DIMM_CMD_NG_DDR_M_DLL_4\" )
					)
					( Units "uMatchProp" "ns" 1.000000)
					( Status sCSetFlattened )
					( Origin gBackEnd )
				)
			)
			( pinPair "@baseboard_fab2_lib.baseboard_fab2(sch_1):\PP3320\"
				( pinRef "@baseboard_fab2_lib.baseboard_fab2(sch_1):page88_i111:A10" )
				( pinRef "@baseboard_fab2_lib.baseboard_fab2(sch_1):page62_i172:DDR5_MA(10)" )
				( attribute "RELATIVE_PROPAGATION_DELAY_SCOPE" "G"
					( Parent
						( matchGroupRef "@crescent_city_bb_fab1_lib.crescent_city_bb_fab1(sch_1):\MG_DDR_NEAR_DIMM-CLK1_CLS_DDR_M_CAC-CLKS\" )
					)
					( Status sCSetFlattened )
					( Origin gBackEnd )
				)
				( attribute "RELATIVE_PROPAGATION_DELAY" "0.00 MIL,700.00 MIL"
					( Parent
						( matchGroupRef "@crescent_city_bb_fab1_lib.crescent_city_bb_fab1(sch_1):\MG_DDR_NEAR_DIMM-CLK1_CLS_DDR_M_CAC-CLKS\" )
					)
					( Units "uMatchProp" "ns" 1.000000)
					( Status sCSetFlattened )
					( Origin gBackEnd )
				)
				( attribute "RELATIVE_PROPAGATION_DELAY_SCOPE" "G"
					( Parent
						( matchGroupRef "@baseboard_fab2_lib.baseboard_fab2(sch_1):\MG_DDR_CMD_NEAR_DIMM_NG_DDR_M_DLL_4\" )
					)
					( Status sCSetFlattened )
					( Origin gBackEnd )
				)
				( attribute "RELATIVE_PROPAGATION_DELAY" "0.00 MIL,25.00 MIL"
					( Parent
						( matchGroupRef "@baseboard_fab2_lib.baseboard_fab2(sch_1):\MG_DDR_CMD_NEAR_DIMM_NG_DDR_M_DLL_4\" )
					)
					( Units "uMatchProp" "ns" 1.000000)
					( Status sCSetFlattened )
					( Origin gBackEnd )
				)
			)
			( pinPair "@baseboard_fab2_lib.baseboard_fab2(sch_1):\PP3313\"
				( pinRef "@baseboard_fab2_lib.baseboard_fab2(sch_1):page62_i172:DDR5_BA(0)" )
				( pinRef "@baseboard_fab2_lib.baseboard_fab2(sch_1):page87_i186:BA(0)" )
				( attribute "RELATIVE_PROPAGATION_DELAY_SCOPE" "G"
					( Parent
						( matchGroupRef "@crescent_city_bb_fab1_lib.crescent_city_bb_fab1(sch_1):\MG_DDR_FAR_DIMM-CLK0_CLS_DDR_M_CAC-CLKS\" )
					)
					( Status sCSetFlattened )
					( Origin gBackEnd )
				)
				( attribute "RELATIVE_PROPAGATION_DELAY" "0.00 MIL,700.00 MIL"
					( Parent
						( matchGroupRef "@crescent_city_bb_fab1_lib.crescent_city_bb_fab1(sch_1):\MG_DDR_FAR_DIMM-CLK0_CLS_DDR_M_CAC-CLKS\" )
					)
					( Units "uMatchProp" "ns" 1.000000)
					( Status sCSetFlattened )
					( Origin gBackEnd )
				)
				( attribute "RELATIVE_PROPAGATION_DELAY_SCOPE" "G"
					( Parent
						( matchGroupRef "@baseboard_fab2_lib.baseboard_fab2(sch_1):\MG_DDR_FAR_DIMM_CMD_NG_DDR_M_DLL_5\" )
					)
					( Status sCSetFlattened )
					( Origin gBackEnd )
				)
				( attribute "RELATIVE_PROPAGATION_DELAY" "0.00 MIL,25.00 MIL"
					( Parent
						( matchGroupRef "@baseboard_fab2_lib.baseboard_fab2(sch_1):\MG_DDR_FAR_DIMM_CMD_NG_DDR_M_DLL_5\" )
					)
					( Units "uMatchProp" "ns" 1.000000)
					( Status sCSetFlattened )
					( Origin gBackEnd )
				)
			)
			( pinPair "@baseboard_fab2_lib.baseboard_fab2(sch_1):\PP3314\"
				( pinRef "@baseboard_fab2_lib.baseboard_fab2(sch_1):page88_i111:BA(0)" )
				( pinRef "@baseboard_fab2_lib.baseboard_fab2(sch_1):page62_i172:DDR5_BA(0)" )
				( attribute "RELATIVE_PROPAGATION_DELAY_SCOPE" "G"
					( Parent
						( matchGroupRef "@crescent_city_bb_fab1_lib.crescent_city_bb_fab1(sch_1):\MG_DDR_NEAR_DIMM-CLK1_CLS_DDR_M_CAC-CLKS\" )
					)
					( Status sCSetFlattened )
					( Origin gBackEnd )
				)
				( attribute "RELATIVE_PROPAGATION_DELAY" "0.00 MIL,700.00 MIL"
					( Parent
						( matchGroupRef "@crescent_city_bb_fab1_lib.crescent_city_bb_fab1(sch_1):\MG_DDR_NEAR_DIMM-CLK1_CLS_DDR_M_CAC-CLKS\" )
					)
					( Units "uMatchProp" "ns" 1.000000)
					( Status sCSetFlattened )
					( Origin gBackEnd )
				)
				( attribute "RELATIVE_PROPAGATION_DELAY_SCOPE" "G"
					( Parent
						( matchGroupRef "@baseboard_fab2_lib.baseboard_fab2(sch_1):\MG_DDR_CMD_NEAR_DIMM_NG_DDR_M_DLL_5\" )
					)
					( Status sCSetFlattened )
					( Origin gBackEnd )
				)
				( attribute "RELATIVE_PROPAGATION_DELAY" "0.00 MIL,25.00 MIL"
					( Parent
						( matchGroupRef "@baseboard_fab2_lib.baseboard_fab2(sch_1):\MG_DDR_CMD_NEAR_DIMM_NG_DDR_M_DLL_5\" )
					)
					( Units "uMatchProp" "ns" 1.000000)
					( Status sCSetFlattened )
					( Origin gBackEnd )
				)
			)
			( pinPair "@baseboard_fab2_lib.baseboard_fab2(sch_1):\PP3315\"
				( pinRef "@baseboard_fab2_lib.baseboard_fab2(sch_1):page62_i172:DDR5_MA(0)" )
				( pinRef "@baseboard_fab2_lib.baseboard_fab2(sch_1):page87_i186:A0" )
				( attribute "RELATIVE_PROPAGATION_DELAY_SCOPE" "G"
					( Parent
						( matchGroupRef "@crescent_city_bb_fab1_lib.crescent_city_bb_fab1(sch_1):\MG_DDR_FAR_DIMM-CLK0_CLS_DDR_M_CAC-CLKS\" )
					)
					( Status sCSetFlattened )
					( Origin gBackEnd )
				)
				( attribute "RELATIVE_PROPAGATION_DELAY" "0.00 MIL,700.00 MIL"
					( Parent
						( matchGroupRef "@crescent_city_bb_fab1_lib.crescent_city_bb_fab1(sch_1):\MG_DDR_FAR_DIMM-CLK0_CLS_DDR_M_CAC-CLKS\" )
					)
					( Units "uMatchProp" "ns" 1.000000)
					( Status sCSetFlattened )
					( Origin gBackEnd )
				)
				( attribute "RELATIVE_PROPAGATION_DELAY_SCOPE" "G"
					( Parent
						( matchGroupRef "@baseboard_fab2_lib.baseboard_fab2(sch_1):\MG_DDR_FAR_DIMM_CMD_NG_DDR_M_DLL_5\" )
					)
					( Status sCSetFlattened )
					( Origin gBackEnd )
				)
				( attribute "RELATIVE_PROPAGATION_DELAY" "0.00 MIL,25.00 MIL"
					( Parent
						( matchGroupRef "@baseboard_fab2_lib.baseboard_fab2(sch_1):\MG_DDR_FAR_DIMM_CMD_NG_DDR_M_DLL_5\" )
					)
					( Units "uMatchProp" "ns" 1.000000)
					( Status sCSetFlattened )
					( Origin gBackEnd )
				)
			)
			( pinPair "@baseboard_fab2_lib.baseboard_fab2(sch_1):\PP3316\"
				( pinRef "@baseboard_fab2_lib.baseboard_fab2(sch_1):page88_i111:A0" )
				( pinRef "@baseboard_fab2_lib.baseboard_fab2(sch_1):page62_i172:DDR5_MA(0)" )
				( attribute "RELATIVE_PROPAGATION_DELAY_SCOPE" "G"
					( Parent
						( matchGroupRef "@crescent_city_bb_fab1_lib.crescent_city_bb_fab1(sch_1):\MG_DDR_NEAR_DIMM-CLK1_CLS_DDR_M_CAC-CLKS\" )
					)
					( Status sCSetFlattened )
					( Origin gBackEnd )
				)
				( attribute "RELATIVE_PROPAGATION_DELAY" "0.00 MIL,700.00 MIL"
					( Parent
						( matchGroupRef "@crescent_city_bb_fab1_lib.crescent_city_bb_fab1(sch_1):\MG_DDR_NEAR_DIMM-CLK1_CLS_DDR_M_CAC-CLKS\" )
					)
					( Units "uMatchProp" "ns" 1.000000)
					( Status sCSetFlattened )
					( Origin gBackEnd )
				)
				( attribute "RELATIVE_PROPAGATION_DELAY_SCOPE" "G"
					( Parent
						( matchGroupRef "@baseboard_fab2_lib.baseboard_fab2(sch_1):\MG_DDR_CMD_NEAR_DIMM_NG_DDR_M_DLL_5\" )
					)
					( Status sCSetFlattened )
					( Origin gBackEnd )
				)
				( attribute "RELATIVE_PROPAGATION_DELAY" "0.00 MIL,25.00 MIL"
					( Parent
						( matchGroupRef "@baseboard_fab2_lib.baseboard_fab2(sch_1):\MG_DDR_CMD_NEAR_DIMM_NG_DDR_M_DLL_5\" )
					)
					( Units "uMatchProp" "ns" 1.000000)
					( Status sCSetFlattened )
					( Origin gBackEnd )
				)
			)
			( pinPair "@baseboard_fab2_lib.baseboard_fab2(sch_1):\PP3311\"
				( pinRef "@baseboard_fab2_lib.baseboard_fab2(sch_1):page62_i172:DDR5_PAR" )
				( pinRef "@baseboard_fab2_lib.baseboard_fab2(sch_1):page87_i186:PAR" )
				( attribute "RELATIVE_PROPAGATION_DELAY_SCOPE" "G"
					( Parent
						( matchGroupRef "@crescent_city_bb_fab1_lib.crescent_city_bb_fab1(sch_1):\MG_DDR_FAR_DIMM-CLK0_CLS_DDR_M_CAC-CLKS\" )
					)
					( Status sCSetFlattened )
					( Origin gBackEnd )
				)
				( attribute "RELATIVE_PROPAGATION_DELAY" "0.00 MIL,700.00 MIL"
					( Parent
						( matchGroupRef "@crescent_city_bb_fab1_lib.crescent_city_bb_fab1(sch_1):\MG_DDR_FAR_DIMM-CLK0_CLS_DDR_M_CAC-CLKS\" )
					)
					( Units "uMatchProp" "ns" 1.000000)
					( Status sCSetFlattened )
					( Origin gBackEnd )
				)
				( attribute "RELATIVE_PROPAGATION_DELAY_SCOPE" "G"
					( Parent
						( matchGroupRef "@baseboard_fab2_lib.baseboard_fab2(sch_1):\MG_DDR_FAR_DIMM_CMD_NG_DDR_M_DLL_6\" )
					)
					( Status sCSetFlattened )
					( Origin gBackEnd )
				)
				( attribute "RELATIVE_PROPAGATION_DELAY" "0.00 MIL,25.00 MIL"
					( Parent
						( matchGroupRef "@baseboard_fab2_lib.baseboard_fab2(sch_1):\MG_DDR_FAR_DIMM_CMD_NG_DDR_M_DLL_6\" )
					)
					( Units "uMatchProp" "ns" 1.000000)
					( Status sCSetFlattened )
					( Origin gBackEnd )
				)
			)
			( pinPair "@baseboard_fab2_lib.baseboard_fab2(sch_1):\PP3312\"
				( pinRef "@baseboard_fab2_lib.baseboard_fab2(sch_1):page88_i111:PAR" )
				( pinRef "@baseboard_fab2_lib.baseboard_fab2(sch_1):page62_i172:DDR5_PAR" )
				( attribute "RELATIVE_PROPAGATION_DELAY_SCOPE" "G"
					( Parent
						( matchGroupRef "@crescent_city_bb_fab1_lib.crescent_city_bb_fab1(sch_1):\MG_DDR_NEAR_DIMM-CLK1_CLS_DDR_M_CAC-CLKS\" )
					)
					( Status sCSetFlattened )
					( Origin gBackEnd )
				)
				( attribute "RELATIVE_PROPAGATION_DELAY" "0.00 MIL,700.00 MIL"
					( Parent
						( matchGroupRef "@crescent_city_bb_fab1_lib.crescent_city_bb_fab1(sch_1):\MG_DDR_NEAR_DIMM-CLK1_CLS_DDR_M_CAC-CLKS\" )
					)
					( Units "uMatchProp" "ns" 1.000000)
					( Status sCSetFlattened )
					( Origin gBackEnd )
				)
				( attribute "RELATIVE_PROPAGATION_DELAY_SCOPE" "G"
					( Parent
						( matchGroupRef "@baseboard_fab2_lib.baseboard_fab2(sch_1):\MG_DDR_CMD_NEAR_DIMM_NG_DDR_M_DLL_6\" )
					)
					( Status sCSetFlattened )
					( Origin gBackEnd )
				)
				( attribute "RELATIVE_PROPAGATION_DELAY" "0.00 MIL,25.00 MIL"
					( Parent
						( matchGroupRef "@baseboard_fab2_lib.baseboard_fab2(sch_1):\MG_DDR_CMD_NEAR_DIMM_NG_DDR_M_DLL_6\" )
					)
					( Units "uMatchProp" "ns" 1.000000)
					( Status sCSetFlattened )
					( Origin gBackEnd )
				)
			)
			( pinPair "@baseboard_fab2_lib.baseboard_fab2(sch_1):\PP3307\"
				( pinRef "@baseboard_fab2_lib.baseboard_fab2(sch_1):page62_i172:DDR5_MA(1)" )
				( pinRef "@baseboard_fab2_lib.baseboard_fab2(sch_1):page87_i186:A1" )
				( attribute "RELATIVE_PROPAGATION_DELAY_SCOPE" "G"
					( Parent
						( matchGroupRef "@crescent_city_bb_fab1_lib.crescent_city_bb_fab1(sch_1):\MG_DDR_FAR_DIMM-CLK0_CLS_DDR_M_CAC-CLKS\" )
					)
					( Status sCSetFlattened )
					( Origin gBackEnd )
				)
				( attribute "RELATIVE_PROPAGATION_DELAY" "0.00 MIL,700.00 MIL"
					( Parent
						( matchGroupRef "@crescent_city_bb_fab1_lib.crescent_city_bb_fab1(sch_1):\MG_DDR_FAR_DIMM-CLK0_CLS_DDR_M_CAC-CLKS\" )
					)
					( Units "uMatchProp" "ns" 1.000000)
					( Status sCSetFlattened )
					( Origin gBackEnd )
				)
				( attribute "RELATIVE_PROPAGATION_DELAY_SCOPE" "G"
					( Parent
						( matchGroupRef "@baseboard_fab2_lib.baseboard_fab2(sch_1):\MG_DDR_FAR_DIMM_CMD_NG_DDR_M_DLL_7\" )
					)
					( Status sCSetFlattened )
					( Origin gBackEnd )
				)
				( attribute "RELATIVE_PROPAGATION_DELAY" "0.00 MIL,25.00 MIL"
					( Parent
						( matchGroupRef "@baseboard_fab2_lib.baseboard_fab2(sch_1):\MG_DDR_FAR_DIMM_CMD_NG_DDR_M_DLL_7\" )
					)
					( Units "uMatchProp" "ns" 1.000000)
					( Status sCSetFlattened )
					( Origin gBackEnd )
				)
			)
			( pinPair "@baseboard_fab2_lib.baseboard_fab2(sch_1):\PP3308\"
				( pinRef "@baseboard_fab2_lib.baseboard_fab2(sch_1):page88_i111:A1" )
				( pinRef "@baseboard_fab2_lib.baseboard_fab2(sch_1):page62_i172:DDR5_MA(1)" )
				( attribute "RELATIVE_PROPAGATION_DELAY_SCOPE" "G"
					( Parent
						( matchGroupRef "@crescent_city_bb_fab1_lib.crescent_city_bb_fab1(sch_1):\MG_DDR_NEAR_DIMM-CLK1_CLS_DDR_M_CAC-CLKS\" )
					)
					( Status sCSetFlattened )
					( Origin gBackEnd )
				)
				( attribute "RELATIVE_PROPAGATION_DELAY" "0.00 MIL,700.00 MIL"
					( Parent
						( matchGroupRef "@crescent_city_bb_fab1_lib.crescent_city_bb_fab1(sch_1):\MG_DDR_NEAR_DIMM-CLK1_CLS_DDR_M_CAC-CLKS\" )
					)
					( Units "uMatchProp" "ns" 1.000000)
					( Status sCSetFlattened )
					( Origin gBackEnd )
				)
				( attribute "RELATIVE_PROPAGATION_DELAY_SCOPE" "G"
					( Parent
						( matchGroupRef "@baseboard_fab2_lib.baseboard_fab2(sch_1):\MG_DDR_CMD_NEAR_DIMM_NG_DDR_M_DLL_7\" )
					)
					( Status sCSetFlattened )
					( Origin gBackEnd )
				)
				( attribute "RELATIVE_PROPAGATION_DELAY" "0.00 MIL,25.00 MIL"
					( Parent
						( matchGroupRef "@baseboard_fab2_lib.baseboard_fab2(sch_1):\MG_DDR_CMD_NEAR_DIMM_NG_DDR_M_DLL_7\" )
					)
					( Units "uMatchProp" "ns" 1.000000)
					( Status sCSetFlattened )
					( Origin gBackEnd )
				)
			)
			( pinPair "@baseboard_fab2_lib.baseboard_fab2(sch_1):\PP3309\"
				( pinRef "@baseboard_fab2_lib.baseboard_fab2(sch_1):page62_i172:DDR5_MA(3)" )
				( pinRef "@baseboard_fab2_lib.baseboard_fab2(sch_1):page87_i186:A3" )
				( attribute "RELATIVE_PROPAGATION_DELAY_SCOPE" "G"
					( Parent
						( matchGroupRef "@crescent_city_bb_fab1_lib.crescent_city_bb_fab1(sch_1):\MG_DDR_FAR_DIMM-CLK0_CLS_DDR_M_CAC-CLKS\" )
					)
					( Status sCSetFlattened )
					( Origin gBackEnd )
				)
				( attribute "RELATIVE_PROPAGATION_DELAY" "0.00 MIL,700.00 MIL"
					( Parent
						( matchGroupRef "@crescent_city_bb_fab1_lib.crescent_city_bb_fab1(sch_1):\MG_DDR_FAR_DIMM-CLK0_CLS_DDR_M_CAC-CLKS\" )
					)
					( Units "uMatchProp" "ns" 1.000000)
					( Status sCSetFlattened )
					( Origin gBackEnd )
				)
				( attribute "RELATIVE_PROPAGATION_DELAY_SCOPE" "G"
					( Parent
						( matchGroupRef "@baseboard_fab2_lib.baseboard_fab2(sch_1):\MG_DDR_FAR_DIMM_CMD_NG_DDR_M_DLL_7\" )
					)
					( Status sCSetFlattened )
					( Origin gBackEnd )
				)
				( attribute "RELATIVE_PROPAGATION_DELAY" "0.00 MIL,25.00 MIL"
					( Parent
						( matchGroupRef "@baseboard_fab2_lib.baseboard_fab2(sch_1):\MG_DDR_FAR_DIMM_CMD_NG_DDR_M_DLL_7\" )
					)
					( Units "uMatchProp" "ns" 1.000000)
					( Status sCSetFlattened )
					( Origin gBackEnd )
				)
			)
			( pinPair "@baseboard_fab2_lib.baseboard_fab2(sch_1):\PP3310\"
				( pinRef "@baseboard_fab2_lib.baseboard_fab2(sch_1):page88_i111:A3" )
				( pinRef "@baseboard_fab2_lib.baseboard_fab2(sch_1):page62_i172:DDR5_MA(3)" )
				( attribute "RELATIVE_PROPAGATION_DELAY_SCOPE" "G"
					( Parent
						( matchGroupRef "@crescent_city_bb_fab1_lib.crescent_city_bb_fab1(sch_1):\MG_DDR_NEAR_DIMM-CLK1_CLS_DDR_M_CAC-CLKS\" )
					)
					( Status sCSetFlattened )
					( Origin gBackEnd )
				)
				( attribute "RELATIVE_PROPAGATION_DELAY" "0.00 MIL,700.00 MIL"
					( Parent
						( matchGroupRef "@crescent_city_bb_fab1_lib.crescent_city_bb_fab1(sch_1):\MG_DDR_NEAR_DIMM-CLK1_CLS_DDR_M_CAC-CLKS\" )
					)
					( Units "uMatchProp" "ns" 1.000000)
					( Status sCSetFlattened )
					( Origin gBackEnd )
				)
				( attribute "RELATIVE_PROPAGATION_DELAY_SCOPE" "G"
					( Parent
						( matchGroupRef "@baseboard_fab2_lib.baseboard_fab2(sch_1):\MG_DDR_CMD_NEAR_DIMM_NG_DDR_M_DLL_7\" )
					)
					( Status sCSetFlattened )
					( Origin gBackEnd )
				)
				( attribute "RELATIVE_PROPAGATION_DELAY" "0.00 MIL,25.00 MIL"
					( Parent
						( matchGroupRef "@baseboard_fab2_lib.baseboard_fab2(sch_1):\MG_DDR_CMD_NEAR_DIMM_NG_DDR_M_DLL_7\" )
					)
					( Units "uMatchProp" "ns" 1.000000)
					( Status sCSetFlattened )
					( Origin gBackEnd )
				)
			)
			( pinPair "@baseboard_fab2_lib.baseboard_fab2(sch_1):\PP3303\"
				( pinRef "@baseboard_fab2_lib.baseboard_fab2(sch_1):page62_i172:DDR5_MA(2)" )
				( pinRef "@baseboard_fab2_lib.baseboard_fab2(sch_1):page87_i186:A2" )
				( attribute "RELATIVE_PROPAGATION_DELAY_SCOPE" "G"
					( Parent
						( matchGroupRef "@crescent_city_bb_fab1_lib.crescent_city_bb_fab1(sch_1):\MG_DDR_FAR_DIMM-CLK0_CLS_DDR_M_CAC-CLKS\" )
					)
					( Status sCSetFlattened )
					( Origin gBackEnd )
				)
				( attribute "RELATIVE_PROPAGATION_DELAY" "0.00 MIL,700.00 MIL"
					( Parent
						( matchGroupRef "@crescent_city_bb_fab1_lib.crescent_city_bb_fab1(sch_1):\MG_DDR_FAR_DIMM-CLK0_CLS_DDR_M_CAC-CLKS\" )
					)
					( Units "uMatchProp" "ns" 1.000000)
					( Status sCSetFlattened )
					( Origin gBackEnd )
				)
				( attribute "RELATIVE_PROPAGATION_DELAY_SCOPE" "G"
					( Parent
						( matchGroupRef "@baseboard_fab2_lib.baseboard_fab2(sch_1):\MG_DDR_FAR_DIMM_CMD_NG_DDR_M_DLL_8\" )
					)
					( Status sCSetFlattened )
					( Origin gBackEnd )
				)
				( attribute "RELATIVE_PROPAGATION_DELAY" "0.00 MIL,25.00 MIL"
					( Parent
						( matchGroupRef "@baseboard_fab2_lib.baseboard_fab2(sch_1):\MG_DDR_FAR_DIMM_CMD_NG_DDR_M_DLL_8\" )
					)
					( Units "uMatchProp" "ns" 1.000000)
					( Status sCSetFlattened )
					( Origin gBackEnd )
				)
			)
			( pinPair "@baseboard_fab2_lib.baseboard_fab2(sch_1):\PP3304\"
				( pinRef "@baseboard_fab2_lib.baseboard_fab2(sch_1):page88_i111:A2" )
				( pinRef "@baseboard_fab2_lib.baseboard_fab2(sch_1):page62_i172:DDR5_MA(2)" )
				( attribute "RELATIVE_PROPAGATION_DELAY_SCOPE" "G"
					( Parent
						( matchGroupRef "@crescent_city_bb_fab1_lib.crescent_city_bb_fab1(sch_1):\MG_DDR_NEAR_DIMM-CLK1_CLS_DDR_M_CAC-CLKS\" )
					)
					( Status sCSetFlattened )
					( Origin gBackEnd )
				)
				( attribute "RELATIVE_PROPAGATION_DELAY" "0.00 MIL,700.00 MIL"
					( Parent
						( matchGroupRef "@crescent_city_bb_fab1_lib.crescent_city_bb_fab1(sch_1):\MG_DDR_NEAR_DIMM-CLK1_CLS_DDR_M_CAC-CLKS\" )
					)
					( Units "uMatchProp" "ns" 1.000000)
					( Status sCSetFlattened )
					( Origin gBackEnd )
				)
				( attribute "RELATIVE_PROPAGATION_DELAY_SCOPE" "G"
					( Parent
						( matchGroupRef "@baseboard_fab2_lib.baseboard_fab2(sch_1):\MG_DDR_CMD_NEAR_DIMM_NG_DDR_M_DLL_8\" )
					)
					( Status sCSetFlattened )
					( Origin gBackEnd )
				)
				( attribute "RELATIVE_PROPAGATION_DELAY" "0.00 MIL,25.00 MIL"
					( Parent
						( matchGroupRef "@baseboard_fab2_lib.baseboard_fab2(sch_1):\MG_DDR_CMD_NEAR_DIMM_NG_DDR_M_DLL_8\" )
					)
					( Units "uMatchProp" "ns" 1.000000)
					( Status sCSetFlattened )
					( Origin gBackEnd )
				)
			)
			( pinPair "@baseboard_fab2_lib.baseboard_fab2(sch_1):\PP3305\"
				( pinRef "@baseboard_fab2_lib.baseboard_fab2(sch_1):page62_i172:DDR5_MA(4)" )
				( pinRef "@baseboard_fab2_lib.baseboard_fab2(sch_1):page87_i186:A4" )
				( attribute "RELATIVE_PROPAGATION_DELAY_SCOPE" "G"
					( Parent
						( matchGroupRef "@crescent_city_bb_fab1_lib.crescent_city_bb_fab1(sch_1):\MG_DDR_FAR_DIMM-CLK0_CLS_DDR_M_CAC-CLKS\" )
					)
					( Status sCSetFlattened )
					( Origin gBackEnd )
				)
				( attribute "RELATIVE_PROPAGATION_DELAY" "0.00 MIL,700.00 MIL"
					( Parent
						( matchGroupRef "@crescent_city_bb_fab1_lib.crescent_city_bb_fab1(sch_1):\MG_DDR_FAR_DIMM-CLK0_CLS_DDR_M_CAC-CLKS\" )
					)
					( Units "uMatchProp" "ns" 1.000000)
					( Status sCSetFlattened )
					( Origin gBackEnd )
				)
				( attribute "RELATIVE_PROPAGATION_DELAY_SCOPE" "G"
					( Parent
						( matchGroupRef "@baseboard_fab2_lib.baseboard_fab2(sch_1):\MG_DDR_FAR_DIMM_CMD_NG_DDR_M_DLL_8\" )
					)
					( Status sCSetFlattened )
					( Origin gBackEnd )
				)
				( attribute "RELATIVE_PROPAGATION_DELAY" "0.00 MIL,25.00 MIL"
					( Parent
						( matchGroupRef "@baseboard_fab2_lib.baseboard_fab2(sch_1):\MG_DDR_FAR_DIMM_CMD_NG_DDR_M_DLL_8\" )
					)
					( Units "uMatchProp" "ns" 1.000000)
					( Status sCSetFlattened )
					( Origin gBackEnd )
				)
			)
			( pinPair "@baseboard_fab2_lib.baseboard_fab2(sch_1):\PP3306\"
				( pinRef "@baseboard_fab2_lib.baseboard_fab2(sch_1):page88_i111:A4" )
				( pinRef "@baseboard_fab2_lib.baseboard_fab2(sch_1):page62_i172:DDR5_MA(4)" )
				( attribute "RELATIVE_PROPAGATION_DELAY_SCOPE" "G"
					( Parent
						( matchGroupRef "@crescent_city_bb_fab1_lib.crescent_city_bb_fab1(sch_1):\MG_DDR_NEAR_DIMM-CLK1_CLS_DDR_M_CAC-CLKS\" )
					)
					( Status sCSetFlattened )
					( Origin gBackEnd )
				)
				( attribute "RELATIVE_PROPAGATION_DELAY" "0.00 MIL,700.00 MIL"
					( Parent
						( matchGroupRef "@crescent_city_bb_fab1_lib.crescent_city_bb_fab1(sch_1):\MG_DDR_NEAR_DIMM-CLK1_CLS_DDR_M_CAC-CLKS\" )
					)
					( Units "uMatchProp" "ns" 1.000000)
					( Status sCSetFlattened )
					( Origin gBackEnd )
				)
				( attribute "RELATIVE_PROPAGATION_DELAY_SCOPE" "G"
					( Parent
						( matchGroupRef "@baseboard_fab2_lib.baseboard_fab2(sch_1):\MG_DDR_CMD_NEAR_DIMM_NG_DDR_M_DLL_8\" )
					)
					( Status sCSetFlattened )
					( Origin gBackEnd )
				)
				( attribute "RELATIVE_PROPAGATION_DELAY" "0.00 MIL,25.00 MIL"
					( Parent
						( matchGroupRef "@baseboard_fab2_lib.baseboard_fab2(sch_1):\MG_DDR_CMD_NEAR_DIMM_NG_DDR_M_DLL_8\" )
					)
					( Units "uMatchProp" "ns" 1.000000)
					( Status sCSetFlattened )
					( Origin gBackEnd )
				)
			)
			( pinPair "@baseboard_fab2_lib.baseboard_fab2(sch_1):\PP3299\"
				( pinRef "@baseboard_fab2_lib.baseboard_fab2(sch_1):page62_i172:DDR5_MA(5)" )
				( pinRef "@baseboard_fab2_lib.baseboard_fab2(sch_1):page87_i186:A5" )
				( attribute "RELATIVE_PROPAGATION_DELAY_SCOPE" "G"
					( Parent
						( matchGroupRef "@crescent_city_bb_fab1_lib.crescent_city_bb_fab1(sch_1):\MG_DDR_FAR_DIMM-CLK0_CLS_DDR_M_CAC-CLKS\" )
					)
					( Status sCSetFlattened )
					( Origin gBackEnd )
				)
				( attribute "RELATIVE_PROPAGATION_DELAY" "0.00 MIL,700.00 MIL"
					( Parent
						( matchGroupRef "@crescent_city_bb_fab1_lib.crescent_city_bb_fab1(sch_1):\MG_DDR_FAR_DIMM-CLK0_CLS_DDR_M_CAC-CLKS\" )
					)
					( Units "uMatchProp" "ns" 1.000000)
					( Status sCSetFlattened )
					( Origin gBackEnd )
				)
				( attribute "RELATIVE_PROPAGATION_DELAY_SCOPE" "G"
					( Parent
						( matchGroupRef "@baseboard_fab2_lib.baseboard_fab2(sch_1):\MG_DDR_FAR_DIMM_CMD_NG_DDR_M_DLL_9\" )
					)
					( Status sCSetFlattened )
					( Origin gBackEnd )
				)
				( attribute "RELATIVE_PROPAGATION_DELAY" "0.00 MIL,25.00 MIL"
					( Parent
						( matchGroupRef "@baseboard_fab2_lib.baseboard_fab2(sch_1):\MG_DDR_FAR_DIMM_CMD_NG_DDR_M_DLL_9\" )
					)
					( Units "uMatchProp" "ns" 1.000000)
					( Status sCSetFlattened )
					( Origin gBackEnd )
				)
			)
			( pinPair "@baseboard_fab2_lib.baseboard_fab2(sch_1):\PP3300\"
				( pinRef "@baseboard_fab2_lib.baseboard_fab2(sch_1):page88_i111:A5" )
				( pinRef "@baseboard_fab2_lib.baseboard_fab2(sch_1):page62_i172:DDR5_MA(5)" )
				( attribute "RELATIVE_PROPAGATION_DELAY_SCOPE" "G"
					( Parent
						( matchGroupRef "@crescent_city_bb_fab1_lib.crescent_city_bb_fab1(sch_1):\MG_DDR_NEAR_DIMM-CLK1_CLS_DDR_M_CAC-CLKS\" )
					)
					( Status sCSetFlattened )
					( Origin gBackEnd )
				)
				( attribute "RELATIVE_PROPAGATION_DELAY" "0.00 MIL,700.00 MIL"
					( Parent
						( matchGroupRef "@crescent_city_bb_fab1_lib.crescent_city_bb_fab1(sch_1):\MG_DDR_NEAR_DIMM-CLK1_CLS_DDR_M_CAC-CLKS\" )
					)
					( Units "uMatchProp" "ns" 1.000000)
					( Status sCSetFlattened )
					( Origin gBackEnd )
				)
				( attribute "RELATIVE_PROPAGATION_DELAY_SCOPE" "G"
					( Parent
						( matchGroupRef "@baseboard_fab2_lib.baseboard_fab2(sch_1):\MG_DDR_CMD_NEAR_DIMM_NG_DDR_M_DLL_9\" )
					)
					( Status sCSetFlattened )
					( Origin gBackEnd )
				)
				( attribute "RELATIVE_PROPAGATION_DELAY" "0.00 MIL,25.00 MIL"
					( Parent
						( matchGroupRef "@baseboard_fab2_lib.baseboard_fab2(sch_1):\MG_DDR_CMD_NEAR_DIMM_NG_DDR_M_DLL_9\" )
					)
					( Units "uMatchProp" "ns" 1.000000)
					( Status sCSetFlattened )
					( Origin gBackEnd )
				)
			)
			( pinPair "@baseboard_fab2_lib.baseboard_fab2(sch_1):\PP3301\"
				( pinRef "@baseboard_fab2_lib.baseboard_fab2(sch_1):page62_i172:DDR5_MA(6)" )
				( pinRef "@baseboard_fab2_lib.baseboard_fab2(sch_1):page87_i186:A6" )
				( attribute "RELATIVE_PROPAGATION_DELAY_SCOPE" "G"
					( Parent
						( matchGroupRef "@crescent_city_bb_fab1_lib.crescent_city_bb_fab1(sch_1):\MG_DDR_FAR_DIMM-CLK0_CLS_DDR_M_CAC-CLKS\" )
					)
					( Status sCSetFlattened )
					( Origin gBackEnd )
				)
				( attribute "RELATIVE_PROPAGATION_DELAY" "0.00 MIL,700.00 MIL"
					( Parent
						( matchGroupRef "@crescent_city_bb_fab1_lib.crescent_city_bb_fab1(sch_1):\MG_DDR_FAR_DIMM-CLK0_CLS_DDR_M_CAC-CLKS\" )
					)
					( Units "uMatchProp" "ns" 1.000000)
					( Status sCSetFlattened )
					( Origin gBackEnd )
				)
				( attribute "RELATIVE_PROPAGATION_DELAY_SCOPE" "G"
					( Parent
						( matchGroupRef "@baseboard_fab2_lib.baseboard_fab2(sch_1):\MG_DDR_FAR_DIMM_CMD_NG_DDR_M_DLL_9\" )
					)
					( Status sCSetFlattened )
					( Origin gBackEnd )
				)
				( attribute "RELATIVE_PROPAGATION_DELAY" "0.00 MIL,25.00 MIL"
					( Parent
						( matchGroupRef "@baseboard_fab2_lib.baseboard_fab2(sch_1):\MG_DDR_FAR_DIMM_CMD_NG_DDR_M_DLL_9\" )
					)
					( Units "uMatchProp" "ns" 1.000000)
					( Status sCSetFlattened )
					( Origin gBackEnd )
				)
			)
			( pinPair "@baseboard_fab2_lib.baseboard_fab2(sch_1):\PP3302\"
				( pinRef "@baseboard_fab2_lib.baseboard_fab2(sch_1):page88_i111:A6" )
				( pinRef "@baseboard_fab2_lib.baseboard_fab2(sch_1):page62_i172:DDR5_MA(6)" )
				( attribute "RELATIVE_PROPAGATION_DELAY_SCOPE" "G"
					( Parent
						( matchGroupRef "@crescent_city_bb_fab1_lib.crescent_city_bb_fab1(sch_1):\MG_DDR_NEAR_DIMM-CLK1_CLS_DDR_M_CAC-CLKS\" )
					)
					( Status sCSetFlattened )
					( Origin gBackEnd )
				)
				( attribute "RELATIVE_PROPAGATION_DELAY" "0.00 MIL,700.00 MIL"
					( Parent
						( matchGroupRef "@crescent_city_bb_fab1_lib.crescent_city_bb_fab1(sch_1):\MG_DDR_NEAR_DIMM-CLK1_CLS_DDR_M_CAC-CLKS\" )
					)
					( Units "uMatchProp" "ns" 1.000000)
					( Status sCSetFlattened )
					( Origin gBackEnd )
				)
				( attribute "RELATIVE_PROPAGATION_DELAY_SCOPE" "G"
					( Parent
						( matchGroupRef "@baseboard_fab2_lib.baseboard_fab2(sch_1):\MG_DDR_CMD_NEAR_DIMM_NG_DDR_M_DLL_9\" )
					)
					( Status sCSetFlattened )
					( Origin gBackEnd )
				)
				( attribute "RELATIVE_PROPAGATION_DELAY" "0.00 MIL,25.00 MIL"
					( Parent
						( matchGroupRef "@baseboard_fab2_lib.baseboard_fab2(sch_1):\MG_DDR_CMD_NEAR_DIMM_NG_DDR_M_DLL_9\" )
					)
					( Units "uMatchProp" "ns" 1.000000)
					( Status sCSetFlattened )
					( Origin gBackEnd )
				)
			)
			( pinPair "@baseboard_fab2_lib.baseboard_fab2(sch_1):\PP3295\"
				( pinRef "@baseboard_fab2_lib.baseboard_fab2(sch_1):page62_i172:DDR5_MA(7)" )
				( pinRef "@baseboard_fab2_lib.baseboard_fab2(sch_1):page87_i186:A7" )
				( attribute "RELATIVE_PROPAGATION_DELAY_SCOPE" "G"
					( Parent
						( matchGroupRef "@crescent_city_bb_fab1_lib.crescent_city_bb_fab1(sch_1):\MG_DDR_FAR_DIMM-CLK0_CLS_DDR_M_CAC-CLKS\" )
					)
					( Status sCSetFlattened )
					( Origin gBackEnd )
				)
				( attribute "RELATIVE_PROPAGATION_DELAY" "0.00 MIL,700.00 MIL"
					( Parent
						( matchGroupRef "@crescent_city_bb_fab1_lib.crescent_city_bb_fab1(sch_1):\MG_DDR_FAR_DIMM-CLK0_CLS_DDR_M_CAC-CLKS\" )
					)
					( Units "uMatchProp" "ns" 1.000000)
					( Status sCSetFlattened )
					( Origin gBackEnd )
				)
				( attribute "RELATIVE_PROPAGATION_DELAY_SCOPE" "G"
					( Parent
						( matchGroupRef "@baseboard_fab2_lib.baseboard_fab2(sch_1):\MG_DDR_FAR_DIMM_CMD_NG_DDR_M_DLL_10\" )
					)
					( Status sCSetFlattened )
					( Origin gBackEnd )
				)
				( attribute "RELATIVE_PROPAGATION_DELAY" "0.00 MIL,25.00 MIL"
					( Parent
						( matchGroupRef "@baseboard_fab2_lib.baseboard_fab2(sch_1):\MG_DDR_FAR_DIMM_CMD_NG_DDR_M_DLL_10\" )
					)
					( Units "uMatchProp" "ns" 1.000000)
					( Status sCSetFlattened )
					( Origin gBackEnd )
				)
			)
			( pinPair "@baseboard_fab2_lib.baseboard_fab2(sch_1):\PP3296\"
				( pinRef "@baseboard_fab2_lib.baseboard_fab2(sch_1):page88_i111:A7" )
				( pinRef "@baseboard_fab2_lib.baseboard_fab2(sch_1):page62_i172:DDR5_MA(7)" )
				( attribute "RELATIVE_PROPAGATION_DELAY_SCOPE" "G"
					( Parent
						( matchGroupRef "@crescent_city_bb_fab1_lib.crescent_city_bb_fab1(sch_1):\MG_DDR_NEAR_DIMM-CLK1_CLS_DDR_M_CAC-CLKS\" )
					)
					( Status sCSetFlattened )
					( Origin gBackEnd )
				)
				( attribute "RELATIVE_PROPAGATION_DELAY" "0.00 MIL,700.00 MIL"
					( Parent
						( matchGroupRef "@crescent_city_bb_fab1_lib.crescent_city_bb_fab1(sch_1):\MG_DDR_NEAR_DIMM-CLK1_CLS_DDR_M_CAC-CLKS\" )
					)
					( Units "uMatchProp" "ns" 1.000000)
					( Status sCSetFlattened )
					( Origin gBackEnd )
				)
				( attribute "RELATIVE_PROPAGATION_DELAY_SCOPE" "G"
					( Parent
						( matchGroupRef "@baseboard_fab2_lib.baseboard_fab2(sch_1):\MG_DDR_CMD_NEAR_DIMM_NG_DDR_M_DLL_10\" )
					)
					( Status sCSetFlattened )
					( Origin gBackEnd )
				)
				( attribute "RELATIVE_PROPAGATION_DELAY" "0.00 MIL,25.00 MIL"
					( Parent
						( matchGroupRef "@baseboard_fab2_lib.baseboard_fab2(sch_1):\MG_DDR_CMD_NEAR_DIMM_NG_DDR_M_DLL_10\" )
					)
					( Units "uMatchProp" "ns" 1.000000)
					( Status sCSetFlattened )
					( Origin gBackEnd )
				)
			)
			( pinPair "@baseboard_fab2_lib.baseboard_fab2(sch_1):\PP3297\"
				( pinRef "@baseboard_fab2_lib.baseboard_fab2(sch_1):page62_i172:DDR5_MA(8)" )
				( pinRef "@baseboard_fab2_lib.baseboard_fab2(sch_1):page87_i186:A8" )
				( attribute "RELATIVE_PROPAGATION_DELAY_SCOPE" "G"
					( Parent
						( matchGroupRef "@crescent_city_bb_fab1_lib.crescent_city_bb_fab1(sch_1):\MG_DDR_FAR_DIMM-CLK0_CLS_DDR_M_CAC-CLKS\" )
					)
					( Status sCSetFlattened )
					( Origin gBackEnd )
				)
				( attribute "RELATIVE_PROPAGATION_DELAY" "0.00 MIL,700.00 MIL"
					( Parent
						( matchGroupRef "@crescent_city_bb_fab1_lib.crescent_city_bb_fab1(sch_1):\MG_DDR_FAR_DIMM-CLK0_CLS_DDR_M_CAC-CLKS\" )
					)
					( Units "uMatchProp" "ns" 1.000000)
					( Status sCSetFlattened )
					( Origin gBackEnd )
				)
				( attribute "RELATIVE_PROPAGATION_DELAY_SCOPE" "G"
					( Parent
						( matchGroupRef "@baseboard_fab2_lib.baseboard_fab2(sch_1):\MG_DDR_FAR_DIMM_CMD_NG_DDR_M_DLL_10\" )
					)
					( Status sCSetFlattened )
					( Origin gBackEnd )
				)
				( attribute "RELATIVE_PROPAGATION_DELAY" "0.00 MIL,25.00 MIL"
					( Parent
						( matchGroupRef "@baseboard_fab2_lib.baseboard_fab2(sch_1):\MG_DDR_FAR_DIMM_CMD_NG_DDR_M_DLL_10\" )
					)
					( Units "uMatchProp" "ns" 1.000000)
					( Status sCSetFlattened )
					( Origin gBackEnd )
				)
			)
			( pinPair "@baseboard_fab2_lib.baseboard_fab2(sch_1):\PP3298\"
				( pinRef "@baseboard_fab2_lib.baseboard_fab2(sch_1):page88_i111:A8" )
				( pinRef "@baseboard_fab2_lib.baseboard_fab2(sch_1):page62_i172:DDR5_MA(8)" )
				( attribute "RELATIVE_PROPAGATION_DELAY_SCOPE" "G"
					( Parent
						( matchGroupRef "@crescent_city_bb_fab1_lib.crescent_city_bb_fab1(sch_1):\MG_DDR_NEAR_DIMM-CLK1_CLS_DDR_M_CAC-CLKS\" )
					)
					( Status sCSetFlattened )
					( Origin gBackEnd )
				)
				( attribute "RELATIVE_PROPAGATION_DELAY" "0.00 MIL,700.00 MIL"
					( Parent
						( matchGroupRef "@crescent_city_bb_fab1_lib.crescent_city_bb_fab1(sch_1):\MG_DDR_NEAR_DIMM-CLK1_CLS_DDR_M_CAC-CLKS\" )
					)
					( Units "uMatchProp" "ns" 1.000000)
					( Status sCSetFlattened )
					( Origin gBackEnd )
				)
				( attribute "RELATIVE_PROPAGATION_DELAY_SCOPE" "G"
					( Parent
						( matchGroupRef "@baseboard_fab2_lib.baseboard_fab2(sch_1):\MG_DDR_CMD_NEAR_DIMM_NG_DDR_M_DLL_10\" )
					)
					( Status sCSetFlattened )
					( Origin gBackEnd )
				)
				( attribute "RELATIVE_PROPAGATION_DELAY" "0.00 MIL,25.00 MIL"
					( Parent
						( matchGroupRef "@baseboard_fab2_lib.baseboard_fab2(sch_1):\MG_DDR_CMD_NEAR_DIMM_NG_DDR_M_DLL_10\" )
					)
					( Units "uMatchProp" "ns" 1.000000)
					( Status sCSetFlattened )
					( Origin gBackEnd )
				)
			)
			( pinPair "@baseboard_fab2_lib.baseboard_fab2(sch_1):\PP3291\"
				( pinRef "@baseboard_fab2_lib.baseboard_fab2(sch_1):page62_i172:DDR5_MA(9)" )
				( pinRef "@baseboard_fab2_lib.baseboard_fab2(sch_1):page87_i186:A9" )
				( attribute "RELATIVE_PROPAGATION_DELAY_SCOPE" "G"
					( Parent
						( matchGroupRef "@crescent_city_bb_fab1_lib.crescent_city_bb_fab1(sch_1):\MG_DDR_FAR_DIMM-CLK0_CLS_DDR_M_CAC-CLKS\" )
					)
					( Status sCSetFlattened )
					( Origin gBackEnd )
				)
				( attribute "RELATIVE_PROPAGATION_DELAY" "0.00 MIL,700.00 MIL"
					( Parent
						( matchGroupRef "@crescent_city_bb_fab1_lib.crescent_city_bb_fab1(sch_1):\MG_DDR_FAR_DIMM-CLK0_CLS_DDR_M_CAC-CLKS\" )
					)
					( Units "uMatchProp" "ns" 1.000000)
					( Status sCSetFlattened )
					( Origin gBackEnd )
				)
				( attribute "RELATIVE_PROPAGATION_DELAY_SCOPE" "G"
					( Parent
						( matchGroupRef "@baseboard_fab2_lib.baseboard_fab2(sch_1):\MG_DDR_FAR_DIMM_CMD_NG_DDR_M_DLL_11\" )
					)
					( Status sCSetFlattened )
					( Origin gBackEnd )
				)
				( attribute "RELATIVE_PROPAGATION_DELAY" "0.00 MIL,25.00 MIL"
					( Parent
						( matchGroupRef "@baseboard_fab2_lib.baseboard_fab2(sch_1):\MG_DDR_FAR_DIMM_CMD_NG_DDR_M_DLL_11\" )
					)
					( Units "uMatchProp" "ns" 1.000000)
					( Status sCSetFlattened )
					( Origin gBackEnd )
				)
			)
			( pinPair "@baseboard_fab2_lib.baseboard_fab2(sch_1):\PP3292\"
				( pinRef "@baseboard_fab2_lib.baseboard_fab2(sch_1):page88_i111:A9" )
				( pinRef "@baseboard_fab2_lib.baseboard_fab2(sch_1):page62_i172:DDR5_MA(9)" )
				( attribute "RELATIVE_PROPAGATION_DELAY_SCOPE" "G"
					( Parent
						( matchGroupRef "@crescent_city_bb_fab1_lib.crescent_city_bb_fab1(sch_1):\MG_DDR_NEAR_DIMM-CLK1_CLS_DDR_M_CAC-CLKS\" )
					)
					( Status sCSetFlattened )
					( Origin gBackEnd )
				)
				( attribute "RELATIVE_PROPAGATION_DELAY" "0.00 MIL,700.00 MIL"
					( Parent
						( matchGroupRef "@crescent_city_bb_fab1_lib.crescent_city_bb_fab1(sch_1):\MG_DDR_NEAR_DIMM-CLK1_CLS_DDR_M_CAC-CLKS\" )
					)
					( Units "uMatchProp" "ns" 1.000000)
					( Status sCSetFlattened )
					( Origin gBackEnd )
				)
				( attribute "RELATIVE_PROPAGATION_DELAY_SCOPE" "G"
					( Parent
						( matchGroupRef "@baseboard_fab2_lib.baseboard_fab2(sch_1):\MG_DDR_CMD_NEAR_DIMM_NG_DDR_M_DLL_11\" )
					)
					( Status sCSetFlattened )
					( Origin gBackEnd )
				)
				( attribute "RELATIVE_PROPAGATION_DELAY" "0.00 MIL,25.00 MIL"
					( Parent
						( matchGroupRef "@baseboard_fab2_lib.baseboard_fab2(sch_1):\MG_DDR_CMD_NEAR_DIMM_NG_DDR_M_DLL_11\" )
					)
					( Units "uMatchProp" "ns" 1.000000)
					( Status sCSetFlattened )
					( Origin gBackEnd )
				)
			)
			( pinPair "@baseboard_fab2_lib.baseboard_fab2(sch_1):\PP3293\"
				( pinRef "@baseboard_fab2_lib.baseboard_fab2(sch_1):page62_i172:DDR5_MA(12)" )
				( pinRef "@baseboard_fab2_lib.baseboard_fab2(sch_1):page87_i186:A12" )
				( attribute "RELATIVE_PROPAGATION_DELAY_SCOPE" "G"
					( Parent
						( matchGroupRef "@crescent_city_bb_fab1_lib.crescent_city_bb_fab1(sch_1):\MG_DDR_FAR_DIMM-CLK0_CLS_DDR_M_CAC-CLKS\" )
					)
					( Status sCSetFlattened )
					( Origin gBackEnd )
				)
				( attribute "RELATIVE_PROPAGATION_DELAY" "0.00 MIL,700.00 MIL"
					( Parent
						( matchGroupRef "@crescent_city_bb_fab1_lib.crescent_city_bb_fab1(sch_1):\MG_DDR_FAR_DIMM-CLK0_CLS_DDR_M_CAC-CLKS\" )
					)
					( Units "uMatchProp" "ns" 1.000000)
					( Status sCSetFlattened )
					( Origin gBackEnd )
				)
				( attribute "RELATIVE_PROPAGATION_DELAY_SCOPE" "G"
					( Parent
						( matchGroupRef "@baseboard_fab2_lib.baseboard_fab2(sch_1):\MG_DDR_FAR_DIMM_CMD_NG_DDR_M_DLL_11\" )
					)
					( Status sCSetFlattened )
					( Origin gBackEnd )
				)
				( attribute "RELATIVE_PROPAGATION_DELAY" "0.00 MIL,25.00 MIL"
					( Parent
						( matchGroupRef "@baseboard_fab2_lib.baseboard_fab2(sch_1):\MG_DDR_FAR_DIMM_CMD_NG_DDR_M_DLL_11\" )
					)
					( Units "uMatchProp" "ns" 1.000000)
					( Status sCSetFlattened )
					( Origin gBackEnd )
				)
			)
			( pinPair "@baseboard_fab2_lib.baseboard_fab2(sch_1):\PP3294\"
				( pinRef "@baseboard_fab2_lib.baseboard_fab2(sch_1):page88_i111:A12" )
				( pinRef "@baseboard_fab2_lib.baseboard_fab2(sch_1):page62_i172:DDR5_MA(12)" )
				( attribute "RELATIVE_PROPAGATION_DELAY_SCOPE" "G"
					( Parent
						( matchGroupRef "@crescent_city_bb_fab1_lib.crescent_city_bb_fab1(sch_1):\MG_DDR_NEAR_DIMM-CLK1_CLS_DDR_M_CAC-CLKS\" )
					)
					( Status sCSetFlattened )
					( Origin gBackEnd )
				)
				( attribute "RELATIVE_PROPAGATION_DELAY" "0.00 MIL,700.00 MIL"
					( Parent
						( matchGroupRef "@crescent_city_bb_fab1_lib.crescent_city_bb_fab1(sch_1):\MG_DDR_NEAR_DIMM-CLK1_CLS_DDR_M_CAC-CLKS\" )
					)
					( Units "uMatchProp" "ns" 1.000000)
					( Status sCSetFlattened )
					( Origin gBackEnd )
				)
				( attribute "RELATIVE_PROPAGATION_DELAY_SCOPE" "G"
					( Parent
						( matchGroupRef "@baseboard_fab2_lib.baseboard_fab2(sch_1):\MG_DDR_CMD_NEAR_DIMM_NG_DDR_M_DLL_11\" )
					)
					( Status sCSetFlattened )
					( Origin gBackEnd )
				)
				( attribute "RELATIVE_PROPAGATION_DELAY" "0.00 MIL,25.00 MIL"
					( Parent
						( matchGroupRef "@baseboard_fab2_lib.baseboard_fab2(sch_1):\MG_DDR_CMD_NEAR_DIMM_NG_DDR_M_DLL_11\" )
					)
					( Units "uMatchProp" "ns" 1.000000)
					( Status sCSetFlattened )
					( Origin gBackEnd )
				)
			)
			( pinPair "@baseboard_fab2_lib.baseboard_fab2(sch_1):\PP3287\"
				( pinRef "@baseboard_fab2_lib.baseboard_fab2(sch_1):page62_i172:DDR5_BG(1)" )
				( pinRef "@baseboard_fab2_lib.baseboard_fab2(sch_1):page87_i186:BG(1)" )
				( attribute "RELATIVE_PROPAGATION_DELAY_SCOPE" "G"
					( Parent
						( matchGroupRef "@crescent_city_bb_fab1_lib.crescent_city_bb_fab1(sch_1):\MG_DDR_FAR_DIMM-CLK0_CLS_DDR_M_CAC-CLKS\" )
					)
					( Status sCSetFlattened )
					( Origin gBackEnd )
				)
				( attribute "RELATIVE_PROPAGATION_DELAY" "0.00 MIL,700.00 MIL"
					( Parent
						( matchGroupRef "@crescent_city_bb_fab1_lib.crescent_city_bb_fab1(sch_1):\MG_DDR_FAR_DIMM-CLK0_CLS_DDR_M_CAC-CLKS\" )
					)
					( Units "uMatchProp" "ns" 1.000000)
					( Status sCSetFlattened )
					( Origin gBackEnd )
				)
				( attribute "RELATIVE_PROPAGATION_DELAY_SCOPE" "G"
					( Parent
						( matchGroupRef "@baseboard_fab2_lib.baseboard_fab2(sch_1):\MG_DDR_FAR_DIMM_CMD_NG_DDR_M_DLL_12\" )
					)
					( Status sCSetFlattened )
					( Origin gBackEnd )
				)
				( attribute "RELATIVE_PROPAGATION_DELAY" "0.00 MIL,25.00 MIL"
					( Parent
						( matchGroupRef "@baseboard_fab2_lib.baseboard_fab2(sch_1):\MG_DDR_FAR_DIMM_CMD_NG_DDR_M_DLL_12\" )
					)
					( Units "uMatchProp" "ns" 1.000000)
					( Status sCSetFlattened )
					( Origin gBackEnd )
				)
			)
			( pinPair "@baseboard_fab2_lib.baseboard_fab2(sch_1):\PP3288\"
				( pinRef "@baseboard_fab2_lib.baseboard_fab2(sch_1):page88_i111:BG(1)" )
				( pinRef "@baseboard_fab2_lib.baseboard_fab2(sch_1):page62_i172:DDR5_BG(1)" )
				( attribute "RELATIVE_PROPAGATION_DELAY_SCOPE" "G"
					( Parent
						( matchGroupRef "@crescent_city_bb_fab1_lib.crescent_city_bb_fab1(sch_1):\MG_DDR_NEAR_DIMM-CLK1_CLS_DDR_M_CAC-CLKS\" )
					)
					( Status sCSetFlattened )
					( Origin gBackEnd )
				)
				( attribute "RELATIVE_PROPAGATION_DELAY" "0.00 MIL,700.00 MIL"
					( Parent
						( matchGroupRef "@crescent_city_bb_fab1_lib.crescent_city_bb_fab1(sch_1):\MG_DDR_NEAR_DIMM-CLK1_CLS_DDR_M_CAC-CLKS\" )
					)
					( Units "uMatchProp" "ns" 1.000000)
					( Status sCSetFlattened )
					( Origin gBackEnd )
				)
				( attribute "RELATIVE_PROPAGATION_DELAY_SCOPE" "G"
					( Parent
						( matchGroupRef "@baseboard_fab2_lib.baseboard_fab2(sch_1):\MG_DDR_CMD_NEAR_DIMM_NG_DDR_M_DLL_12\" )
					)
					( Status sCSetFlattened )
					( Origin gBackEnd )
				)
				( attribute "RELATIVE_PROPAGATION_DELAY" "0.00 MIL,25.00 MIL"
					( Parent
						( matchGroupRef "@baseboard_fab2_lib.baseboard_fab2(sch_1):\MG_DDR_CMD_NEAR_DIMM_NG_DDR_M_DLL_12\" )
					)
					( Units "uMatchProp" "ns" 1.000000)
					( Status sCSetFlattened )
					( Origin gBackEnd )
				)
			)
			( pinPair "@baseboard_fab2_lib.baseboard_fab2(sch_1):\PP3289\"
				( pinRef "@baseboard_fab2_lib.baseboard_fab2(sch_1):page62_i172:DDR5_MA(11)" )
				( pinRef "@baseboard_fab2_lib.baseboard_fab2(sch_1):page87_i186:A11" )
				( attribute "RELATIVE_PROPAGATION_DELAY_SCOPE" "G"
					( Parent
						( matchGroupRef "@crescent_city_bb_fab1_lib.crescent_city_bb_fab1(sch_1):\MG_DDR_FAR_DIMM-CLK0_CLS_DDR_M_CAC-CLKS\" )
					)
					( Status sCSetFlattened )
					( Origin gBackEnd )
				)
				( attribute "RELATIVE_PROPAGATION_DELAY" "0.00 MIL,700.00 MIL"
					( Parent
						( matchGroupRef "@crescent_city_bb_fab1_lib.crescent_city_bb_fab1(sch_1):\MG_DDR_FAR_DIMM-CLK0_CLS_DDR_M_CAC-CLKS\" )
					)
					( Units "uMatchProp" "ns" 1.000000)
					( Status sCSetFlattened )
					( Origin gBackEnd )
				)
				( attribute "RELATIVE_PROPAGATION_DELAY_SCOPE" "G"
					( Parent
						( matchGroupRef "@baseboard_fab2_lib.baseboard_fab2(sch_1):\MG_DDR_FAR_DIMM_CMD_NG_DDR_M_DLL_12\" )
					)
					( Status sCSetFlattened )
					( Origin gBackEnd )
				)
				( attribute "RELATIVE_PROPAGATION_DELAY" "0.00 MIL,25.00 MIL"
					( Parent
						( matchGroupRef "@baseboard_fab2_lib.baseboard_fab2(sch_1):\MG_DDR_FAR_DIMM_CMD_NG_DDR_M_DLL_12\" )
					)
					( Units "uMatchProp" "ns" 1.000000)
					( Status sCSetFlattened )
					( Origin gBackEnd )
				)
			)
			( pinPair "@baseboard_fab2_lib.baseboard_fab2(sch_1):\PP3290\"
				( pinRef "@baseboard_fab2_lib.baseboard_fab2(sch_1):page88_i111:A11" )
				( pinRef "@baseboard_fab2_lib.baseboard_fab2(sch_1):page62_i172:DDR5_MA(11)" )
				( attribute "RELATIVE_PROPAGATION_DELAY_SCOPE" "G"
					( Parent
						( matchGroupRef "@crescent_city_bb_fab1_lib.crescent_city_bb_fab1(sch_1):\MG_DDR_NEAR_DIMM-CLK1_CLS_DDR_M_CAC-CLKS\" )
					)
					( Status sCSetFlattened )
					( Origin gBackEnd )
				)
				( attribute "RELATIVE_PROPAGATION_DELAY" "0.00 MIL,700.00 MIL"
					( Parent
						( matchGroupRef "@crescent_city_bb_fab1_lib.crescent_city_bb_fab1(sch_1):\MG_DDR_NEAR_DIMM-CLK1_CLS_DDR_M_CAC-CLKS\" )
					)
					( Units "uMatchProp" "ns" 1.000000)
					( Status sCSetFlattened )
					( Origin gBackEnd )
				)
				( attribute "RELATIVE_PROPAGATION_DELAY_SCOPE" "G"
					( Parent
						( matchGroupRef "@baseboard_fab2_lib.baseboard_fab2(sch_1):\MG_DDR_CMD_NEAR_DIMM_NG_DDR_M_DLL_12\" )
					)
					( Status sCSetFlattened )
					( Origin gBackEnd )
				)
				( attribute "RELATIVE_PROPAGATION_DELAY" "0.00 MIL,25.00 MIL"
					( Parent
						( matchGroupRef "@baseboard_fab2_lib.baseboard_fab2(sch_1):\MG_DDR_CMD_NEAR_DIMM_NG_DDR_M_DLL_12\" )
					)
					( Units "uMatchProp" "ns" 1.000000)
					( Status sCSetFlattened )
					( Origin gBackEnd )
				)
			)
			( pinPair "@baseboard_fab2_lib.baseboard_fab2(sch_1):\PP3283\"
				( pinRef "@baseboard_fab2_lib.baseboard_fab2(sch_1):page62_i172:DDR5_ACT_N" )
				( pinRef "@baseboard_fab2_lib.baseboard_fab2(sch_1):page87_i186:ACT_N" )
				( attribute "RELATIVE_PROPAGATION_DELAY_SCOPE" "G"
					( Parent
						( matchGroupRef "@crescent_city_bb_fab1_lib.crescent_city_bb_fab1(sch_1):\MG_DDR_FAR_DIMM-CLK0_CLS_DDR_M_CAC-CLKS\" )
					)
					( Status sCSetFlattened )
					( Origin gBackEnd )
				)
				( attribute "RELATIVE_PROPAGATION_DELAY" "0.00 MIL,700.00 MIL"
					( Parent
						( matchGroupRef "@crescent_city_bb_fab1_lib.crescent_city_bb_fab1(sch_1):\MG_DDR_FAR_DIMM-CLK0_CLS_DDR_M_CAC-CLKS\" )
					)
					( Units "uMatchProp" "ns" 1.000000)
					( Status sCSetFlattened )
					( Origin gBackEnd )
				)
				( attribute "RELATIVE_PROPAGATION_DELAY_SCOPE" "G"
					( Parent
						( matchGroupRef "@baseboard_fab2_lib.baseboard_fab2(sch_1):\MG_DDR_FAR_DIMM_CMD_NG_DDR_M_DLL_13\" )
					)
					( Status sCSetFlattened )
					( Origin gBackEnd )
				)
				( attribute "RELATIVE_PROPAGATION_DELAY" "0.00 MIL,25.00 MIL"
					( Parent
						( matchGroupRef "@baseboard_fab2_lib.baseboard_fab2(sch_1):\MG_DDR_FAR_DIMM_CMD_NG_DDR_M_DLL_13\" )
					)
					( Units "uMatchProp" "ns" 1.000000)
					( Status sCSetFlattened )
					( Origin gBackEnd )
				)
			)
			( pinPair "@baseboard_fab2_lib.baseboard_fab2(sch_1):\PP3284\"
				( pinRef "@baseboard_fab2_lib.baseboard_fab2(sch_1):page88_i111:ACT_N" )
				( pinRef "@baseboard_fab2_lib.baseboard_fab2(sch_1):page62_i172:DDR5_ACT_N" )
				( attribute "RELATIVE_PROPAGATION_DELAY_SCOPE" "G"
					( Parent
						( matchGroupRef "@crescent_city_bb_fab1_lib.crescent_city_bb_fab1(sch_1):\MG_DDR_NEAR_DIMM-CLK1_CLS_DDR_M_CAC-CLKS\" )
					)
					( Status sCSetFlattened )
					( Origin gBackEnd )
				)
				( attribute "RELATIVE_PROPAGATION_DELAY" "0.00 MIL,700.00 MIL"
					( Parent
						( matchGroupRef "@crescent_city_bb_fab1_lib.crescent_city_bb_fab1(sch_1):\MG_DDR_NEAR_DIMM-CLK1_CLS_DDR_M_CAC-CLKS\" )
					)
					( Units "uMatchProp" "ns" 1.000000)
					( Status sCSetFlattened )
					( Origin gBackEnd )
				)
				( attribute "RELATIVE_PROPAGATION_DELAY_SCOPE" "G"
					( Parent
						( matchGroupRef "@baseboard_fab2_lib.baseboard_fab2(sch_1):\MG_DDR_CMD_NEAR_DIMM_NG_DDR_M_DLL_13\" )
					)
					( Status sCSetFlattened )
					( Origin gBackEnd )
				)
				( attribute "RELATIVE_PROPAGATION_DELAY" "0.00 MIL,25.00 MIL"
					( Parent
						( matchGroupRef "@baseboard_fab2_lib.baseboard_fab2(sch_1):\MG_DDR_CMD_NEAR_DIMM_NG_DDR_M_DLL_13\" )
					)
					( Units "uMatchProp" "ns" 1.000000)
					( Status sCSetFlattened )
					( Origin gBackEnd )
				)
			)
			( pinPair "@baseboard_fab2_lib.baseboard_fab2(sch_1):\PP3285\"
				( pinRef "@baseboard_fab2_lib.baseboard_fab2(sch_1):page62_i172:DDR5_BG(0)" )
				( pinRef "@baseboard_fab2_lib.baseboard_fab2(sch_1):page87_i186:BG(0)" )
				( attribute "RELATIVE_PROPAGATION_DELAY_SCOPE" "G"
					( Parent
						( matchGroupRef "@crescent_city_bb_fab1_lib.crescent_city_bb_fab1(sch_1):\MG_DDR_FAR_DIMM-CLK0_CLS_DDR_M_CAC-CLKS\" )
					)
					( Status sCSetFlattened )
					( Origin gBackEnd )
				)
				( attribute "RELATIVE_PROPAGATION_DELAY" "0.00 MIL,700.00 MIL"
					( Parent
						( matchGroupRef "@crescent_city_bb_fab1_lib.crescent_city_bb_fab1(sch_1):\MG_DDR_FAR_DIMM-CLK0_CLS_DDR_M_CAC-CLKS\" )
					)
					( Units "uMatchProp" "ns" 1.000000)
					( Status sCSetFlattened )
					( Origin gBackEnd )
				)
				( attribute "RELATIVE_PROPAGATION_DELAY_SCOPE" "G"
					( Parent
						( matchGroupRef "@baseboard_fab2_lib.baseboard_fab2(sch_1):\MG_DDR_FAR_DIMM_CMD_NG_DDR_M_DLL_13\" )
					)
					( Status sCSetFlattened )
					( Origin gBackEnd )
				)
				( attribute "RELATIVE_PROPAGATION_DELAY" "0.00 MIL,25.00 MIL"
					( Parent
						( matchGroupRef "@baseboard_fab2_lib.baseboard_fab2(sch_1):\MG_DDR_FAR_DIMM_CMD_NG_DDR_M_DLL_13\" )
					)
					( Units "uMatchProp" "ns" 1.000000)
					( Status sCSetFlattened )
					( Origin gBackEnd )
				)
			)
			( pinPair "@baseboard_fab2_lib.baseboard_fab2(sch_1):\PP3286\"
				( pinRef "@baseboard_fab2_lib.baseboard_fab2(sch_1):page88_i111:BG(0)" )
				( pinRef "@baseboard_fab2_lib.baseboard_fab2(sch_1):page62_i172:DDR5_BG(0)" )
				( attribute "RELATIVE_PROPAGATION_DELAY_SCOPE" "G"
					( Parent
						( matchGroupRef "@crescent_city_bb_fab1_lib.crescent_city_bb_fab1(sch_1):\MG_DDR_NEAR_DIMM-CLK1_CLS_DDR_M_CAC-CLKS\" )
					)
					( Status sCSetFlattened )
					( Origin gBackEnd )
				)
				( attribute "RELATIVE_PROPAGATION_DELAY" "0.00 MIL,700.00 MIL"
					( Parent
						( matchGroupRef "@crescent_city_bb_fab1_lib.crescent_city_bb_fab1(sch_1):\MG_DDR_NEAR_DIMM-CLK1_CLS_DDR_M_CAC-CLKS\" )
					)
					( Units "uMatchProp" "ns" 1.000000)
					( Status sCSetFlattened )
					( Origin gBackEnd )
				)
				( attribute "RELATIVE_PROPAGATION_DELAY_SCOPE" "G"
					( Parent
						( matchGroupRef "@baseboard_fab2_lib.baseboard_fab2(sch_1):\MG_DDR_CMD_NEAR_DIMM_NG_DDR_M_DLL_13\" )
					)
					( Status sCSetFlattened )
					( Origin gBackEnd )
				)
				( attribute "RELATIVE_PROPAGATION_DELAY" "0.00 MIL,25.00 MIL"
					( Parent
						( matchGroupRef "@baseboard_fab2_lib.baseboard_fab2(sch_1):\MG_DDR_CMD_NEAR_DIMM_NG_DDR_M_DLL_13\" )
					)
					( Units "uMatchProp" "ns" 1.000000)
					( Status sCSetFlattened )
					( Origin gBackEnd )
				)
			)
			( pinPair "@baseboard_fab2_lib.baseboard_fab2(sch_1):\PP3281\"
				( pinRef "@baseboard_fab2_lib.baseboard_fab2(sch_1):page87_i186:S0_N" )
				( pinRef "@baseboard_fab2_lib.baseboard_fab2(sch_1):page62_i172:DDR5_CS_N(0)" )
				( attribute "RELATIVE_PROPAGATION_DELAY_SCOPE" "G"
					( Parent
						( matchGroupRef "@crescent_city_bb_fab1_lib.crescent_city_bb_fab1(sch_1):\MG_DDR_FAR_DIMM-CLK0_CLS_DDR_M_CAC-CLKS\" )
					)
					( Status sCSetFlattened )
					( Origin gBackEnd )
				)
				( attribute "RELATIVE_PROPAGATION_DELAY" "0.00 MIL,300.00 MIL"
					( Parent
						( matchGroupRef "@crescent_city_bb_fab1_lib.crescent_city_bb_fab1(sch_1):\MG_DDR_FAR_DIMM-CLK0_CLS_DDR_M_CAC-CLKS\" )
					)
					( Units "uMatchProp" "ns" 1.000000)
					( Status sCSetFlattened )
					( Origin gBackEnd )
				)
				( attribute "RELATIVE_PROPAGATION_DELAY_SCOPE" "G"
					( Parent
						( matchGroupRef "@baseboard_fab2_lib.baseboard_fab2(sch_1):\MG_DDR_CTRL_NG_DDR_M_DLL_14\" )
					)
					( Status sCSetFlattened )
					( Origin gBackEnd )
				)
				( attribute "RELATIVE_PROPAGATION_DELAY" "0.00 MIL,25.00 MIL"
					( Parent
						( matchGroupRef "@baseboard_fab2_lib.baseboard_fab2(sch_1):\MG_DDR_CTRL_NG_DDR_M_DLL_14\" )
					)
					( Units "uMatchProp" "ns" 1.000000)
					( Status sCSetFlattened )
					( Origin gBackEnd )
				)
			)
			( pinPair "@baseboard_fab2_lib.baseboard_fab2(sch_1):\PP3282\"
				( pinRef "@baseboard_fab2_lib.baseboard_fab2(sch_1):page87_i186:ODT(0)" )
				( pinRef "@baseboard_fab2_lib.baseboard_fab2(sch_1):page62_i172:DDR5_ODT(0)" )
				( attribute "RELATIVE_PROPAGATION_DELAY_SCOPE" "G"
					( Parent
						( matchGroupRef "@crescent_city_bb_fab1_lib.crescent_city_bb_fab1(sch_1):\MG_DDR_FAR_DIMM-CLK0_CLS_DDR_M_CAC-CLKS\" )
					)
					( Status sCSetFlattened )
					( Origin gBackEnd )
				)
				( attribute "RELATIVE_PROPAGATION_DELAY" "0.00 MIL,300.00 MIL"
					( Parent
						( matchGroupRef "@crescent_city_bb_fab1_lib.crescent_city_bb_fab1(sch_1):\MG_DDR_FAR_DIMM-CLK0_CLS_DDR_M_CAC-CLKS\" )
					)
					( Units "uMatchProp" "ns" 1.000000)
					( Status sCSetFlattened )
					( Origin gBackEnd )
				)
				( attribute "RELATIVE_PROPAGATION_DELAY_SCOPE" "G"
					( Parent
						( matchGroupRef "@baseboard_fab2_lib.baseboard_fab2(sch_1):\MG_DDR_CTRL_NG_DDR_M_DLL_14\" )
					)
					( Status sCSetFlattened )
					( Origin gBackEnd )
				)
				( attribute "RELATIVE_PROPAGATION_DELAY" "0.00 MIL,25.00 MIL"
					( Parent
						( matchGroupRef "@baseboard_fab2_lib.baseboard_fab2(sch_1):\MG_DDR_CTRL_NG_DDR_M_DLL_14\" )
					)
					( Units "uMatchProp" "ns" 1.000000)
					( Status sCSetFlattened )
					( Origin gBackEnd )
				)
			)
			( pinPair "@baseboard_fab2_lib.baseboard_fab2(sch_1):\PP3280\"
				( pinRef "@baseboard_fab2_lib.baseboard_fab2(sch_1):page87_i186:CKE(0)" )
				( pinRef "@baseboard_fab2_lib.baseboard_fab2(sch_1):page62_i172:DDR5_CKE(0)" )
				( attribute "RELATIVE_PROPAGATION_DELAY_SCOPE" "G"
					( Parent
						( matchGroupRef "@crescent_city_bb_fab1_lib.crescent_city_bb_fab1(sch_1):\MG_DDR_FAR_DIMM-CLK0_CLS_DDR_M_CAC-CLKS\" )
					)
					( Status sCSetFlattened )
					( Origin gBackEnd )
				)
				( attribute "RELATIVE_PROPAGATION_DELAY" "0.00 MIL,300.00 MIL"
					( Parent
						( matchGroupRef "@crescent_city_bb_fab1_lib.crescent_city_bb_fab1(sch_1):\MG_DDR_FAR_DIMM-CLK0_CLS_DDR_M_CAC-CLKS\" )
					)
					( Units "uMatchProp" "ns" 1.000000)
					( Status sCSetFlattened )
					( Origin gBackEnd )
				)
				( attribute "RELATIVE_PROPAGATION_DELAY_SCOPE" "G"
					( Parent
						( matchGroupRef "@baseboard_fab2_lib.baseboard_fab2(sch_1):\MG_DDR_CTRL_NG_DDR_M_DLL_15\" )
					)
					( Status sCSetFlattened )
					( Origin gBackEnd )
				)
				( attribute "RELATIVE_PROPAGATION_DELAY" "0.00 MIL,25.00 MIL"
					( Parent
						( matchGroupRef "@baseboard_fab2_lib.baseboard_fab2(sch_1):\MG_DDR_CTRL_NG_DDR_M_DLL_15\" )
					)
					( Units "uMatchProp" "ns" 1.000000)
					( Status sCSetFlattened )
					( Origin gBackEnd )
				)
			)
			( pinPair "@baseboard_fab2_lib.baseboard_fab2(sch_1):\PP3279\"
				( pinRef "@baseboard_fab2_lib.baseboard_fab2(sch_1):page87_i186:S2_N_C(0)" )
				( pinRef "@baseboard_fab2_lib.baseboard_fab2(sch_1):page62_i172:DDR5_CS_N(2)" )
				( attribute "RELATIVE_PROPAGATION_DELAY_SCOPE" "G"
					( Parent
						( matchGroupRef "@crescent_city_bb_fab1_lib.crescent_city_bb_fab1(sch_1):\MG_DDR_FAR_DIMM-CLK0_CLS_DDR_M_CAC-CLKS\" )
					)
					( Status sCSetFlattened )
					( Origin gBackEnd )
				)
				( attribute "RELATIVE_PROPAGATION_DELAY" "0.00 MIL,300.00 MIL"
					( Parent
						( matchGroupRef "@crescent_city_bb_fab1_lib.crescent_city_bb_fab1(sch_1):\MG_DDR_FAR_DIMM-CLK0_CLS_DDR_M_CAC-CLKS\" )
					)
					( Units "uMatchProp" "ns" 1.000000)
					( Status sCSetFlattened )
					( Origin gBackEnd )
				)
				( attribute "RELATIVE_PROPAGATION_DELAY_SCOPE" "G"
					( Parent
						( matchGroupRef "@baseboard_fab2_lib.baseboard_fab2(sch_1):\MG_DDR_CTRL_NG_DDR_M_DLL_16\" )
					)
					( Status sCSetFlattened )
					( Origin gBackEnd )
				)
				( attribute "RELATIVE_PROPAGATION_DELAY" "0.00 MIL,25.00 MIL"
					( Parent
						( matchGroupRef "@baseboard_fab2_lib.baseboard_fab2(sch_1):\MG_DDR_CTRL_NG_DDR_M_DLL_16\" )
					)
					( Units "uMatchProp" "ns" 1.000000)
					( Status sCSetFlattened )
					( Origin gBackEnd )
				)
			)
			( pinPair "@baseboard_fab2_lib.baseboard_fab2(sch_1):\PP3278\"
				( pinRef "@baseboard_fab2_lib.baseboard_fab2(sch_1):page87_i186:S3_N_C(1)" )
				( pinRef "@baseboard_fab2_lib.baseboard_fab2(sch_1):page62_i172:DDR5_CS_N(3)" )
				( attribute "RELATIVE_PROPAGATION_DELAY_SCOPE" "G"
					( Parent
						( matchGroupRef "@crescent_city_bb_fab1_lib.crescent_city_bb_fab1(sch_1):\MG_DDR_FAR_DIMM-CLK0_CLS_DDR_M_CAC-CLKS\" )
					)
					( Status sCSetFlattened )
					( Origin gBackEnd )
				)
				( attribute "RELATIVE_PROPAGATION_DELAY" "0.00 MIL,300.00 MIL"
					( Parent
						( matchGroupRef "@crescent_city_bb_fab1_lib.crescent_city_bb_fab1(sch_1):\MG_DDR_FAR_DIMM-CLK0_CLS_DDR_M_CAC-CLKS\" )
					)
					( Units "uMatchProp" "ns" 1.000000)
					( Status sCSetFlattened )
					( Origin gBackEnd )
				)
				( attribute "RELATIVE_PROPAGATION_DELAY_SCOPE" "G"
					( Parent
						( matchGroupRef "@baseboard_fab2_lib.baseboard_fab2(sch_1):\MG_DDR_CTRL_NG_DDR_M_DLL_17\" )
					)
					( Status sCSetFlattened )
					( Origin gBackEnd )
				)
				( attribute "RELATIVE_PROPAGATION_DELAY" "0.00 MIL,25.00 MIL"
					( Parent
						( matchGroupRef "@baseboard_fab2_lib.baseboard_fab2(sch_1):\MG_DDR_CTRL_NG_DDR_M_DLL_17\" )
					)
					( Units "uMatchProp" "ns" 1.000000)
					( Status sCSetFlattened )
					( Origin gBackEnd )
				)
			)
			( pinPair "@baseboard_fab2_lib.baseboard_fab2(sch_1):\PP3276\"
				( pinRef "@baseboard_fab2_lib.baseboard_fab2(sch_1):page87_i186:S1_N" )
				( pinRef "@baseboard_fab2_lib.baseboard_fab2(sch_1):page62_i172:DDR5_CS_N(1)" )
				( attribute "RELATIVE_PROPAGATION_DELAY_SCOPE" "G"
					( Parent
						( matchGroupRef "@crescent_city_bb_fab1_lib.crescent_city_bb_fab1(sch_1):\MG_DDR_FAR_DIMM-CLK0_CLS_DDR_M_CAC-CLKS\" )
					)
					( Status sCSetFlattened )
					( Origin gBackEnd )
				)
				( attribute "RELATIVE_PROPAGATION_DELAY" "0.00 MIL,300.00 MIL"
					( Parent
						( matchGroupRef "@crescent_city_bb_fab1_lib.crescent_city_bb_fab1(sch_1):\MG_DDR_FAR_DIMM-CLK0_CLS_DDR_M_CAC-CLKS\" )
					)
					( Units "uMatchProp" "ns" 1.000000)
					( Status sCSetFlattened )
					( Origin gBackEnd )
				)
				( attribute "RELATIVE_PROPAGATION_DELAY_SCOPE" "G"
					( Parent
						( matchGroupRef "@baseboard_fab2_lib.baseboard_fab2(sch_1):\MG_DDR_CTRL_NG_DDR_M_DLL_18\" )
					)
					( Status sCSetFlattened )
					( Origin gBackEnd )
				)
				( attribute "RELATIVE_PROPAGATION_DELAY" "0.00 MIL,25.00 MIL"
					( Parent
						( matchGroupRef "@baseboard_fab2_lib.baseboard_fab2(sch_1):\MG_DDR_CTRL_NG_DDR_M_DLL_18\" )
					)
					( Units "uMatchProp" "ns" 1.000000)
					( Status sCSetFlattened )
					( Origin gBackEnd )
				)
			)
			( pinPair "@baseboard_fab2_lib.baseboard_fab2(sch_1):\PP3277\"
				( pinRef "@baseboard_fab2_lib.baseboard_fab2(sch_1):page87_i186:ODT(1)" )
				( pinRef "@baseboard_fab2_lib.baseboard_fab2(sch_1):page62_i172:DDR5_ODT(1)" )
				( attribute "RELATIVE_PROPAGATION_DELAY_SCOPE" "G"
					( Parent
						( matchGroupRef "@crescent_city_bb_fab1_lib.crescent_city_bb_fab1(sch_1):\MG_DDR_FAR_DIMM-CLK0_CLS_DDR_M_CAC-CLKS\" )
					)
					( Status sCSetFlattened )
					( Origin gBackEnd )
				)
				( attribute "RELATIVE_PROPAGATION_DELAY" "0.00 MIL,300.00 MIL"
					( Parent
						( matchGroupRef "@crescent_city_bb_fab1_lib.crescent_city_bb_fab1(sch_1):\MG_DDR_FAR_DIMM-CLK0_CLS_DDR_M_CAC-CLKS\" )
					)
					( Units "uMatchProp" "ns" 1.000000)
					( Status sCSetFlattened )
					( Origin gBackEnd )
				)
				( attribute "RELATIVE_PROPAGATION_DELAY_SCOPE" "G"
					( Parent
						( matchGroupRef "@baseboard_fab2_lib.baseboard_fab2(sch_1):\MG_DDR_CTRL_NG_DDR_M_DLL_18\" )
					)
					( Status sCSetFlattened )
					( Origin gBackEnd )
				)
				( attribute "RELATIVE_PROPAGATION_DELAY" "0.00 MIL,25.00 MIL"
					( Parent
						( matchGroupRef "@baseboard_fab2_lib.baseboard_fab2(sch_1):\MG_DDR_CTRL_NG_DDR_M_DLL_18\" )
					)
					( Units "uMatchProp" "ns" 1.000000)
					( Status sCSetFlattened )
					( Origin gBackEnd )
				)
			)
			( pinPair "@baseboard_fab2_lib.baseboard_fab2(sch_1):\PP3275\"
				( pinRef "@baseboard_fab2_lib.baseboard_fab2(sch_1):page87_i186:CKE(1)" )
				( pinRef "@baseboard_fab2_lib.baseboard_fab2(sch_1):page62_i172:DDR5_CKE(1)" )
				( attribute "RELATIVE_PROPAGATION_DELAY_SCOPE" "G"
					( Parent
						( matchGroupRef "@crescent_city_bb_fab1_lib.crescent_city_bb_fab1(sch_1):\MG_DDR_FAR_DIMM-CLK0_CLS_DDR_M_CAC-CLKS\" )
					)
					( Status sCSetFlattened )
					( Origin gBackEnd )
				)
				( attribute "RELATIVE_PROPAGATION_DELAY" "0.00 MIL,300.00 MIL"
					( Parent
						( matchGroupRef "@crescent_city_bb_fab1_lib.crescent_city_bb_fab1(sch_1):\MG_DDR_FAR_DIMM-CLK0_CLS_DDR_M_CAC-CLKS\" )
					)
					( Units "uMatchProp" "ns" 1.000000)
					( Status sCSetFlattened )
					( Origin gBackEnd )
				)
				( attribute "RELATIVE_PROPAGATION_DELAY_SCOPE" "G"
					( Parent
						( matchGroupRef "@baseboard_fab2_lib.baseboard_fab2(sch_1):\MG_DDR_CTRL_NG_DDR_M_DLL_19\" )
					)
					( Status sCSetFlattened )
					( Origin gBackEnd )
				)
				( attribute "RELATIVE_PROPAGATION_DELAY" "0.00 MIL,25.00 MIL"
					( Parent
						( matchGroupRef "@baseboard_fab2_lib.baseboard_fab2(sch_1):\MG_DDR_CTRL_NG_DDR_M_DLL_19\" )
					)
					( Units "uMatchProp" "ns" 1.000000)
					( Status sCSetFlattened )
					( Origin gBackEnd )
				)
			)
			( pinPair "@baseboard_fab2_lib.baseboard_fab2(sch_1):\PP3273\"
				( pinRef "@baseboard_fab2_lib.baseboard_fab2(sch_1):page62_i172:DDR5_CS_N(4)" )
				( pinRef "@baseboard_fab2_lib.baseboard_fab2(sch_1):page88_i111:S0_N" )
				( attribute "RELATIVE_PROPAGATION_DELAY_SCOPE" "G"
					( Parent
						( matchGroupRef "@crescent_city_bb_fab1_lib.crescent_city_bb_fab1(sch_1):\MG_DDR_NEAR_DIMM-CLK1_CLS_DDR_M_CAC-CLKS\" )
					)
					( Status sCSetFlattened )
					( Origin gBackEnd )
				)
				( attribute "RELATIVE_PROPAGATION_DELAY" "0.00 MIL,300.00 MIL"
					( Parent
						( matchGroupRef "@crescent_city_bb_fab1_lib.crescent_city_bb_fab1(sch_1):\MG_DDR_NEAR_DIMM-CLK1_CLS_DDR_M_CAC-CLKS\" )
					)
					( Units "uMatchProp" "ns" 1.000000)
					( Status sCSetFlattened )
					( Origin gBackEnd )
				)
				( attribute "RELATIVE_PROPAGATION_DELAY_SCOPE" "G"
					( Parent
						( matchGroupRef "@baseboard_fab2_lib.baseboard_fab2(sch_1):\MG_DDR_CTRL_NG_DDR_M_DLL_20\" )
					)
					( Status sCSetFlattened )
					( Origin gBackEnd )
				)
				( attribute "RELATIVE_PROPAGATION_DELAY" "0.00 MIL,25.00 MIL"
					( Parent
						( matchGroupRef "@baseboard_fab2_lib.baseboard_fab2(sch_1):\MG_DDR_CTRL_NG_DDR_M_DLL_20\" )
					)
					( Units "uMatchProp" "ns" 1.000000)
					( Status sCSetFlattened )
					( Origin gBackEnd )
				)
			)
			( pinPair "@baseboard_fab2_lib.baseboard_fab2(sch_1):\PP3274\"
				( pinRef "@baseboard_fab2_lib.baseboard_fab2(sch_1):page62_i172:DDR5_ODT(2)" )
				( pinRef "@baseboard_fab2_lib.baseboard_fab2(sch_1):page88_i111:ODT(0)" )
				( attribute "RELATIVE_PROPAGATION_DELAY_SCOPE" "G"
					( Parent
						( matchGroupRef "@crescent_city_bb_fab1_lib.crescent_city_bb_fab1(sch_1):\MG_DDR_NEAR_DIMM-CLK1_CLS_DDR_M_CAC-CLKS\" )
					)
					( Status sCSetFlattened )
					( Origin gBackEnd )
				)
				( attribute "RELATIVE_PROPAGATION_DELAY" "0.00 MIL,300.00 MIL"
					( Parent
						( matchGroupRef "@crescent_city_bb_fab1_lib.crescent_city_bb_fab1(sch_1):\MG_DDR_NEAR_DIMM-CLK1_CLS_DDR_M_CAC-CLKS\" )
					)
					( Units "uMatchProp" "ns" 1.000000)
					( Status sCSetFlattened )
					( Origin gBackEnd )
				)
				( attribute "RELATIVE_PROPAGATION_DELAY_SCOPE" "G"
					( Parent
						( matchGroupRef "@baseboard_fab2_lib.baseboard_fab2(sch_1):\MG_DDR_CTRL_NG_DDR_M_DLL_20\" )
					)
					( Status sCSetFlattened )
					( Origin gBackEnd )
				)
				( attribute "RELATIVE_PROPAGATION_DELAY" "0.00 MIL,25.00 MIL"
					( Parent
						( matchGroupRef "@baseboard_fab2_lib.baseboard_fab2(sch_1):\MG_DDR_CTRL_NG_DDR_M_DLL_20\" )
					)
					( Units "uMatchProp" "ns" 1.000000)
					( Status sCSetFlattened )
					( Origin gBackEnd )
				)
			)
			( pinPair "@baseboard_fab2_lib.baseboard_fab2(sch_1):\PP3272\"
				( pinRef "@baseboard_fab2_lib.baseboard_fab2(sch_1):page62_i172:DDR5_CKE(2)" )
				( pinRef "@baseboard_fab2_lib.baseboard_fab2(sch_1):page88_i111:CKE(0)" )
				( attribute "RELATIVE_PROPAGATION_DELAY_SCOPE" "G"
					( Parent
						( matchGroupRef "@crescent_city_bb_fab1_lib.crescent_city_bb_fab1(sch_1):\MG_DDR_NEAR_DIMM-CLK1_CLS_DDR_M_CAC-CLKS\" )
					)
					( Status sCSetFlattened )
					( Origin gBackEnd )
				)
				( attribute "RELATIVE_PROPAGATION_DELAY" "0.00 MIL,300.00 MIL"
					( Parent
						( matchGroupRef "@crescent_city_bb_fab1_lib.crescent_city_bb_fab1(sch_1):\MG_DDR_NEAR_DIMM-CLK1_CLS_DDR_M_CAC-CLKS\" )
					)
					( Units "uMatchProp" "ns" 1.000000)
					( Status sCSetFlattened )
					( Origin gBackEnd )
				)
				( attribute "RELATIVE_PROPAGATION_DELAY_SCOPE" "G"
					( Parent
						( matchGroupRef "@baseboard_fab2_lib.baseboard_fab2(sch_1):\MG_DDR_CTRL_NG_DDR_M_DLL_21\" )
					)
					( Status sCSetFlattened )
					( Origin gBackEnd )
				)
				( attribute "RELATIVE_PROPAGATION_DELAY" "0.00 MIL,25.00 MIL"
					( Parent
						( matchGroupRef "@baseboard_fab2_lib.baseboard_fab2(sch_1):\MG_DDR_CTRL_NG_DDR_M_DLL_21\" )
					)
					( Units "uMatchProp" "ns" 1.000000)
					( Status sCSetFlattened )
					( Origin gBackEnd )
				)
			)
			( pinPair "@baseboard_fab2_lib.baseboard_fab2(sch_1):\PP3270\"
				( pinRef "@baseboard_fab2_lib.baseboard_fab2(sch_1):page62_i172:DDR5_CS_N(6)" )
				( pinRef "@baseboard_fab2_lib.baseboard_fab2(sch_1):page88_i111:S2_N_C(0)" )
				( attribute "RELATIVE_PROPAGATION_DELAY_SCOPE" "G"
					( Parent
						( matchGroupRef "@crescent_city_bb_fab1_lib.crescent_city_bb_fab1(sch_1):\MG_DDR_NEAR_DIMM-CLK1_CLS_DDR_M_CAC-CLKS\" )
					)
					( Status sCSetFlattened )
					( Origin gBackEnd )
				)
				( attribute "RELATIVE_PROPAGATION_DELAY" "0.00 MIL,300.00 MIL"
					( Parent
						( matchGroupRef "@crescent_city_bb_fab1_lib.crescent_city_bb_fab1(sch_1):\MG_DDR_NEAR_DIMM-CLK1_CLS_DDR_M_CAC-CLKS\" )
					)
					( Units "uMatchProp" "ns" 1.000000)
					( Status sCSetFlattened )
					( Origin gBackEnd )
				)
				( attribute "RELATIVE_PROPAGATION_DELAY_SCOPE" "G"
					( Parent
						( matchGroupRef "@baseboard_fab2_lib.baseboard_fab2(sch_1):\MG_DDR_CTRL_NG_DDR_M_DLL_22\" )
					)
					( Status sCSetFlattened )
					( Origin gBackEnd )
				)
				( attribute "RELATIVE_PROPAGATION_DELAY" "0.00 MIL,25.00 MIL"
					( Parent
						( matchGroupRef "@baseboard_fab2_lib.baseboard_fab2(sch_1):\MG_DDR_CTRL_NG_DDR_M_DLL_22\" )
					)
					( Units "uMatchProp" "ns" 1.000000)
					( Status sCSetFlattened )
					( Origin gBackEnd )
				)
			)
			( pinPair "@baseboard_fab2_lib.baseboard_fab2(sch_1):\PP3271\"
				( pinRef "@baseboard_fab2_lib.baseboard_fab2(sch_1):page62_i172:DDR5_CS_N(7)" )
				( pinRef "@baseboard_fab2_lib.baseboard_fab2(sch_1):page88_i111:S3_N_C(1)" )
				( attribute "RELATIVE_PROPAGATION_DELAY_SCOPE" "G"
					( Parent
						( matchGroupRef "@crescent_city_bb_fab1_lib.crescent_city_bb_fab1(sch_1):\MG_DDR_NEAR_DIMM-CLK1_CLS_DDR_M_CAC-CLKS\" )
					)
					( Status sCSetFlattened )
					( Origin gBackEnd )
				)
				( attribute "RELATIVE_PROPAGATION_DELAY" "0.00 MIL,300.00 MIL"
					( Parent
						( matchGroupRef "@crescent_city_bb_fab1_lib.crescent_city_bb_fab1(sch_1):\MG_DDR_NEAR_DIMM-CLK1_CLS_DDR_M_CAC-CLKS\" )
					)
					( Units "uMatchProp" "ns" 1.000000)
					( Status sCSetFlattened )
					( Origin gBackEnd )
				)
				( attribute "RELATIVE_PROPAGATION_DELAY_SCOPE" "G"
					( Parent
						( matchGroupRef "@baseboard_fab2_lib.baseboard_fab2(sch_1):\MG_DDR_CTRL_NG_DDR_M_DLL_22\" )
					)
					( Status sCSetFlattened )
					( Origin gBackEnd )
				)
				( attribute "RELATIVE_PROPAGATION_DELAY" "0.00 MIL,25.00 MIL"
					( Parent
						( matchGroupRef "@baseboard_fab2_lib.baseboard_fab2(sch_1):\MG_DDR_CTRL_NG_DDR_M_DLL_22\" )
					)
					( Units "uMatchProp" "ns" 1.000000)
					( Status sCSetFlattened )
					( Origin gBackEnd )
				)
			)
			( pinPair "@baseboard_fab2_lib.baseboard_fab2(sch_1):\PP3268\"
				( pinRef "@baseboard_fab2_lib.baseboard_fab2(sch_1):page62_i172:DDR5_CS_N(5)" )
				( pinRef "@baseboard_fab2_lib.baseboard_fab2(sch_1):page88_i111:S1_N" )
				( attribute "RELATIVE_PROPAGATION_DELAY_SCOPE" "G"
					( Parent
						( matchGroupRef "@crescent_city_bb_fab1_lib.crescent_city_bb_fab1(sch_1):\MG_DDR_NEAR_DIMM-CLK1_CLS_DDR_M_CAC-CLKS\" )
					)
					( Status sCSetFlattened )
					( Origin gBackEnd )
				)
				( attribute "RELATIVE_PROPAGATION_DELAY" "0.00 MIL,300.00 MIL"
					( Parent
						( matchGroupRef "@crescent_city_bb_fab1_lib.crescent_city_bb_fab1(sch_1):\MG_DDR_NEAR_DIMM-CLK1_CLS_DDR_M_CAC-CLKS\" )
					)
					( Units "uMatchProp" "ns" 1.000000)
					( Status sCSetFlattened )
					( Origin gBackEnd )
				)
				( attribute "RELATIVE_PROPAGATION_DELAY_SCOPE" "G"
					( Parent
						( matchGroupRef "@baseboard_fab2_lib.baseboard_fab2(sch_1):\MG_DDR_CTRL_NG_DDR_M_DLL_23\" )
					)
					( Status sCSetFlattened )
					( Origin gBackEnd )
				)
				( attribute "RELATIVE_PROPAGATION_DELAY" "0.00 MIL,25.00 MIL"
					( Parent
						( matchGroupRef "@baseboard_fab2_lib.baseboard_fab2(sch_1):\MG_DDR_CTRL_NG_DDR_M_DLL_23\" )
					)
					( Units "uMatchProp" "ns" 1.000000)
					( Status sCSetFlattened )
					( Origin gBackEnd )
				)
			)
			( pinPair "@baseboard_fab2_lib.baseboard_fab2(sch_1):\PP3269\"
				( pinRef "@baseboard_fab2_lib.baseboard_fab2(sch_1):page62_i172:DDR5_ODT(3)" )
				( pinRef "@baseboard_fab2_lib.baseboard_fab2(sch_1):page88_i111:ODT(1)" )
				( attribute "RELATIVE_PROPAGATION_DELAY_SCOPE" "G"
					( Parent
						( matchGroupRef "@crescent_city_bb_fab1_lib.crescent_city_bb_fab1(sch_1):\MG_DDR_NEAR_DIMM-CLK1_CLS_DDR_M_CAC-CLKS\" )
					)
					( Status sCSetFlattened )
					( Origin gBackEnd )
				)
				( attribute "RELATIVE_PROPAGATION_DELAY" "0.00 MIL,300.00 MIL"
					( Parent
						( matchGroupRef "@crescent_city_bb_fab1_lib.crescent_city_bb_fab1(sch_1):\MG_DDR_NEAR_DIMM-CLK1_CLS_DDR_M_CAC-CLKS\" )
					)
					( Units "uMatchProp" "ns" 1.000000)
					( Status sCSetFlattened )
					( Origin gBackEnd )
				)
				( attribute "RELATIVE_PROPAGATION_DELAY_SCOPE" "G"
					( Parent
						( matchGroupRef "@baseboard_fab2_lib.baseboard_fab2(sch_1):\MG_DDR_CTRL_NG_DDR_M_DLL_23\" )
					)
					( Status sCSetFlattened )
					( Origin gBackEnd )
				)
				( attribute "RELATIVE_PROPAGATION_DELAY" "0.00 MIL,25.00 MIL"
					( Parent
						( matchGroupRef "@baseboard_fab2_lib.baseboard_fab2(sch_1):\MG_DDR_CTRL_NG_DDR_M_DLL_23\" )
					)
					( Units "uMatchProp" "ns" 1.000000)
					( Status sCSetFlattened )
					( Origin gBackEnd )
				)
			)
			( pinPair "@baseboard_fab2_lib.baseboard_fab2(sch_1):\PP3267\"
				( pinRef "@baseboard_fab2_lib.baseboard_fab2(sch_1):page62_i172:DDR5_CKE(3)" )
				( pinRef "@baseboard_fab2_lib.baseboard_fab2(sch_1):page88_i111:CKE(1)" )
				( attribute "RELATIVE_PROPAGATION_DELAY_SCOPE" "G"
					( Parent
						( matchGroupRef "@crescent_city_bb_fab1_lib.crescent_city_bb_fab1(sch_1):\MG_DDR_NEAR_DIMM-CLK1_CLS_DDR_M_CAC-CLKS\" )
					)
					( Status sCSetFlattened )
					( Origin gBackEnd )
				)
				( attribute "RELATIVE_PROPAGATION_DELAY" "0.00 MIL,300.00 MIL"
					( Parent
						( matchGroupRef "@crescent_city_bb_fab1_lib.crescent_city_bb_fab1(sch_1):\MG_DDR_NEAR_DIMM-CLK1_CLS_DDR_M_CAC-CLKS\" )
					)
					( Units "uMatchProp" "ns" 1.000000)
					( Status sCSetFlattened )
					( Origin gBackEnd )
				)
				( attribute "RELATIVE_PROPAGATION_DELAY_SCOPE" "G"
					( Parent
						( matchGroupRef "@baseboard_fab2_lib.baseboard_fab2(sch_1):\MG_DDR_CTRL_NG_DDR_M_DLL_24\" )
					)
					( Status sCSetFlattened )
					( Origin gBackEnd )
				)
				( attribute "RELATIVE_PROPAGATION_DELAY" "0.00 MIL,25.00 MIL"
					( Parent
						( matchGroupRef "@baseboard_fab2_lib.baseboard_fab2(sch_1):\MG_DDR_CTRL_NG_DDR_M_DLL_24\" )
					)
					( Units "uMatchProp" "ns" 1.000000)
					( Status sCSetFlattened )
					( Origin gBackEnd )
				)
			)
			( pinPair "@baseboard_fab2_lib.baseboard_fab2(sch_1):\PP3395\"
				( pinRef "@baseboard_fab2_lib.baseboard_fab2(sch_1):page61_i172:DDR4_CID(2)" )
				( pinRef "@baseboard_fab2_lib.baseboard_fab2(sch_1):page85_i111:C(2)" )
				( attribute "RELATIVE_PROPAGATION_DELAY_SCOPE" "G"
					( Parent
						( matchGroupRef "@baseboard_fab2_lib.baseboard_fab2(sch_1):\MG_DDR_FAR_DIMM_CMD_NG_DDR_L_DLL_1\" )
					)
					( Status sCSetFlattened )
					( Origin gBackEnd )
				)
				( attribute "RELATIVE_PROPAGATION_DELAY" "0.00 MIL,25.00 MIL"
					( Parent
						( matchGroupRef "@baseboard_fab2_lib.baseboard_fab2(sch_1):\MG_DDR_FAR_DIMM_CMD_NG_DDR_L_DLL_1\" )
					)
					( Units "uMatchProp" "ns" 1.000000)
					( Status sCSetFlattened )
					( Origin gBackEnd )
				)
				( attribute "RELATIVE_PROPAGATION_DELAY_SCOPE" "G"
					( Parent
						( matchGroupRef "@crescent_city_bb_fab1_lib.crescent_city_bb_fab1(sch_1):\MG_DDR_FAR_DIMM-CLK0_CLS_DDR_L_CAC-CLKS\" )
					)
					( Status sCSetFlattened )
					( Origin gBackEnd )
				)
				( attribute "RELATIVE_PROPAGATION_DELAY" "0.00 MIL,700.00 MIL"
					( Parent
						( matchGroupRef "@crescent_city_bb_fab1_lib.crescent_city_bb_fab1(sch_1):\MG_DDR_FAR_DIMM-CLK0_CLS_DDR_L_CAC-CLKS\" )
					)
					( Units "uMatchProp" "ns" 1.000000)
					( Status sCSetFlattened )
					( Origin gBackEnd )
				)
			)
			( pinPair "@baseboard_fab2_lib.baseboard_fab2(sch_1):\PP3396\"
				( pinRef "@baseboard_fab2_lib.baseboard_fab2(sch_1):page86_i12:C(2)" )
				( pinRef "@baseboard_fab2_lib.baseboard_fab2(sch_1):page61_i172:DDR4_CID(2)" )
				( attribute "RELATIVE_PROPAGATION_DELAY_SCOPE" "G"
					( Parent
						( matchGroupRef "@crescent_city_bb_fab1_lib.crescent_city_bb_fab1(sch_1):\MG_DDR_NEAR_DIMM-CLK1_CLS_DDR_L_CAC-CLKS\" )
					)
					( Status sCSetFlattened )
					( Origin gBackEnd )
				)
				( attribute "RELATIVE_PROPAGATION_DELAY" "0.00 MIL,700.00 MIL"
					( Parent
						( matchGroupRef "@crescent_city_bb_fab1_lib.crescent_city_bb_fab1(sch_1):\MG_DDR_NEAR_DIMM-CLK1_CLS_DDR_L_CAC-CLKS\" )
					)
					( Units "uMatchProp" "ns" 1.000000)
					( Status sCSetFlattened )
					( Origin gBackEnd )
				)
				( attribute "RELATIVE_PROPAGATION_DELAY_SCOPE" "G"
					( Parent
						( matchGroupRef "@baseboard_fab2_lib.baseboard_fab2(sch_1):\MG_DDR_CMD_NEAR_DIMM_NG_DDR_L_DLL_1\" )
					)
					( Status sCSetFlattened )
					( Origin gBackEnd )
				)
				( attribute "RELATIVE_PROPAGATION_DELAY" "0.00 MIL,25.00 MIL"
					( Parent
						( matchGroupRef "@baseboard_fab2_lib.baseboard_fab2(sch_1):\MG_DDR_CMD_NEAR_DIMM_NG_DDR_L_DLL_1\" )
					)
					( Units "uMatchProp" "ns" 1.000000)
					( Status sCSetFlattened )
					( Origin gBackEnd )
				)
			)
			( pinPair "@baseboard_fab2_lib.baseboard_fab2(sch_1):\PP3397\"
				( pinRef "@baseboard_fab2_lib.baseboard_fab2(sch_1):page61_i172:DDR4_MA(17)" )
				( pinRef "@baseboard_fab2_lib.baseboard_fab2(sch_1):page85_i111:A17" )
				( attribute "RELATIVE_PROPAGATION_DELAY_SCOPE" "G"
					( Parent
						( matchGroupRef "@baseboard_fab2_lib.baseboard_fab2(sch_1):\MG_DDR_FAR_DIMM_CMD_NG_DDR_L_DLL_1\" )
					)
					( Status sCSetFlattened )
					( Origin gBackEnd )
				)
				( attribute "RELATIVE_PROPAGATION_DELAY" "0.00 MIL,25.00 MIL"
					( Parent
						( matchGroupRef "@baseboard_fab2_lib.baseboard_fab2(sch_1):\MG_DDR_FAR_DIMM_CMD_NG_DDR_L_DLL_1\" )
					)
					( Units "uMatchProp" "ns" 1.000000)
					( Status sCSetFlattened )
					( Origin gBackEnd )
				)
				( attribute "RELATIVE_PROPAGATION_DELAY_SCOPE" "G"
					( Parent
						( matchGroupRef "@crescent_city_bb_fab1_lib.crescent_city_bb_fab1(sch_1):\MG_DDR_FAR_DIMM-CLK0_CLS_DDR_L_CAC-CLKS\" )
					)
					( Status sCSetFlattened )
					( Origin gBackEnd )
				)
				( attribute "RELATIVE_PROPAGATION_DELAY" "0.00 MIL,700.00 MIL"
					( Parent
						( matchGroupRef "@crescent_city_bb_fab1_lib.crescent_city_bb_fab1(sch_1):\MG_DDR_FAR_DIMM-CLK0_CLS_DDR_L_CAC-CLKS\" )
					)
					( Units "uMatchProp" "ns" 1.000000)
					( Status sCSetFlattened )
					( Origin gBackEnd )
				)
			)
			( pinPair "@baseboard_fab2_lib.baseboard_fab2(sch_1):\PP3398\"
				( pinRef "@baseboard_fab2_lib.baseboard_fab2(sch_1):page86_i12:A17" )
				( pinRef "@baseboard_fab2_lib.baseboard_fab2(sch_1):page61_i172:DDR4_MA(17)" )
				( attribute "RELATIVE_PROPAGATION_DELAY_SCOPE" "G"
					( Parent
						( matchGroupRef "@crescent_city_bb_fab1_lib.crescent_city_bb_fab1(sch_1):\MG_DDR_NEAR_DIMM-CLK1_CLS_DDR_L_CAC-CLKS\" )
					)
					( Status sCSetFlattened )
					( Origin gBackEnd )
				)
				( attribute "RELATIVE_PROPAGATION_DELAY" "0.00 MIL,700.00 MIL"
					( Parent
						( matchGroupRef "@crescent_city_bb_fab1_lib.crescent_city_bb_fab1(sch_1):\MG_DDR_NEAR_DIMM-CLK1_CLS_DDR_L_CAC-CLKS\" )
					)
					( Units "uMatchProp" "ns" 1.000000)
					( Status sCSetFlattened )
					( Origin gBackEnd )
				)
				( attribute "RELATIVE_PROPAGATION_DELAY_SCOPE" "G"
					( Parent
						( matchGroupRef "@baseboard_fab2_lib.baseboard_fab2(sch_1):\MG_DDR_CMD_NEAR_DIMM_NG_DDR_L_DLL_1\" )
					)
					( Status sCSetFlattened )
					( Origin gBackEnd )
				)
				( attribute "RELATIVE_PROPAGATION_DELAY" "0.00 MIL,25.00 MIL"
					( Parent
						( matchGroupRef "@baseboard_fab2_lib.baseboard_fab2(sch_1):\MG_DDR_CMD_NEAR_DIMM_NG_DDR_L_DLL_1\" )
					)
					( Units "uMatchProp" "ns" 1.000000)
					( Status sCSetFlattened )
					( Origin gBackEnd )
				)
			)
			( pinPair "@baseboard_fab2_lib.baseboard_fab2(sch_1):\PP3391\"
				( pinRef "@baseboard_fab2_lib.baseboard_fab2(sch_1):page61_i172:DDR4_MA(13)" )
				( pinRef "@baseboard_fab2_lib.baseboard_fab2(sch_1):page85_i111:A13" )
				( attribute "RELATIVE_PROPAGATION_DELAY_SCOPE" "G"
					( Parent
						( matchGroupRef "@crescent_city_bb_fab1_lib.crescent_city_bb_fab1(sch_1):\MG_DDR_FAR_DIMM-CLK0_CLS_DDR_L_CAC-CLKS\" )
					)
					( Status sCSetFlattened )
					( Origin gBackEnd )
				)
				( attribute "RELATIVE_PROPAGATION_DELAY" "0.00 MIL,700.00 MIL"
					( Parent
						( matchGroupRef "@crescent_city_bb_fab1_lib.crescent_city_bb_fab1(sch_1):\MG_DDR_FAR_DIMM-CLK0_CLS_DDR_L_CAC-CLKS\" )
					)
					( Units "uMatchProp" "ns" 1.000000)
					( Status sCSetFlattened )
					( Origin gBackEnd )
				)
				( attribute "RELATIVE_PROPAGATION_DELAY_SCOPE" "G"
					( Parent
						( matchGroupRef "@baseboard_fab2_lib.baseboard_fab2(sch_1):\MG_DDR_FAR_DIMM_CMD_NG_DDR_L_DLL_2\" )
					)
					( Status sCSetFlattened )
					( Origin gBackEnd )
				)
				( attribute "RELATIVE_PROPAGATION_DELAY" "0.00 MIL,25.00 MIL"
					( Parent
						( matchGroupRef "@baseboard_fab2_lib.baseboard_fab2(sch_1):\MG_DDR_FAR_DIMM_CMD_NG_DDR_L_DLL_2\" )
					)
					( Units "uMatchProp" "ns" 1.000000)
					( Status sCSetFlattened )
					( Origin gBackEnd )
				)
			)
			( pinPair "@baseboard_fab2_lib.baseboard_fab2(sch_1):\PP3392\"
				( pinRef "@baseboard_fab2_lib.baseboard_fab2(sch_1):page86_i12:A13" )
				( pinRef "@baseboard_fab2_lib.baseboard_fab2(sch_1):page61_i172:DDR4_MA(13)" )
				( attribute "RELATIVE_PROPAGATION_DELAY_SCOPE" "G"
					( Parent
						( matchGroupRef "@crescent_city_bb_fab1_lib.crescent_city_bb_fab1(sch_1):\MG_DDR_NEAR_DIMM-CLK1_CLS_DDR_L_CAC-CLKS\" )
					)
					( Status sCSetFlattened )
					( Origin gBackEnd )
				)
				( attribute "RELATIVE_PROPAGATION_DELAY" "0.00 MIL,700.00 MIL"
					( Parent
						( matchGroupRef "@crescent_city_bb_fab1_lib.crescent_city_bb_fab1(sch_1):\MG_DDR_NEAR_DIMM-CLK1_CLS_DDR_L_CAC-CLKS\" )
					)
					( Units "uMatchProp" "ns" 1.000000)
					( Status sCSetFlattened )
					( Origin gBackEnd )
				)
				( attribute "RELATIVE_PROPAGATION_DELAY_SCOPE" "G"
					( Parent
						( matchGroupRef "@baseboard_fab2_lib.baseboard_fab2(sch_1):\MG_DDR_CMD_NEAR_DIMM_NG_DDR_L_DLL_2\" )
					)
					( Status sCSetFlattened )
					( Origin gBackEnd )
				)
				( attribute "RELATIVE_PROPAGATION_DELAY" "0.00 MIL,25.00 MIL"
					( Parent
						( matchGroupRef "@baseboard_fab2_lib.baseboard_fab2(sch_1):\MG_DDR_CMD_NEAR_DIMM_NG_DDR_L_DLL_2\" )
					)
					( Units "uMatchProp" "ns" 1.000000)
					( Status sCSetFlattened )
					( Origin gBackEnd )
				)
			)
			( pinPair "@baseboard_fab2_lib.baseboard_fab2(sch_1):\PP3393\"
				( pinRef "@baseboard_fab2_lib.baseboard_fab2(sch_1):page61_i172:DDR4_MA(15)" )
				( pinRef "@baseboard_fab2_lib.baseboard_fab2(sch_1):page85_i111:A15_CAS_N" )
				( attribute "RELATIVE_PROPAGATION_DELAY_SCOPE" "G"
					( Parent
						( matchGroupRef "@crescent_city_bb_fab1_lib.crescent_city_bb_fab1(sch_1):\MG_DDR_FAR_DIMM-CLK0_CLS_DDR_L_CAC-CLKS\" )
					)
					( Status sCSetFlattened )
					( Origin gBackEnd )
				)
				( attribute "RELATIVE_PROPAGATION_DELAY" "0.00 MIL,700.00 MIL"
					( Parent
						( matchGroupRef "@crescent_city_bb_fab1_lib.crescent_city_bb_fab1(sch_1):\MG_DDR_FAR_DIMM-CLK0_CLS_DDR_L_CAC-CLKS\" )
					)
					( Units "uMatchProp" "ns" 1.000000)
					( Status sCSetFlattened )
					( Origin gBackEnd )
				)
				( attribute "RELATIVE_PROPAGATION_DELAY_SCOPE" "G"
					( Parent
						( matchGroupRef "@baseboard_fab2_lib.baseboard_fab2(sch_1):\MG_DDR_FAR_DIMM_CMD_NG_DDR_L_DLL_2\" )
					)
					( Status sCSetFlattened )
					( Origin gBackEnd )
				)
				( attribute "RELATIVE_PROPAGATION_DELAY" "0.00 MIL,25.00 MIL"
					( Parent
						( matchGroupRef "@baseboard_fab2_lib.baseboard_fab2(sch_1):\MG_DDR_FAR_DIMM_CMD_NG_DDR_L_DLL_2\" )
					)
					( Units "uMatchProp" "ns" 1.000000)
					( Status sCSetFlattened )
					( Origin gBackEnd )
				)
			)
			( pinPair "@baseboard_fab2_lib.baseboard_fab2(sch_1):\PP3394\"
				( pinRef "@baseboard_fab2_lib.baseboard_fab2(sch_1):page86_i12:A15_CAS_N" )
				( pinRef "@baseboard_fab2_lib.baseboard_fab2(sch_1):page61_i172:DDR4_MA(15)" )
				( attribute "RELATIVE_PROPAGATION_DELAY_SCOPE" "G"
					( Parent
						( matchGroupRef "@crescent_city_bb_fab1_lib.crescent_city_bb_fab1(sch_1):\MG_DDR_NEAR_DIMM-CLK1_CLS_DDR_L_CAC-CLKS\" )
					)
					( Status sCSetFlattened )
					( Origin gBackEnd )
				)
				( attribute "RELATIVE_PROPAGATION_DELAY" "0.00 MIL,700.00 MIL"
					( Parent
						( matchGroupRef "@crescent_city_bb_fab1_lib.crescent_city_bb_fab1(sch_1):\MG_DDR_NEAR_DIMM-CLK1_CLS_DDR_L_CAC-CLKS\" )
					)
					( Units "uMatchProp" "ns" 1.000000)
					( Status sCSetFlattened )
					( Origin gBackEnd )
				)
				( attribute "RELATIVE_PROPAGATION_DELAY_SCOPE" "G"
					( Parent
						( matchGroupRef "@baseboard_fab2_lib.baseboard_fab2(sch_1):\MG_DDR_CMD_NEAR_DIMM_NG_DDR_L_DLL_2\" )
					)
					( Status sCSetFlattened )
					( Origin gBackEnd )
				)
				( attribute "RELATIVE_PROPAGATION_DELAY" "0.00 MIL,25.00 MIL"
					( Parent
						( matchGroupRef "@baseboard_fab2_lib.baseboard_fab2(sch_1):\MG_DDR_CMD_NEAR_DIMM_NG_DDR_L_DLL_2\" )
					)
					( Units "uMatchProp" "ns" 1.000000)
					( Status sCSetFlattened )
					( Origin gBackEnd )
				)
			)
			( pinPair "@baseboard_fab2_lib.baseboard_fab2(sch_1):\PP3387\"
				( pinRef "@baseboard_fab2_lib.baseboard_fab2(sch_1):page61_i172:DDR4_MA(14)" )
				( pinRef "@baseboard_fab2_lib.baseboard_fab2(sch_1):page85_i111:A14_WE_N" )
				( attribute "RELATIVE_PROPAGATION_DELAY_SCOPE" "G"
					( Parent
						( matchGroupRef "@crescent_city_bb_fab1_lib.crescent_city_bb_fab1(sch_1):\MG_DDR_FAR_DIMM-CLK0_CLS_DDR_L_CAC-CLKS\" )
					)
					( Status sCSetFlattened )
					( Origin gBackEnd )
				)
				( attribute "RELATIVE_PROPAGATION_DELAY" "0.00 MIL,700.00 MIL"
					( Parent
						( matchGroupRef "@crescent_city_bb_fab1_lib.crescent_city_bb_fab1(sch_1):\MG_DDR_FAR_DIMM-CLK0_CLS_DDR_L_CAC-CLKS\" )
					)
					( Units "uMatchProp" "ns" 1.000000)
					( Status sCSetFlattened )
					( Origin gBackEnd )
				)
				( attribute "RELATIVE_PROPAGATION_DELAY_SCOPE" "G"
					( Parent
						( matchGroupRef "@baseboard_fab2_lib.baseboard_fab2(sch_1):\MG_DDR_FAR_DIMM_CMD_NG_DDR_L_DLL_3\" )
					)
					( Status sCSetFlattened )
					( Origin gBackEnd )
				)
				( attribute "RELATIVE_PROPAGATION_DELAY" "0.00 MIL,25.00 MIL"
					( Parent
						( matchGroupRef "@baseboard_fab2_lib.baseboard_fab2(sch_1):\MG_DDR_FAR_DIMM_CMD_NG_DDR_L_DLL_3\" )
					)
					( Units "uMatchProp" "ns" 1.000000)
					( Status sCSetFlattened )
					( Origin gBackEnd )
				)
			)
			( pinPair "@baseboard_fab2_lib.baseboard_fab2(sch_1):\PP3388\"
				( pinRef "@baseboard_fab2_lib.baseboard_fab2(sch_1):page86_i12:A14_WE_N" )
				( pinRef "@baseboard_fab2_lib.baseboard_fab2(sch_1):page61_i172:DDR4_MA(14)" )
				( attribute "RELATIVE_PROPAGATION_DELAY_SCOPE" "G"
					( Parent
						( matchGroupRef "@crescent_city_bb_fab1_lib.crescent_city_bb_fab1(sch_1):\MG_DDR_NEAR_DIMM-CLK1_CLS_DDR_L_CAC-CLKS\" )
					)
					( Status sCSetFlattened )
					( Origin gBackEnd )
				)
				( attribute "RELATIVE_PROPAGATION_DELAY" "0.00 MIL,700.00 MIL"
					( Parent
						( matchGroupRef "@crescent_city_bb_fab1_lib.crescent_city_bb_fab1(sch_1):\MG_DDR_NEAR_DIMM-CLK1_CLS_DDR_L_CAC-CLKS\" )
					)
					( Units "uMatchProp" "ns" 1.000000)
					( Status sCSetFlattened )
					( Origin gBackEnd )
				)
				( attribute "RELATIVE_PROPAGATION_DELAY_SCOPE" "G"
					( Parent
						( matchGroupRef "@baseboard_fab2_lib.baseboard_fab2(sch_1):\MG_DDR_CMD_NEAR_DIMM_NG_DDR_L_DLL_3\" )
					)
					( Status sCSetFlattened )
					( Origin gBackEnd )
				)
				( attribute "RELATIVE_PROPAGATION_DELAY" "0.00 MIL,25.00 MIL"
					( Parent
						( matchGroupRef "@baseboard_fab2_lib.baseboard_fab2(sch_1):\MG_DDR_CMD_NEAR_DIMM_NG_DDR_L_DLL_3\" )
					)
					( Units "uMatchProp" "ns" 1.000000)
					( Status sCSetFlattened )
					( Origin gBackEnd )
				)
			)
			( pinPair "@baseboard_fab2_lib.baseboard_fab2(sch_1):\PP3389\"
				( pinRef "@baseboard_fab2_lib.baseboard_fab2(sch_1):page61_i172:DDR4_MA(16)" )
				( pinRef "@baseboard_fab2_lib.baseboard_fab2(sch_1):page85_i111:A16_RAS_N" )
				( attribute "RELATIVE_PROPAGATION_DELAY_SCOPE" "G"
					( Parent
						( matchGroupRef "@crescent_city_bb_fab1_lib.crescent_city_bb_fab1(sch_1):\MG_DDR_FAR_DIMM-CLK0_CLS_DDR_L_CAC-CLKS\" )
					)
					( Status sCSetFlattened )
					( Origin gBackEnd )
				)
				( attribute "RELATIVE_PROPAGATION_DELAY" "0.00 MIL,700.00 MIL"
					( Parent
						( matchGroupRef "@crescent_city_bb_fab1_lib.crescent_city_bb_fab1(sch_1):\MG_DDR_FAR_DIMM-CLK0_CLS_DDR_L_CAC-CLKS\" )
					)
					( Units "uMatchProp" "ns" 1.000000)
					( Status sCSetFlattened )
					( Origin gBackEnd )
				)
				( attribute "RELATIVE_PROPAGATION_DELAY_SCOPE" "G"
					( Parent
						( matchGroupRef "@baseboard_fab2_lib.baseboard_fab2(sch_1):\MG_DDR_FAR_DIMM_CMD_NG_DDR_L_DLL_3\" )
					)
					( Status sCSetFlattened )
					( Origin gBackEnd )
				)
				( attribute "RELATIVE_PROPAGATION_DELAY" "0.00 MIL,25.00 MIL"
					( Parent
						( matchGroupRef "@baseboard_fab2_lib.baseboard_fab2(sch_1):\MG_DDR_FAR_DIMM_CMD_NG_DDR_L_DLL_3\" )
					)
					( Units "uMatchProp" "ns" 1.000000)
					( Status sCSetFlattened )
					( Origin gBackEnd )
				)
			)
			( pinPair "@baseboard_fab2_lib.baseboard_fab2(sch_1):\PP3390\"
				( pinRef "@baseboard_fab2_lib.baseboard_fab2(sch_1):page86_i12:A16_RAS_N" )
				( pinRef "@baseboard_fab2_lib.baseboard_fab2(sch_1):page61_i172:DDR4_MA(16)" )
				( attribute "RELATIVE_PROPAGATION_DELAY_SCOPE" "G"
					( Parent
						( matchGroupRef "@crescent_city_bb_fab1_lib.crescent_city_bb_fab1(sch_1):\MG_DDR_NEAR_DIMM-CLK1_CLS_DDR_L_CAC-CLKS\" )
					)
					( Status sCSetFlattened )
					( Origin gBackEnd )
				)
				( attribute "RELATIVE_PROPAGATION_DELAY" "0.00 MIL,700.00 MIL"
					( Parent
						( matchGroupRef "@crescent_city_bb_fab1_lib.crescent_city_bb_fab1(sch_1):\MG_DDR_NEAR_DIMM-CLK1_CLS_DDR_L_CAC-CLKS\" )
					)
					( Units "uMatchProp" "ns" 1.000000)
					( Status sCSetFlattened )
					( Origin gBackEnd )
				)
				( attribute "RELATIVE_PROPAGATION_DELAY_SCOPE" "G"
					( Parent
						( matchGroupRef "@baseboard_fab2_lib.baseboard_fab2(sch_1):\MG_DDR_CMD_NEAR_DIMM_NG_DDR_L_DLL_3\" )
					)
					( Status sCSetFlattened )
					( Origin gBackEnd )
				)
				( attribute "RELATIVE_PROPAGATION_DELAY" "0.00 MIL,25.00 MIL"
					( Parent
						( matchGroupRef "@baseboard_fab2_lib.baseboard_fab2(sch_1):\MG_DDR_CMD_NEAR_DIMM_NG_DDR_L_DLL_3\" )
					)
					( Units "uMatchProp" "ns" 1.000000)
					( Status sCSetFlattened )
					( Origin gBackEnd )
				)
			)
			( pinPair "@baseboard_fab2_lib.baseboard_fab2(sch_1):\PP3383\"
				( pinRef "@baseboard_fab2_lib.baseboard_fab2(sch_1):page61_i172:DDR4_BA(1)" )
				( pinRef "@baseboard_fab2_lib.baseboard_fab2(sch_1):page85_i111:BA(1)" )
				( attribute "RELATIVE_PROPAGATION_DELAY_SCOPE" "G"
					( Parent
						( matchGroupRef "@crescent_city_bb_fab1_lib.crescent_city_bb_fab1(sch_1):\MG_DDR_FAR_DIMM-CLK0_CLS_DDR_L_CAC-CLKS\" )
					)
					( Status sCSetFlattened )
					( Origin gBackEnd )
				)
				( attribute "RELATIVE_PROPAGATION_DELAY" "0.00 MIL,700.00 MIL"
					( Parent
						( matchGroupRef "@crescent_city_bb_fab1_lib.crescent_city_bb_fab1(sch_1):\MG_DDR_FAR_DIMM-CLK0_CLS_DDR_L_CAC-CLKS\" )
					)
					( Units "uMatchProp" "ns" 1.000000)
					( Status sCSetFlattened )
					( Origin gBackEnd )
				)
				( attribute "RELATIVE_PROPAGATION_DELAY_SCOPE" "G"
					( Parent
						( matchGroupRef "@baseboard_fab2_lib.baseboard_fab2(sch_1):\MG_DDR_FAR_DIMM_CMD_NG_DDR_L_DLL_4\" )
					)
					( Status sCSetFlattened )
					( Origin gBackEnd )
				)
				( attribute "RELATIVE_PROPAGATION_DELAY" "0.00 MIL,25.00 MIL"
					( Parent
						( matchGroupRef "@baseboard_fab2_lib.baseboard_fab2(sch_1):\MG_DDR_FAR_DIMM_CMD_NG_DDR_L_DLL_4\" )
					)
					( Units "uMatchProp" "ns" 1.000000)
					( Status sCSetFlattened )
					( Origin gBackEnd )
				)
			)
			( pinPair "@baseboard_fab2_lib.baseboard_fab2(sch_1):\PP3384\"
				( pinRef "@baseboard_fab2_lib.baseboard_fab2(sch_1):page86_i12:BA(1)" )
				( pinRef "@baseboard_fab2_lib.baseboard_fab2(sch_1):page61_i172:DDR4_BA(1)" )
				( attribute "RELATIVE_PROPAGATION_DELAY_SCOPE" "G"
					( Parent
						( matchGroupRef "@crescent_city_bb_fab1_lib.crescent_city_bb_fab1(sch_1):\MG_DDR_NEAR_DIMM-CLK1_CLS_DDR_L_CAC-CLKS\" )
					)
					( Status sCSetFlattened )
					( Origin gBackEnd )
				)
				( attribute "RELATIVE_PROPAGATION_DELAY" "0.00 MIL,700.00 MIL"
					( Parent
						( matchGroupRef "@crescent_city_bb_fab1_lib.crescent_city_bb_fab1(sch_1):\MG_DDR_NEAR_DIMM-CLK1_CLS_DDR_L_CAC-CLKS\" )
					)
					( Units "uMatchProp" "ns" 1.000000)
					( Status sCSetFlattened )
					( Origin gBackEnd )
				)
				( attribute "RELATIVE_PROPAGATION_DELAY_SCOPE" "G"
					( Parent
						( matchGroupRef "@baseboard_fab2_lib.baseboard_fab2(sch_1):\MG_DDR_CMD_NEAR_DIMM_NG_DDR_L_DLL_4\" )
					)
					( Status sCSetFlattened )
					( Origin gBackEnd )
				)
				( attribute "RELATIVE_PROPAGATION_DELAY" "0.00 MIL,25.00 MIL"
					( Parent
						( matchGroupRef "@baseboard_fab2_lib.baseboard_fab2(sch_1):\MG_DDR_CMD_NEAR_DIMM_NG_DDR_L_DLL_4\" )
					)
					( Units "uMatchProp" "ns" 1.000000)
					( Status sCSetFlattened )
					( Origin gBackEnd )
				)
			)
			( pinPair "@baseboard_fab2_lib.baseboard_fab2(sch_1):\PP3385\"
				( pinRef "@baseboard_fab2_lib.baseboard_fab2(sch_1):page61_i172:DDR4_MA(10)" )
				( pinRef "@baseboard_fab2_lib.baseboard_fab2(sch_1):page85_i111:A10" )
				( attribute "RELATIVE_PROPAGATION_DELAY_SCOPE" "G"
					( Parent
						( matchGroupRef "@crescent_city_bb_fab1_lib.crescent_city_bb_fab1(sch_1):\MG_DDR_FAR_DIMM-CLK0_CLS_DDR_L_CAC-CLKS\" )
					)
					( Status sCSetFlattened )
					( Origin gBackEnd )
				)
				( attribute "RELATIVE_PROPAGATION_DELAY" "0.00 MIL,700.00 MIL"
					( Parent
						( matchGroupRef "@crescent_city_bb_fab1_lib.crescent_city_bb_fab1(sch_1):\MG_DDR_FAR_DIMM-CLK0_CLS_DDR_L_CAC-CLKS\" )
					)
					( Units "uMatchProp" "ns" 1.000000)
					( Status sCSetFlattened )
					( Origin gBackEnd )
				)
				( attribute "RELATIVE_PROPAGATION_DELAY_SCOPE" "G"
					( Parent
						( matchGroupRef "@baseboard_fab2_lib.baseboard_fab2(sch_1):\MG_DDR_FAR_DIMM_CMD_NG_DDR_L_DLL_4\" )
					)
					( Status sCSetFlattened )
					( Origin gBackEnd )
				)
				( attribute "RELATIVE_PROPAGATION_DELAY" "0.00 MIL,25.00 MIL"
					( Parent
						( matchGroupRef "@baseboard_fab2_lib.baseboard_fab2(sch_1):\MG_DDR_FAR_DIMM_CMD_NG_DDR_L_DLL_4\" )
					)
					( Units "uMatchProp" "ns" 1.000000)
					( Status sCSetFlattened )
					( Origin gBackEnd )
				)
			)
			( pinPair "@baseboard_fab2_lib.baseboard_fab2(sch_1):\PP3386\"
				( pinRef "@baseboard_fab2_lib.baseboard_fab2(sch_1):page86_i12:A10" )
				( pinRef "@baseboard_fab2_lib.baseboard_fab2(sch_1):page61_i172:DDR4_MA(10)" )
				( attribute "RELATIVE_PROPAGATION_DELAY_SCOPE" "G"
					( Parent
						( matchGroupRef "@crescent_city_bb_fab1_lib.crescent_city_bb_fab1(sch_1):\MG_DDR_NEAR_DIMM-CLK1_CLS_DDR_L_CAC-CLKS\" )
					)
					( Status sCSetFlattened )
					( Origin gBackEnd )
				)
				( attribute "RELATIVE_PROPAGATION_DELAY" "0.00 MIL,700.00 MIL"
					( Parent
						( matchGroupRef "@crescent_city_bb_fab1_lib.crescent_city_bb_fab1(sch_1):\MG_DDR_NEAR_DIMM-CLK1_CLS_DDR_L_CAC-CLKS\" )
					)
					( Units "uMatchProp" "ns" 1.000000)
					( Status sCSetFlattened )
					( Origin gBackEnd )
				)
				( attribute "RELATIVE_PROPAGATION_DELAY_SCOPE" "G"
					( Parent
						( matchGroupRef "@baseboard_fab2_lib.baseboard_fab2(sch_1):\MG_DDR_CMD_NEAR_DIMM_NG_DDR_L_DLL_4\" )
					)
					( Status sCSetFlattened )
					( Origin gBackEnd )
				)
				( attribute "RELATIVE_PROPAGATION_DELAY" "0.00 MIL,25.00 MIL"
					( Parent
						( matchGroupRef "@baseboard_fab2_lib.baseboard_fab2(sch_1):\MG_DDR_CMD_NEAR_DIMM_NG_DDR_L_DLL_4\" )
					)
					( Units "uMatchProp" "ns" 1.000000)
					( Status sCSetFlattened )
					( Origin gBackEnd )
				)
			)
			( pinPair "@baseboard_fab2_lib.baseboard_fab2(sch_1):\PP3379\"
				( pinRef "@baseboard_fab2_lib.baseboard_fab2(sch_1):page61_i172:DDR4_BA(0)" )
				( pinRef "@baseboard_fab2_lib.baseboard_fab2(sch_1):page85_i111:BA(0)" )
				( attribute "RELATIVE_PROPAGATION_DELAY_SCOPE" "G"
					( Parent
						( matchGroupRef "@crescent_city_bb_fab1_lib.crescent_city_bb_fab1(sch_1):\MG_DDR_FAR_DIMM-CLK0_CLS_DDR_L_CAC-CLKS\" )
					)
					( Status sCSetFlattened )
					( Origin gBackEnd )
				)
				( attribute "RELATIVE_PROPAGATION_DELAY" "0.00 MIL,700.00 MIL"
					( Parent
						( matchGroupRef "@crescent_city_bb_fab1_lib.crescent_city_bb_fab1(sch_1):\MG_DDR_FAR_DIMM-CLK0_CLS_DDR_L_CAC-CLKS\" )
					)
					( Units "uMatchProp" "ns" 1.000000)
					( Status sCSetFlattened )
					( Origin gBackEnd )
				)
				( attribute "RELATIVE_PROPAGATION_DELAY_SCOPE" "G"
					( Parent
						( matchGroupRef "@baseboard_fab2_lib.baseboard_fab2(sch_1):\MG_DDR_FAR_DIMM_CMD_NG_DDR_L_DLL_5\" )
					)
					( Status sCSetFlattened )
					( Origin gBackEnd )
				)
				( attribute "RELATIVE_PROPAGATION_DELAY" "0.00 MIL,25.00 MIL"
					( Parent
						( matchGroupRef "@baseboard_fab2_lib.baseboard_fab2(sch_1):\MG_DDR_FAR_DIMM_CMD_NG_DDR_L_DLL_5\" )
					)
					( Units "uMatchProp" "ns" 1.000000)
					( Status sCSetFlattened )
					( Origin gBackEnd )
				)
			)
			( pinPair "@baseboard_fab2_lib.baseboard_fab2(sch_1):\PP3380\"
				( pinRef "@baseboard_fab2_lib.baseboard_fab2(sch_1):page86_i12:BA(0)" )
				( pinRef "@baseboard_fab2_lib.baseboard_fab2(sch_1):page61_i172:DDR4_BA(0)" )
				( attribute "RELATIVE_PROPAGATION_DELAY_SCOPE" "G"
					( Parent
						( matchGroupRef "@crescent_city_bb_fab1_lib.crescent_city_bb_fab1(sch_1):\MG_DDR_NEAR_DIMM-CLK1_CLS_DDR_L_CAC-CLKS\" )
					)
					( Status sCSetFlattened )
					( Origin gBackEnd )
				)
				( attribute "RELATIVE_PROPAGATION_DELAY" "0.00 MIL,700.00 MIL"
					( Parent
						( matchGroupRef "@crescent_city_bb_fab1_lib.crescent_city_bb_fab1(sch_1):\MG_DDR_NEAR_DIMM-CLK1_CLS_DDR_L_CAC-CLKS\" )
					)
					( Units "uMatchProp" "ns" 1.000000)
					( Status sCSetFlattened )
					( Origin gBackEnd )
				)
				( attribute "RELATIVE_PROPAGATION_DELAY_SCOPE" "G"
					( Parent
						( matchGroupRef "@baseboard_fab2_lib.baseboard_fab2(sch_1):\MG_DDR_CMD_NEAR_DIMM_NG_DDR_L_DLL_5\" )
					)
					( Status sCSetFlattened )
					( Origin gBackEnd )
				)
				( attribute "RELATIVE_PROPAGATION_DELAY" "0.00 MIL,25.00 MIL"
					( Parent
						( matchGroupRef "@baseboard_fab2_lib.baseboard_fab2(sch_1):\MG_DDR_CMD_NEAR_DIMM_NG_DDR_L_DLL_5\" )
					)
					( Units "uMatchProp" "ns" 1.000000)
					( Status sCSetFlattened )
					( Origin gBackEnd )
				)
			)
			( pinPair "@baseboard_fab2_lib.baseboard_fab2(sch_1):\PP3381\"
				( pinRef "@baseboard_fab2_lib.baseboard_fab2(sch_1):page61_i172:DDR4_MA(0)" )
				( pinRef "@baseboard_fab2_lib.baseboard_fab2(sch_1):page85_i111:A0" )
				( attribute "RELATIVE_PROPAGATION_DELAY_SCOPE" "G"
					( Parent
						( matchGroupRef "@crescent_city_bb_fab1_lib.crescent_city_bb_fab1(sch_1):\MG_DDR_FAR_DIMM-CLK0_CLS_DDR_L_CAC-CLKS\" )
					)
					( Status sCSetFlattened )
					( Origin gBackEnd )
				)
				( attribute "RELATIVE_PROPAGATION_DELAY" "0.00 MIL,700.00 MIL"
					( Parent
						( matchGroupRef "@crescent_city_bb_fab1_lib.crescent_city_bb_fab1(sch_1):\MG_DDR_FAR_DIMM-CLK0_CLS_DDR_L_CAC-CLKS\" )
					)
					( Units "uMatchProp" "ns" 1.000000)
					( Status sCSetFlattened )
					( Origin gBackEnd )
				)
				( attribute "RELATIVE_PROPAGATION_DELAY_SCOPE" "G"
					( Parent
						( matchGroupRef "@baseboard_fab2_lib.baseboard_fab2(sch_1):\MG_DDR_FAR_DIMM_CMD_NG_DDR_L_DLL_5\" )
					)
					( Status sCSetFlattened )
					( Origin gBackEnd )
				)
				( attribute "RELATIVE_PROPAGATION_DELAY" "0.00 MIL,25.00 MIL"
					( Parent
						( matchGroupRef "@baseboard_fab2_lib.baseboard_fab2(sch_1):\MG_DDR_FAR_DIMM_CMD_NG_DDR_L_DLL_5\" )
					)
					( Units "uMatchProp" "ns" 1.000000)
					( Status sCSetFlattened )
					( Origin gBackEnd )
				)
			)
			( pinPair "@baseboard_fab2_lib.baseboard_fab2(sch_1):\PP3382\"
				( pinRef "@baseboard_fab2_lib.baseboard_fab2(sch_1):page86_i12:A0" )
				( pinRef "@baseboard_fab2_lib.baseboard_fab2(sch_1):page61_i172:DDR4_MA(0)" )
				( attribute "RELATIVE_PROPAGATION_DELAY_SCOPE" "G"
					( Parent
						( matchGroupRef "@crescent_city_bb_fab1_lib.crescent_city_bb_fab1(sch_1):\MG_DDR_NEAR_DIMM-CLK1_CLS_DDR_L_CAC-CLKS\" )
					)
					( Status sCSetFlattened )
					( Origin gBackEnd )
				)
				( attribute "RELATIVE_PROPAGATION_DELAY" "0.00 MIL,700.00 MIL"
					( Parent
						( matchGroupRef "@crescent_city_bb_fab1_lib.crescent_city_bb_fab1(sch_1):\MG_DDR_NEAR_DIMM-CLK1_CLS_DDR_L_CAC-CLKS\" )
					)
					( Units "uMatchProp" "ns" 1.000000)
					( Status sCSetFlattened )
					( Origin gBackEnd )
				)
				( attribute "RELATIVE_PROPAGATION_DELAY_SCOPE" "G"
					( Parent
						( matchGroupRef "@baseboard_fab2_lib.baseboard_fab2(sch_1):\MG_DDR_CMD_NEAR_DIMM_NG_DDR_L_DLL_5\" )
					)
					( Status sCSetFlattened )
					( Origin gBackEnd )
				)
				( attribute "RELATIVE_PROPAGATION_DELAY" "0.00 MIL,25.00 MIL"
					( Parent
						( matchGroupRef "@baseboard_fab2_lib.baseboard_fab2(sch_1):\MG_DDR_CMD_NEAR_DIMM_NG_DDR_L_DLL_5\" )
					)
					( Units "uMatchProp" "ns" 1.000000)
					( Status sCSetFlattened )
					( Origin gBackEnd )
				)
			)
			( pinPair "@baseboard_fab2_lib.baseboard_fab2(sch_1):\PP3377\"
				( pinRef "@baseboard_fab2_lib.baseboard_fab2(sch_1):page61_i172:DDR4_PAR" )
				( pinRef "@baseboard_fab2_lib.baseboard_fab2(sch_1):page85_i111:PAR" )
				( attribute "RELATIVE_PROPAGATION_DELAY_SCOPE" "G"
					( Parent
						( matchGroupRef "@crescent_city_bb_fab1_lib.crescent_city_bb_fab1(sch_1):\MG_DDR_FAR_DIMM-CLK0_CLS_DDR_L_CAC-CLKS\" )
					)
					( Status sCSetFlattened )
					( Origin gBackEnd )
				)
				( attribute "RELATIVE_PROPAGATION_DELAY" "0.00 MIL,700.00 MIL"
					( Parent
						( matchGroupRef "@crescent_city_bb_fab1_lib.crescent_city_bb_fab1(sch_1):\MG_DDR_FAR_DIMM-CLK0_CLS_DDR_L_CAC-CLKS\" )
					)
					( Units "uMatchProp" "ns" 1.000000)
					( Status sCSetFlattened )
					( Origin gBackEnd )
				)
				( attribute "RELATIVE_PROPAGATION_DELAY_SCOPE" "G"
					( Parent
						( matchGroupRef "@baseboard_fab2_lib.baseboard_fab2(sch_1):\MG_DDR_FAR_DIMM_CMD_NG_DDR_L_DLL_6\" )
					)
					( Status sCSetFlattened )
					( Origin gBackEnd )
				)
				( attribute "RELATIVE_PROPAGATION_DELAY" "0.00 MIL,25.00 MIL"
					( Parent
						( matchGroupRef "@baseboard_fab2_lib.baseboard_fab2(sch_1):\MG_DDR_FAR_DIMM_CMD_NG_DDR_L_DLL_6\" )
					)
					( Units "uMatchProp" "ns" 1.000000)
					( Status sCSetFlattened )
					( Origin gBackEnd )
				)
			)
			( pinPair "@baseboard_fab2_lib.baseboard_fab2(sch_1):\PP3378\"
				( pinRef "@baseboard_fab2_lib.baseboard_fab2(sch_1):page86_i12:PAR" )
				( pinRef "@baseboard_fab2_lib.baseboard_fab2(sch_1):page61_i172:DDR4_PAR" )
				( attribute "RELATIVE_PROPAGATION_DELAY_SCOPE" "G"
					( Parent
						( matchGroupRef "@crescent_city_bb_fab1_lib.crescent_city_bb_fab1(sch_1):\MG_DDR_NEAR_DIMM-CLK1_CLS_DDR_L_CAC-CLKS\" )
					)
					( Status sCSetFlattened )
					( Origin gBackEnd )
				)
				( attribute "RELATIVE_PROPAGATION_DELAY" "0.00 MIL,700.00 MIL"
					( Parent
						( matchGroupRef "@crescent_city_bb_fab1_lib.crescent_city_bb_fab1(sch_1):\MG_DDR_NEAR_DIMM-CLK1_CLS_DDR_L_CAC-CLKS\" )
					)
					( Units "uMatchProp" "ns" 1.000000)
					( Status sCSetFlattened )
					( Origin gBackEnd )
				)
				( attribute "RELATIVE_PROPAGATION_DELAY_SCOPE" "G"
					( Parent
						( matchGroupRef "@baseboard_fab2_lib.baseboard_fab2(sch_1):\MG_DDR_CMD_NEAR_DIMM_NG_DDR_L_DLL_6\" )
					)
					( Status sCSetFlattened )
					( Origin gBackEnd )
				)
				( attribute "RELATIVE_PROPAGATION_DELAY" "0.00 MIL,25.00 MIL"
					( Parent
						( matchGroupRef "@baseboard_fab2_lib.baseboard_fab2(sch_1):\MG_DDR_CMD_NEAR_DIMM_NG_DDR_L_DLL_6\" )
					)
					( Units "uMatchProp" "ns" 1.000000)
					( Status sCSetFlattened )
					( Origin gBackEnd )
				)
			)
			( pinPair "@baseboard_fab2_lib.baseboard_fab2(sch_1):\PP3373\"
				( pinRef "@baseboard_fab2_lib.baseboard_fab2(sch_1):page61_i172:DDR4_MA(1)" )
				( pinRef "@baseboard_fab2_lib.baseboard_fab2(sch_1):page85_i111:A1" )
				( attribute "RELATIVE_PROPAGATION_DELAY_SCOPE" "G"
					( Parent
						( matchGroupRef "@crescent_city_bb_fab1_lib.crescent_city_bb_fab1(sch_1):\MG_DDR_FAR_DIMM-CLK0_CLS_DDR_L_CAC-CLKS\" )
					)
					( Status sCSetFlattened )
					( Origin gBackEnd )
				)
				( attribute "RELATIVE_PROPAGATION_DELAY" "0.00 MIL,700.00 MIL"
					( Parent
						( matchGroupRef "@crescent_city_bb_fab1_lib.crescent_city_bb_fab1(sch_1):\MG_DDR_FAR_DIMM-CLK0_CLS_DDR_L_CAC-CLKS\" )
					)
					( Units "uMatchProp" "ns" 1.000000)
					( Status sCSetFlattened )
					( Origin gBackEnd )
				)
				( attribute "RELATIVE_PROPAGATION_DELAY_SCOPE" "G"
					( Parent
						( matchGroupRef "@baseboard_fab2_lib.baseboard_fab2(sch_1):\MG_DDR_FAR_DIMM_CMD_NG_DDR_L_DLL_7\" )
					)
					( Status sCSetFlattened )
					( Origin gBackEnd )
				)
				( attribute "RELATIVE_PROPAGATION_DELAY" "0.00 MIL,25.00 MIL"
					( Parent
						( matchGroupRef "@baseboard_fab2_lib.baseboard_fab2(sch_1):\MG_DDR_FAR_DIMM_CMD_NG_DDR_L_DLL_7\" )
					)
					( Units "uMatchProp" "ns" 1.000000)
					( Status sCSetFlattened )
					( Origin gBackEnd )
				)
			)
			( pinPair "@baseboard_fab2_lib.baseboard_fab2(sch_1):\PP3374\"
				( pinRef "@baseboard_fab2_lib.baseboard_fab2(sch_1):page86_i12:A1" )
				( pinRef "@baseboard_fab2_lib.baseboard_fab2(sch_1):page61_i172:DDR4_MA(1)" )
				( attribute "RELATIVE_PROPAGATION_DELAY_SCOPE" "G"
					( Parent
						( matchGroupRef "@crescent_city_bb_fab1_lib.crescent_city_bb_fab1(sch_1):\MG_DDR_NEAR_DIMM-CLK1_CLS_DDR_L_CAC-CLKS\" )
					)
					( Status sCSetFlattened )
					( Origin gBackEnd )
				)
				( attribute "RELATIVE_PROPAGATION_DELAY" "0.00 MIL,700.00 MIL"
					( Parent
						( matchGroupRef "@crescent_city_bb_fab1_lib.crescent_city_bb_fab1(sch_1):\MG_DDR_NEAR_DIMM-CLK1_CLS_DDR_L_CAC-CLKS\" )
					)
					( Units "uMatchProp" "ns" 1.000000)
					( Status sCSetFlattened )
					( Origin gBackEnd )
				)
				( attribute "RELATIVE_PROPAGATION_DELAY_SCOPE" "G"
					( Parent
						( matchGroupRef "@baseboard_fab2_lib.baseboard_fab2(sch_1):\MG_DDR_CMD_NEAR_DIMM_NG_DDR_L_DLL_7\" )
					)
					( Status sCSetFlattened )
					( Origin gBackEnd )
				)
				( attribute "RELATIVE_PROPAGATION_DELAY" "0.00 MIL,25.00 MIL"
					( Parent
						( matchGroupRef "@baseboard_fab2_lib.baseboard_fab2(sch_1):\MG_DDR_CMD_NEAR_DIMM_NG_DDR_L_DLL_7\" )
					)
					( Units "uMatchProp" "ns" 1.000000)
					( Status sCSetFlattened )
					( Origin gBackEnd )
				)
			)
			( pinPair "@baseboard_fab2_lib.baseboard_fab2(sch_1):\PP3375\"
				( pinRef "@baseboard_fab2_lib.baseboard_fab2(sch_1):page61_i172:DDR4_MA(3)" )
				( pinRef "@baseboard_fab2_lib.baseboard_fab2(sch_1):page85_i111:A3" )
				( attribute "RELATIVE_PROPAGATION_DELAY_SCOPE" "G"
					( Parent
						( matchGroupRef "@crescent_city_bb_fab1_lib.crescent_city_bb_fab1(sch_1):\MG_DDR_FAR_DIMM-CLK0_CLS_DDR_L_CAC-CLKS\" )
					)
					( Status sCSetFlattened )
					( Origin gBackEnd )
				)
				( attribute "RELATIVE_PROPAGATION_DELAY" "0.00 MIL,700.00 MIL"
					( Parent
						( matchGroupRef "@crescent_city_bb_fab1_lib.crescent_city_bb_fab1(sch_1):\MG_DDR_FAR_DIMM-CLK0_CLS_DDR_L_CAC-CLKS\" )
					)
					( Units "uMatchProp" "ns" 1.000000)
					( Status sCSetFlattened )
					( Origin gBackEnd )
				)
				( attribute "RELATIVE_PROPAGATION_DELAY_SCOPE" "G"
					( Parent
						( matchGroupRef "@baseboard_fab2_lib.baseboard_fab2(sch_1):\MG_DDR_FAR_DIMM_CMD_NG_DDR_L_DLL_7\" )
					)
					( Status sCSetFlattened )
					( Origin gBackEnd )
				)
				( attribute "RELATIVE_PROPAGATION_DELAY" "0.00 MIL,25.00 MIL"
					( Parent
						( matchGroupRef "@baseboard_fab2_lib.baseboard_fab2(sch_1):\MG_DDR_FAR_DIMM_CMD_NG_DDR_L_DLL_7\" )
					)
					( Units "uMatchProp" "ns" 1.000000)
					( Status sCSetFlattened )
					( Origin gBackEnd )
				)
			)
			( pinPair "@baseboard_fab2_lib.baseboard_fab2(sch_1):\PP3376\"
				( pinRef "@baseboard_fab2_lib.baseboard_fab2(sch_1):page86_i12:A3" )
				( pinRef "@baseboard_fab2_lib.baseboard_fab2(sch_1):page61_i172:DDR4_MA(3)" )
				( attribute "RELATIVE_PROPAGATION_DELAY_SCOPE" "G"
					( Parent
						( matchGroupRef "@crescent_city_bb_fab1_lib.crescent_city_bb_fab1(sch_1):\MG_DDR_NEAR_DIMM-CLK1_CLS_DDR_L_CAC-CLKS\" )
					)
					( Status sCSetFlattened )
					( Origin gBackEnd )
				)
				( attribute "RELATIVE_PROPAGATION_DELAY" "0.00 MIL,700.00 MIL"
					( Parent
						( matchGroupRef "@crescent_city_bb_fab1_lib.crescent_city_bb_fab1(sch_1):\MG_DDR_NEAR_DIMM-CLK1_CLS_DDR_L_CAC-CLKS\" )
					)
					( Units "uMatchProp" "ns" 1.000000)
					( Status sCSetFlattened )
					( Origin gBackEnd )
				)
				( attribute "RELATIVE_PROPAGATION_DELAY_SCOPE" "G"
					( Parent
						( matchGroupRef "@baseboard_fab2_lib.baseboard_fab2(sch_1):\MG_DDR_CMD_NEAR_DIMM_NG_DDR_L_DLL_7\" )
					)
					( Status sCSetFlattened )
					( Origin gBackEnd )
				)
				( attribute "RELATIVE_PROPAGATION_DELAY" "0.00 MIL,25.00 MIL"
					( Parent
						( matchGroupRef "@baseboard_fab2_lib.baseboard_fab2(sch_1):\MG_DDR_CMD_NEAR_DIMM_NG_DDR_L_DLL_7\" )
					)
					( Units "uMatchProp" "ns" 1.000000)
					( Status sCSetFlattened )
					( Origin gBackEnd )
				)
			)
			( pinPair "@baseboard_fab2_lib.baseboard_fab2(sch_1):\PP3369\"
				( pinRef "@baseboard_fab2_lib.baseboard_fab2(sch_1):page61_i172:DDR4_MA(2)" )
				( pinRef "@baseboard_fab2_lib.baseboard_fab2(sch_1):page85_i111:A2" )
				( attribute "RELATIVE_PROPAGATION_DELAY_SCOPE" "G"
					( Parent
						( matchGroupRef "@crescent_city_bb_fab1_lib.crescent_city_bb_fab1(sch_1):\MG_DDR_FAR_DIMM-CLK0_CLS_DDR_L_CAC-CLKS\" )
					)
					( Status sCSetFlattened )
					( Origin gBackEnd )
				)
				( attribute "RELATIVE_PROPAGATION_DELAY" "0.00 MIL,700.00 MIL"
					( Parent
						( matchGroupRef "@crescent_city_bb_fab1_lib.crescent_city_bb_fab1(sch_1):\MG_DDR_FAR_DIMM-CLK0_CLS_DDR_L_CAC-CLKS\" )
					)
					( Units "uMatchProp" "ns" 1.000000)
					( Status sCSetFlattened )
					( Origin gBackEnd )
				)
				( attribute "RELATIVE_PROPAGATION_DELAY_SCOPE" "G"
					( Parent
						( matchGroupRef "@baseboard_fab2_lib.baseboard_fab2(sch_1):\MG_DDR_FAR_DIMM_CMD_NG_DDR_L_DLL_8\" )
					)
					( Status sCSetFlattened )
					( Origin gBackEnd )
				)
				( attribute "RELATIVE_PROPAGATION_DELAY" "0.00 MIL,25.00 MIL"
					( Parent
						( matchGroupRef "@baseboard_fab2_lib.baseboard_fab2(sch_1):\MG_DDR_FAR_DIMM_CMD_NG_DDR_L_DLL_8\" )
					)
					( Units "uMatchProp" "ns" 1.000000)
					( Status sCSetFlattened )
					( Origin gBackEnd )
				)
			)
			( pinPair "@baseboard_fab2_lib.baseboard_fab2(sch_1):\PP3370\"
				( pinRef "@baseboard_fab2_lib.baseboard_fab2(sch_1):page86_i12:A2" )
				( pinRef "@baseboard_fab2_lib.baseboard_fab2(sch_1):page61_i172:DDR4_MA(2)" )
				( attribute "RELATIVE_PROPAGATION_DELAY_SCOPE" "G"
					( Parent
						( matchGroupRef "@crescent_city_bb_fab1_lib.crescent_city_bb_fab1(sch_1):\MG_DDR_NEAR_DIMM-CLK1_CLS_DDR_L_CAC-CLKS\" )
					)
					( Status sCSetFlattened )
					( Origin gBackEnd )
				)
				( attribute "RELATIVE_PROPAGATION_DELAY" "0.00 MIL,700.00 MIL"
					( Parent
						( matchGroupRef "@crescent_city_bb_fab1_lib.crescent_city_bb_fab1(sch_1):\MG_DDR_NEAR_DIMM-CLK1_CLS_DDR_L_CAC-CLKS\" )
					)
					( Units "uMatchProp" "ns" 1.000000)
					( Status sCSetFlattened )
					( Origin gBackEnd )
				)
				( attribute "RELATIVE_PROPAGATION_DELAY_SCOPE" "G"
					( Parent
						( matchGroupRef "@baseboard_fab2_lib.baseboard_fab2(sch_1):\MG_DDR_CMD_NEAR_DIMM_NG_DDR_L_DLL_8\" )
					)
					( Status sCSetFlattened )
					( Origin gBackEnd )
				)
				( attribute "RELATIVE_PROPAGATION_DELAY" "0.00 MIL,25.00 MIL"
					( Parent
						( matchGroupRef "@baseboard_fab2_lib.baseboard_fab2(sch_1):\MG_DDR_CMD_NEAR_DIMM_NG_DDR_L_DLL_8\" )
					)
					( Units "uMatchProp" "ns" 1.000000)
					( Status sCSetFlattened )
					( Origin gBackEnd )
				)
			)
			( pinPair "@baseboard_fab2_lib.baseboard_fab2(sch_1):\PP3371\"
				( pinRef "@baseboard_fab2_lib.baseboard_fab2(sch_1):page61_i172:DDR4_MA(4)" )
				( pinRef "@baseboard_fab2_lib.baseboard_fab2(sch_1):page85_i111:A4" )
				( attribute "RELATIVE_PROPAGATION_DELAY_SCOPE" "G"
					( Parent
						( matchGroupRef "@crescent_city_bb_fab1_lib.crescent_city_bb_fab1(sch_1):\MG_DDR_FAR_DIMM-CLK0_CLS_DDR_L_CAC-CLKS\" )
					)
					( Status sCSetFlattened )
					( Origin gBackEnd )
				)
				( attribute "RELATIVE_PROPAGATION_DELAY" "0.00 MIL,700.00 MIL"
					( Parent
						( matchGroupRef "@crescent_city_bb_fab1_lib.crescent_city_bb_fab1(sch_1):\MG_DDR_FAR_DIMM-CLK0_CLS_DDR_L_CAC-CLKS\" )
					)
					( Units "uMatchProp" "ns" 1.000000)
					( Status sCSetFlattened )
					( Origin gBackEnd )
				)
				( attribute "RELATIVE_PROPAGATION_DELAY_SCOPE" "G"
					( Parent
						( matchGroupRef "@baseboard_fab2_lib.baseboard_fab2(sch_1):\MG_DDR_FAR_DIMM_CMD_NG_DDR_L_DLL_8\" )
					)
					( Status sCSetFlattened )
					( Origin gBackEnd )
				)
				( attribute "RELATIVE_PROPAGATION_DELAY" "0.00 MIL,25.00 MIL"
					( Parent
						( matchGroupRef "@baseboard_fab2_lib.baseboard_fab2(sch_1):\MG_DDR_FAR_DIMM_CMD_NG_DDR_L_DLL_8\" )
					)
					( Units "uMatchProp" "ns" 1.000000)
					( Status sCSetFlattened )
					( Origin gBackEnd )
				)
			)
			( pinPair "@baseboard_fab2_lib.baseboard_fab2(sch_1):\PP3372\"
				( pinRef "@baseboard_fab2_lib.baseboard_fab2(sch_1):page86_i12:A4" )
				( pinRef "@baseboard_fab2_lib.baseboard_fab2(sch_1):page61_i172:DDR4_MA(4)" )
				( attribute "RELATIVE_PROPAGATION_DELAY_SCOPE" "G"
					( Parent
						( matchGroupRef "@crescent_city_bb_fab1_lib.crescent_city_bb_fab1(sch_1):\MG_DDR_NEAR_DIMM-CLK1_CLS_DDR_L_CAC-CLKS\" )
					)
					( Status sCSetFlattened )
					( Origin gBackEnd )
				)
				( attribute "RELATIVE_PROPAGATION_DELAY" "0.00 MIL,700.00 MIL"
					( Parent
						( matchGroupRef "@crescent_city_bb_fab1_lib.crescent_city_bb_fab1(sch_1):\MG_DDR_NEAR_DIMM-CLK1_CLS_DDR_L_CAC-CLKS\" )
					)
					( Units "uMatchProp" "ns" 1.000000)
					( Status sCSetFlattened )
					( Origin gBackEnd )
				)
				( attribute "RELATIVE_PROPAGATION_DELAY_SCOPE" "G"
					( Parent
						( matchGroupRef "@baseboard_fab2_lib.baseboard_fab2(sch_1):\MG_DDR_CMD_NEAR_DIMM_NG_DDR_L_DLL_8\" )
					)
					( Status sCSetFlattened )
					( Origin gBackEnd )
				)
				( attribute "RELATIVE_PROPAGATION_DELAY" "0.00 MIL,25.00 MIL"
					( Parent
						( matchGroupRef "@baseboard_fab2_lib.baseboard_fab2(sch_1):\MG_DDR_CMD_NEAR_DIMM_NG_DDR_L_DLL_8\" )
					)
					( Units "uMatchProp" "ns" 1.000000)
					( Status sCSetFlattened )
					( Origin gBackEnd )
				)
			)
			( pinPair "@baseboard_fab2_lib.baseboard_fab2(sch_1):\PP3365\"
				( pinRef "@baseboard_fab2_lib.baseboard_fab2(sch_1):page61_i172:DDR4_MA(5)" )
				( pinRef "@baseboard_fab2_lib.baseboard_fab2(sch_1):page85_i111:A5" )
				( attribute "RELATIVE_PROPAGATION_DELAY_SCOPE" "G"
					( Parent
						( matchGroupRef "@crescent_city_bb_fab1_lib.crescent_city_bb_fab1(sch_1):\MG_DDR_FAR_DIMM-CLK0_CLS_DDR_L_CAC-CLKS\" )
					)
					( Status sCSetFlattened )
					( Origin gBackEnd )
				)
				( attribute "RELATIVE_PROPAGATION_DELAY" "0.00 MIL,700.00 MIL"
					( Parent
						( matchGroupRef "@crescent_city_bb_fab1_lib.crescent_city_bb_fab1(sch_1):\MG_DDR_FAR_DIMM-CLK0_CLS_DDR_L_CAC-CLKS\" )
					)
					( Units "uMatchProp" "ns" 1.000000)
					( Status sCSetFlattened )
					( Origin gBackEnd )
				)
				( attribute "RELATIVE_PROPAGATION_DELAY_SCOPE" "G"
					( Parent
						( matchGroupRef "@baseboard_fab2_lib.baseboard_fab2(sch_1):\MG_DDR_FAR_DIMM_CMD_NG_DDR_L_DLL_9\" )
					)
					( Status sCSetFlattened )
					( Origin gBackEnd )
				)
				( attribute "RELATIVE_PROPAGATION_DELAY" "0.00 MIL,25.00 MIL"
					( Parent
						( matchGroupRef "@baseboard_fab2_lib.baseboard_fab2(sch_1):\MG_DDR_FAR_DIMM_CMD_NG_DDR_L_DLL_9\" )
					)
					( Units "uMatchProp" "ns" 1.000000)
					( Status sCSetFlattened )
					( Origin gBackEnd )
				)
			)
			( pinPair "@baseboard_fab2_lib.baseboard_fab2(sch_1):\PP3366\"
				( pinRef "@baseboard_fab2_lib.baseboard_fab2(sch_1):page86_i12:A5" )
				( pinRef "@baseboard_fab2_lib.baseboard_fab2(sch_1):page61_i172:DDR4_MA(5)" )
				( attribute "RELATIVE_PROPAGATION_DELAY_SCOPE" "G"
					( Parent
						( matchGroupRef "@crescent_city_bb_fab1_lib.crescent_city_bb_fab1(sch_1):\MG_DDR_NEAR_DIMM-CLK1_CLS_DDR_L_CAC-CLKS\" )
					)
					( Status sCSetFlattened )
					( Origin gBackEnd )
				)
				( attribute "RELATIVE_PROPAGATION_DELAY" "0.00 MIL,700.00 MIL"
					( Parent
						( matchGroupRef "@crescent_city_bb_fab1_lib.crescent_city_bb_fab1(sch_1):\MG_DDR_NEAR_DIMM-CLK1_CLS_DDR_L_CAC-CLKS\" )
					)
					( Units "uMatchProp" "ns" 1.000000)
					( Status sCSetFlattened )
					( Origin gBackEnd )
				)
				( attribute "RELATIVE_PROPAGATION_DELAY_SCOPE" "G"
					( Parent
						( matchGroupRef "@baseboard_fab2_lib.baseboard_fab2(sch_1):\MG_DDR_CMD_NEAR_DIMM_NG_DDR_L_DLL_9\" )
					)
					( Status sCSetFlattened )
					( Origin gBackEnd )
				)
				( attribute "RELATIVE_PROPAGATION_DELAY" "0.00 MIL,25.00 MIL"
					( Parent
						( matchGroupRef "@baseboard_fab2_lib.baseboard_fab2(sch_1):\MG_DDR_CMD_NEAR_DIMM_NG_DDR_L_DLL_9\" )
					)
					( Units "uMatchProp" "ns" 1.000000)
					( Status sCSetFlattened )
					( Origin gBackEnd )
				)
			)
			( pinPair "@baseboard_fab2_lib.baseboard_fab2(sch_1):\PP3367\"
				( pinRef "@baseboard_fab2_lib.baseboard_fab2(sch_1):page61_i172:DDR4_MA(6)" )
				( pinRef "@baseboard_fab2_lib.baseboard_fab2(sch_1):page85_i111:A6" )
				( attribute "RELATIVE_PROPAGATION_DELAY_SCOPE" "G"
					( Parent
						( matchGroupRef "@crescent_city_bb_fab1_lib.crescent_city_bb_fab1(sch_1):\MG_DDR_FAR_DIMM-CLK0_CLS_DDR_L_CAC-CLKS\" )
					)
					( Status sCSetFlattened )
					( Origin gBackEnd )
				)
				( attribute "RELATIVE_PROPAGATION_DELAY" "0.00 MIL,700.00 MIL"
					( Parent
						( matchGroupRef "@crescent_city_bb_fab1_lib.crescent_city_bb_fab1(sch_1):\MG_DDR_FAR_DIMM-CLK0_CLS_DDR_L_CAC-CLKS\" )
					)
					( Units "uMatchProp" "ns" 1.000000)
					( Status sCSetFlattened )
					( Origin gBackEnd )
				)
				( attribute "RELATIVE_PROPAGATION_DELAY_SCOPE" "G"
					( Parent
						( matchGroupRef "@baseboard_fab2_lib.baseboard_fab2(sch_1):\MG_DDR_FAR_DIMM_CMD_NG_DDR_L_DLL_9\" )
					)
					( Status sCSetFlattened )
					( Origin gBackEnd )
				)
				( attribute "RELATIVE_PROPAGATION_DELAY" "0.00 MIL,25.00 MIL"
					( Parent
						( matchGroupRef "@baseboard_fab2_lib.baseboard_fab2(sch_1):\MG_DDR_FAR_DIMM_CMD_NG_DDR_L_DLL_9\" )
					)
					( Units "uMatchProp" "ns" 1.000000)
					( Status sCSetFlattened )
					( Origin gBackEnd )
				)
			)
			( pinPair "@baseboard_fab2_lib.baseboard_fab2(sch_1):\PP3368\"
				( pinRef "@baseboard_fab2_lib.baseboard_fab2(sch_1):page86_i12:A6" )
				( pinRef "@baseboard_fab2_lib.baseboard_fab2(sch_1):page61_i172:DDR4_MA(6)" )
				( attribute "RELATIVE_PROPAGATION_DELAY_SCOPE" "G"
					( Parent
						( matchGroupRef "@crescent_city_bb_fab1_lib.crescent_city_bb_fab1(sch_1):\MG_DDR_NEAR_DIMM-CLK1_CLS_DDR_L_CAC-CLKS\" )
					)
					( Status sCSetFlattened )
					( Origin gBackEnd )
				)
				( attribute "RELATIVE_PROPAGATION_DELAY" "0.00 MIL,700.00 MIL"
					( Parent
						( matchGroupRef "@crescent_city_bb_fab1_lib.crescent_city_bb_fab1(sch_1):\MG_DDR_NEAR_DIMM-CLK1_CLS_DDR_L_CAC-CLKS\" )
					)
					( Units "uMatchProp" "ns" 1.000000)
					( Status sCSetFlattened )
					( Origin gBackEnd )
				)
				( attribute "RELATIVE_PROPAGATION_DELAY_SCOPE" "G"
					( Parent
						( matchGroupRef "@baseboard_fab2_lib.baseboard_fab2(sch_1):\MG_DDR_CMD_NEAR_DIMM_NG_DDR_L_DLL_9\" )
					)
					( Status sCSetFlattened )
					( Origin gBackEnd )
				)
				( attribute "RELATIVE_PROPAGATION_DELAY" "0.00 MIL,25.00 MIL"
					( Parent
						( matchGroupRef "@baseboard_fab2_lib.baseboard_fab2(sch_1):\MG_DDR_CMD_NEAR_DIMM_NG_DDR_L_DLL_9\" )
					)
					( Units "uMatchProp" "ns" 1.000000)
					( Status sCSetFlattened )
					( Origin gBackEnd )
				)
			)
			( pinPair "@baseboard_fab2_lib.baseboard_fab2(sch_1):\PP3361\"
				( pinRef "@baseboard_fab2_lib.baseboard_fab2(sch_1):page61_i172:DDR4_MA(7)" )
				( pinRef "@baseboard_fab2_lib.baseboard_fab2(sch_1):page85_i111:A7" )
				( attribute "RELATIVE_PROPAGATION_DELAY_SCOPE" "G"
					( Parent
						( matchGroupRef "@crescent_city_bb_fab1_lib.crescent_city_bb_fab1(sch_1):\MG_DDR_FAR_DIMM-CLK0_CLS_DDR_L_CAC-CLKS\" )
					)
					( Status sCSetFlattened )
					( Origin gBackEnd )
				)
				( attribute "RELATIVE_PROPAGATION_DELAY" "0.00 MIL,700.00 MIL"
					( Parent
						( matchGroupRef "@crescent_city_bb_fab1_lib.crescent_city_bb_fab1(sch_1):\MG_DDR_FAR_DIMM-CLK0_CLS_DDR_L_CAC-CLKS\" )
					)
					( Units "uMatchProp" "ns" 1.000000)
					( Status sCSetFlattened )
					( Origin gBackEnd )
				)
				( attribute "RELATIVE_PROPAGATION_DELAY_SCOPE" "G"
					( Parent
						( matchGroupRef "@baseboard_fab2_lib.baseboard_fab2(sch_1):\MG_DDR_FAR_DIMM_CMD_NG_DDR_L_DLL_10\" )
					)
					( Status sCSetFlattened )
					( Origin gBackEnd )
				)
				( attribute "RELATIVE_PROPAGATION_DELAY" "0.00 MIL,25.00 MIL"
					( Parent
						( matchGroupRef "@baseboard_fab2_lib.baseboard_fab2(sch_1):\MG_DDR_FAR_DIMM_CMD_NG_DDR_L_DLL_10\" )
					)
					( Units "uMatchProp" "ns" 1.000000)
					( Status sCSetFlattened )
					( Origin gBackEnd )
				)
			)
			( pinPair "@baseboard_fab2_lib.baseboard_fab2(sch_1):\PP3362\"
				( pinRef "@baseboard_fab2_lib.baseboard_fab2(sch_1):page86_i12:A7" )
				( pinRef "@baseboard_fab2_lib.baseboard_fab2(sch_1):page61_i172:DDR4_MA(7)" )
				( attribute "RELATIVE_PROPAGATION_DELAY_SCOPE" "G"
					( Parent
						( matchGroupRef "@crescent_city_bb_fab1_lib.crescent_city_bb_fab1(sch_1):\MG_DDR_NEAR_DIMM-CLK1_CLS_DDR_L_CAC-CLKS\" )
					)
					( Status sCSetFlattened )
					( Origin gBackEnd )
				)
				( attribute "RELATIVE_PROPAGATION_DELAY" "0.00 MIL,700.00 MIL"
					( Parent
						( matchGroupRef "@crescent_city_bb_fab1_lib.crescent_city_bb_fab1(sch_1):\MG_DDR_NEAR_DIMM-CLK1_CLS_DDR_L_CAC-CLKS\" )
					)
					( Units "uMatchProp" "ns" 1.000000)
					( Status sCSetFlattened )
					( Origin gBackEnd )
				)
				( attribute "RELATIVE_PROPAGATION_DELAY_SCOPE" "G"
					( Parent
						( matchGroupRef "@baseboard_fab2_lib.baseboard_fab2(sch_1):\MG_DDR_CMD_NEAR_DIMM_NG_DDR_L_DLL_10\" )
					)
					( Status sCSetFlattened )
					( Origin gBackEnd )
				)
				( attribute "RELATIVE_PROPAGATION_DELAY" "0.00 MIL,25.00 MIL"
					( Parent
						( matchGroupRef "@baseboard_fab2_lib.baseboard_fab2(sch_1):\MG_DDR_CMD_NEAR_DIMM_NG_DDR_L_DLL_10\" )
					)
					( Units "uMatchProp" "ns" 1.000000)
					( Status sCSetFlattened )
					( Origin gBackEnd )
				)
			)
			( pinPair "@baseboard_fab2_lib.baseboard_fab2(sch_1):\PP3363\"
				( pinRef "@baseboard_fab2_lib.baseboard_fab2(sch_1):page61_i172:DDR4_MA(8)" )
				( pinRef "@baseboard_fab2_lib.baseboard_fab2(sch_1):page85_i111:A8" )
				( attribute "RELATIVE_PROPAGATION_DELAY_SCOPE" "G"
					( Parent
						( matchGroupRef "@crescent_city_bb_fab1_lib.crescent_city_bb_fab1(sch_1):\MG_DDR_FAR_DIMM-CLK0_CLS_DDR_L_CAC-CLKS\" )
					)
					( Status sCSetFlattened )
					( Origin gBackEnd )
				)
				( attribute "RELATIVE_PROPAGATION_DELAY" "0.00 MIL,700.00 MIL"
					( Parent
						( matchGroupRef "@crescent_city_bb_fab1_lib.crescent_city_bb_fab1(sch_1):\MG_DDR_FAR_DIMM-CLK0_CLS_DDR_L_CAC-CLKS\" )
					)
					( Units "uMatchProp" "ns" 1.000000)
					( Status sCSetFlattened )
					( Origin gBackEnd )
				)
				( attribute "RELATIVE_PROPAGATION_DELAY_SCOPE" "G"
					( Parent
						( matchGroupRef "@baseboard_fab2_lib.baseboard_fab2(sch_1):\MG_DDR_FAR_DIMM_CMD_NG_DDR_L_DLL_10\" )
					)
					( Status sCSetFlattened )
					( Origin gBackEnd )
				)
				( attribute "RELATIVE_PROPAGATION_DELAY" "0.00 MIL,25.00 MIL"
					( Parent
						( matchGroupRef "@baseboard_fab2_lib.baseboard_fab2(sch_1):\MG_DDR_FAR_DIMM_CMD_NG_DDR_L_DLL_10\" )
					)
					( Units "uMatchProp" "ns" 1.000000)
					( Status sCSetFlattened )
					( Origin gBackEnd )
				)
			)
			( pinPair "@baseboard_fab2_lib.baseboard_fab2(sch_1):\PP3364\"
				( pinRef "@baseboard_fab2_lib.baseboard_fab2(sch_1):page86_i12:A8" )
				( pinRef "@baseboard_fab2_lib.baseboard_fab2(sch_1):page61_i172:DDR4_MA(8)" )
				( attribute "RELATIVE_PROPAGATION_DELAY_SCOPE" "G"
					( Parent
						( matchGroupRef "@crescent_city_bb_fab1_lib.crescent_city_bb_fab1(sch_1):\MG_DDR_NEAR_DIMM-CLK1_CLS_DDR_L_CAC-CLKS\" )
					)
					( Status sCSetFlattened )
					( Origin gBackEnd )
				)
				( attribute "RELATIVE_PROPAGATION_DELAY" "0.00 MIL,700.00 MIL"
					( Parent
						( matchGroupRef "@crescent_city_bb_fab1_lib.crescent_city_bb_fab1(sch_1):\MG_DDR_NEAR_DIMM-CLK1_CLS_DDR_L_CAC-CLKS\" )
					)
					( Units "uMatchProp" "ns" 1.000000)
					( Status sCSetFlattened )
					( Origin gBackEnd )
				)
				( attribute "RELATIVE_PROPAGATION_DELAY_SCOPE" "G"
					( Parent
						( matchGroupRef "@baseboard_fab2_lib.baseboard_fab2(sch_1):\MG_DDR_CMD_NEAR_DIMM_NG_DDR_L_DLL_10\" )
					)
					( Status sCSetFlattened )
					( Origin gBackEnd )
				)
				( attribute "RELATIVE_PROPAGATION_DELAY" "0.00 MIL,25.00 MIL"
					( Parent
						( matchGroupRef "@baseboard_fab2_lib.baseboard_fab2(sch_1):\MG_DDR_CMD_NEAR_DIMM_NG_DDR_L_DLL_10\" )
					)
					( Units "uMatchProp" "ns" 1.000000)
					( Status sCSetFlattened )
					( Origin gBackEnd )
				)
			)
			( pinPair "@baseboard_fab2_lib.baseboard_fab2(sch_1):\PP3357\"
				( pinRef "@baseboard_fab2_lib.baseboard_fab2(sch_1):page61_i172:DDR4_MA(9)" )
				( pinRef "@baseboard_fab2_lib.baseboard_fab2(sch_1):page85_i111:A9" )
				( attribute "RELATIVE_PROPAGATION_DELAY_SCOPE" "G"
					( Parent
						( matchGroupRef "@crescent_city_bb_fab1_lib.crescent_city_bb_fab1(sch_1):\MG_DDR_FAR_DIMM-CLK0_CLS_DDR_L_CAC-CLKS\" )
					)
					( Status sCSetFlattened )
					( Origin gBackEnd )
				)
				( attribute "RELATIVE_PROPAGATION_DELAY" "0.00 MIL,700.00 MIL"
					( Parent
						( matchGroupRef "@crescent_city_bb_fab1_lib.crescent_city_bb_fab1(sch_1):\MG_DDR_FAR_DIMM-CLK0_CLS_DDR_L_CAC-CLKS\" )
					)
					( Units "uMatchProp" "ns" 1.000000)
					( Status sCSetFlattened )
					( Origin gBackEnd )
				)
				( attribute "RELATIVE_PROPAGATION_DELAY_SCOPE" "G"
					( Parent
						( matchGroupRef "@baseboard_fab2_lib.baseboard_fab2(sch_1):\MG_DDR_FAR_DIMM_CMD_NG_DDR_L_DLL_11\" )
					)
					( Status sCSetFlattened )
					( Origin gBackEnd )
				)
				( attribute "RELATIVE_PROPAGATION_DELAY" "0.00 MIL,25.00 MIL"
					( Parent
						( matchGroupRef "@baseboard_fab2_lib.baseboard_fab2(sch_1):\MG_DDR_FAR_DIMM_CMD_NG_DDR_L_DLL_11\" )
					)
					( Units "uMatchProp" "ns" 1.000000)
					( Status sCSetFlattened )
					( Origin gBackEnd )
				)
			)
			( pinPair "@baseboard_fab2_lib.baseboard_fab2(sch_1):\PP3358\"
				( pinRef "@baseboard_fab2_lib.baseboard_fab2(sch_1):page86_i12:A9" )
				( pinRef "@baseboard_fab2_lib.baseboard_fab2(sch_1):page61_i172:DDR4_MA(9)" )
				( attribute "RELATIVE_PROPAGATION_DELAY_SCOPE" "G"
					( Parent
						( matchGroupRef "@crescent_city_bb_fab1_lib.crescent_city_bb_fab1(sch_1):\MG_DDR_NEAR_DIMM-CLK1_CLS_DDR_L_CAC-CLKS\" )
					)
					( Status sCSetFlattened )
					( Origin gBackEnd )
				)
				( attribute "RELATIVE_PROPAGATION_DELAY" "0.00 MIL,700.00 MIL"
					( Parent
						( matchGroupRef "@crescent_city_bb_fab1_lib.crescent_city_bb_fab1(sch_1):\MG_DDR_NEAR_DIMM-CLK1_CLS_DDR_L_CAC-CLKS\" )
					)
					( Units "uMatchProp" "ns" 1.000000)
					( Status sCSetFlattened )
					( Origin gBackEnd )
				)
				( attribute "RELATIVE_PROPAGATION_DELAY_SCOPE" "G"
					( Parent
						( matchGroupRef "@baseboard_fab2_lib.baseboard_fab2(sch_1):\MG_DDR_CMD_NEAR_DIMM_NG_DDR_L_DLL_11\" )
					)
					( Status sCSetFlattened )
					( Origin gBackEnd )
				)
				( attribute "RELATIVE_PROPAGATION_DELAY" "0.00 MIL,25.00 MIL"
					( Parent
						( matchGroupRef "@baseboard_fab2_lib.baseboard_fab2(sch_1):\MG_DDR_CMD_NEAR_DIMM_NG_DDR_L_DLL_11\" )
					)
					( Units "uMatchProp" "ns" 1.000000)
					( Status sCSetFlattened )
					( Origin gBackEnd )
				)
			)
			( pinPair "@baseboard_fab2_lib.baseboard_fab2(sch_1):\PP3359\"
				( pinRef "@baseboard_fab2_lib.baseboard_fab2(sch_1):page61_i172:DDR4_MA(12)" )
				( pinRef "@baseboard_fab2_lib.baseboard_fab2(sch_1):page85_i111:A12" )
				( attribute "RELATIVE_PROPAGATION_DELAY_SCOPE" "G"
					( Parent
						( matchGroupRef "@crescent_city_bb_fab1_lib.crescent_city_bb_fab1(sch_1):\MG_DDR_FAR_DIMM-CLK0_CLS_DDR_L_CAC-CLKS\" )
					)
					( Status sCSetFlattened )
					( Origin gBackEnd )
				)
				( attribute "RELATIVE_PROPAGATION_DELAY" "0.00 MIL,700.00 MIL"
					( Parent
						( matchGroupRef "@crescent_city_bb_fab1_lib.crescent_city_bb_fab1(sch_1):\MG_DDR_FAR_DIMM-CLK0_CLS_DDR_L_CAC-CLKS\" )
					)
					( Units "uMatchProp" "ns" 1.000000)
					( Status sCSetFlattened )
					( Origin gBackEnd )
				)
				( attribute "RELATIVE_PROPAGATION_DELAY_SCOPE" "G"
					( Parent
						( matchGroupRef "@baseboard_fab2_lib.baseboard_fab2(sch_1):\MG_DDR_FAR_DIMM_CMD_NG_DDR_L_DLL_11\" )
					)
					( Status sCSetFlattened )
					( Origin gBackEnd )
				)
				( attribute "RELATIVE_PROPAGATION_DELAY" "0.00 MIL,25.00 MIL"
					( Parent
						( matchGroupRef "@baseboard_fab2_lib.baseboard_fab2(sch_1):\MG_DDR_FAR_DIMM_CMD_NG_DDR_L_DLL_11\" )
					)
					( Units "uMatchProp" "ns" 1.000000)
					( Status sCSetFlattened )
					( Origin gBackEnd )
				)
			)
			( pinPair "@baseboard_fab2_lib.baseboard_fab2(sch_1):\PP3360\"
				( pinRef "@baseboard_fab2_lib.baseboard_fab2(sch_1):page86_i12:A12" )
				( pinRef "@baseboard_fab2_lib.baseboard_fab2(sch_1):page61_i172:DDR4_MA(12)" )
				( attribute "RELATIVE_PROPAGATION_DELAY_SCOPE" "G"
					( Parent
						( matchGroupRef "@crescent_city_bb_fab1_lib.crescent_city_bb_fab1(sch_1):\MG_DDR_NEAR_DIMM-CLK1_CLS_DDR_L_CAC-CLKS\" )
					)
					( Status sCSetFlattened )
					( Origin gBackEnd )
				)
				( attribute "RELATIVE_PROPAGATION_DELAY" "0.00 MIL,700.00 MIL"
					( Parent
						( matchGroupRef "@crescent_city_bb_fab1_lib.crescent_city_bb_fab1(sch_1):\MG_DDR_NEAR_DIMM-CLK1_CLS_DDR_L_CAC-CLKS\" )
					)
					( Units "uMatchProp" "ns" 1.000000)
					( Status sCSetFlattened )
					( Origin gBackEnd )
				)
				( attribute "RELATIVE_PROPAGATION_DELAY_SCOPE" "G"
					( Parent
						( matchGroupRef "@baseboard_fab2_lib.baseboard_fab2(sch_1):\MG_DDR_CMD_NEAR_DIMM_NG_DDR_L_DLL_11\" )
					)
					( Status sCSetFlattened )
					( Origin gBackEnd )
				)
				( attribute "RELATIVE_PROPAGATION_DELAY" "0.00 MIL,25.00 MIL"
					( Parent
						( matchGroupRef "@baseboard_fab2_lib.baseboard_fab2(sch_1):\MG_DDR_CMD_NEAR_DIMM_NG_DDR_L_DLL_11\" )
					)
					( Units "uMatchProp" "ns" 1.000000)
					( Status sCSetFlattened )
					( Origin gBackEnd )
				)
			)
			( pinPair "@baseboard_fab2_lib.baseboard_fab2(sch_1):\PP3353\"
				( pinRef "@baseboard_fab2_lib.baseboard_fab2(sch_1):page61_i172:DDR4_BG(1)" )
				( pinRef "@baseboard_fab2_lib.baseboard_fab2(sch_1):page85_i111:BG(1)" )
				( attribute "RELATIVE_PROPAGATION_DELAY_SCOPE" "G"
					( Parent
						( matchGroupRef "@crescent_city_bb_fab1_lib.crescent_city_bb_fab1(sch_1):\MG_DDR_FAR_DIMM-CLK0_CLS_DDR_L_CAC-CLKS\" )
					)
					( Status sCSetFlattened )
					( Origin gBackEnd )
				)
				( attribute "RELATIVE_PROPAGATION_DELAY" "0.00 MIL,700.00 MIL"
					( Parent
						( matchGroupRef "@crescent_city_bb_fab1_lib.crescent_city_bb_fab1(sch_1):\MG_DDR_FAR_DIMM-CLK0_CLS_DDR_L_CAC-CLKS\" )
					)
					( Units "uMatchProp" "ns" 1.000000)
					( Status sCSetFlattened )
					( Origin gBackEnd )
				)
				( attribute "RELATIVE_PROPAGATION_DELAY_SCOPE" "G"
					( Parent
						( matchGroupRef "@baseboard_fab2_lib.baseboard_fab2(sch_1):\MG_DDR_FAR_DIMM_CMD_NG_DDR_L_DLL_12\" )
					)
					( Status sCSetFlattened )
					( Origin gBackEnd )
				)
				( attribute "RELATIVE_PROPAGATION_DELAY" "0.00 MIL,25.00 MIL"
					( Parent
						( matchGroupRef "@baseboard_fab2_lib.baseboard_fab2(sch_1):\MG_DDR_FAR_DIMM_CMD_NG_DDR_L_DLL_12\" )
					)
					( Units "uMatchProp" "ns" 1.000000)
					( Status sCSetFlattened )
					( Origin gBackEnd )
				)
			)
			( pinPair "@baseboard_fab2_lib.baseboard_fab2(sch_1):\PP3354\"
				( pinRef "@baseboard_fab2_lib.baseboard_fab2(sch_1):page86_i12:BG(1)" )
				( pinRef "@baseboard_fab2_lib.baseboard_fab2(sch_1):page61_i172:DDR4_BG(1)" )
				( attribute "RELATIVE_PROPAGATION_DELAY_SCOPE" "G"
					( Parent
						( matchGroupRef "@crescent_city_bb_fab1_lib.crescent_city_bb_fab1(sch_1):\MG_DDR_NEAR_DIMM-CLK1_CLS_DDR_L_CAC-CLKS\" )
					)
					( Status sCSetFlattened )
					( Origin gBackEnd )
				)
				( attribute "RELATIVE_PROPAGATION_DELAY" "0.00 MIL,700.00 MIL"
					( Parent
						( matchGroupRef "@crescent_city_bb_fab1_lib.crescent_city_bb_fab1(sch_1):\MG_DDR_NEAR_DIMM-CLK1_CLS_DDR_L_CAC-CLKS\" )
					)
					( Units "uMatchProp" "ns" 1.000000)
					( Status sCSetFlattened )
					( Origin gBackEnd )
				)
				( attribute "RELATIVE_PROPAGATION_DELAY_SCOPE" "G"
					( Parent
						( matchGroupRef "@baseboard_fab2_lib.baseboard_fab2(sch_1):\MG_DDR_CMD_NEAR_DIMM_NG_DDR_L_DLL_12\" )
					)
					( Status sCSetFlattened )
					( Origin gBackEnd )
				)
				( attribute "RELATIVE_PROPAGATION_DELAY" "0.00 MIL,25.00 MIL"
					( Parent
						( matchGroupRef "@baseboard_fab2_lib.baseboard_fab2(sch_1):\MG_DDR_CMD_NEAR_DIMM_NG_DDR_L_DLL_12\" )
					)
					( Units "uMatchProp" "ns" 1.000000)
					( Status sCSetFlattened )
					( Origin gBackEnd )
				)
			)
			( pinPair "@baseboard_fab2_lib.baseboard_fab2(sch_1):\PP3355\"
				( pinRef "@baseboard_fab2_lib.baseboard_fab2(sch_1):page61_i172:DDR4_MA(11)" )
				( pinRef "@baseboard_fab2_lib.baseboard_fab2(sch_1):page85_i111:A11" )
				( attribute "RELATIVE_PROPAGATION_DELAY_SCOPE" "G"
					( Parent
						( matchGroupRef "@crescent_city_bb_fab1_lib.crescent_city_bb_fab1(sch_1):\MG_DDR_FAR_DIMM-CLK0_CLS_DDR_L_CAC-CLKS\" )
					)
					( Status sCSetFlattened )
					( Origin gBackEnd )
				)
				( attribute "RELATIVE_PROPAGATION_DELAY" "0.00 MIL,700.00 MIL"
					( Parent
						( matchGroupRef "@crescent_city_bb_fab1_lib.crescent_city_bb_fab1(sch_1):\MG_DDR_FAR_DIMM-CLK0_CLS_DDR_L_CAC-CLKS\" )
					)
					( Units "uMatchProp" "ns" 1.000000)
					( Status sCSetFlattened )
					( Origin gBackEnd )
				)
				( attribute "RELATIVE_PROPAGATION_DELAY_SCOPE" "G"
					( Parent
						( matchGroupRef "@baseboard_fab2_lib.baseboard_fab2(sch_1):\MG_DDR_FAR_DIMM_CMD_NG_DDR_L_DLL_12\" )
					)
					( Status sCSetFlattened )
					( Origin gBackEnd )
				)
				( attribute "RELATIVE_PROPAGATION_DELAY" "0.00 MIL,25.00 MIL"
					( Parent
						( matchGroupRef "@baseboard_fab2_lib.baseboard_fab2(sch_1):\MG_DDR_FAR_DIMM_CMD_NG_DDR_L_DLL_12\" )
					)
					( Units "uMatchProp" "ns" 1.000000)
					( Status sCSetFlattened )
					( Origin gBackEnd )
				)
			)
			( pinPair "@baseboard_fab2_lib.baseboard_fab2(sch_1):\PP3356\"
				( pinRef "@baseboard_fab2_lib.baseboard_fab2(sch_1):page86_i12:A11" )
				( pinRef "@baseboard_fab2_lib.baseboard_fab2(sch_1):page61_i172:DDR4_MA(11)" )
				( attribute "RELATIVE_PROPAGATION_DELAY_SCOPE" "G"
					( Parent
						( matchGroupRef "@crescent_city_bb_fab1_lib.crescent_city_bb_fab1(sch_1):\MG_DDR_NEAR_DIMM-CLK1_CLS_DDR_L_CAC-CLKS\" )
					)
					( Status sCSetFlattened )
					( Origin gBackEnd )
				)
				( attribute "RELATIVE_PROPAGATION_DELAY" "0.00 MIL,700.00 MIL"
					( Parent
						( matchGroupRef "@crescent_city_bb_fab1_lib.crescent_city_bb_fab1(sch_1):\MG_DDR_NEAR_DIMM-CLK1_CLS_DDR_L_CAC-CLKS\" )
					)
					( Units "uMatchProp" "ns" 1.000000)
					( Status sCSetFlattened )
					( Origin gBackEnd )
				)
				( attribute "RELATIVE_PROPAGATION_DELAY_SCOPE" "G"
					( Parent
						( matchGroupRef "@baseboard_fab2_lib.baseboard_fab2(sch_1):\MG_DDR_CMD_NEAR_DIMM_NG_DDR_L_DLL_12\" )
					)
					( Status sCSetFlattened )
					( Origin gBackEnd )
				)
				( attribute "RELATIVE_PROPAGATION_DELAY" "0.00 MIL,25.00 MIL"
					( Parent
						( matchGroupRef "@baseboard_fab2_lib.baseboard_fab2(sch_1):\MG_DDR_CMD_NEAR_DIMM_NG_DDR_L_DLL_12\" )
					)
					( Units "uMatchProp" "ns" 1.000000)
					( Status sCSetFlattened )
					( Origin gBackEnd )
				)
			)
			( pinPair "@baseboard_fab2_lib.baseboard_fab2(sch_1):\PP3349\"
				( pinRef "@baseboard_fab2_lib.baseboard_fab2(sch_1):page61_i172:DDR4_ACT_N" )
				( pinRef "@baseboard_fab2_lib.baseboard_fab2(sch_1):page85_i111:ACT_N" )
				( attribute "RELATIVE_PROPAGATION_DELAY_SCOPE" "G"
					( Parent
						( matchGroupRef "@crescent_city_bb_fab1_lib.crescent_city_bb_fab1(sch_1):\MG_DDR_FAR_DIMM-CLK0_CLS_DDR_L_CAC-CLKS\" )
					)
					( Status sCSetFlattened )
					( Origin gBackEnd )
				)
				( attribute "RELATIVE_PROPAGATION_DELAY" "0.00 MIL,700.00 MIL"
					( Parent
						( matchGroupRef "@crescent_city_bb_fab1_lib.crescent_city_bb_fab1(sch_1):\MG_DDR_FAR_DIMM-CLK0_CLS_DDR_L_CAC-CLKS\" )
					)
					( Units "uMatchProp" "ns" 1.000000)
					( Status sCSetFlattened )
					( Origin gBackEnd )
				)
				( attribute "RELATIVE_PROPAGATION_DELAY_SCOPE" "G"
					( Parent
						( matchGroupRef "@baseboard_fab2_lib.baseboard_fab2(sch_1):\MG_DDR_FAR_DIMM_CMD_NG_DDR_L_DLL_13\" )
					)
					( Status sCSetFlattened )
					( Origin gBackEnd )
				)
				( attribute "RELATIVE_PROPAGATION_DELAY" "0.00 MIL,25.00 MIL"
					( Parent
						( matchGroupRef "@baseboard_fab2_lib.baseboard_fab2(sch_1):\MG_DDR_FAR_DIMM_CMD_NG_DDR_L_DLL_13\" )
					)
					( Units "uMatchProp" "ns" 1.000000)
					( Status sCSetFlattened )
					( Origin gBackEnd )
				)
			)
			( pinPair "@baseboard_fab2_lib.baseboard_fab2(sch_1):\PP3350\"
				( pinRef "@baseboard_fab2_lib.baseboard_fab2(sch_1):page86_i12:ACT_N" )
				( pinRef "@baseboard_fab2_lib.baseboard_fab2(sch_1):page61_i172:DDR4_ACT_N" )
				( attribute "RELATIVE_PROPAGATION_DELAY_SCOPE" "G"
					( Parent
						( matchGroupRef "@crescent_city_bb_fab1_lib.crescent_city_bb_fab1(sch_1):\MG_DDR_NEAR_DIMM-CLK1_CLS_DDR_L_CAC-CLKS\" )
					)
					( Status sCSetFlattened )
					( Origin gBackEnd )
				)
				( attribute "RELATIVE_PROPAGATION_DELAY" "0.00 MIL,700.00 MIL"
					( Parent
						( matchGroupRef "@crescent_city_bb_fab1_lib.crescent_city_bb_fab1(sch_1):\MG_DDR_NEAR_DIMM-CLK1_CLS_DDR_L_CAC-CLKS\" )
					)
					( Units "uMatchProp" "ns" 1.000000)
					( Status sCSetFlattened )
					( Origin gBackEnd )
				)
				( attribute "RELATIVE_PROPAGATION_DELAY_SCOPE" "G"
					( Parent
						( matchGroupRef "@baseboard_fab2_lib.baseboard_fab2(sch_1):\MG_DDR_CMD_NEAR_DIMM_NG_DDR_L_DLL_13\" )
					)
					( Status sCSetFlattened )
					( Origin gBackEnd )
				)
				( attribute "RELATIVE_PROPAGATION_DELAY" "0.00 MIL,25.00 MIL"
					( Parent
						( matchGroupRef "@baseboard_fab2_lib.baseboard_fab2(sch_1):\MG_DDR_CMD_NEAR_DIMM_NG_DDR_L_DLL_13\" )
					)
					( Units "uMatchProp" "ns" 1.000000)
					( Status sCSetFlattened )
					( Origin gBackEnd )
				)
			)
			( pinPair "@baseboard_fab2_lib.baseboard_fab2(sch_1):\PP3351\"
				( pinRef "@baseboard_fab2_lib.baseboard_fab2(sch_1):page61_i172:DDR4_BG(0)" )
				( pinRef "@baseboard_fab2_lib.baseboard_fab2(sch_1):page85_i111:BG(0)" )
				( attribute "RELATIVE_PROPAGATION_DELAY_SCOPE" "G"
					( Parent
						( matchGroupRef "@crescent_city_bb_fab1_lib.crescent_city_bb_fab1(sch_1):\MG_DDR_FAR_DIMM-CLK0_CLS_DDR_L_CAC-CLKS\" )
					)
					( Status sCSetFlattened )
					( Origin gBackEnd )
				)
				( attribute "RELATIVE_PROPAGATION_DELAY" "0.00 MIL,700.00 MIL"
					( Parent
						( matchGroupRef "@crescent_city_bb_fab1_lib.crescent_city_bb_fab1(sch_1):\MG_DDR_FAR_DIMM-CLK0_CLS_DDR_L_CAC-CLKS\" )
					)
					( Units "uMatchProp" "ns" 1.000000)
					( Status sCSetFlattened )
					( Origin gBackEnd )
				)
				( attribute "RELATIVE_PROPAGATION_DELAY_SCOPE" "G"
					( Parent
						( matchGroupRef "@baseboard_fab2_lib.baseboard_fab2(sch_1):\MG_DDR_FAR_DIMM_CMD_NG_DDR_L_DLL_13\" )
					)
					( Status sCSetFlattened )
					( Origin gBackEnd )
				)
				( attribute "RELATIVE_PROPAGATION_DELAY" "0.00 MIL,25.00 MIL"
					( Parent
						( matchGroupRef "@baseboard_fab2_lib.baseboard_fab2(sch_1):\MG_DDR_FAR_DIMM_CMD_NG_DDR_L_DLL_13\" )
					)
					( Units "uMatchProp" "ns" 1.000000)
					( Status sCSetFlattened )
					( Origin gBackEnd )
				)
			)
			( pinPair "@baseboard_fab2_lib.baseboard_fab2(sch_1):\PP3352\"
				( pinRef "@baseboard_fab2_lib.baseboard_fab2(sch_1):page86_i12:BG(0)" )
				( pinRef "@baseboard_fab2_lib.baseboard_fab2(sch_1):page61_i172:DDR4_BG(0)" )
				( attribute "RELATIVE_PROPAGATION_DELAY_SCOPE" "G"
					( Parent
						( matchGroupRef "@crescent_city_bb_fab1_lib.crescent_city_bb_fab1(sch_1):\MG_DDR_NEAR_DIMM-CLK1_CLS_DDR_L_CAC-CLKS\" )
					)
					( Status sCSetFlattened )
					( Origin gBackEnd )
				)
				( attribute "RELATIVE_PROPAGATION_DELAY" "0.00 MIL,700.00 MIL"
					( Parent
						( matchGroupRef "@crescent_city_bb_fab1_lib.crescent_city_bb_fab1(sch_1):\MG_DDR_NEAR_DIMM-CLK1_CLS_DDR_L_CAC-CLKS\" )
					)
					( Units "uMatchProp" "ns" 1.000000)
					( Status sCSetFlattened )
					( Origin gBackEnd )
				)
				( attribute "RELATIVE_PROPAGATION_DELAY_SCOPE" "G"
					( Parent
						( matchGroupRef "@baseboard_fab2_lib.baseboard_fab2(sch_1):\MG_DDR_CMD_NEAR_DIMM_NG_DDR_L_DLL_13\" )
					)
					( Status sCSetFlattened )
					( Origin gBackEnd )
				)
				( attribute "RELATIVE_PROPAGATION_DELAY" "0.00 MIL,25.00 MIL"
					( Parent
						( matchGroupRef "@baseboard_fab2_lib.baseboard_fab2(sch_1):\MG_DDR_CMD_NEAR_DIMM_NG_DDR_L_DLL_13\" )
					)
					( Units "uMatchProp" "ns" 1.000000)
					( Status sCSetFlattened )
					( Origin gBackEnd )
				)
			)
			( pinPair "@baseboard_fab2_lib.baseboard_fab2(sch_1):\PP3347\"
				( pinRef "@baseboard_fab2_lib.baseboard_fab2(sch_1):page85_i111:S0_N" )
				( pinRef "@baseboard_fab2_lib.baseboard_fab2(sch_1):page61_i172:DDR4_CS_N(0)" )
				( attribute "RELATIVE_PROPAGATION_DELAY_SCOPE" "G"
					( Parent
						( matchGroupRef "@crescent_city_bb_fab1_lib.crescent_city_bb_fab1(sch_1):\MG_DDR_FAR_DIMM-CLK0_CLS_DDR_L_CAC-CLKS\" )
					)
					( Status sCSetFlattened )
					( Origin gBackEnd )
				)
				( attribute "RELATIVE_PROPAGATION_DELAY" "0.00 MIL,300.00 MIL"
					( Parent
						( matchGroupRef "@crescent_city_bb_fab1_lib.crescent_city_bb_fab1(sch_1):\MG_DDR_FAR_DIMM-CLK0_CLS_DDR_L_CAC-CLKS\" )
					)
					( Units "uMatchProp" "ns" 1.000000)
					( Status sCSetFlattened )
					( Origin gBackEnd )
				)
				( attribute "RELATIVE_PROPAGATION_DELAY_SCOPE" "G"
					( Parent
						( matchGroupRef "@baseboard_fab2_lib.baseboard_fab2(sch_1):\MG_DDR_CTRL_NG_DDR_L_DLL_14\" )
					)
					( Status sCSetFlattened )
					( Origin gBackEnd )
				)
				( attribute "RELATIVE_PROPAGATION_DELAY" "0.00 MIL,25.00 MIL"
					( Parent
						( matchGroupRef "@baseboard_fab2_lib.baseboard_fab2(sch_1):\MG_DDR_CTRL_NG_DDR_L_DLL_14\" )
					)
					( Units "uMatchProp" "ns" 1.000000)
					( Status sCSetFlattened )
					( Origin gBackEnd )
				)
			)
			( pinPair "@baseboard_fab2_lib.baseboard_fab2(sch_1):\PP3348\"
				( pinRef "@baseboard_fab2_lib.baseboard_fab2(sch_1):page85_i111:ODT(0)" )
				( pinRef "@baseboard_fab2_lib.baseboard_fab2(sch_1):page61_i172:DDR4_ODT(0)" )
				( attribute "RELATIVE_PROPAGATION_DELAY_SCOPE" "G"
					( Parent
						( matchGroupRef "@crescent_city_bb_fab1_lib.crescent_city_bb_fab1(sch_1):\MG_DDR_FAR_DIMM-CLK0_CLS_DDR_L_CAC-CLKS\" )
					)
					( Status sCSetFlattened )
					( Origin gBackEnd )
				)
				( attribute "RELATIVE_PROPAGATION_DELAY" "0.00 MIL,300.00 MIL"
					( Parent
						( matchGroupRef "@crescent_city_bb_fab1_lib.crescent_city_bb_fab1(sch_1):\MG_DDR_FAR_DIMM-CLK0_CLS_DDR_L_CAC-CLKS\" )
					)
					( Units "uMatchProp" "ns" 1.000000)
					( Status sCSetFlattened )
					( Origin gBackEnd )
				)
				( attribute "RELATIVE_PROPAGATION_DELAY_SCOPE" "G"
					( Parent
						( matchGroupRef "@baseboard_fab2_lib.baseboard_fab2(sch_1):\MG_DDR_CTRL_NG_DDR_L_DLL_14\" )
					)
					( Status sCSetFlattened )
					( Origin gBackEnd )
				)
				( attribute "RELATIVE_PROPAGATION_DELAY" "0.00 MIL,25.00 MIL"
					( Parent
						( matchGroupRef "@baseboard_fab2_lib.baseboard_fab2(sch_1):\MG_DDR_CTRL_NG_DDR_L_DLL_14\" )
					)
					( Units "uMatchProp" "ns" 1.000000)
					( Status sCSetFlattened )
					( Origin gBackEnd )
				)
			)
			( pinPair "@baseboard_fab2_lib.baseboard_fab2(sch_1):\PP3346\"
				( pinRef "@baseboard_fab2_lib.baseboard_fab2(sch_1):page85_i111:CKE(0)" )
				( pinRef "@baseboard_fab2_lib.baseboard_fab2(sch_1):page61_i172:DDR4_CKE(0)" )
				( attribute "RELATIVE_PROPAGATION_DELAY_SCOPE" "G"
					( Parent
						( matchGroupRef "@crescent_city_bb_fab1_lib.crescent_city_bb_fab1(sch_1):\MG_DDR_FAR_DIMM-CLK0_CLS_DDR_L_CAC-CLKS\" )
					)
					( Status sCSetFlattened )
					( Origin gBackEnd )
				)
				( attribute "RELATIVE_PROPAGATION_DELAY" "0.00 MIL,300.00 MIL"
					( Parent
						( matchGroupRef "@crescent_city_bb_fab1_lib.crescent_city_bb_fab1(sch_1):\MG_DDR_FAR_DIMM-CLK0_CLS_DDR_L_CAC-CLKS\" )
					)
					( Units "uMatchProp" "ns" 1.000000)
					( Status sCSetFlattened )
					( Origin gBackEnd )
				)
				( attribute "RELATIVE_PROPAGATION_DELAY_SCOPE" "G"
					( Parent
						( matchGroupRef "@baseboard_fab2_lib.baseboard_fab2(sch_1):\MG_DDR_CTRL_NG_DDR_L_DLL_15\" )
					)
					( Status sCSetFlattened )
					( Origin gBackEnd )
				)
				( attribute "RELATIVE_PROPAGATION_DELAY" "0.00 MIL,25.00 MIL"
					( Parent
						( matchGroupRef "@baseboard_fab2_lib.baseboard_fab2(sch_1):\MG_DDR_CTRL_NG_DDR_L_DLL_15\" )
					)
					( Units "uMatchProp" "ns" 1.000000)
					( Status sCSetFlattened )
					( Origin gBackEnd )
				)
			)
			( pinPair "@baseboard_fab2_lib.baseboard_fab2(sch_1):\PP3345\"
				( pinRef "@baseboard_fab2_lib.baseboard_fab2(sch_1):page85_i111:S2_N_C(0)" )
				( pinRef "@baseboard_fab2_lib.baseboard_fab2(sch_1):page61_i172:DDR4_CS_N(2)" )
				( attribute "RELATIVE_PROPAGATION_DELAY_SCOPE" "G"
					( Parent
						( matchGroupRef "@crescent_city_bb_fab1_lib.crescent_city_bb_fab1(sch_1):\MG_DDR_FAR_DIMM-CLK0_CLS_DDR_L_CAC-CLKS\" )
					)
					( Status sCSetFlattened )
					( Origin gBackEnd )
				)
				( attribute "RELATIVE_PROPAGATION_DELAY" "0.00 MIL,300.00 MIL"
					( Parent
						( matchGroupRef "@crescent_city_bb_fab1_lib.crescent_city_bb_fab1(sch_1):\MG_DDR_FAR_DIMM-CLK0_CLS_DDR_L_CAC-CLKS\" )
					)
					( Units "uMatchProp" "ns" 1.000000)
					( Status sCSetFlattened )
					( Origin gBackEnd )
				)
				( attribute "RELATIVE_PROPAGATION_DELAY_SCOPE" "G"
					( Parent
						( matchGroupRef "@baseboard_fab2_lib.baseboard_fab2(sch_1):\MG_DDR_CTRL_NG_DDR_L_DLL_16\" )
					)
					( Status sCSetFlattened )
					( Origin gBackEnd )
				)
				( attribute "RELATIVE_PROPAGATION_DELAY" "0.00 MIL,25.00 MIL"
					( Parent
						( matchGroupRef "@baseboard_fab2_lib.baseboard_fab2(sch_1):\MG_DDR_CTRL_NG_DDR_L_DLL_16\" )
					)
					( Units "uMatchProp" "ns" 1.000000)
					( Status sCSetFlattened )
					( Origin gBackEnd )
				)
			)
			( pinPair "@baseboard_fab2_lib.baseboard_fab2(sch_1):\PP3344\"
				( pinRef "@baseboard_fab2_lib.baseboard_fab2(sch_1):page85_i111:S3_N_C(1)" )
				( pinRef "@baseboard_fab2_lib.baseboard_fab2(sch_1):page61_i172:DDR4_CS_N(3)" )
				( attribute "RELATIVE_PROPAGATION_DELAY_SCOPE" "G"
					( Parent
						( matchGroupRef "@crescent_city_bb_fab1_lib.crescent_city_bb_fab1(sch_1):\MG_DDR_FAR_DIMM-CLK0_CLS_DDR_L_CAC-CLKS\" )
					)
					( Status sCSetFlattened )
					( Origin gBackEnd )
				)
				( attribute "RELATIVE_PROPAGATION_DELAY" "0.00 MIL,300.00 MIL"
					( Parent
						( matchGroupRef "@crescent_city_bb_fab1_lib.crescent_city_bb_fab1(sch_1):\MG_DDR_FAR_DIMM-CLK0_CLS_DDR_L_CAC-CLKS\" )
					)
					( Units "uMatchProp" "ns" 1.000000)
					( Status sCSetFlattened )
					( Origin gBackEnd )
				)
				( attribute "RELATIVE_PROPAGATION_DELAY_SCOPE" "G"
					( Parent
						( matchGroupRef "@baseboard_fab2_lib.baseboard_fab2(sch_1):\MG_DDR_CTRL_NG_DDR_L_DLL_17\" )
					)
					( Status sCSetFlattened )
					( Origin gBackEnd )
				)
				( attribute "RELATIVE_PROPAGATION_DELAY" "0.00 MIL,25.00 MIL"
					( Parent
						( matchGroupRef "@baseboard_fab2_lib.baseboard_fab2(sch_1):\MG_DDR_CTRL_NG_DDR_L_DLL_17\" )
					)
					( Units "uMatchProp" "ns" 1.000000)
					( Status sCSetFlattened )
					( Origin gBackEnd )
				)
			)
			( pinPair "@baseboard_fab2_lib.baseboard_fab2(sch_1):\PP3342\"
				( pinRef "@baseboard_fab2_lib.baseboard_fab2(sch_1):page85_i111:S1_N" )
				( pinRef "@baseboard_fab2_lib.baseboard_fab2(sch_1):page61_i172:DDR4_CS_N(1)" )
				( attribute "RELATIVE_PROPAGATION_DELAY_SCOPE" "G"
					( Parent
						( matchGroupRef "@crescent_city_bb_fab1_lib.crescent_city_bb_fab1(sch_1):\MG_DDR_FAR_DIMM-CLK0_CLS_DDR_L_CAC-CLKS\" )
					)
					( Status sCSetFlattened )
					( Origin gBackEnd )
				)
				( attribute "RELATIVE_PROPAGATION_DELAY" "0.00 MIL,300.00 MIL"
					( Parent
						( matchGroupRef "@crescent_city_bb_fab1_lib.crescent_city_bb_fab1(sch_1):\MG_DDR_FAR_DIMM-CLK0_CLS_DDR_L_CAC-CLKS\" )
					)
					( Units "uMatchProp" "ns" 1.000000)
					( Status sCSetFlattened )
					( Origin gBackEnd )
				)
				( attribute "RELATIVE_PROPAGATION_DELAY_SCOPE" "G"
					( Parent
						( matchGroupRef "@baseboard_fab2_lib.baseboard_fab2(sch_1):\MG_DDR_CTRL_NG_DDR_L_DLL_18\" )
					)
					( Status sCSetFlattened )
					( Origin gBackEnd )
				)
				( attribute "RELATIVE_PROPAGATION_DELAY" "0.00 MIL,25.00 MIL"
					( Parent
						( matchGroupRef "@baseboard_fab2_lib.baseboard_fab2(sch_1):\MG_DDR_CTRL_NG_DDR_L_DLL_18\" )
					)
					( Units "uMatchProp" "ns" 1.000000)
					( Status sCSetFlattened )
					( Origin gBackEnd )
				)
			)
			( pinPair "@baseboard_fab2_lib.baseboard_fab2(sch_1):\PP3343\"
				( pinRef "@baseboard_fab2_lib.baseboard_fab2(sch_1):page85_i111:ODT(1)" )
				( pinRef "@baseboard_fab2_lib.baseboard_fab2(sch_1):page61_i172:DDR4_ODT(1)" )
				( attribute "RELATIVE_PROPAGATION_DELAY_SCOPE" "G"
					( Parent
						( matchGroupRef "@crescent_city_bb_fab1_lib.crescent_city_bb_fab1(sch_1):\MG_DDR_FAR_DIMM-CLK0_CLS_DDR_L_CAC-CLKS\" )
					)
					( Status sCSetFlattened )
					( Origin gBackEnd )
				)
				( attribute "RELATIVE_PROPAGATION_DELAY" "0.00 MIL,300.00 MIL"
					( Parent
						( matchGroupRef "@crescent_city_bb_fab1_lib.crescent_city_bb_fab1(sch_1):\MG_DDR_FAR_DIMM-CLK0_CLS_DDR_L_CAC-CLKS\" )
					)
					( Units "uMatchProp" "ns" 1.000000)
					( Status sCSetFlattened )
					( Origin gBackEnd )
				)
				( attribute "RELATIVE_PROPAGATION_DELAY_SCOPE" "G"
					( Parent
						( matchGroupRef "@baseboard_fab2_lib.baseboard_fab2(sch_1):\MG_DDR_CTRL_NG_DDR_L_DLL_18\" )
					)
					( Status sCSetFlattened )
					( Origin gBackEnd )
				)
				( attribute "RELATIVE_PROPAGATION_DELAY" "0.00 MIL,25.00 MIL"
					( Parent
						( matchGroupRef "@baseboard_fab2_lib.baseboard_fab2(sch_1):\MG_DDR_CTRL_NG_DDR_L_DLL_18\" )
					)
					( Units "uMatchProp" "ns" 1.000000)
					( Status sCSetFlattened )
					( Origin gBackEnd )
				)
			)
			( pinPair "@baseboard_fab2_lib.baseboard_fab2(sch_1):\PP3341\"
				( pinRef "@baseboard_fab2_lib.baseboard_fab2(sch_1):page85_i111:CKE(1)" )
				( pinRef "@baseboard_fab2_lib.baseboard_fab2(sch_1):page61_i172:DDR4_CKE(1)" )
				( attribute "RELATIVE_PROPAGATION_DELAY_SCOPE" "G"
					( Parent
						( matchGroupRef "@crescent_city_bb_fab1_lib.crescent_city_bb_fab1(sch_1):\MG_DDR_FAR_DIMM-CLK0_CLS_DDR_L_CAC-CLKS\" )
					)
					( Status sCSetFlattened )
					( Origin gBackEnd )
				)
				( attribute "RELATIVE_PROPAGATION_DELAY" "0.00 MIL,300.00 MIL"
					( Parent
						( matchGroupRef "@crescent_city_bb_fab1_lib.crescent_city_bb_fab1(sch_1):\MG_DDR_FAR_DIMM-CLK0_CLS_DDR_L_CAC-CLKS\" )
					)
					( Units "uMatchProp" "ns" 1.000000)
					( Status sCSetFlattened )
					( Origin gBackEnd )
				)
				( attribute "RELATIVE_PROPAGATION_DELAY_SCOPE" "G"
					( Parent
						( matchGroupRef "@baseboard_fab2_lib.baseboard_fab2(sch_1):\MG_DDR_CTRL_NG_DDR_L_DLL_19\" )
					)
					( Status sCSetFlattened )
					( Origin gBackEnd )
				)
				( attribute "RELATIVE_PROPAGATION_DELAY" "0.00 MIL,25.00 MIL"
					( Parent
						( matchGroupRef "@baseboard_fab2_lib.baseboard_fab2(sch_1):\MG_DDR_CTRL_NG_DDR_L_DLL_19\" )
					)
					( Units "uMatchProp" "ns" 1.000000)
					( Status sCSetFlattened )
					( Origin gBackEnd )
				)
			)
			( pinPair "@baseboard_fab2_lib.baseboard_fab2(sch_1):\PP3339\"
				( pinRef "@baseboard_fab2_lib.baseboard_fab2(sch_1):page61_i172:DDR4_CS_N(4)" )
				( pinRef "@baseboard_fab2_lib.baseboard_fab2(sch_1):page86_i12:S0_N" )
				( attribute "RELATIVE_PROPAGATION_DELAY_SCOPE" "G"
					( Parent
						( matchGroupRef "@crescent_city_bb_fab1_lib.crescent_city_bb_fab1(sch_1):\MG_DDR_NEAR_DIMM-CLK1_CLS_DDR_L_CAC-CLKS\" )
					)
					( Status sCSetFlattened )
					( Origin gBackEnd )
				)
				( attribute "RELATIVE_PROPAGATION_DELAY" "0.00 MIL,300.00 MIL"
					( Parent
						( matchGroupRef "@crescent_city_bb_fab1_lib.crescent_city_bb_fab1(sch_1):\MG_DDR_NEAR_DIMM-CLK1_CLS_DDR_L_CAC-CLKS\" )
					)
					( Units "uMatchProp" "ns" 1.000000)
					( Status sCSetFlattened )
					( Origin gBackEnd )
				)
				( attribute "RELATIVE_PROPAGATION_DELAY_SCOPE" "G"
					( Parent
						( matchGroupRef "@baseboard_fab2_lib.baseboard_fab2(sch_1):\MG_DDR_CTRL_NG_DDR_L_DLL_20\" )
					)
					( Status sCSetFlattened )
					( Origin gBackEnd )
				)
				( attribute "RELATIVE_PROPAGATION_DELAY" "0.00 MIL,25.00 MIL"
					( Parent
						( matchGroupRef "@baseboard_fab2_lib.baseboard_fab2(sch_1):\MG_DDR_CTRL_NG_DDR_L_DLL_20\" )
					)
					( Units "uMatchProp" "ns" 1.000000)
					( Status sCSetFlattened )
					( Origin gBackEnd )
				)
			)
			( pinPair "@baseboard_fab2_lib.baseboard_fab2(sch_1):\PP3340\"
				( pinRef "@baseboard_fab2_lib.baseboard_fab2(sch_1):page61_i172:DDR4_ODT(2)" )
				( pinRef "@baseboard_fab2_lib.baseboard_fab2(sch_1):page86_i12:ODT(0)" )
				( attribute "RELATIVE_PROPAGATION_DELAY_SCOPE" "G"
					( Parent
						( matchGroupRef "@crescent_city_bb_fab1_lib.crescent_city_bb_fab1(sch_1):\MG_DDR_NEAR_DIMM-CLK1_CLS_DDR_L_CAC-CLKS\" )
					)
					( Status sCSetFlattened )
					( Origin gBackEnd )
				)
				( attribute "RELATIVE_PROPAGATION_DELAY" "0.00 MIL,300.00 MIL"
					( Parent
						( matchGroupRef "@crescent_city_bb_fab1_lib.crescent_city_bb_fab1(sch_1):\MG_DDR_NEAR_DIMM-CLK1_CLS_DDR_L_CAC-CLKS\" )
					)
					( Units "uMatchProp" "ns" 1.000000)
					( Status sCSetFlattened )
					( Origin gBackEnd )
				)
				( attribute "RELATIVE_PROPAGATION_DELAY_SCOPE" "G"
					( Parent
						( matchGroupRef "@baseboard_fab2_lib.baseboard_fab2(sch_1):\MG_DDR_CTRL_NG_DDR_L_DLL_20\" )
					)
					( Status sCSetFlattened )
					( Origin gBackEnd )
				)
				( attribute "RELATIVE_PROPAGATION_DELAY" "0.00 MIL,25.00 MIL"
					( Parent
						( matchGroupRef "@baseboard_fab2_lib.baseboard_fab2(sch_1):\MG_DDR_CTRL_NG_DDR_L_DLL_20\" )
					)
					( Units "uMatchProp" "ns" 1.000000)
					( Status sCSetFlattened )
					( Origin gBackEnd )
				)
			)
			( pinPair "@baseboard_fab2_lib.baseboard_fab2(sch_1):\PP3338\"
				( pinRef "@baseboard_fab2_lib.baseboard_fab2(sch_1):page61_i172:DDR4_CKE(2)" )
				( pinRef "@baseboard_fab2_lib.baseboard_fab2(sch_1):page86_i12:CKE(0)" )
				( attribute "RELATIVE_PROPAGATION_DELAY_SCOPE" "G"
					( Parent
						( matchGroupRef "@crescent_city_bb_fab1_lib.crescent_city_bb_fab1(sch_1):\MG_DDR_NEAR_DIMM-CLK1_CLS_DDR_L_CAC-CLKS\" )
					)
					( Status sCSetFlattened )
					( Origin gBackEnd )
				)
				( attribute "RELATIVE_PROPAGATION_DELAY" "0.00 MIL,300.00 MIL"
					( Parent
						( matchGroupRef "@crescent_city_bb_fab1_lib.crescent_city_bb_fab1(sch_1):\MG_DDR_NEAR_DIMM-CLK1_CLS_DDR_L_CAC-CLKS\" )
					)
					( Units "uMatchProp" "ns" 1.000000)
					( Status sCSetFlattened )
					( Origin gBackEnd )
				)
				( attribute "RELATIVE_PROPAGATION_DELAY_SCOPE" "G"
					( Parent
						( matchGroupRef "@baseboard_fab2_lib.baseboard_fab2(sch_1):\MG_DDR_CTRL_NG_DDR_L_DLL_21\" )
					)
					( Status sCSetFlattened )
					( Origin gBackEnd )
				)
				( attribute "RELATIVE_PROPAGATION_DELAY" "0.00 MIL,25.00 MIL"
					( Parent
						( matchGroupRef "@baseboard_fab2_lib.baseboard_fab2(sch_1):\MG_DDR_CTRL_NG_DDR_L_DLL_21\" )
					)
					( Units "uMatchProp" "ns" 1.000000)
					( Status sCSetFlattened )
					( Origin gBackEnd )
				)
			)
			( pinPair "@baseboard_fab2_lib.baseboard_fab2(sch_1):\PP3336\"
				( pinRef "@baseboard_fab2_lib.baseboard_fab2(sch_1):page61_i172:DDR4_CS_N(6)" )
				( pinRef "@baseboard_fab2_lib.baseboard_fab2(sch_1):page86_i12:S2_N_C(0)" )
				( attribute "RELATIVE_PROPAGATION_DELAY_SCOPE" "G"
					( Parent
						( matchGroupRef "@crescent_city_bb_fab1_lib.crescent_city_bb_fab1(sch_1):\MG_DDR_NEAR_DIMM-CLK1_CLS_DDR_L_CAC-CLKS\" )
					)
					( Status sCSetFlattened )
					( Origin gBackEnd )
				)
				( attribute "RELATIVE_PROPAGATION_DELAY" "0.00 MIL,300.00 MIL"
					( Parent
						( matchGroupRef "@crescent_city_bb_fab1_lib.crescent_city_bb_fab1(sch_1):\MG_DDR_NEAR_DIMM-CLK1_CLS_DDR_L_CAC-CLKS\" )
					)
					( Units "uMatchProp" "ns" 1.000000)
					( Status sCSetFlattened )
					( Origin gBackEnd )
				)
				( attribute "RELATIVE_PROPAGATION_DELAY_SCOPE" "G"
					( Parent
						( matchGroupRef "@baseboard_fab2_lib.baseboard_fab2(sch_1):\MG_DDR_CTRL_NG_DDR_L_DLL_22\" )
					)
					( Status sCSetFlattened )
					( Origin gBackEnd )
				)
				( attribute "RELATIVE_PROPAGATION_DELAY" "0.00 MIL,25.00 MIL"
					( Parent
						( matchGroupRef "@baseboard_fab2_lib.baseboard_fab2(sch_1):\MG_DDR_CTRL_NG_DDR_L_DLL_22\" )
					)
					( Units "uMatchProp" "ns" 1.000000)
					( Status sCSetFlattened )
					( Origin gBackEnd )
				)
			)
			( pinPair "@baseboard_fab2_lib.baseboard_fab2(sch_1):\PP3337\"
				( pinRef "@baseboard_fab2_lib.baseboard_fab2(sch_1):page61_i172:DDR4_CS_N(7)" )
				( pinRef "@baseboard_fab2_lib.baseboard_fab2(sch_1):page86_i12:S3_N_C(1)" )
				( attribute "RELATIVE_PROPAGATION_DELAY_SCOPE" "G"
					( Parent
						( matchGroupRef "@crescent_city_bb_fab1_lib.crescent_city_bb_fab1(sch_1):\MG_DDR_NEAR_DIMM-CLK1_CLS_DDR_L_CAC-CLKS\" )
					)
					( Status sCSetFlattened )
					( Origin gBackEnd )
				)
				( attribute "RELATIVE_PROPAGATION_DELAY" "0.00 MIL,300.00 MIL"
					( Parent
						( matchGroupRef "@crescent_city_bb_fab1_lib.crescent_city_bb_fab1(sch_1):\MG_DDR_NEAR_DIMM-CLK1_CLS_DDR_L_CAC-CLKS\" )
					)
					( Units "uMatchProp" "ns" 1.000000)
					( Status sCSetFlattened )
					( Origin gBackEnd )
				)
				( attribute "RELATIVE_PROPAGATION_DELAY_SCOPE" "G"
					( Parent
						( matchGroupRef "@baseboard_fab2_lib.baseboard_fab2(sch_1):\MG_DDR_CTRL_NG_DDR_L_DLL_22\" )
					)
					( Status sCSetFlattened )
					( Origin gBackEnd )
				)
				( attribute "RELATIVE_PROPAGATION_DELAY" "0.00 MIL,25.00 MIL"
					( Parent
						( matchGroupRef "@baseboard_fab2_lib.baseboard_fab2(sch_1):\MG_DDR_CTRL_NG_DDR_L_DLL_22\" )
					)
					( Units "uMatchProp" "ns" 1.000000)
					( Status sCSetFlattened )
					( Origin gBackEnd )
				)
			)
			( pinPair "@baseboard_fab2_lib.baseboard_fab2(sch_1):\PP3334\"
				( pinRef "@baseboard_fab2_lib.baseboard_fab2(sch_1):page61_i172:DDR4_CS_N(5)" )
				( pinRef "@baseboard_fab2_lib.baseboard_fab2(sch_1):page86_i12:S1_N" )
				( attribute "RELATIVE_PROPAGATION_DELAY_SCOPE" "G"
					( Parent
						( matchGroupRef "@crescent_city_bb_fab1_lib.crescent_city_bb_fab1(sch_1):\MG_DDR_NEAR_DIMM-CLK1_CLS_DDR_L_CAC-CLKS\" )
					)
					( Status sCSetFlattened )
					( Origin gBackEnd )
				)
				( attribute "RELATIVE_PROPAGATION_DELAY" "0.00 MIL,300.00 MIL"
					( Parent
						( matchGroupRef "@crescent_city_bb_fab1_lib.crescent_city_bb_fab1(sch_1):\MG_DDR_NEAR_DIMM-CLK1_CLS_DDR_L_CAC-CLKS\" )
					)
					( Units "uMatchProp" "ns" 1.000000)
					( Status sCSetFlattened )
					( Origin gBackEnd )
				)
				( attribute "RELATIVE_PROPAGATION_DELAY_SCOPE" "G"
					( Parent
						( matchGroupRef "@baseboard_fab2_lib.baseboard_fab2(sch_1):\MG_DDR_CTRL_NG_DDR_L_DLL_23\" )
					)
					( Status sCSetFlattened )
					( Origin gBackEnd )
				)
				( attribute "RELATIVE_PROPAGATION_DELAY" "0.00 MIL,25.00 MIL"
					( Parent
						( matchGroupRef "@baseboard_fab2_lib.baseboard_fab2(sch_1):\MG_DDR_CTRL_NG_DDR_L_DLL_23\" )
					)
					( Units "uMatchProp" "ns" 1.000000)
					( Status sCSetFlattened )
					( Origin gBackEnd )
				)
			)
			( pinPair "@baseboard_fab2_lib.baseboard_fab2(sch_1):\PP3335\"
				( pinRef "@baseboard_fab2_lib.baseboard_fab2(sch_1):page61_i172:DDR4_ODT(3)" )
				( pinRef "@baseboard_fab2_lib.baseboard_fab2(sch_1):page86_i12:ODT(1)" )
				( attribute "RELATIVE_PROPAGATION_DELAY_SCOPE" "G"
					( Parent
						( matchGroupRef "@crescent_city_bb_fab1_lib.crescent_city_bb_fab1(sch_1):\MG_DDR_NEAR_DIMM-CLK1_CLS_DDR_L_CAC-CLKS\" )
					)
					( Status sCSetFlattened )
					( Origin gBackEnd )
				)
				( attribute "RELATIVE_PROPAGATION_DELAY" "0.00 MIL,300.00 MIL"
					( Parent
						( matchGroupRef "@crescent_city_bb_fab1_lib.crescent_city_bb_fab1(sch_1):\MG_DDR_NEAR_DIMM-CLK1_CLS_DDR_L_CAC-CLKS\" )
					)
					( Units "uMatchProp" "ns" 1.000000)
					( Status sCSetFlattened )
					( Origin gBackEnd )
				)
				( attribute "RELATIVE_PROPAGATION_DELAY_SCOPE" "G"
					( Parent
						( matchGroupRef "@baseboard_fab2_lib.baseboard_fab2(sch_1):\MG_DDR_CTRL_NG_DDR_L_DLL_23\" )
					)
					( Status sCSetFlattened )
					( Origin gBackEnd )
				)
				( attribute "RELATIVE_PROPAGATION_DELAY" "0.00 MIL,25.00 MIL"
					( Parent
						( matchGroupRef "@baseboard_fab2_lib.baseboard_fab2(sch_1):\MG_DDR_CTRL_NG_DDR_L_DLL_23\" )
					)
					( Units "uMatchProp" "ns" 1.000000)
					( Status sCSetFlattened )
					( Origin gBackEnd )
				)
			)
			( pinPair "@baseboard_fab2_lib.baseboard_fab2(sch_1):\PP3333\"
				( pinRef "@baseboard_fab2_lib.baseboard_fab2(sch_1):page61_i172:DDR4_CKE(3)" )
				( pinRef "@baseboard_fab2_lib.baseboard_fab2(sch_1):page86_i12:CKE(1)" )
				( attribute "RELATIVE_PROPAGATION_DELAY_SCOPE" "G"
					( Parent
						( matchGroupRef "@crescent_city_bb_fab1_lib.crescent_city_bb_fab1(sch_1):\MG_DDR_NEAR_DIMM-CLK1_CLS_DDR_L_CAC-CLKS\" )
					)
					( Status sCSetFlattened )
					( Origin gBackEnd )
				)
				( attribute "RELATIVE_PROPAGATION_DELAY" "0.00 MIL,300.00 MIL"
					( Parent
						( matchGroupRef "@crescent_city_bb_fab1_lib.crescent_city_bb_fab1(sch_1):\MG_DDR_NEAR_DIMM-CLK1_CLS_DDR_L_CAC-CLKS\" )
					)
					( Units "uMatchProp" "ns" 1.000000)
					( Status sCSetFlattened )
					( Origin gBackEnd )
				)
				( attribute "RELATIVE_PROPAGATION_DELAY_SCOPE" "G"
					( Parent
						( matchGroupRef "@baseboard_fab2_lib.baseboard_fab2(sch_1):\MG_DDR_CTRL_NG_DDR_L_DLL_24\" )
					)
					( Status sCSetFlattened )
					( Origin gBackEnd )
				)
				( attribute "RELATIVE_PROPAGATION_DELAY" "0.00 MIL,25.00 MIL"
					( Parent
						( matchGroupRef "@baseboard_fab2_lib.baseboard_fab2(sch_1):\MG_DDR_CTRL_NG_DDR_L_DLL_24\" )
					)
					( Units "uMatchProp" "ns" 1.000000)
					( Status sCSetFlattened )
					( Origin gBackEnd )
				)
			)
			( pinPair "@baseboard_fab2_lib.baseboard_fab2(sch_1):\PP3461\"
				( pinRef "@baseboard_fab2_lib.baseboard_fab2(sch_1):page60_i172:DDR3_CID(2)" )
				( pinRef "@baseboard_fab2_lib.baseboard_fab2(sch_1):page83_i111:C(2)" )
				( attribute "RELATIVE_PROPAGATION_DELAY_SCOPE" "G"
					( Parent
						( matchGroupRef "@baseboard_fab2_lib.baseboard_fab2(sch_1):\MG_DDR_FAR_DIMM_CMD_NG_DDR_K_DLL_1\" )
					)
					( Status sCSetFlattened )
					( Origin gBackEnd )
				)
				( attribute "RELATIVE_PROPAGATION_DELAY" "0.00 MIL,25.00 MIL"
					( Parent
						( matchGroupRef "@baseboard_fab2_lib.baseboard_fab2(sch_1):\MG_DDR_FAR_DIMM_CMD_NG_DDR_K_DLL_1\" )
					)
					( Units "uMatchProp" "ns" 1.000000)
					( Status sCSetFlattened )
					( Origin gBackEnd )
				)
				( attribute "RELATIVE_PROPAGATION_DELAY_SCOPE" "G"
					( Parent
						( matchGroupRef "@crescent_city_bb_fab1_lib.crescent_city_bb_fab1(sch_1):\MG_DDR_FAR_DIMM-CLK0_CLS_DDR_K_CAC-CLKS\" )
					)
					( Status sCSetFlattened )
					( Origin gBackEnd )
				)
				( attribute "RELATIVE_PROPAGATION_DELAY" "0.00 MIL,700.00 MIL"
					( Parent
						( matchGroupRef "@crescent_city_bb_fab1_lib.crescent_city_bb_fab1(sch_1):\MG_DDR_FAR_DIMM-CLK0_CLS_DDR_K_CAC-CLKS\" )
					)
					( Units "uMatchProp" "ns" 1.000000)
					( Status sCSetFlattened )
					( Origin gBackEnd )
				)
			)
			( pinPair "@baseboard_fab2_lib.baseboard_fab2(sch_1):\PP3462\"
				( pinRef "@baseboard_fab2_lib.baseboard_fab2(sch_1):page84_i14:C(2)" )
				( pinRef "@baseboard_fab2_lib.baseboard_fab2(sch_1):page60_i172:DDR3_CID(2)" )
				( attribute "RELATIVE_PROPAGATION_DELAY_SCOPE" "G"
					( Parent
						( matchGroupRef "@crescent_city_bb_fab1_lib.crescent_city_bb_fab1(sch_1):\MG_DDR_NEAR_DIMM-CLK1_CLS_DDR_K_CAC-CLKS\" )
					)
					( Status sCSetFlattened )
					( Origin gBackEnd )
				)
				( attribute "RELATIVE_PROPAGATION_DELAY" "0.00 MIL,700.00 MIL"
					( Parent
						( matchGroupRef "@crescent_city_bb_fab1_lib.crescent_city_bb_fab1(sch_1):\MG_DDR_NEAR_DIMM-CLK1_CLS_DDR_K_CAC-CLKS\" )
					)
					( Units "uMatchProp" "ns" 1.000000)
					( Status sCSetFlattened )
					( Origin gBackEnd )
				)
				( attribute "RELATIVE_PROPAGATION_DELAY_SCOPE" "G"
					( Parent
						( matchGroupRef "@baseboard_fab2_lib.baseboard_fab2(sch_1):\MG_DDR_CMD_NEAR_DIMM_NG_DDR_K_DLL_1\" )
					)
					( Status sCSetFlattened )
					( Origin gBackEnd )
				)
				( attribute "RELATIVE_PROPAGATION_DELAY" "0.00 MIL,25.00 MIL"
					( Parent
						( matchGroupRef "@baseboard_fab2_lib.baseboard_fab2(sch_1):\MG_DDR_CMD_NEAR_DIMM_NG_DDR_K_DLL_1\" )
					)
					( Units "uMatchProp" "ns" 1.000000)
					( Status sCSetFlattened )
					( Origin gBackEnd )
				)
			)
			( pinPair "@baseboard_fab2_lib.baseboard_fab2(sch_1):\PP3463\"
				( pinRef "@baseboard_fab2_lib.baseboard_fab2(sch_1):page60_i172:DDR3_MA(17)" )
				( pinRef "@baseboard_fab2_lib.baseboard_fab2(sch_1):page83_i111:A17" )
				( attribute "RELATIVE_PROPAGATION_DELAY_SCOPE" "G"
					( Parent
						( matchGroupRef "@baseboard_fab2_lib.baseboard_fab2(sch_1):\MG_DDR_FAR_DIMM_CMD_NG_DDR_K_DLL_1\" )
					)
					( Status sCSetFlattened )
					( Origin gBackEnd )
				)
				( attribute "RELATIVE_PROPAGATION_DELAY" "0.00 MIL,25.00 MIL"
					( Parent
						( matchGroupRef "@baseboard_fab2_lib.baseboard_fab2(sch_1):\MG_DDR_FAR_DIMM_CMD_NG_DDR_K_DLL_1\" )
					)
					( Units "uMatchProp" "ns" 1.000000)
					( Status sCSetFlattened )
					( Origin gBackEnd )
				)
				( attribute "RELATIVE_PROPAGATION_DELAY_SCOPE" "G"
					( Parent
						( matchGroupRef "@crescent_city_bb_fab1_lib.crescent_city_bb_fab1(sch_1):\MG_DDR_FAR_DIMM-CLK0_CLS_DDR_K_CAC-CLKS\" )
					)
					( Status sCSetFlattened )
					( Origin gBackEnd )
				)
				( attribute "RELATIVE_PROPAGATION_DELAY" "0.00 MIL,700.00 MIL"
					( Parent
						( matchGroupRef "@crescent_city_bb_fab1_lib.crescent_city_bb_fab1(sch_1):\MG_DDR_FAR_DIMM-CLK0_CLS_DDR_K_CAC-CLKS\" )
					)
					( Units "uMatchProp" "ns" 1.000000)
					( Status sCSetFlattened )
					( Origin gBackEnd )
				)
			)
			( pinPair "@baseboard_fab2_lib.baseboard_fab2(sch_1):\PP3464\"
				( pinRef "@baseboard_fab2_lib.baseboard_fab2(sch_1):page84_i14:A17" )
				( pinRef "@baseboard_fab2_lib.baseboard_fab2(sch_1):page60_i172:DDR3_MA(17)" )
				( attribute "RELATIVE_PROPAGATION_DELAY_SCOPE" "G"
					( Parent
						( matchGroupRef "@crescent_city_bb_fab1_lib.crescent_city_bb_fab1(sch_1):\MG_DDR_NEAR_DIMM-CLK1_CLS_DDR_K_CAC-CLKS\" )
					)
					( Status sCSetFlattened )
					( Origin gBackEnd )
				)
				( attribute "RELATIVE_PROPAGATION_DELAY" "0.00 MIL,700.00 MIL"
					( Parent
						( matchGroupRef "@crescent_city_bb_fab1_lib.crescent_city_bb_fab1(sch_1):\MG_DDR_NEAR_DIMM-CLK1_CLS_DDR_K_CAC-CLKS\" )
					)
					( Units "uMatchProp" "ns" 1.000000)
					( Status sCSetFlattened )
					( Origin gBackEnd )
				)
				( attribute "RELATIVE_PROPAGATION_DELAY_SCOPE" "G"
					( Parent
						( matchGroupRef "@baseboard_fab2_lib.baseboard_fab2(sch_1):\MG_DDR_CMD_NEAR_DIMM_NG_DDR_K_DLL_1\" )
					)
					( Status sCSetFlattened )
					( Origin gBackEnd )
				)
				( attribute "RELATIVE_PROPAGATION_DELAY" "0.00 MIL,25.00 MIL"
					( Parent
						( matchGroupRef "@baseboard_fab2_lib.baseboard_fab2(sch_1):\MG_DDR_CMD_NEAR_DIMM_NG_DDR_K_DLL_1\" )
					)
					( Units "uMatchProp" "ns" 1.000000)
					( Status sCSetFlattened )
					( Origin gBackEnd )
				)
			)
			( pinPair "@baseboard_fab2_lib.baseboard_fab2(sch_1):\PP3457\"
				( pinRef "@baseboard_fab2_lib.baseboard_fab2(sch_1):page60_i172:DDR3_MA(13)" )
				( pinRef "@baseboard_fab2_lib.baseboard_fab2(sch_1):page83_i111:A13" )
				( attribute "RELATIVE_PROPAGATION_DELAY_SCOPE" "G"
					( Parent
						( matchGroupRef "@crescent_city_bb_fab1_lib.crescent_city_bb_fab1(sch_1):\MG_DDR_FAR_DIMM-CLK0_CLS_DDR_K_CAC-CLKS\" )
					)
					( Status sCSetFlattened )
					( Origin gBackEnd )
				)
				( attribute "RELATIVE_PROPAGATION_DELAY" "0.00 MIL,700.00 MIL"
					( Parent
						( matchGroupRef "@crescent_city_bb_fab1_lib.crescent_city_bb_fab1(sch_1):\MG_DDR_FAR_DIMM-CLK0_CLS_DDR_K_CAC-CLKS\" )
					)
					( Units "uMatchProp" "ns" 1.000000)
					( Status sCSetFlattened )
					( Origin gBackEnd )
				)
				( attribute "RELATIVE_PROPAGATION_DELAY_SCOPE" "G"
					( Parent
						( matchGroupRef "@baseboard_fab2_lib.baseboard_fab2(sch_1):\MG_DDR_FAR_DIMM_CMD_NG_DDR_K_DLL_2\" )
					)
					( Status sCSetFlattened )
					( Origin gBackEnd )
				)
				( attribute "RELATIVE_PROPAGATION_DELAY" "0.00 MIL,25.00 MIL"
					( Parent
						( matchGroupRef "@baseboard_fab2_lib.baseboard_fab2(sch_1):\MG_DDR_FAR_DIMM_CMD_NG_DDR_K_DLL_2\" )
					)
					( Units "uMatchProp" "ns" 1.000000)
					( Status sCSetFlattened )
					( Origin gBackEnd )
				)
			)
			( pinPair "@baseboard_fab2_lib.baseboard_fab2(sch_1):\PP3458\"
				( pinRef "@baseboard_fab2_lib.baseboard_fab2(sch_1):page84_i14:A13" )
				( pinRef "@baseboard_fab2_lib.baseboard_fab2(sch_1):page60_i172:DDR3_MA(13)" )
				( attribute "RELATIVE_PROPAGATION_DELAY_SCOPE" "G"
					( Parent
						( matchGroupRef "@crescent_city_bb_fab1_lib.crescent_city_bb_fab1(sch_1):\MG_DDR_NEAR_DIMM-CLK1_CLS_DDR_K_CAC-CLKS\" )
					)
					( Status sCSetFlattened )
					( Origin gBackEnd )
				)
				( attribute "RELATIVE_PROPAGATION_DELAY" "0.00 MIL,700.00 MIL"
					( Parent
						( matchGroupRef "@crescent_city_bb_fab1_lib.crescent_city_bb_fab1(sch_1):\MG_DDR_NEAR_DIMM-CLK1_CLS_DDR_K_CAC-CLKS\" )
					)
					( Units "uMatchProp" "ns" 1.000000)
					( Status sCSetFlattened )
					( Origin gBackEnd )
				)
				( attribute "RELATIVE_PROPAGATION_DELAY_SCOPE" "G"
					( Parent
						( matchGroupRef "@baseboard_fab2_lib.baseboard_fab2(sch_1):\MG_DDR_CMD_NEAR_DIMM_NG_DDR_K_DLL_2\" )
					)
					( Status sCSetFlattened )
					( Origin gBackEnd )
				)
				( attribute "RELATIVE_PROPAGATION_DELAY" "0.00 MIL,25.00 MIL"
					( Parent
						( matchGroupRef "@baseboard_fab2_lib.baseboard_fab2(sch_1):\MG_DDR_CMD_NEAR_DIMM_NG_DDR_K_DLL_2\" )
					)
					( Units "uMatchProp" "ns" 1.000000)
					( Status sCSetFlattened )
					( Origin gBackEnd )
				)
			)
			( pinPair "@baseboard_fab2_lib.baseboard_fab2(sch_1):\PP3459\"
				( pinRef "@baseboard_fab2_lib.baseboard_fab2(sch_1):page60_i172:DDR3_MA(15)" )
				( pinRef "@baseboard_fab2_lib.baseboard_fab2(sch_1):page83_i111:A15_CAS_N" )
				( attribute "RELATIVE_PROPAGATION_DELAY_SCOPE" "G"
					( Parent
						( matchGroupRef "@crescent_city_bb_fab1_lib.crescent_city_bb_fab1(sch_1):\MG_DDR_FAR_DIMM-CLK0_CLS_DDR_K_CAC-CLKS\" )
					)
					( Status sCSetFlattened )
					( Origin gBackEnd )
				)
				( attribute "RELATIVE_PROPAGATION_DELAY" "0.00 MIL,700.00 MIL"
					( Parent
						( matchGroupRef "@crescent_city_bb_fab1_lib.crescent_city_bb_fab1(sch_1):\MG_DDR_FAR_DIMM-CLK0_CLS_DDR_K_CAC-CLKS\" )
					)
					( Units "uMatchProp" "ns" 1.000000)
					( Status sCSetFlattened )
					( Origin gBackEnd )
				)
				( attribute "RELATIVE_PROPAGATION_DELAY_SCOPE" "G"
					( Parent
						( matchGroupRef "@baseboard_fab2_lib.baseboard_fab2(sch_1):\MG_DDR_FAR_DIMM_CMD_NG_DDR_K_DLL_2\" )
					)
					( Status sCSetFlattened )
					( Origin gBackEnd )
				)
				( attribute "RELATIVE_PROPAGATION_DELAY" "0.00 MIL,25.00 MIL"
					( Parent
						( matchGroupRef "@baseboard_fab2_lib.baseboard_fab2(sch_1):\MG_DDR_FAR_DIMM_CMD_NG_DDR_K_DLL_2\" )
					)
					( Units "uMatchProp" "ns" 1.000000)
					( Status sCSetFlattened )
					( Origin gBackEnd )
				)
			)
			( pinPair "@baseboard_fab2_lib.baseboard_fab2(sch_1):\PP3460\"
				( pinRef "@baseboard_fab2_lib.baseboard_fab2(sch_1):page84_i14:A15_CAS_N" )
				( pinRef "@baseboard_fab2_lib.baseboard_fab2(sch_1):page60_i172:DDR3_MA(15)" )
				( attribute "RELATIVE_PROPAGATION_DELAY_SCOPE" "G"
					( Parent
						( matchGroupRef "@crescent_city_bb_fab1_lib.crescent_city_bb_fab1(sch_1):\MG_DDR_NEAR_DIMM-CLK1_CLS_DDR_K_CAC-CLKS\" )
					)
					( Status sCSetFlattened )
					( Origin gBackEnd )
				)
				( attribute "RELATIVE_PROPAGATION_DELAY" "0.00 MIL,700.00 MIL"
					( Parent
						( matchGroupRef "@crescent_city_bb_fab1_lib.crescent_city_bb_fab1(sch_1):\MG_DDR_NEAR_DIMM-CLK1_CLS_DDR_K_CAC-CLKS\" )
					)
					( Units "uMatchProp" "ns" 1.000000)
					( Status sCSetFlattened )
					( Origin gBackEnd )
				)
				( attribute "RELATIVE_PROPAGATION_DELAY_SCOPE" "G"
					( Parent
						( matchGroupRef "@baseboard_fab2_lib.baseboard_fab2(sch_1):\MG_DDR_CMD_NEAR_DIMM_NG_DDR_K_DLL_2\" )
					)
					( Status sCSetFlattened )
					( Origin gBackEnd )
				)
				( attribute "RELATIVE_PROPAGATION_DELAY" "0.00 MIL,25.00 MIL"
					( Parent
						( matchGroupRef "@baseboard_fab2_lib.baseboard_fab2(sch_1):\MG_DDR_CMD_NEAR_DIMM_NG_DDR_K_DLL_2\" )
					)
					( Units "uMatchProp" "ns" 1.000000)
					( Status sCSetFlattened )
					( Origin gBackEnd )
				)
			)
			( pinPair "@baseboard_fab2_lib.baseboard_fab2(sch_1):\PP3453\"
				( pinRef "@baseboard_fab2_lib.baseboard_fab2(sch_1):page60_i172:DDR3_MA(14)" )
				( pinRef "@baseboard_fab2_lib.baseboard_fab2(sch_1):page83_i111:A14_WE_N" )
				( attribute "RELATIVE_PROPAGATION_DELAY_SCOPE" "G"
					( Parent
						( matchGroupRef "@crescent_city_bb_fab1_lib.crescent_city_bb_fab1(sch_1):\MG_DDR_FAR_DIMM-CLK0_CLS_DDR_K_CAC-CLKS\" )
					)
					( Status sCSetFlattened )
					( Origin gBackEnd )
				)
				( attribute "RELATIVE_PROPAGATION_DELAY" "0.00 MIL,700.00 MIL"
					( Parent
						( matchGroupRef "@crescent_city_bb_fab1_lib.crescent_city_bb_fab1(sch_1):\MG_DDR_FAR_DIMM-CLK0_CLS_DDR_K_CAC-CLKS\" )
					)
					( Units "uMatchProp" "ns" 1.000000)
					( Status sCSetFlattened )
					( Origin gBackEnd )
				)
				( attribute "RELATIVE_PROPAGATION_DELAY_SCOPE" "G"
					( Parent
						( matchGroupRef "@baseboard_fab2_lib.baseboard_fab2(sch_1):\MG_DDR_FAR_DIMM_CMD_NG_DDR_K_DLL_3\" )
					)
					( Status sCSetFlattened )
					( Origin gBackEnd )
				)
				( attribute "RELATIVE_PROPAGATION_DELAY" "0.00 MIL,25.00 MIL"
					( Parent
						( matchGroupRef "@baseboard_fab2_lib.baseboard_fab2(sch_1):\MG_DDR_FAR_DIMM_CMD_NG_DDR_K_DLL_3\" )
					)
					( Units "uMatchProp" "ns" 1.000000)
					( Status sCSetFlattened )
					( Origin gBackEnd )
				)
			)
			( pinPair "@baseboard_fab2_lib.baseboard_fab2(sch_1):\PP3454\"
				( pinRef "@baseboard_fab2_lib.baseboard_fab2(sch_1):page84_i14:A14_WE_N" )
				( pinRef "@baseboard_fab2_lib.baseboard_fab2(sch_1):page60_i172:DDR3_MA(14)" )
				( attribute "RELATIVE_PROPAGATION_DELAY_SCOPE" "G"
					( Parent
						( matchGroupRef "@crescent_city_bb_fab1_lib.crescent_city_bb_fab1(sch_1):\MG_DDR_NEAR_DIMM-CLK1_CLS_DDR_K_CAC-CLKS\" )
					)
					( Status sCSetFlattened )
					( Origin gBackEnd )
				)
				( attribute "RELATIVE_PROPAGATION_DELAY" "0.00 MIL,700.00 MIL"
					( Parent
						( matchGroupRef "@crescent_city_bb_fab1_lib.crescent_city_bb_fab1(sch_1):\MG_DDR_NEAR_DIMM-CLK1_CLS_DDR_K_CAC-CLKS\" )
					)
					( Units "uMatchProp" "ns" 1.000000)
					( Status sCSetFlattened )
					( Origin gBackEnd )
				)
				( attribute "RELATIVE_PROPAGATION_DELAY_SCOPE" "G"
					( Parent
						( matchGroupRef "@baseboard_fab2_lib.baseboard_fab2(sch_1):\MG_DDR_CMD_NEAR_DIMM_NG_DDR_K_DLL_3\" )
					)
					( Status sCSetFlattened )
					( Origin gBackEnd )
				)
				( attribute "RELATIVE_PROPAGATION_DELAY" "0.00 MIL,25.00 MIL"
					( Parent
						( matchGroupRef "@baseboard_fab2_lib.baseboard_fab2(sch_1):\MG_DDR_CMD_NEAR_DIMM_NG_DDR_K_DLL_3\" )
					)
					( Units "uMatchProp" "ns" 1.000000)
					( Status sCSetFlattened )
					( Origin gBackEnd )
				)
			)
			( pinPair "@baseboard_fab2_lib.baseboard_fab2(sch_1):\PP3455\"
				( pinRef "@baseboard_fab2_lib.baseboard_fab2(sch_1):page60_i172:DDR3_MA(16)" )
				( pinRef "@baseboard_fab2_lib.baseboard_fab2(sch_1):page83_i111:A16_RAS_N" )
				( attribute "RELATIVE_PROPAGATION_DELAY_SCOPE" "G"
					( Parent
						( matchGroupRef "@crescent_city_bb_fab1_lib.crescent_city_bb_fab1(sch_1):\MG_DDR_FAR_DIMM-CLK0_CLS_DDR_K_CAC-CLKS\" )
					)
					( Status sCSetFlattened )
					( Origin gBackEnd )
				)
				( attribute "RELATIVE_PROPAGATION_DELAY" "0.00 MIL,700.00 MIL"
					( Parent
						( matchGroupRef "@crescent_city_bb_fab1_lib.crescent_city_bb_fab1(sch_1):\MG_DDR_FAR_DIMM-CLK0_CLS_DDR_K_CAC-CLKS\" )
					)
					( Units "uMatchProp" "ns" 1.000000)
					( Status sCSetFlattened )
					( Origin gBackEnd )
				)
				( attribute "RELATIVE_PROPAGATION_DELAY_SCOPE" "G"
					( Parent
						( matchGroupRef "@baseboard_fab2_lib.baseboard_fab2(sch_1):\MG_DDR_FAR_DIMM_CMD_NG_DDR_K_DLL_3\" )
					)
					( Status sCSetFlattened )
					( Origin gBackEnd )
				)
				( attribute "RELATIVE_PROPAGATION_DELAY" "0.00 MIL,25.00 MIL"
					( Parent
						( matchGroupRef "@baseboard_fab2_lib.baseboard_fab2(sch_1):\MG_DDR_FAR_DIMM_CMD_NG_DDR_K_DLL_3\" )
					)
					( Units "uMatchProp" "ns" 1.000000)
					( Status sCSetFlattened )
					( Origin gBackEnd )
				)
			)
			( pinPair "@baseboard_fab2_lib.baseboard_fab2(sch_1):\PP3456\"
				( pinRef "@baseboard_fab2_lib.baseboard_fab2(sch_1):page84_i14:A16_RAS_N" )
				( pinRef "@baseboard_fab2_lib.baseboard_fab2(sch_1):page60_i172:DDR3_MA(16)" )
				( attribute "RELATIVE_PROPAGATION_DELAY_SCOPE" "G"
					( Parent
						( matchGroupRef "@crescent_city_bb_fab1_lib.crescent_city_bb_fab1(sch_1):\MG_DDR_NEAR_DIMM-CLK1_CLS_DDR_K_CAC-CLKS\" )
					)
					( Status sCSetFlattened )
					( Origin gBackEnd )
				)
				( attribute "RELATIVE_PROPAGATION_DELAY" "0.00 MIL,700.00 MIL"
					( Parent
						( matchGroupRef "@crescent_city_bb_fab1_lib.crescent_city_bb_fab1(sch_1):\MG_DDR_NEAR_DIMM-CLK1_CLS_DDR_K_CAC-CLKS\" )
					)
					( Units "uMatchProp" "ns" 1.000000)
					( Status sCSetFlattened )
					( Origin gBackEnd )
				)
				( attribute "RELATIVE_PROPAGATION_DELAY_SCOPE" "G"
					( Parent
						( matchGroupRef "@baseboard_fab2_lib.baseboard_fab2(sch_1):\MG_DDR_CMD_NEAR_DIMM_NG_DDR_K_DLL_3\" )
					)
					( Status sCSetFlattened )
					( Origin gBackEnd )
				)
				( attribute "RELATIVE_PROPAGATION_DELAY" "0.00 MIL,25.00 MIL"
					( Parent
						( matchGroupRef "@baseboard_fab2_lib.baseboard_fab2(sch_1):\MG_DDR_CMD_NEAR_DIMM_NG_DDR_K_DLL_3\" )
					)
					( Units "uMatchProp" "ns" 1.000000)
					( Status sCSetFlattened )
					( Origin gBackEnd )
				)
			)
			( pinPair "@baseboard_fab2_lib.baseboard_fab2(sch_1):\PP3449\"
				( pinRef "@baseboard_fab2_lib.baseboard_fab2(sch_1):page60_i172:DDR3_BA(1)" )
				( pinRef "@baseboard_fab2_lib.baseboard_fab2(sch_1):page83_i111:BA(1)" )
				( attribute "RELATIVE_PROPAGATION_DELAY_SCOPE" "G"
					( Parent
						( matchGroupRef "@crescent_city_bb_fab1_lib.crescent_city_bb_fab1(sch_1):\MG_DDR_FAR_DIMM-CLK0_CLS_DDR_K_CAC-CLKS\" )
					)
					( Status sCSetFlattened )
					( Origin gBackEnd )
				)
				( attribute "RELATIVE_PROPAGATION_DELAY" "0.00 MIL,700.00 MIL"
					( Parent
						( matchGroupRef "@crescent_city_bb_fab1_lib.crescent_city_bb_fab1(sch_1):\MG_DDR_FAR_DIMM-CLK0_CLS_DDR_K_CAC-CLKS\" )
					)
					( Units "uMatchProp" "ns" 1.000000)
					( Status sCSetFlattened )
					( Origin gBackEnd )
				)
				( attribute "RELATIVE_PROPAGATION_DELAY_SCOPE" "G"
					( Parent
						( matchGroupRef "@baseboard_fab2_lib.baseboard_fab2(sch_1):\MG_DDR_FAR_DIMM_CMD_NG_DDR_K_DLL_4\" )
					)
					( Status sCSetFlattened )
					( Origin gBackEnd )
				)
				( attribute "RELATIVE_PROPAGATION_DELAY" "0.00 MIL,25.00 MIL"
					( Parent
						( matchGroupRef "@baseboard_fab2_lib.baseboard_fab2(sch_1):\MG_DDR_FAR_DIMM_CMD_NG_DDR_K_DLL_4\" )
					)
					( Units "uMatchProp" "ns" 1.000000)
					( Status sCSetFlattened )
					( Origin gBackEnd )
				)
			)
			( pinPair "@baseboard_fab2_lib.baseboard_fab2(sch_1):\PP3450\"
				( pinRef "@baseboard_fab2_lib.baseboard_fab2(sch_1):page84_i14:BA(1)" )
				( pinRef "@baseboard_fab2_lib.baseboard_fab2(sch_1):page60_i172:DDR3_BA(1)" )
				( attribute "RELATIVE_PROPAGATION_DELAY_SCOPE" "G"
					( Parent
						( matchGroupRef "@crescent_city_bb_fab1_lib.crescent_city_bb_fab1(sch_1):\MG_DDR_NEAR_DIMM-CLK1_CLS_DDR_K_CAC-CLKS\" )
					)
					( Status sCSetFlattened )
					( Origin gBackEnd )
				)
				( attribute "RELATIVE_PROPAGATION_DELAY" "0.00 MIL,700.00 MIL"
					( Parent
						( matchGroupRef "@crescent_city_bb_fab1_lib.crescent_city_bb_fab1(sch_1):\MG_DDR_NEAR_DIMM-CLK1_CLS_DDR_K_CAC-CLKS\" )
					)
					( Units "uMatchProp" "ns" 1.000000)
					( Status sCSetFlattened )
					( Origin gBackEnd )
				)
				( attribute "RELATIVE_PROPAGATION_DELAY_SCOPE" "G"
					( Parent
						( matchGroupRef "@baseboard_fab2_lib.baseboard_fab2(sch_1):\MG_DDR_CMD_NEAR_DIMM_NG_DDR_K_DLL_4\" )
					)
					( Status sCSetFlattened )
					( Origin gBackEnd )
				)
				( attribute "RELATIVE_PROPAGATION_DELAY" "0.00 MIL,25.00 MIL"
					( Parent
						( matchGroupRef "@baseboard_fab2_lib.baseboard_fab2(sch_1):\MG_DDR_CMD_NEAR_DIMM_NG_DDR_K_DLL_4\" )
					)
					( Units "uMatchProp" "ns" 1.000000)
					( Status sCSetFlattened )
					( Origin gBackEnd )
				)
			)
			( pinPair "@baseboard_fab2_lib.baseboard_fab2(sch_1):\PP3451\"
				( pinRef "@baseboard_fab2_lib.baseboard_fab2(sch_1):page60_i172:DDR3_MA(10)" )
				( pinRef "@baseboard_fab2_lib.baseboard_fab2(sch_1):page83_i111:A10" )
				( attribute "RELATIVE_PROPAGATION_DELAY_SCOPE" "G"
					( Parent
						( matchGroupRef "@crescent_city_bb_fab1_lib.crescent_city_bb_fab1(sch_1):\MG_DDR_FAR_DIMM-CLK0_CLS_DDR_K_CAC-CLKS\" )
					)
					( Status sCSetFlattened )
					( Origin gBackEnd )
				)
				( attribute "RELATIVE_PROPAGATION_DELAY" "0.00 MIL,700.00 MIL"
					( Parent
						( matchGroupRef "@crescent_city_bb_fab1_lib.crescent_city_bb_fab1(sch_1):\MG_DDR_FAR_DIMM-CLK0_CLS_DDR_K_CAC-CLKS\" )
					)
					( Units "uMatchProp" "ns" 1.000000)
					( Status sCSetFlattened )
					( Origin gBackEnd )
				)
				( attribute "RELATIVE_PROPAGATION_DELAY_SCOPE" "G"
					( Parent
						( matchGroupRef "@baseboard_fab2_lib.baseboard_fab2(sch_1):\MG_DDR_FAR_DIMM_CMD_NG_DDR_K_DLL_4\" )
					)
					( Status sCSetFlattened )
					( Origin gBackEnd )
				)
				( attribute "RELATIVE_PROPAGATION_DELAY" "0.00 MIL,25.00 MIL"
					( Parent
						( matchGroupRef "@baseboard_fab2_lib.baseboard_fab2(sch_1):\MG_DDR_FAR_DIMM_CMD_NG_DDR_K_DLL_4\" )
					)
					( Units "uMatchProp" "ns" 1.000000)
					( Status sCSetFlattened )
					( Origin gBackEnd )
				)
			)
			( pinPair "@baseboard_fab2_lib.baseboard_fab2(sch_1):\PP3452\"
				( pinRef "@baseboard_fab2_lib.baseboard_fab2(sch_1):page84_i14:A10" )
				( pinRef "@baseboard_fab2_lib.baseboard_fab2(sch_1):page60_i172:DDR3_MA(10)" )
				( attribute "RELATIVE_PROPAGATION_DELAY_SCOPE" "G"
					( Parent
						( matchGroupRef "@crescent_city_bb_fab1_lib.crescent_city_bb_fab1(sch_1):\MG_DDR_NEAR_DIMM-CLK1_CLS_DDR_K_CAC-CLKS\" )
					)
					( Status sCSetFlattened )
					( Origin gBackEnd )
				)
				( attribute "RELATIVE_PROPAGATION_DELAY" "0.00 MIL,700.00 MIL"
					( Parent
						( matchGroupRef "@crescent_city_bb_fab1_lib.crescent_city_bb_fab1(sch_1):\MG_DDR_NEAR_DIMM-CLK1_CLS_DDR_K_CAC-CLKS\" )
					)
					( Units "uMatchProp" "ns" 1.000000)
					( Status sCSetFlattened )
					( Origin gBackEnd )
				)
				( attribute "RELATIVE_PROPAGATION_DELAY_SCOPE" "G"
					( Parent
						( matchGroupRef "@baseboard_fab2_lib.baseboard_fab2(sch_1):\MG_DDR_CMD_NEAR_DIMM_NG_DDR_K_DLL_4\" )
					)
					( Status sCSetFlattened )
					( Origin gBackEnd )
				)
				( attribute "RELATIVE_PROPAGATION_DELAY" "0.00 MIL,25.00 MIL"
					( Parent
						( matchGroupRef "@baseboard_fab2_lib.baseboard_fab2(sch_1):\MG_DDR_CMD_NEAR_DIMM_NG_DDR_K_DLL_4\" )
					)
					( Units "uMatchProp" "ns" 1.000000)
					( Status sCSetFlattened )
					( Origin gBackEnd )
				)
			)
			( pinPair "@baseboard_fab2_lib.baseboard_fab2(sch_1):\PP3445\"
				( pinRef "@baseboard_fab2_lib.baseboard_fab2(sch_1):page60_i172:DDR3_BA(0)" )
				( pinRef "@baseboard_fab2_lib.baseboard_fab2(sch_1):page83_i111:BA(0)" )
				( attribute "RELATIVE_PROPAGATION_DELAY_SCOPE" "G"
					( Parent
						( matchGroupRef "@crescent_city_bb_fab1_lib.crescent_city_bb_fab1(sch_1):\MG_DDR_FAR_DIMM-CLK0_CLS_DDR_K_CAC-CLKS\" )
					)
					( Status sCSetFlattened )
					( Origin gBackEnd )
				)
				( attribute "RELATIVE_PROPAGATION_DELAY" "0.00 MIL,700.00 MIL"
					( Parent
						( matchGroupRef "@crescent_city_bb_fab1_lib.crescent_city_bb_fab1(sch_1):\MG_DDR_FAR_DIMM-CLK0_CLS_DDR_K_CAC-CLKS\" )
					)
					( Units "uMatchProp" "ns" 1.000000)
					( Status sCSetFlattened )
					( Origin gBackEnd )
				)
				( attribute "RELATIVE_PROPAGATION_DELAY_SCOPE" "G"
					( Parent
						( matchGroupRef "@baseboard_fab2_lib.baseboard_fab2(sch_1):\MG_DDR_FAR_DIMM_CMD_NG_DDR_K_DLL_5\" )
					)
					( Status sCSetFlattened )
					( Origin gBackEnd )
				)
				( attribute "RELATIVE_PROPAGATION_DELAY" "0.00 MIL,25.00 MIL"
					( Parent
						( matchGroupRef "@baseboard_fab2_lib.baseboard_fab2(sch_1):\MG_DDR_FAR_DIMM_CMD_NG_DDR_K_DLL_5\" )
					)
					( Units "uMatchProp" "ns" 1.000000)
					( Status sCSetFlattened )
					( Origin gBackEnd )
				)
			)
			( pinPair "@baseboard_fab2_lib.baseboard_fab2(sch_1):\PP3446\"
				( pinRef "@baseboard_fab2_lib.baseboard_fab2(sch_1):page84_i14:BA(0)" )
				( pinRef "@baseboard_fab2_lib.baseboard_fab2(sch_1):page60_i172:DDR3_BA(0)" )
				( attribute "RELATIVE_PROPAGATION_DELAY_SCOPE" "G"
					( Parent
						( matchGroupRef "@crescent_city_bb_fab1_lib.crescent_city_bb_fab1(sch_1):\MG_DDR_NEAR_DIMM-CLK1_CLS_DDR_K_CAC-CLKS\" )
					)
					( Status sCSetFlattened )
					( Origin gBackEnd )
				)
				( attribute "RELATIVE_PROPAGATION_DELAY" "0.00 MIL,700.00 MIL"
					( Parent
						( matchGroupRef "@crescent_city_bb_fab1_lib.crescent_city_bb_fab1(sch_1):\MG_DDR_NEAR_DIMM-CLK1_CLS_DDR_K_CAC-CLKS\" )
					)
					( Units "uMatchProp" "ns" 1.000000)
					( Status sCSetFlattened )
					( Origin gBackEnd )
				)
				( attribute "RELATIVE_PROPAGATION_DELAY_SCOPE" "G"
					( Parent
						( matchGroupRef "@baseboard_fab2_lib.baseboard_fab2(sch_1):\MG_DDR_CMD_NEAR_DIMM_NG_DDR_K_DLL_5\" )
					)
					( Status sCSetFlattened )
					( Origin gBackEnd )
				)
				( attribute "RELATIVE_PROPAGATION_DELAY" "0.00 MIL,25.00 MIL"
					( Parent
						( matchGroupRef "@baseboard_fab2_lib.baseboard_fab2(sch_1):\MG_DDR_CMD_NEAR_DIMM_NG_DDR_K_DLL_5\" )
					)
					( Units "uMatchProp" "ns" 1.000000)
					( Status sCSetFlattened )
					( Origin gBackEnd )
				)
			)
			( pinPair "@baseboard_fab2_lib.baseboard_fab2(sch_1):\PP3447\"
				( pinRef "@baseboard_fab2_lib.baseboard_fab2(sch_1):page60_i172:DDR3_MA(0)" )
				( pinRef "@baseboard_fab2_lib.baseboard_fab2(sch_1):page83_i111:A0" )
				( attribute "RELATIVE_PROPAGATION_DELAY_SCOPE" "G"
					( Parent
						( matchGroupRef "@crescent_city_bb_fab1_lib.crescent_city_bb_fab1(sch_1):\MG_DDR_FAR_DIMM-CLK0_CLS_DDR_K_CAC-CLKS\" )
					)
					( Status sCSetFlattened )
					( Origin gBackEnd )
				)
				( attribute "RELATIVE_PROPAGATION_DELAY" "0.00 MIL,700.00 MIL"
					( Parent
						( matchGroupRef "@crescent_city_bb_fab1_lib.crescent_city_bb_fab1(sch_1):\MG_DDR_FAR_DIMM-CLK0_CLS_DDR_K_CAC-CLKS\" )
					)
					( Units "uMatchProp" "ns" 1.000000)
					( Status sCSetFlattened )
					( Origin gBackEnd )
				)
				( attribute "RELATIVE_PROPAGATION_DELAY_SCOPE" "G"
					( Parent
						( matchGroupRef "@baseboard_fab2_lib.baseboard_fab2(sch_1):\MG_DDR_FAR_DIMM_CMD_NG_DDR_K_DLL_5\" )
					)
					( Status sCSetFlattened )
					( Origin gBackEnd )
				)
				( attribute "RELATIVE_PROPAGATION_DELAY" "0.00 MIL,25.00 MIL"
					( Parent
						( matchGroupRef "@baseboard_fab2_lib.baseboard_fab2(sch_1):\MG_DDR_FAR_DIMM_CMD_NG_DDR_K_DLL_5\" )
					)
					( Units "uMatchProp" "ns" 1.000000)
					( Status sCSetFlattened )
					( Origin gBackEnd )
				)
			)
			( pinPair "@baseboard_fab2_lib.baseboard_fab2(sch_1):\PP3448\"
				( pinRef "@baseboard_fab2_lib.baseboard_fab2(sch_1):page84_i14:A0" )
				( pinRef "@baseboard_fab2_lib.baseboard_fab2(sch_1):page60_i172:DDR3_MA(0)" )
				( attribute "RELATIVE_PROPAGATION_DELAY_SCOPE" "G"
					( Parent
						( matchGroupRef "@crescent_city_bb_fab1_lib.crescent_city_bb_fab1(sch_1):\MG_DDR_NEAR_DIMM-CLK1_CLS_DDR_K_CAC-CLKS\" )
					)
					( Status sCSetFlattened )
					( Origin gBackEnd )
				)
				( attribute "RELATIVE_PROPAGATION_DELAY" "0.00 MIL,700.00 MIL"
					( Parent
						( matchGroupRef "@crescent_city_bb_fab1_lib.crescent_city_bb_fab1(sch_1):\MG_DDR_NEAR_DIMM-CLK1_CLS_DDR_K_CAC-CLKS\" )
					)
					( Units "uMatchProp" "ns" 1.000000)
					( Status sCSetFlattened )
					( Origin gBackEnd )
				)
				( attribute "RELATIVE_PROPAGATION_DELAY_SCOPE" "G"
					( Parent
						( matchGroupRef "@baseboard_fab2_lib.baseboard_fab2(sch_1):\MG_DDR_CMD_NEAR_DIMM_NG_DDR_K_DLL_5\" )
					)
					( Status sCSetFlattened )
					( Origin gBackEnd )
				)
				( attribute "RELATIVE_PROPAGATION_DELAY" "0.00 MIL,25.00 MIL"
					( Parent
						( matchGroupRef "@baseboard_fab2_lib.baseboard_fab2(sch_1):\MG_DDR_CMD_NEAR_DIMM_NG_DDR_K_DLL_5\" )
					)
					( Units "uMatchProp" "ns" 1.000000)
					( Status sCSetFlattened )
					( Origin gBackEnd )
				)
			)
			( pinPair "@baseboard_fab2_lib.baseboard_fab2(sch_1):\PP3443\"
				( pinRef "@baseboard_fab2_lib.baseboard_fab2(sch_1):page60_i172:DDR3_PAR" )
				( pinRef "@baseboard_fab2_lib.baseboard_fab2(sch_1):page83_i111:PAR" )
				( attribute "RELATIVE_PROPAGATION_DELAY_SCOPE" "G"
					( Parent
						( matchGroupRef "@crescent_city_bb_fab1_lib.crescent_city_bb_fab1(sch_1):\MG_DDR_FAR_DIMM-CLK0_CLS_DDR_K_CAC-CLKS\" )
					)
					( Status sCSetFlattened )
					( Origin gBackEnd )
				)
				( attribute "RELATIVE_PROPAGATION_DELAY" "0.00 MIL,700.00 MIL"
					( Parent
						( matchGroupRef "@crescent_city_bb_fab1_lib.crescent_city_bb_fab1(sch_1):\MG_DDR_FAR_DIMM-CLK0_CLS_DDR_K_CAC-CLKS\" )
					)
					( Units "uMatchProp" "ns" 1.000000)
					( Status sCSetFlattened )
					( Origin gBackEnd )
				)
				( attribute "RELATIVE_PROPAGATION_DELAY_SCOPE" "G"
					( Parent
						( matchGroupRef "@baseboard_fab2_lib.baseboard_fab2(sch_1):\MG_DDR_FAR_DIMM_CMD_NG_DDR_K_DLL_6\" )
					)
					( Status sCSetFlattened )
					( Origin gBackEnd )
				)
				( attribute "RELATIVE_PROPAGATION_DELAY" "0.00 MIL,25.00 MIL"
					( Parent
						( matchGroupRef "@baseboard_fab2_lib.baseboard_fab2(sch_1):\MG_DDR_FAR_DIMM_CMD_NG_DDR_K_DLL_6\" )
					)
					( Units "uMatchProp" "ns" 1.000000)
					( Status sCSetFlattened )
					( Origin gBackEnd )
				)
			)
			( pinPair "@baseboard_fab2_lib.baseboard_fab2(sch_1):\PP3444\"
				( pinRef "@baseboard_fab2_lib.baseboard_fab2(sch_1):page84_i14:PAR" )
				( pinRef "@baseboard_fab2_lib.baseboard_fab2(sch_1):page60_i172:DDR3_PAR" )
				( attribute "RELATIVE_PROPAGATION_DELAY_SCOPE" "G"
					( Parent
						( matchGroupRef "@crescent_city_bb_fab1_lib.crescent_city_bb_fab1(sch_1):\MG_DDR_NEAR_DIMM-CLK1_CLS_DDR_K_CAC-CLKS\" )
					)
					( Status sCSetFlattened )
					( Origin gBackEnd )
				)
				( attribute "RELATIVE_PROPAGATION_DELAY" "0.00 MIL,700.00 MIL"
					( Parent
						( matchGroupRef "@crescent_city_bb_fab1_lib.crescent_city_bb_fab1(sch_1):\MG_DDR_NEAR_DIMM-CLK1_CLS_DDR_K_CAC-CLKS\" )
					)
					( Units "uMatchProp" "ns" 1.000000)
					( Status sCSetFlattened )
					( Origin gBackEnd )
				)
				( attribute "RELATIVE_PROPAGATION_DELAY_SCOPE" "G"
					( Parent
						( matchGroupRef "@baseboard_fab2_lib.baseboard_fab2(sch_1):\MG_DDR_CMD_NEAR_DIMM_NG_DDR_K_DLL_6\" )
					)
					( Status sCSetFlattened )
					( Origin gBackEnd )
				)
				( attribute "RELATIVE_PROPAGATION_DELAY" "0.00 MIL,25.00 MIL"
					( Parent
						( matchGroupRef "@baseboard_fab2_lib.baseboard_fab2(sch_1):\MG_DDR_CMD_NEAR_DIMM_NG_DDR_K_DLL_6\" )
					)
					( Units "uMatchProp" "ns" 1.000000)
					( Status sCSetFlattened )
					( Origin gBackEnd )
				)
			)
			( pinPair "@baseboard_fab2_lib.baseboard_fab2(sch_1):\PP3439\"
				( pinRef "@baseboard_fab2_lib.baseboard_fab2(sch_1):page60_i172:DDR3_MA(1)" )
				( pinRef "@baseboard_fab2_lib.baseboard_fab2(sch_1):page83_i111:A1" )
				( attribute "RELATIVE_PROPAGATION_DELAY_SCOPE" "G"
					( Parent
						( matchGroupRef "@crescent_city_bb_fab1_lib.crescent_city_bb_fab1(sch_1):\MG_DDR_FAR_DIMM-CLK0_CLS_DDR_K_CAC-CLKS\" )
					)
					( Status sCSetFlattened )
					( Origin gBackEnd )
				)
				( attribute "RELATIVE_PROPAGATION_DELAY" "0.00 MIL,700.00 MIL"
					( Parent
						( matchGroupRef "@crescent_city_bb_fab1_lib.crescent_city_bb_fab1(sch_1):\MG_DDR_FAR_DIMM-CLK0_CLS_DDR_K_CAC-CLKS\" )
					)
					( Units "uMatchProp" "ns" 1.000000)
					( Status sCSetFlattened )
					( Origin gBackEnd )
				)
				( attribute "RELATIVE_PROPAGATION_DELAY_SCOPE" "G"
					( Parent
						( matchGroupRef "@baseboard_fab2_lib.baseboard_fab2(sch_1):\MG_DDR_FAR_DIMM_CMD_NG_DDR_K_DLL_7\" )
					)
					( Status sCSetFlattened )
					( Origin gBackEnd )
				)
				( attribute "RELATIVE_PROPAGATION_DELAY" "0.00 MIL,25.00 MIL"
					( Parent
						( matchGroupRef "@baseboard_fab2_lib.baseboard_fab2(sch_1):\MG_DDR_FAR_DIMM_CMD_NG_DDR_K_DLL_7\" )
					)
					( Units "uMatchProp" "ns" 1.000000)
					( Status sCSetFlattened )
					( Origin gBackEnd )
				)
			)
			( pinPair "@baseboard_fab2_lib.baseboard_fab2(sch_1):\PP3440\"
				( pinRef "@baseboard_fab2_lib.baseboard_fab2(sch_1):page84_i14:A1" )
				( pinRef "@baseboard_fab2_lib.baseboard_fab2(sch_1):page60_i172:DDR3_MA(1)" )
				( attribute "RELATIVE_PROPAGATION_DELAY_SCOPE" "G"
					( Parent
						( matchGroupRef "@crescent_city_bb_fab1_lib.crescent_city_bb_fab1(sch_1):\MG_DDR_NEAR_DIMM-CLK1_CLS_DDR_K_CAC-CLKS\" )
					)
					( Status sCSetFlattened )
					( Origin gBackEnd )
				)
				( attribute "RELATIVE_PROPAGATION_DELAY" "0.00 MIL,700.00 MIL"
					( Parent
						( matchGroupRef "@crescent_city_bb_fab1_lib.crescent_city_bb_fab1(sch_1):\MG_DDR_NEAR_DIMM-CLK1_CLS_DDR_K_CAC-CLKS\" )
					)
					( Units "uMatchProp" "ns" 1.000000)
					( Status sCSetFlattened )
					( Origin gBackEnd )
				)
				( attribute "RELATIVE_PROPAGATION_DELAY_SCOPE" "G"
					( Parent
						( matchGroupRef "@baseboard_fab2_lib.baseboard_fab2(sch_1):\MG_DDR_CMD_NEAR_DIMM_NG_DDR_K_DLL_7\" )
					)
					( Status sCSetFlattened )
					( Origin gBackEnd )
				)
				( attribute "RELATIVE_PROPAGATION_DELAY" "0.00 MIL,25.00 MIL"
					( Parent
						( matchGroupRef "@baseboard_fab2_lib.baseboard_fab2(sch_1):\MG_DDR_CMD_NEAR_DIMM_NG_DDR_K_DLL_7\" )
					)
					( Units "uMatchProp" "ns" 1.000000)
					( Status sCSetFlattened )
					( Origin gBackEnd )
				)
			)
			( pinPair "@baseboard_fab2_lib.baseboard_fab2(sch_1):\PP3441\"
				( pinRef "@baseboard_fab2_lib.baseboard_fab2(sch_1):page60_i172:DDR3_MA(3)" )
				( pinRef "@baseboard_fab2_lib.baseboard_fab2(sch_1):page83_i111:A3" )
				( attribute "RELATIVE_PROPAGATION_DELAY_SCOPE" "G"
					( Parent
						( matchGroupRef "@crescent_city_bb_fab1_lib.crescent_city_bb_fab1(sch_1):\MG_DDR_FAR_DIMM-CLK0_CLS_DDR_K_CAC-CLKS\" )
					)
					( Status sCSetFlattened )
					( Origin gBackEnd )
				)
				( attribute "RELATIVE_PROPAGATION_DELAY" "0.00 MIL,700.00 MIL"
					( Parent
						( matchGroupRef "@crescent_city_bb_fab1_lib.crescent_city_bb_fab1(sch_1):\MG_DDR_FAR_DIMM-CLK0_CLS_DDR_K_CAC-CLKS\" )
					)
					( Units "uMatchProp" "ns" 1.000000)
					( Status sCSetFlattened )
					( Origin gBackEnd )
				)
				( attribute "RELATIVE_PROPAGATION_DELAY_SCOPE" "G"
					( Parent
						( matchGroupRef "@baseboard_fab2_lib.baseboard_fab2(sch_1):\MG_DDR_FAR_DIMM_CMD_NG_DDR_K_DLL_7\" )
					)
					( Status sCSetFlattened )
					( Origin gBackEnd )
				)
				( attribute "RELATIVE_PROPAGATION_DELAY" "0.00 MIL,25.00 MIL"
					( Parent
						( matchGroupRef "@baseboard_fab2_lib.baseboard_fab2(sch_1):\MG_DDR_FAR_DIMM_CMD_NG_DDR_K_DLL_7\" )
					)
					( Units "uMatchProp" "ns" 1.000000)
					( Status sCSetFlattened )
					( Origin gBackEnd )
				)
			)
			( pinPair "@baseboard_fab2_lib.baseboard_fab2(sch_1):\PP3442\"
				( pinRef "@baseboard_fab2_lib.baseboard_fab2(sch_1):page84_i14:A3" )
				( pinRef "@baseboard_fab2_lib.baseboard_fab2(sch_1):page60_i172:DDR3_MA(3)" )
				( attribute "RELATIVE_PROPAGATION_DELAY_SCOPE" "G"
					( Parent
						( matchGroupRef "@crescent_city_bb_fab1_lib.crescent_city_bb_fab1(sch_1):\MG_DDR_NEAR_DIMM-CLK1_CLS_DDR_K_CAC-CLKS\" )
					)
					( Status sCSetFlattened )
					( Origin gBackEnd )
				)
				( attribute "RELATIVE_PROPAGATION_DELAY" "0.00 MIL,700.00 MIL"
					( Parent
						( matchGroupRef "@crescent_city_bb_fab1_lib.crescent_city_bb_fab1(sch_1):\MG_DDR_NEAR_DIMM-CLK1_CLS_DDR_K_CAC-CLKS\" )
					)
					( Units "uMatchProp" "ns" 1.000000)
					( Status sCSetFlattened )
					( Origin gBackEnd )
				)
				( attribute "RELATIVE_PROPAGATION_DELAY_SCOPE" "G"
					( Parent
						( matchGroupRef "@baseboard_fab2_lib.baseboard_fab2(sch_1):\MG_DDR_CMD_NEAR_DIMM_NG_DDR_K_DLL_7\" )
					)
					( Status sCSetFlattened )
					( Origin gBackEnd )
				)
				( attribute "RELATIVE_PROPAGATION_DELAY" "0.00 MIL,25.00 MIL"
					( Parent
						( matchGroupRef "@baseboard_fab2_lib.baseboard_fab2(sch_1):\MG_DDR_CMD_NEAR_DIMM_NG_DDR_K_DLL_7\" )
					)
					( Units "uMatchProp" "ns" 1.000000)
					( Status sCSetFlattened )
					( Origin gBackEnd )
				)
			)
			( pinPair "@baseboard_fab2_lib.baseboard_fab2(sch_1):\PP3435\"
				( pinRef "@baseboard_fab2_lib.baseboard_fab2(sch_1):page60_i172:DDR3_MA(2)" )
				( pinRef "@baseboard_fab2_lib.baseboard_fab2(sch_1):page83_i111:A2" )
				( attribute "RELATIVE_PROPAGATION_DELAY_SCOPE" "G"
					( Parent
						( matchGroupRef "@crescent_city_bb_fab1_lib.crescent_city_bb_fab1(sch_1):\MG_DDR_FAR_DIMM-CLK0_CLS_DDR_K_CAC-CLKS\" )
					)
					( Status sCSetFlattened )
					( Origin gBackEnd )
				)
				( attribute "RELATIVE_PROPAGATION_DELAY" "0.00 MIL,700.00 MIL"
					( Parent
						( matchGroupRef "@crescent_city_bb_fab1_lib.crescent_city_bb_fab1(sch_1):\MG_DDR_FAR_DIMM-CLK0_CLS_DDR_K_CAC-CLKS\" )
					)
					( Units "uMatchProp" "ns" 1.000000)
					( Status sCSetFlattened )
					( Origin gBackEnd )
				)
				( attribute "RELATIVE_PROPAGATION_DELAY_SCOPE" "G"
					( Parent
						( matchGroupRef "@baseboard_fab2_lib.baseboard_fab2(sch_1):\MG_DDR_FAR_DIMM_CMD_NG_DDR_K_DLL_8\" )
					)
					( Status sCSetFlattened )
					( Origin gBackEnd )
				)
				( attribute "RELATIVE_PROPAGATION_DELAY" "0.00 MIL,25.00 MIL"
					( Parent
						( matchGroupRef "@baseboard_fab2_lib.baseboard_fab2(sch_1):\MG_DDR_FAR_DIMM_CMD_NG_DDR_K_DLL_8\" )
					)
					( Units "uMatchProp" "ns" 1.000000)
					( Status sCSetFlattened )
					( Origin gBackEnd )
				)
			)
			( pinPair "@baseboard_fab2_lib.baseboard_fab2(sch_1):\PP3436\"
				( pinRef "@baseboard_fab2_lib.baseboard_fab2(sch_1):page84_i14:A2" )
				( pinRef "@baseboard_fab2_lib.baseboard_fab2(sch_1):page60_i172:DDR3_MA(2)" )
				( attribute "RELATIVE_PROPAGATION_DELAY_SCOPE" "G"
					( Parent
						( matchGroupRef "@crescent_city_bb_fab1_lib.crescent_city_bb_fab1(sch_1):\MG_DDR_NEAR_DIMM-CLK1_CLS_DDR_K_CAC-CLKS\" )
					)
					( Status sCSetFlattened )
					( Origin gBackEnd )
				)
				( attribute "RELATIVE_PROPAGATION_DELAY" "0.00 MIL,700.00 MIL"
					( Parent
						( matchGroupRef "@crescent_city_bb_fab1_lib.crescent_city_bb_fab1(sch_1):\MG_DDR_NEAR_DIMM-CLK1_CLS_DDR_K_CAC-CLKS\" )
					)
					( Units "uMatchProp" "ns" 1.000000)
					( Status sCSetFlattened )
					( Origin gBackEnd )
				)
				( attribute "RELATIVE_PROPAGATION_DELAY_SCOPE" "G"
					( Parent
						( matchGroupRef "@baseboard_fab2_lib.baseboard_fab2(sch_1):\MG_DDR_CMD_NEAR_DIMM_NG_DDR_K_DLL_8\" )
					)
					( Status sCSetFlattened )
					( Origin gBackEnd )
				)
				( attribute "RELATIVE_PROPAGATION_DELAY" "0.00 MIL,25.00 MIL"
					( Parent
						( matchGroupRef "@baseboard_fab2_lib.baseboard_fab2(sch_1):\MG_DDR_CMD_NEAR_DIMM_NG_DDR_K_DLL_8\" )
					)
					( Units "uMatchProp" "ns" 1.000000)
					( Status sCSetFlattened )
					( Origin gBackEnd )
				)
			)
			( pinPair "@baseboard_fab2_lib.baseboard_fab2(sch_1):\PP3437\"
				( pinRef "@baseboard_fab2_lib.baseboard_fab2(sch_1):page60_i172:DDR3_MA(4)" )
				( pinRef "@baseboard_fab2_lib.baseboard_fab2(sch_1):page83_i111:A4" )
				( attribute "RELATIVE_PROPAGATION_DELAY_SCOPE" "G"
					( Parent
						( matchGroupRef "@crescent_city_bb_fab1_lib.crescent_city_bb_fab1(sch_1):\MG_DDR_FAR_DIMM-CLK0_CLS_DDR_K_CAC-CLKS\" )
					)
					( Status sCSetFlattened )
					( Origin gBackEnd )
				)
				( attribute "RELATIVE_PROPAGATION_DELAY" "0.00 MIL,700.00 MIL"
					( Parent
						( matchGroupRef "@crescent_city_bb_fab1_lib.crescent_city_bb_fab1(sch_1):\MG_DDR_FAR_DIMM-CLK0_CLS_DDR_K_CAC-CLKS\" )
					)
					( Units "uMatchProp" "ns" 1.000000)
					( Status sCSetFlattened )
					( Origin gBackEnd )
				)
				( attribute "RELATIVE_PROPAGATION_DELAY_SCOPE" "G"
					( Parent
						( matchGroupRef "@baseboard_fab2_lib.baseboard_fab2(sch_1):\MG_DDR_FAR_DIMM_CMD_NG_DDR_K_DLL_8\" )
					)
					( Status sCSetFlattened )
					( Origin gBackEnd )
				)
				( attribute "RELATIVE_PROPAGATION_DELAY" "0.00 MIL,25.00 MIL"
					( Parent
						( matchGroupRef "@baseboard_fab2_lib.baseboard_fab2(sch_1):\MG_DDR_FAR_DIMM_CMD_NG_DDR_K_DLL_8\" )
					)
					( Units "uMatchProp" "ns" 1.000000)
					( Status sCSetFlattened )
					( Origin gBackEnd )
				)
			)
			( pinPair "@baseboard_fab2_lib.baseboard_fab2(sch_1):\PP3438\"
				( pinRef "@baseboard_fab2_lib.baseboard_fab2(sch_1):page84_i14:A4" )
				( pinRef "@baseboard_fab2_lib.baseboard_fab2(sch_1):page60_i172:DDR3_MA(4)" )
				( attribute "RELATIVE_PROPAGATION_DELAY_SCOPE" "G"
					( Parent
						( matchGroupRef "@crescent_city_bb_fab1_lib.crescent_city_bb_fab1(sch_1):\MG_DDR_NEAR_DIMM-CLK1_CLS_DDR_K_CAC-CLKS\" )
					)
					( Status sCSetFlattened )
					( Origin gBackEnd )
				)
				( attribute "RELATIVE_PROPAGATION_DELAY" "0.00 MIL,700.00 MIL"
					( Parent
						( matchGroupRef "@crescent_city_bb_fab1_lib.crescent_city_bb_fab1(sch_1):\MG_DDR_NEAR_DIMM-CLK1_CLS_DDR_K_CAC-CLKS\" )
					)
					( Units "uMatchProp" "ns" 1.000000)
					( Status sCSetFlattened )
					( Origin gBackEnd )
				)
				( attribute "RELATIVE_PROPAGATION_DELAY_SCOPE" "G"
					( Parent
						( matchGroupRef "@baseboard_fab2_lib.baseboard_fab2(sch_1):\MG_DDR_CMD_NEAR_DIMM_NG_DDR_K_DLL_8\" )
					)
					( Status sCSetFlattened )
					( Origin gBackEnd )
				)
				( attribute "RELATIVE_PROPAGATION_DELAY" "0.00 MIL,25.00 MIL"
					( Parent
						( matchGroupRef "@baseboard_fab2_lib.baseboard_fab2(sch_1):\MG_DDR_CMD_NEAR_DIMM_NG_DDR_K_DLL_8\" )
					)
					( Units "uMatchProp" "ns" 1.000000)
					( Status sCSetFlattened )
					( Origin gBackEnd )
				)
			)
			( pinPair "@baseboard_fab2_lib.baseboard_fab2(sch_1):\PP3431\"
				( pinRef "@baseboard_fab2_lib.baseboard_fab2(sch_1):page60_i172:DDR3_MA(5)" )
				( pinRef "@baseboard_fab2_lib.baseboard_fab2(sch_1):page83_i111:A5" )
				( attribute "RELATIVE_PROPAGATION_DELAY_SCOPE" "G"
					( Parent
						( matchGroupRef "@crescent_city_bb_fab1_lib.crescent_city_bb_fab1(sch_1):\MG_DDR_FAR_DIMM-CLK0_CLS_DDR_K_CAC-CLKS\" )
					)
					( Status sCSetFlattened )
					( Origin gBackEnd )
				)
				( attribute "RELATIVE_PROPAGATION_DELAY" "0.00 MIL,700.00 MIL"
					( Parent
						( matchGroupRef "@crescent_city_bb_fab1_lib.crescent_city_bb_fab1(sch_1):\MG_DDR_FAR_DIMM-CLK0_CLS_DDR_K_CAC-CLKS\" )
					)
					( Units "uMatchProp" "ns" 1.000000)
					( Status sCSetFlattened )
					( Origin gBackEnd )
				)
				( attribute "RELATIVE_PROPAGATION_DELAY_SCOPE" "G"
					( Parent
						( matchGroupRef "@baseboard_fab2_lib.baseboard_fab2(sch_1):\MG_DDR_FAR_DIMM_CMD_NG_DDR_K_DLL_9\" )
					)
					( Status sCSetFlattened )
					( Origin gBackEnd )
				)
				( attribute "RELATIVE_PROPAGATION_DELAY" "0.00 MIL,25.00 MIL"
					( Parent
						( matchGroupRef "@baseboard_fab2_lib.baseboard_fab2(sch_1):\MG_DDR_FAR_DIMM_CMD_NG_DDR_K_DLL_9\" )
					)
					( Units "uMatchProp" "ns" 1.000000)
					( Status sCSetFlattened )
					( Origin gBackEnd )
				)
			)
			( pinPair "@baseboard_fab2_lib.baseboard_fab2(sch_1):\PP3432\"
				( pinRef "@baseboard_fab2_lib.baseboard_fab2(sch_1):page84_i14:A5" )
				( pinRef "@baseboard_fab2_lib.baseboard_fab2(sch_1):page60_i172:DDR3_MA(5)" )
				( attribute "RELATIVE_PROPAGATION_DELAY_SCOPE" "G"
					( Parent
						( matchGroupRef "@crescent_city_bb_fab1_lib.crescent_city_bb_fab1(sch_1):\MG_DDR_NEAR_DIMM-CLK1_CLS_DDR_K_CAC-CLKS\" )
					)
					( Status sCSetFlattened )
					( Origin gBackEnd )
				)
				( attribute "RELATIVE_PROPAGATION_DELAY" "0.00 MIL,700.00 MIL"
					( Parent
						( matchGroupRef "@crescent_city_bb_fab1_lib.crescent_city_bb_fab1(sch_1):\MG_DDR_NEAR_DIMM-CLK1_CLS_DDR_K_CAC-CLKS\" )
					)
					( Units "uMatchProp" "ns" 1.000000)
					( Status sCSetFlattened )
					( Origin gBackEnd )
				)
				( attribute "RELATIVE_PROPAGATION_DELAY_SCOPE" "G"
					( Parent
						( matchGroupRef "@baseboard_fab2_lib.baseboard_fab2(sch_1):\MG_DDR_CMD_NEAR_DIMM_NG_DDR_K_DLL_9\" )
					)
					( Status sCSetFlattened )
					( Origin gBackEnd )
				)
				( attribute "RELATIVE_PROPAGATION_DELAY" "0.00 MIL,25.00 MIL"
					( Parent
						( matchGroupRef "@baseboard_fab2_lib.baseboard_fab2(sch_1):\MG_DDR_CMD_NEAR_DIMM_NG_DDR_K_DLL_9\" )
					)
					( Units "uMatchProp" "ns" 1.000000)
					( Status sCSetFlattened )
					( Origin gBackEnd )
				)
			)
			( pinPair "@baseboard_fab2_lib.baseboard_fab2(sch_1):\PP3433\"
				( pinRef "@baseboard_fab2_lib.baseboard_fab2(sch_1):page60_i172:DDR3_MA(6)" )
				( pinRef "@baseboard_fab2_lib.baseboard_fab2(sch_1):page83_i111:A6" )
				( attribute "RELATIVE_PROPAGATION_DELAY_SCOPE" "G"
					( Parent
						( matchGroupRef "@crescent_city_bb_fab1_lib.crescent_city_bb_fab1(sch_1):\MG_DDR_FAR_DIMM-CLK0_CLS_DDR_K_CAC-CLKS\" )
					)
					( Status sCSetFlattened )
					( Origin gBackEnd )
				)
				( attribute "RELATIVE_PROPAGATION_DELAY" "0.00 MIL,700.00 MIL"
					( Parent
						( matchGroupRef "@crescent_city_bb_fab1_lib.crescent_city_bb_fab1(sch_1):\MG_DDR_FAR_DIMM-CLK0_CLS_DDR_K_CAC-CLKS\" )
					)
					( Units "uMatchProp" "ns" 1.000000)
					( Status sCSetFlattened )
					( Origin gBackEnd )
				)
				( attribute "RELATIVE_PROPAGATION_DELAY_SCOPE" "G"
					( Parent
						( matchGroupRef "@baseboard_fab2_lib.baseboard_fab2(sch_1):\MG_DDR_FAR_DIMM_CMD_NG_DDR_K_DLL_9\" )
					)
					( Status sCSetFlattened )
					( Origin gBackEnd )
				)
				( attribute "RELATIVE_PROPAGATION_DELAY" "0.00 MIL,25.00 MIL"
					( Parent
						( matchGroupRef "@baseboard_fab2_lib.baseboard_fab2(sch_1):\MG_DDR_FAR_DIMM_CMD_NG_DDR_K_DLL_9\" )
					)
					( Units "uMatchProp" "ns" 1.000000)
					( Status sCSetFlattened )
					( Origin gBackEnd )
				)
			)
			( pinPair "@baseboard_fab2_lib.baseboard_fab2(sch_1):\PP3434\"
				( pinRef "@baseboard_fab2_lib.baseboard_fab2(sch_1):page84_i14:A6" )
				( pinRef "@baseboard_fab2_lib.baseboard_fab2(sch_1):page60_i172:DDR3_MA(6)" )
				( attribute "RELATIVE_PROPAGATION_DELAY_SCOPE" "G"
					( Parent
						( matchGroupRef "@crescent_city_bb_fab1_lib.crescent_city_bb_fab1(sch_1):\MG_DDR_NEAR_DIMM-CLK1_CLS_DDR_K_CAC-CLKS\" )
					)
					( Status sCSetFlattened )
					( Origin gBackEnd )
				)
				( attribute "RELATIVE_PROPAGATION_DELAY" "0.00 MIL,700.00 MIL"
					( Parent
						( matchGroupRef "@crescent_city_bb_fab1_lib.crescent_city_bb_fab1(sch_1):\MG_DDR_NEAR_DIMM-CLK1_CLS_DDR_K_CAC-CLKS\" )
					)
					( Units "uMatchProp" "ns" 1.000000)
					( Status sCSetFlattened )
					( Origin gBackEnd )
				)
				( attribute "RELATIVE_PROPAGATION_DELAY_SCOPE" "G"
					( Parent
						( matchGroupRef "@baseboard_fab2_lib.baseboard_fab2(sch_1):\MG_DDR_CMD_NEAR_DIMM_NG_DDR_K_DLL_9\" )
					)
					( Status sCSetFlattened )
					( Origin gBackEnd )
				)
				( attribute "RELATIVE_PROPAGATION_DELAY" "0.00 MIL,25.00 MIL"
					( Parent
						( matchGroupRef "@baseboard_fab2_lib.baseboard_fab2(sch_1):\MG_DDR_CMD_NEAR_DIMM_NG_DDR_K_DLL_9\" )
					)
					( Units "uMatchProp" "ns" 1.000000)
					( Status sCSetFlattened )
					( Origin gBackEnd )
				)
			)
			( pinPair "@baseboard_fab2_lib.baseboard_fab2(sch_1):\PP3427\"
				( pinRef "@baseboard_fab2_lib.baseboard_fab2(sch_1):page60_i172:DDR3_MA(7)" )
				( pinRef "@baseboard_fab2_lib.baseboard_fab2(sch_1):page83_i111:A7" )
				( attribute "RELATIVE_PROPAGATION_DELAY_SCOPE" "G"
					( Parent
						( matchGroupRef "@crescent_city_bb_fab1_lib.crescent_city_bb_fab1(sch_1):\MG_DDR_FAR_DIMM-CLK0_CLS_DDR_K_CAC-CLKS\" )
					)
					( Status sCSetFlattened )
					( Origin gBackEnd )
				)
				( attribute "RELATIVE_PROPAGATION_DELAY" "0.00 MIL,700.00 MIL"
					( Parent
						( matchGroupRef "@crescent_city_bb_fab1_lib.crescent_city_bb_fab1(sch_1):\MG_DDR_FAR_DIMM-CLK0_CLS_DDR_K_CAC-CLKS\" )
					)
					( Units "uMatchProp" "ns" 1.000000)
					( Status sCSetFlattened )
					( Origin gBackEnd )
				)
				( attribute "RELATIVE_PROPAGATION_DELAY_SCOPE" "G"
					( Parent
						( matchGroupRef "@baseboard_fab2_lib.baseboard_fab2(sch_1):\MG_DDR_FAR_DIMM_CMD_NG_DDR_K_DLL_10\" )
					)
					( Status sCSetFlattened )
					( Origin gBackEnd )
				)
				( attribute "RELATIVE_PROPAGATION_DELAY" "0.00 MIL,25.00 MIL"
					( Parent
						( matchGroupRef "@baseboard_fab2_lib.baseboard_fab2(sch_1):\MG_DDR_FAR_DIMM_CMD_NG_DDR_K_DLL_10\" )
					)
					( Units "uMatchProp" "ns" 1.000000)
					( Status sCSetFlattened )
					( Origin gBackEnd )
				)
			)
			( pinPair "@baseboard_fab2_lib.baseboard_fab2(sch_1):\PP3428\"
				( pinRef "@baseboard_fab2_lib.baseboard_fab2(sch_1):page84_i14:A7" )
				( pinRef "@baseboard_fab2_lib.baseboard_fab2(sch_1):page60_i172:DDR3_MA(7)" )
				( attribute "RELATIVE_PROPAGATION_DELAY_SCOPE" "G"
					( Parent
						( matchGroupRef "@crescent_city_bb_fab1_lib.crescent_city_bb_fab1(sch_1):\MG_DDR_NEAR_DIMM-CLK1_CLS_DDR_K_CAC-CLKS\" )
					)
					( Status sCSetFlattened )
					( Origin gBackEnd )
				)
				( attribute "RELATIVE_PROPAGATION_DELAY" "0.00 MIL,700.00 MIL"
					( Parent
						( matchGroupRef "@crescent_city_bb_fab1_lib.crescent_city_bb_fab1(sch_1):\MG_DDR_NEAR_DIMM-CLK1_CLS_DDR_K_CAC-CLKS\" )
					)
					( Units "uMatchProp" "ns" 1.000000)
					( Status sCSetFlattened )
					( Origin gBackEnd )
				)
				( attribute "RELATIVE_PROPAGATION_DELAY_SCOPE" "G"
					( Parent
						( matchGroupRef "@baseboard_fab2_lib.baseboard_fab2(sch_1):\MG_DDR_CMD_NEAR_DIMM_NG_DDR_K_DLL_10\" )
					)
					( Status sCSetFlattened )
					( Origin gBackEnd )
				)
				( attribute "RELATIVE_PROPAGATION_DELAY" "0.00 MIL,25.00 MIL"
					( Parent
						( matchGroupRef "@baseboard_fab2_lib.baseboard_fab2(sch_1):\MG_DDR_CMD_NEAR_DIMM_NG_DDR_K_DLL_10\" )
					)
					( Units "uMatchProp" "ns" 1.000000)
					( Status sCSetFlattened )
					( Origin gBackEnd )
				)
			)
			( pinPair "@baseboard_fab2_lib.baseboard_fab2(sch_1):\PP3429\"
				( pinRef "@baseboard_fab2_lib.baseboard_fab2(sch_1):page60_i172:DDR3_MA(8)" )
				( pinRef "@baseboard_fab2_lib.baseboard_fab2(sch_1):page83_i111:A8" )
				( attribute "RELATIVE_PROPAGATION_DELAY_SCOPE" "G"
					( Parent
						( matchGroupRef "@crescent_city_bb_fab1_lib.crescent_city_bb_fab1(sch_1):\MG_DDR_FAR_DIMM-CLK0_CLS_DDR_K_CAC-CLKS\" )
					)
					( Status sCSetFlattened )
					( Origin gBackEnd )
				)
				( attribute "RELATIVE_PROPAGATION_DELAY" "0.00 MIL,700.00 MIL"
					( Parent
						( matchGroupRef "@crescent_city_bb_fab1_lib.crescent_city_bb_fab1(sch_1):\MG_DDR_FAR_DIMM-CLK0_CLS_DDR_K_CAC-CLKS\" )
					)
					( Units "uMatchProp" "ns" 1.000000)
					( Status sCSetFlattened )
					( Origin gBackEnd )
				)
				( attribute "RELATIVE_PROPAGATION_DELAY_SCOPE" "G"
					( Parent
						( matchGroupRef "@baseboard_fab2_lib.baseboard_fab2(sch_1):\MG_DDR_FAR_DIMM_CMD_NG_DDR_K_DLL_10\" )
					)
					( Status sCSetFlattened )
					( Origin gBackEnd )
				)
				( attribute "RELATIVE_PROPAGATION_DELAY" "0.00 MIL,25.00 MIL"
					( Parent
						( matchGroupRef "@baseboard_fab2_lib.baseboard_fab2(sch_1):\MG_DDR_FAR_DIMM_CMD_NG_DDR_K_DLL_10\" )
					)
					( Units "uMatchProp" "ns" 1.000000)
					( Status sCSetFlattened )
					( Origin gBackEnd )
				)
			)
			( pinPair "@baseboard_fab2_lib.baseboard_fab2(sch_1):\PP3430\"
				( pinRef "@baseboard_fab2_lib.baseboard_fab2(sch_1):page84_i14:A8" )
				( pinRef "@baseboard_fab2_lib.baseboard_fab2(sch_1):page60_i172:DDR3_MA(8)" )
				( attribute "RELATIVE_PROPAGATION_DELAY_SCOPE" "G"
					( Parent
						( matchGroupRef "@crescent_city_bb_fab1_lib.crescent_city_bb_fab1(sch_1):\MG_DDR_NEAR_DIMM-CLK1_CLS_DDR_K_CAC-CLKS\" )
					)
					( Status sCSetFlattened )
					( Origin gBackEnd )
				)
				( attribute "RELATIVE_PROPAGATION_DELAY" "0.00 MIL,700.00 MIL"
					( Parent
						( matchGroupRef "@crescent_city_bb_fab1_lib.crescent_city_bb_fab1(sch_1):\MG_DDR_NEAR_DIMM-CLK1_CLS_DDR_K_CAC-CLKS\" )
					)
					( Units "uMatchProp" "ns" 1.000000)
					( Status sCSetFlattened )
					( Origin gBackEnd )
				)
				( attribute "RELATIVE_PROPAGATION_DELAY_SCOPE" "G"
					( Parent
						( matchGroupRef "@baseboard_fab2_lib.baseboard_fab2(sch_1):\MG_DDR_CMD_NEAR_DIMM_NG_DDR_K_DLL_10\" )
					)
					( Status sCSetFlattened )
					( Origin gBackEnd )
				)
				( attribute "RELATIVE_PROPAGATION_DELAY" "0.00 MIL,25.00 MIL"
					( Parent
						( matchGroupRef "@baseboard_fab2_lib.baseboard_fab2(sch_1):\MG_DDR_CMD_NEAR_DIMM_NG_DDR_K_DLL_10\" )
					)
					( Units "uMatchProp" "ns" 1.000000)
					( Status sCSetFlattened )
					( Origin gBackEnd )
				)
			)
			( pinPair "@baseboard_fab2_lib.baseboard_fab2(sch_1):\PP3423\"
				( pinRef "@baseboard_fab2_lib.baseboard_fab2(sch_1):page60_i172:DDR3_MA(9)" )
				( pinRef "@baseboard_fab2_lib.baseboard_fab2(sch_1):page83_i111:A9" )
				( attribute "RELATIVE_PROPAGATION_DELAY_SCOPE" "G"
					( Parent
						( matchGroupRef "@crescent_city_bb_fab1_lib.crescent_city_bb_fab1(sch_1):\MG_DDR_FAR_DIMM-CLK0_CLS_DDR_K_CAC-CLKS\" )
					)
					( Status sCSetFlattened )
					( Origin gBackEnd )
				)
				( attribute "RELATIVE_PROPAGATION_DELAY" "0.00 MIL,700.00 MIL"
					( Parent
						( matchGroupRef "@crescent_city_bb_fab1_lib.crescent_city_bb_fab1(sch_1):\MG_DDR_FAR_DIMM-CLK0_CLS_DDR_K_CAC-CLKS\" )
					)
					( Units "uMatchProp" "ns" 1.000000)
					( Status sCSetFlattened )
					( Origin gBackEnd )
				)
				( attribute "RELATIVE_PROPAGATION_DELAY_SCOPE" "G"
					( Parent
						( matchGroupRef "@baseboard_fab2_lib.baseboard_fab2(sch_1):\MG_DDR_FAR_DIMM_CMD_NG_DDR_K_DLL_11\" )
					)
					( Status sCSetFlattened )
					( Origin gBackEnd )
				)
				( attribute "RELATIVE_PROPAGATION_DELAY" "0.00 MIL,25.00 MIL"
					( Parent
						( matchGroupRef "@baseboard_fab2_lib.baseboard_fab2(sch_1):\MG_DDR_FAR_DIMM_CMD_NG_DDR_K_DLL_11\" )
					)
					( Units "uMatchProp" "ns" 1.000000)
					( Status sCSetFlattened )
					( Origin gBackEnd )
				)
			)
			( pinPair "@baseboard_fab2_lib.baseboard_fab2(sch_1):\PP3424\"
				( pinRef "@baseboard_fab2_lib.baseboard_fab2(sch_1):page84_i14:A9" )
				( pinRef "@baseboard_fab2_lib.baseboard_fab2(sch_1):page60_i172:DDR3_MA(9)" )
				( attribute "RELATIVE_PROPAGATION_DELAY_SCOPE" "G"
					( Parent
						( matchGroupRef "@crescent_city_bb_fab1_lib.crescent_city_bb_fab1(sch_1):\MG_DDR_NEAR_DIMM-CLK1_CLS_DDR_K_CAC-CLKS\" )
					)
					( Status sCSetFlattened )
					( Origin gBackEnd )
				)
				( attribute "RELATIVE_PROPAGATION_DELAY" "0.00 MIL,700.00 MIL"
					( Parent
						( matchGroupRef "@crescent_city_bb_fab1_lib.crescent_city_bb_fab1(sch_1):\MG_DDR_NEAR_DIMM-CLK1_CLS_DDR_K_CAC-CLKS\" )
					)
					( Units "uMatchProp" "ns" 1.000000)
					( Status sCSetFlattened )
					( Origin gBackEnd )
				)
				( attribute "RELATIVE_PROPAGATION_DELAY_SCOPE" "G"
					( Parent
						( matchGroupRef "@baseboard_fab2_lib.baseboard_fab2(sch_1):\MG_DDR_CMD_NEAR_DIMM_NG_DDR_K_DLL_11\" )
					)
					( Status sCSetFlattened )
					( Origin gBackEnd )
				)
				( attribute "RELATIVE_PROPAGATION_DELAY" "0.00 MIL,25.00 MIL"
					( Parent
						( matchGroupRef "@baseboard_fab2_lib.baseboard_fab2(sch_1):\MG_DDR_CMD_NEAR_DIMM_NG_DDR_K_DLL_11\" )
					)
					( Units "uMatchProp" "ns" 1.000000)
					( Status sCSetFlattened )
					( Origin gBackEnd )
				)
			)
			( pinPair "@baseboard_fab2_lib.baseboard_fab2(sch_1):\PP3425\"
				( pinRef "@baseboard_fab2_lib.baseboard_fab2(sch_1):page60_i172:DDR3_MA(12)" )
				( pinRef "@baseboard_fab2_lib.baseboard_fab2(sch_1):page83_i111:A12" )
				( attribute "RELATIVE_PROPAGATION_DELAY_SCOPE" "G"
					( Parent
						( matchGroupRef "@crescent_city_bb_fab1_lib.crescent_city_bb_fab1(sch_1):\MG_DDR_FAR_DIMM-CLK0_CLS_DDR_K_CAC-CLKS\" )
					)
					( Status sCSetFlattened )
					( Origin gBackEnd )
				)
				( attribute "RELATIVE_PROPAGATION_DELAY" "0.00 MIL,700.00 MIL"
					( Parent
						( matchGroupRef "@crescent_city_bb_fab1_lib.crescent_city_bb_fab1(sch_1):\MG_DDR_FAR_DIMM-CLK0_CLS_DDR_K_CAC-CLKS\" )
					)
					( Units "uMatchProp" "ns" 1.000000)
					( Status sCSetFlattened )
					( Origin gBackEnd )
				)
				( attribute "RELATIVE_PROPAGATION_DELAY_SCOPE" "G"
					( Parent
						( matchGroupRef "@baseboard_fab2_lib.baseboard_fab2(sch_1):\MG_DDR_FAR_DIMM_CMD_NG_DDR_K_DLL_11\" )
					)
					( Status sCSetFlattened )
					( Origin gBackEnd )
				)
				( attribute "RELATIVE_PROPAGATION_DELAY" "0.00 MIL,25.00 MIL"
					( Parent
						( matchGroupRef "@baseboard_fab2_lib.baseboard_fab2(sch_1):\MG_DDR_FAR_DIMM_CMD_NG_DDR_K_DLL_11\" )
					)
					( Units "uMatchProp" "ns" 1.000000)
					( Status sCSetFlattened )
					( Origin gBackEnd )
				)
			)
			( pinPair "@baseboard_fab2_lib.baseboard_fab2(sch_1):\PP3426\"
				( pinRef "@baseboard_fab2_lib.baseboard_fab2(sch_1):page84_i14:A12" )
				( pinRef "@baseboard_fab2_lib.baseboard_fab2(sch_1):page60_i172:DDR3_MA(12)" )
				( attribute "RELATIVE_PROPAGATION_DELAY_SCOPE" "G"
					( Parent
						( matchGroupRef "@crescent_city_bb_fab1_lib.crescent_city_bb_fab1(sch_1):\MG_DDR_NEAR_DIMM-CLK1_CLS_DDR_K_CAC-CLKS\" )
					)
					( Status sCSetFlattened )
					( Origin gBackEnd )
				)
				( attribute "RELATIVE_PROPAGATION_DELAY" "0.00 MIL,700.00 MIL"
					( Parent
						( matchGroupRef "@crescent_city_bb_fab1_lib.crescent_city_bb_fab1(sch_1):\MG_DDR_NEAR_DIMM-CLK1_CLS_DDR_K_CAC-CLKS\" )
					)
					( Units "uMatchProp" "ns" 1.000000)
					( Status sCSetFlattened )
					( Origin gBackEnd )
				)
				( attribute "RELATIVE_PROPAGATION_DELAY_SCOPE" "G"
					( Parent
						( matchGroupRef "@baseboard_fab2_lib.baseboard_fab2(sch_1):\MG_DDR_CMD_NEAR_DIMM_NG_DDR_K_DLL_11\" )
					)
					( Status sCSetFlattened )
					( Origin gBackEnd )
				)
				( attribute "RELATIVE_PROPAGATION_DELAY" "0.00 MIL,25.00 MIL"
					( Parent
						( matchGroupRef "@baseboard_fab2_lib.baseboard_fab2(sch_1):\MG_DDR_CMD_NEAR_DIMM_NG_DDR_K_DLL_11\" )
					)
					( Units "uMatchProp" "ns" 1.000000)
					( Status sCSetFlattened )
					( Origin gBackEnd )
				)
			)
			( pinPair "@baseboard_fab2_lib.baseboard_fab2(sch_1):\PP3419\"
				( pinRef "@baseboard_fab2_lib.baseboard_fab2(sch_1):page60_i172:DDR3_BG(1)" )
				( pinRef "@baseboard_fab2_lib.baseboard_fab2(sch_1):page83_i111:BG(1)" )
				( attribute "RELATIVE_PROPAGATION_DELAY_SCOPE" "G"
					( Parent
						( matchGroupRef "@crescent_city_bb_fab1_lib.crescent_city_bb_fab1(sch_1):\MG_DDR_FAR_DIMM-CLK0_CLS_DDR_K_CAC-CLKS\" )
					)
					( Status sCSetFlattened )
					( Origin gBackEnd )
				)
				( attribute "RELATIVE_PROPAGATION_DELAY" "0.00 MIL,700.00 MIL"
					( Parent
						( matchGroupRef "@crescent_city_bb_fab1_lib.crescent_city_bb_fab1(sch_1):\MG_DDR_FAR_DIMM-CLK0_CLS_DDR_K_CAC-CLKS\" )
					)
					( Units "uMatchProp" "ns" 1.000000)
					( Status sCSetFlattened )
					( Origin gBackEnd )
				)
				( attribute "RELATIVE_PROPAGATION_DELAY_SCOPE" "G"
					( Parent
						( matchGroupRef "@baseboard_fab2_lib.baseboard_fab2(sch_1):\MG_DDR_FAR_DIMM_CMD_NG_DDR_K_DLL_12\" )
					)
					( Status sCSetFlattened )
					( Origin gBackEnd )
				)
				( attribute "RELATIVE_PROPAGATION_DELAY" "0.00 MIL,25.00 MIL"
					( Parent
						( matchGroupRef "@baseboard_fab2_lib.baseboard_fab2(sch_1):\MG_DDR_FAR_DIMM_CMD_NG_DDR_K_DLL_12\" )
					)
					( Units "uMatchProp" "ns" 1.000000)
					( Status sCSetFlattened )
					( Origin gBackEnd )
				)
			)
			( pinPair "@baseboard_fab2_lib.baseboard_fab2(sch_1):\PP3420\"
				( pinRef "@baseboard_fab2_lib.baseboard_fab2(sch_1):page84_i14:BG(1)" )
				( pinRef "@baseboard_fab2_lib.baseboard_fab2(sch_1):page60_i172:DDR3_BG(1)" )
				( attribute "RELATIVE_PROPAGATION_DELAY_SCOPE" "G"
					( Parent
						( matchGroupRef "@crescent_city_bb_fab1_lib.crescent_city_bb_fab1(sch_1):\MG_DDR_NEAR_DIMM-CLK1_CLS_DDR_K_CAC-CLKS\" )
					)
					( Status sCSetFlattened )
					( Origin gBackEnd )
				)
				( attribute "RELATIVE_PROPAGATION_DELAY" "0.00 MIL,700.00 MIL"
					( Parent
						( matchGroupRef "@crescent_city_bb_fab1_lib.crescent_city_bb_fab1(sch_1):\MG_DDR_NEAR_DIMM-CLK1_CLS_DDR_K_CAC-CLKS\" )
					)
					( Units "uMatchProp" "ns" 1.000000)
					( Status sCSetFlattened )
					( Origin gBackEnd )
				)
				( attribute "RELATIVE_PROPAGATION_DELAY_SCOPE" "G"
					( Parent
						( matchGroupRef "@baseboard_fab2_lib.baseboard_fab2(sch_1):\MG_DDR_CMD_NEAR_DIMM_NG_DDR_K_DLL_12\" )
					)
					( Status sCSetFlattened )
					( Origin gBackEnd )
				)
				( attribute "RELATIVE_PROPAGATION_DELAY" "0.00 MIL,25.00 MIL"
					( Parent
						( matchGroupRef "@baseboard_fab2_lib.baseboard_fab2(sch_1):\MG_DDR_CMD_NEAR_DIMM_NG_DDR_K_DLL_12\" )
					)
					( Units "uMatchProp" "ns" 1.000000)
					( Status sCSetFlattened )
					( Origin gBackEnd )
				)
			)
			( pinPair "@baseboard_fab2_lib.baseboard_fab2(sch_1):\PP3421\"
				( pinRef "@baseboard_fab2_lib.baseboard_fab2(sch_1):page60_i172:DDR3_MA(11)" )
				( pinRef "@baseboard_fab2_lib.baseboard_fab2(sch_1):page83_i111:A11" )
				( attribute "RELATIVE_PROPAGATION_DELAY_SCOPE" "G"
					( Parent
						( matchGroupRef "@crescent_city_bb_fab1_lib.crescent_city_bb_fab1(sch_1):\MG_DDR_FAR_DIMM-CLK0_CLS_DDR_K_CAC-CLKS\" )
					)
					( Status sCSetFlattened )
					( Origin gBackEnd )
				)
				( attribute "RELATIVE_PROPAGATION_DELAY" "0.00 MIL,700.00 MIL"
					( Parent
						( matchGroupRef "@crescent_city_bb_fab1_lib.crescent_city_bb_fab1(sch_1):\MG_DDR_FAR_DIMM-CLK0_CLS_DDR_K_CAC-CLKS\" )
					)
					( Units "uMatchProp" "ns" 1.000000)
					( Status sCSetFlattened )
					( Origin gBackEnd )
				)
				( attribute "RELATIVE_PROPAGATION_DELAY_SCOPE" "G"
					( Parent
						( matchGroupRef "@baseboard_fab2_lib.baseboard_fab2(sch_1):\MG_DDR_FAR_DIMM_CMD_NG_DDR_K_DLL_12\" )
					)
					( Status sCSetFlattened )
					( Origin gBackEnd )
				)
				( attribute "RELATIVE_PROPAGATION_DELAY" "0.00 MIL,25.00 MIL"
					( Parent
						( matchGroupRef "@baseboard_fab2_lib.baseboard_fab2(sch_1):\MG_DDR_FAR_DIMM_CMD_NG_DDR_K_DLL_12\" )
					)
					( Units "uMatchProp" "ns" 1.000000)
					( Status sCSetFlattened )
					( Origin gBackEnd )
				)
			)
			( pinPair "@baseboard_fab2_lib.baseboard_fab2(sch_1):\PP3422\"
				( pinRef "@baseboard_fab2_lib.baseboard_fab2(sch_1):page84_i14:A11" )
				( pinRef "@baseboard_fab2_lib.baseboard_fab2(sch_1):page60_i172:DDR3_MA(11)" )
				( attribute "RELATIVE_PROPAGATION_DELAY_SCOPE" "G"
					( Parent
						( matchGroupRef "@crescent_city_bb_fab1_lib.crescent_city_bb_fab1(sch_1):\MG_DDR_NEAR_DIMM-CLK1_CLS_DDR_K_CAC-CLKS\" )
					)
					( Status sCSetFlattened )
					( Origin gBackEnd )
				)
				( attribute "RELATIVE_PROPAGATION_DELAY" "0.00 MIL,700.00 MIL"
					( Parent
						( matchGroupRef "@crescent_city_bb_fab1_lib.crescent_city_bb_fab1(sch_1):\MG_DDR_NEAR_DIMM-CLK1_CLS_DDR_K_CAC-CLKS\" )
					)
					( Units "uMatchProp" "ns" 1.000000)
					( Status sCSetFlattened )
					( Origin gBackEnd )
				)
				( attribute "RELATIVE_PROPAGATION_DELAY_SCOPE" "G"
					( Parent
						( matchGroupRef "@baseboard_fab2_lib.baseboard_fab2(sch_1):\MG_DDR_CMD_NEAR_DIMM_NG_DDR_K_DLL_12\" )
					)
					( Status sCSetFlattened )
					( Origin gBackEnd )
				)
				( attribute "RELATIVE_PROPAGATION_DELAY" "0.00 MIL,25.00 MIL"
					( Parent
						( matchGroupRef "@baseboard_fab2_lib.baseboard_fab2(sch_1):\MG_DDR_CMD_NEAR_DIMM_NG_DDR_K_DLL_12\" )
					)
					( Units "uMatchProp" "ns" 1.000000)
					( Status sCSetFlattened )
					( Origin gBackEnd )
				)
			)
			( pinPair "@baseboard_fab2_lib.baseboard_fab2(sch_1):\PP3415\"
				( pinRef "@baseboard_fab2_lib.baseboard_fab2(sch_1):page60_i172:DDR3_ACT_N" )
				( pinRef "@baseboard_fab2_lib.baseboard_fab2(sch_1):page83_i111:ACT_N" )
				( attribute "RELATIVE_PROPAGATION_DELAY_SCOPE" "G"
					( Parent
						( matchGroupRef "@crescent_city_bb_fab1_lib.crescent_city_bb_fab1(sch_1):\MG_DDR_FAR_DIMM-CLK0_CLS_DDR_K_CAC-CLKS\" )
					)
					( Status sCSetFlattened )
					( Origin gBackEnd )
				)
				( attribute "RELATIVE_PROPAGATION_DELAY" "0.00 MIL,700.00 MIL"
					( Parent
						( matchGroupRef "@crescent_city_bb_fab1_lib.crescent_city_bb_fab1(sch_1):\MG_DDR_FAR_DIMM-CLK0_CLS_DDR_K_CAC-CLKS\" )
					)
					( Units "uMatchProp" "ns" 1.000000)
					( Status sCSetFlattened )
					( Origin gBackEnd )
				)
				( attribute "RELATIVE_PROPAGATION_DELAY_SCOPE" "G"
					( Parent
						( matchGroupRef "@baseboard_fab2_lib.baseboard_fab2(sch_1):\MG_DDR_FAR_DIMM_CMD_NG_DDR_K_DLL_13\" )
					)
					( Status sCSetFlattened )
					( Origin gBackEnd )
				)
				( attribute "RELATIVE_PROPAGATION_DELAY" "0.00 MIL,25.00 MIL"
					( Parent
						( matchGroupRef "@baseboard_fab2_lib.baseboard_fab2(sch_1):\MG_DDR_FAR_DIMM_CMD_NG_DDR_K_DLL_13\" )
					)
					( Units "uMatchProp" "ns" 1.000000)
					( Status sCSetFlattened )
					( Origin gBackEnd )
				)
			)
			( pinPair "@baseboard_fab2_lib.baseboard_fab2(sch_1):\PP3416\"
				( pinRef "@baseboard_fab2_lib.baseboard_fab2(sch_1):page84_i14:ACT_N" )
				( pinRef "@baseboard_fab2_lib.baseboard_fab2(sch_1):page60_i172:DDR3_ACT_N" )
				( attribute "RELATIVE_PROPAGATION_DELAY_SCOPE" "G"
					( Parent
						( matchGroupRef "@crescent_city_bb_fab1_lib.crescent_city_bb_fab1(sch_1):\MG_DDR_NEAR_DIMM-CLK1_CLS_DDR_K_CAC-CLKS\" )
					)
					( Status sCSetFlattened )
					( Origin gBackEnd )
				)
				( attribute "RELATIVE_PROPAGATION_DELAY" "0.00 MIL,700.00 MIL"
					( Parent
						( matchGroupRef "@crescent_city_bb_fab1_lib.crescent_city_bb_fab1(sch_1):\MG_DDR_NEAR_DIMM-CLK1_CLS_DDR_K_CAC-CLKS\" )
					)
					( Units "uMatchProp" "ns" 1.000000)
					( Status sCSetFlattened )
					( Origin gBackEnd )
				)
				( attribute "RELATIVE_PROPAGATION_DELAY_SCOPE" "G"
					( Parent
						( matchGroupRef "@baseboard_fab2_lib.baseboard_fab2(sch_1):\MG_DDR_CMD_NEAR_DIMM_NG_DDR_K_DLL_13\" )
					)
					( Status sCSetFlattened )
					( Origin gBackEnd )
				)
				( attribute "RELATIVE_PROPAGATION_DELAY" "0.00 MIL,25.00 MIL"
					( Parent
						( matchGroupRef "@baseboard_fab2_lib.baseboard_fab2(sch_1):\MG_DDR_CMD_NEAR_DIMM_NG_DDR_K_DLL_13\" )
					)
					( Units "uMatchProp" "ns" 1.000000)
					( Status sCSetFlattened )
					( Origin gBackEnd )
				)
			)
			( pinPair "@baseboard_fab2_lib.baseboard_fab2(sch_1):\PP3417\"
				( pinRef "@baseboard_fab2_lib.baseboard_fab2(sch_1):page60_i172:DDR3_BG(0)" )
				( pinRef "@baseboard_fab2_lib.baseboard_fab2(sch_1):page83_i111:BG(0)" )
				( attribute "RELATIVE_PROPAGATION_DELAY_SCOPE" "G"
					( Parent
						( matchGroupRef "@crescent_city_bb_fab1_lib.crescent_city_bb_fab1(sch_1):\MG_DDR_FAR_DIMM-CLK0_CLS_DDR_K_CAC-CLKS\" )
					)
					( Status sCSetFlattened )
					( Origin gBackEnd )
				)
				( attribute "RELATIVE_PROPAGATION_DELAY" "0.00 MIL,700.00 MIL"
					( Parent
						( matchGroupRef "@crescent_city_bb_fab1_lib.crescent_city_bb_fab1(sch_1):\MG_DDR_FAR_DIMM-CLK0_CLS_DDR_K_CAC-CLKS\" )
					)
					( Units "uMatchProp" "ns" 1.000000)
					( Status sCSetFlattened )
					( Origin gBackEnd )
				)
				( attribute "RELATIVE_PROPAGATION_DELAY_SCOPE" "G"
					( Parent
						( matchGroupRef "@baseboard_fab2_lib.baseboard_fab2(sch_1):\MG_DDR_FAR_DIMM_CMD_NG_DDR_K_DLL_13\" )
					)
					( Status sCSetFlattened )
					( Origin gBackEnd )
				)
				( attribute "RELATIVE_PROPAGATION_DELAY" "0.00 MIL,25.00 MIL"
					( Parent
						( matchGroupRef "@baseboard_fab2_lib.baseboard_fab2(sch_1):\MG_DDR_FAR_DIMM_CMD_NG_DDR_K_DLL_13\" )
					)
					( Units "uMatchProp" "ns" 1.000000)
					( Status sCSetFlattened )
					( Origin gBackEnd )
				)
			)
			( pinPair "@baseboard_fab2_lib.baseboard_fab2(sch_1):\PP3418\"
				( pinRef "@baseboard_fab2_lib.baseboard_fab2(sch_1):page84_i14:BG(0)" )
				( pinRef "@baseboard_fab2_lib.baseboard_fab2(sch_1):page60_i172:DDR3_BG(0)" )
				( attribute "RELATIVE_PROPAGATION_DELAY_SCOPE" "G"
					( Parent
						( matchGroupRef "@crescent_city_bb_fab1_lib.crescent_city_bb_fab1(sch_1):\MG_DDR_NEAR_DIMM-CLK1_CLS_DDR_K_CAC-CLKS\" )
					)
					( Status sCSetFlattened )
					( Origin gBackEnd )
				)
				( attribute "RELATIVE_PROPAGATION_DELAY" "0.00 MIL,700.00 MIL"
					( Parent
						( matchGroupRef "@crescent_city_bb_fab1_lib.crescent_city_bb_fab1(sch_1):\MG_DDR_NEAR_DIMM-CLK1_CLS_DDR_K_CAC-CLKS\" )
					)
					( Units "uMatchProp" "ns" 1.000000)
					( Status sCSetFlattened )
					( Origin gBackEnd )
				)
				( attribute "RELATIVE_PROPAGATION_DELAY_SCOPE" "G"
					( Parent
						( matchGroupRef "@baseboard_fab2_lib.baseboard_fab2(sch_1):\MG_DDR_CMD_NEAR_DIMM_NG_DDR_K_DLL_13\" )
					)
					( Status sCSetFlattened )
					( Origin gBackEnd )
				)
				( attribute "RELATIVE_PROPAGATION_DELAY" "0.00 MIL,25.00 MIL"
					( Parent
						( matchGroupRef "@baseboard_fab2_lib.baseboard_fab2(sch_1):\MG_DDR_CMD_NEAR_DIMM_NG_DDR_K_DLL_13\" )
					)
					( Units "uMatchProp" "ns" 1.000000)
					( Status sCSetFlattened )
					( Origin gBackEnd )
				)
			)
			( pinPair "@baseboard_fab2_lib.baseboard_fab2(sch_1):\PP3413\"
				( pinRef "@baseboard_fab2_lib.baseboard_fab2(sch_1):page83_i111:S0_N" )
				( pinRef "@baseboard_fab2_lib.baseboard_fab2(sch_1):page60_i172:DDR3_CS_N(0)" )
				( attribute "RELATIVE_PROPAGATION_DELAY_SCOPE" "G"
					( Parent
						( matchGroupRef "@crescent_city_bb_fab1_lib.crescent_city_bb_fab1(sch_1):\MG_DDR_FAR_DIMM-CLK0_CLS_DDR_K_CAC-CLKS\" )
					)
					( Status sCSetFlattened )
					( Origin gBackEnd )
				)
				( attribute "RELATIVE_PROPAGATION_DELAY" "0.00 MIL,300.00 MIL"
					( Parent
						( matchGroupRef "@crescent_city_bb_fab1_lib.crescent_city_bb_fab1(sch_1):\MG_DDR_FAR_DIMM-CLK0_CLS_DDR_K_CAC-CLKS\" )
					)
					( Units "uMatchProp" "ns" 1.000000)
					( Status sCSetFlattened )
					( Origin gBackEnd )
				)
				( attribute "RELATIVE_PROPAGATION_DELAY_SCOPE" "G"
					( Parent
						( matchGroupRef "@baseboard_fab2_lib.baseboard_fab2(sch_1):\MG_DDR_CTRL_NG_DDR_K_DLL_14\" )
					)
					( Status sCSetFlattened )
					( Origin gBackEnd )
				)
				( attribute "RELATIVE_PROPAGATION_DELAY" "0.00 MIL,25.00 MIL"
					( Parent
						( matchGroupRef "@baseboard_fab2_lib.baseboard_fab2(sch_1):\MG_DDR_CTRL_NG_DDR_K_DLL_14\" )
					)
					( Units "uMatchProp" "ns" 1.000000)
					( Status sCSetFlattened )
					( Origin gBackEnd )
				)
			)
			( pinPair "@baseboard_fab2_lib.baseboard_fab2(sch_1):\PP3414\"
				( pinRef "@baseboard_fab2_lib.baseboard_fab2(sch_1):page83_i111:ODT(0)" )
				( pinRef "@baseboard_fab2_lib.baseboard_fab2(sch_1):page60_i172:DDR3_ODT(0)" )
				( attribute "RELATIVE_PROPAGATION_DELAY_SCOPE" "G"
					( Parent
						( matchGroupRef "@crescent_city_bb_fab1_lib.crescent_city_bb_fab1(sch_1):\MG_DDR_FAR_DIMM-CLK0_CLS_DDR_K_CAC-CLKS\" )
					)
					( Status sCSetFlattened )
					( Origin gBackEnd )
				)
				( attribute "RELATIVE_PROPAGATION_DELAY" "0.00 MIL,300.00 MIL"
					( Parent
						( matchGroupRef "@crescent_city_bb_fab1_lib.crescent_city_bb_fab1(sch_1):\MG_DDR_FAR_DIMM-CLK0_CLS_DDR_K_CAC-CLKS\" )
					)
					( Units "uMatchProp" "ns" 1.000000)
					( Status sCSetFlattened )
					( Origin gBackEnd )
				)
				( attribute "RELATIVE_PROPAGATION_DELAY_SCOPE" "G"
					( Parent
						( matchGroupRef "@baseboard_fab2_lib.baseboard_fab2(sch_1):\MG_DDR_CTRL_NG_DDR_K_DLL_14\" )
					)
					( Status sCSetFlattened )
					( Origin gBackEnd )
				)
				( attribute "RELATIVE_PROPAGATION_DELAY" "0.00 MIL,25.00 MIL"
					( Parent
						( matchGroupRef "@baseboard_fab2_lib.baseboard_fab2(sch_1):\MG_DDR_CTRL_NG_DDR_K_DLL_14\" )
					)
					( Units "uMatchProp" "ns" 1.000000)
					( Status sCSetFlattened )
					( Origin gBackEnd )
				)
			)
			( pinPair "@baseboard_fab2_lib.baseboard_fab2(sch_1):\PP3412\"
				( pinRef "@baseboard_fab2_lib.baseboard_fab2(sch_1):page83_i111:CKE(0)" )
				( pinRef "@baseboard_fab2_lib.baseboard_fab2(sch_1):page60_i172:DDR3_CKE(0)" )
				( attribute "RELATIVE_PROPAGATION_DELAY_SCOPE" "G"
					( Parent
						( matchGroupRef "@crescent_city_bb_fab1_lib.crescent_city_bb_fab1(sch_1):\MG_DDR_FAR_DIMM-CLK0_CLS_DDR_K_CAC-CLKS\" )
					)
					( Status sCSetFlattened )
					( Origin gBackEnd )
				)
				( attribute "RELATIVE_PROPAGATION_DELAY" "0.00 MIL,300.00 MIL"
					( Parent
						( matchGroupRef "@crescent_city_bb_fab1_lib.crescent_city_bb_fab1(sch_1):\MG_DDR_FAR_DIMM-CLK0_CLS_DDR_K_CAC-CLKS\" )
					)
					( Units "uMatchProp" "ns" 1.000000)
					( Status sCSetFlattened )
					( Origin gBackEnd )
				)
				( attribute "RELATIVE_PROPAGATION_DELAY_SCOPE" "G"
					( Parent
						( matchGroupRef "@baseboard_fab2_lib.baseboard_fab2(sch_1):\MG_DDR_CTRL_NG_DDR_K_DLL_15\" )
					)
					( Status sCSetFlattened )
					( Origin gBackEnd )
				)
				( attribute "RELATIVE_PROPAGATION_DELAY" "0.00 MIL,25.00 MIL"
					( Parent
						( matchGroupRef "@baseboard_fab2_lib.baseboard_fab2(sch_1):\MG_DDR_CTRL_NG_DDR_K_DLL_15\" )
					)
					( Units "uMatchProp" "ns" 1.000000)
					( Status sCSetFlattened )
					( Origin gBackEnd )
				)
			)
			( pinPair "@baseboard_fab2_lib.baseboard_fab2(sch_1):\PP3411\"
				( pinRef "@baseboard_fab2_lib.baseboard_fab2(sch_1):page83_i111:S2_N_C(0)" )
				( pinRef "@baseboard_fab2_lib.baseboard_fab2(sch_1):page60_i172:DDR3_CS_N(2)" )
				( attribute "RELATIVE_PROPAGATION_DELAY_SCOPE" "G"
					( Parent
						( matchGroupRef "@crescent_city_bb_fab1_lib.crescent_city_bb_fab1(sch_1):\MG_DDR_FAR_DIMM-CLK0_CLS_DDR_K_CAC-CLKS\" )
					)
					( Status sCSetFlattened )
					( Origin gBackEnd )
				)
				( attribute "RELATIVE_PROPAGATION_DELAY" "0.00 MIL,300.00 MIL"
					( Parent
						( matchGroupRef "@crescent_city_bb_fab1_lib.crescent_city_bb_fab1(sch_1):\MG_DDR_FAR_DIMM-CLK0_CLS_DDR_K_CAC-CLKS\" )
					)
					( Units "uMatchProp" "ns" 1.000000)
					( Status sCSetFlattened )
					( Origin gBackEnd )
				)
				( attribute "RELATIVE_PROPAGATION_DELAY_SCOPE" "G"
					( Parent
						( matchGroupRef "@baseboard_fab2_lib.baseboard_fab2(sch_1):\MG_DDR_CTRL_NG_DDR_K_DLL_16\" )
					)
					( Status sCSetFlattened )
					( Origin gBackEnd )
				)
				( attribute "RELATIVE_PROPAGATION_DELAY" "0.00 MIL,25.00 MIL"
					( Parent
						( matchGroupRef "@baseboard_fab2_lib.baseboard_fab2(sch_1):\MG_DDR_CTRL_NG_DDR_K_DLL_16\" )
					)
					( Units "uMatchProp" "ns" 1.000000)
					( Status sCSetFlattened )
					( Origin gBackEnd )
				)
			)
			( pinPair "@baseboard_fab2_lib.baseboard_fab2(sch_1):\PP3410\"
				( pinRef "@baseboard_fab2_lib.baseboard_fab2(sch_1):page83_i111:S3_N_C(1)" )
				( pinRef "@baseboard_fab2_lib.baseboard_fab2(sch_1):page60_i172:DDR3_CS_N(3)" )
				( attribute "RELATIVE_PROPAGATION_DELAY_SCOPE" "G"
					( Parent
						( matchGroupRef "@crescent_city_bb_fab1_lib.crescent_city_bb_fab1(sch_1):\MG_DDR_FAR_DIMM-CLK0_CLS_DDR_K_CAC-CLKS\" )
					)
					( Status sCSetFlattened )
					( Origin gBackEnd )
				)
				( attribute "RELATIVE_PROPAGATION_DELAY" "0.00 MIL,300.00 MIL"
					( Parent
						( matchGroupRef "@crescent_city_bb_fab1_lib.crescent_city_bb_fab1(sch_1):\MG_DDR_FAR_DIMM-CLK0_CLS_DDR_K_CAC-CLKS\" )
					)
					( Units "uMatchProp" "ns" 1.000000)
					( Status sCSetFlattened )
					( Origin gBackEnd )
				)
				( attribute "RELATIVE_PROPAGATION_DELAY_SCOPE" "G"
					( Parent
						( matchGroupRef "@baseboard_fab2_lib.baseboard_fab2(sch_1):\MG_DDR_CTRL_NG_DDR_K_DLL_17\" )
					)
					( Status sCSetFlattened )
					( Origin gBackEnd )
				)
				( attribute "RELATIVE_PROPAGATION_DELAY" "0.00 MIL,25.00 MIL"
					( Parent
						( matchGroupRef "@baseboard_fab2_lib.baseboard_fab2(sch_1):\MG_DDR_CTRL_NG_DDR_K_DLL_17\" )
					)
					( Units "uMatchProp" "ns" 1.000000)
					( Status sCSetFlattened )
					( Origin gBackEnd )
				)
			)
			( pinPair "@baseboard_fab2_lib.baseboard_fab2(sch_1):\PP3408\"
				( pinRef "@baseboard_fab2_lib.baseboard_fab2(sch_1):page83_i111:S1_N" )
				( pinRef "@baseboard_fab2_lib.baseboard_fab2(sch_1):page60_i172:DDR3_CS_N(1)" )
				( attribute "RELATIVE_PROPAGATION_DELAY_SCOPE" "G"
					( Parent
						( matchGroupRef "@crescent_city_bb_fab1_lib.crescent_city_bb_fab1(sch_1):\MG_DDR_FAR_DIMM-CLK0_CLS_DDR_K_CAC-CLKS\" )
					)
					( Status sCSetFlattened )
					( Origin gBackEnd )
				)
				( attribute "RELATIVE_PROPAGATION_DELAY" "0.00 MIL,300.00 MIL"
					( Parent
						( matchGroupRef "@crescent_city_bb_fab1_lib.crescent_city_bb_fab1(sch_1):\MG_DDR_FAR_DIMM-CLK0_CLS_DDR_K_CAC-CLKS\" )
					)
					( Units "uMatchProp" "ns" 1.000000)
					( Status sCSetFlattened )
					( Origin gBackEnd )
				)
				( attribute "RELATIVE_PROPAGATION_DELAY_SCOPE" "G"
					( Parent
						( matchGroupRef "@baseboard_fab2_lib.baseboard_fab2(sch_1):\MG_DDR_CTRL_NG_DDR_K_DLL_18\" )
					)
					( Status sCSetFlattened )
					( Origin gBackEnd )
				)
				( attribute "RELATIVE_PROPAGATION_DELAY" "0.00 MIL,25.00 MIL"
					( Parent
						( matchGroupRef "@baseboard_fab2_lib.baseboard_fab2(sch_1):\MG_DDR_CTRL_NG_DDR_K_DLL_18\" )
					)
					( Units "uMatchProp" "ns" 1.000000)
					( Status sCSetFlattened )
					( Origin gBackEnd )
				)
			)
			( pinPair "@baseboard_fab2_lib.baseboard_fab2(sch_1):\PP3409\"
				( pinRef "@baseboard_fab2_lib.baseboard_fab2(sch_1):page83_i111:ODT(1)" )
				( pinRef "@baseboard_fab2_lib.baseboard_fab2(sch_1):page60_i172:DDR3_ODT(1)" )
				( attribute "RELATIVE_PROPAGATION_DELAY_SCOPE" "G"
					( Parent
						( matchGroupRef "@crescent_city_bb_fab1_lib.crescent_city_bb_fab1(sch_1):\MG_DDR_FAR_DIMM-CLK0_CLS_DDR_K_CAC-CLKS\" )
					)
					( Status sCSetFlattened )
					( Origin gBackEnd )
				)
				( attribute "RELATIVE_PROPAGATION_DELAY" "0.00 MIL,300.00 MIL"
					( Parent
						( matchGroupRef "@crescent_city_bb_fab1_lib.crescent_city_bb_fab1(sch_1):\MG_DDR_FAR_DIMM-CLK0_CLS_DDR_K_CAC-CLKS\" )
					)
					( Units "uMatchProp" "ns" 1.000000)
					( Status sCSetFlattened )
					( Origin gBackEnd )
				)
				( attribute "RELATIVE_PROPAGATION_DELAY_SCOPE" "G"
					( Parent
						( matchGroupRef "@baseboard_fab2_lib.baseboard_fab2(sch_1):\MG_DDR_CTRL_NG_DDR_K_DLL_18\" )
					)
					( Status sCSetFlattened )
					( Origin gBackEnd )
				)
				( attribute "RELATIVE_PROPAGATION_DELAY" "0.00 MIL,25.00 MIL"
					( Parent
						( matchGroupRef "@baseboard_fab2_lib.baseboard_fab2(sch_1):\MG_DDR_CTRL_NG_DDR_K_DLL_18\" )
					)
					( Units "uMatchProp" "ns" 1.000000)
					( Status sCSetFlattened )
					( Origin gBackEnd )
				)
			)
			( pinPair "@baseboard_fab2_lib.baseboard_fab2(sch_1):\PP3407\"
				( pinRef "@baseboard_fab2_lib.baseboard_fab2(sch_1):page83_i111:CKE(1)" )
				( pinRef "@baseboard_fab2_lib.baseboard_fab2(sch_1):page60_i172:DDR3_CKE(1)" )
				( attribute "RELATIVE_PROPAGATION_DELAY_SCOPE" "G"
					( Parent
						( matchGroupRef "@crescent_city_bb_fab1_lib.crescent_city_bb_fab1(sch_1):\MG_DDR_FAR_DIMM-CLK0_CLS_DDR_K_CAC-CLKS\" )
					)
					( Status sCSetFlattened )
					( Origin gBackEnd )
				)
				( attribute "RELATIVE_PROPAGATION_DELAY" "0.00 MIL,300.00 MIL"
					( Parent
						( matchGroupRef "@crescent_city_bb_fab1_lib.crescent_city_bb_fab1(sch_1):\MG_DDR_FAR_DIMM-CLK0_CLS_DDR_K_CAC-CLKS\" )
					)
					( Units "uMatchProp" "ns" 1.000000)
					( Status sCSetFlattened )
					( Origin gBackEnd )
				)
				( attribute "RELATIVE_PROPAGATION_DELAY_SCOPE" "G"
					( Parent
						( matchGroupRef "@baseboard_fab2_lib.baseboard_fab2(sch_1):\MG_DDR_CTRL_NG_DDR_K_DLL_19\" )
					)
					( Status sCSetFlattened )
					( Origin gBackEnd )
				)
				( attribute "RELATIVE_PROPAGATION_DELAY" "0.00 MIL,25.00 MIL"
					( Parent
						( matchGroupRef "@baseboard_fab2_lib.baseboard_fab2(sch_1):\MG_DDR_CTRL_NG_DDR_K_DLL_19\" )
					)
					( Units "uMatchProp" "ns" 1.000000)
					( Status sCSetFlattened )
					( Origin gBackEnd )
				)
			)
			( pinPair "@baseboard_fab2_lib.baseboard_fab2(sch_1):\PP3405\"
				( pinRef "@baseboard_fab2_lib.baseboard_fab2(sch_1):page60_i172:DDR3_CS_N(4)" )
				( pinRef "@baseboard_fab2_lib.baseboard_fab2(sch_1):page84_i14:S0_N" )
				( attribute "RELATIVE_PROPAGATION_DELAY_SCOPE" "G"
					( Parent
						( matchGroupRef "@crescent_city_bb_fab1_lib.crescent_city_bb_fab1(sch_1):\MG_DDR_NEAR_DIMM-CLK1_CLS_DDR_K_CAC-CLKS\" )
					)
					( Status sCSetFlattened )
					( Origin gBackEnd )
				)
				( attribute "RELATIVE_PROPAGATION_DELAY" "0.00 MIL,300.00 MIL"
					( Parent
						( matchGroupRef "@crescent_city_bb_fab1_lib.crescent_city_bb_fab1(sch_1):\MG_DDR_NEAR_DIMM-CLK1_CLS_DDR_K_CAC-CLKS\" )
					)
					( Units "uMatchProp" "ns" 1.000000)
					( Status sCSetFlattened )
					( Origin gBackEnd )
				)
				( attribute "RELATIVE_PROPAGATION_DELAY_SCOPE" "G"
					( Parent
						( matchGroupRef "@baseboard_fab2_lib.baseboard_fab2(sch_1):\MG_DDR_CTRL_NG_DDR_K_DLL_20\" )
					)
					( Status sCSetFlattened )
					( Origin gBackEnd )
				)
				( attribute "RELATIVE_PROPAGATION_DELAY" "0.00 MIL,25.00 MIL"
					( Parent
						( matchGroupRef "@baseboard_fab2_lib.baseboard_fab2(sch_1):\MG_DDR_CTRL_NG_DDR_K_DLL_20\" )
					)
					( Units "uMatchProp" "ns" 1.000000)
					( Status sCSetFlattened )
					( Origin gBackEnd )
				)
			)
			( pinPair "@baseboard_fab2_lib.baseboard_fab2(sch_1):\PP3406\"
				( pinRef "@baseboard_fab2_lib.baseboard_fab2(sch_1):page60_i172:DDR3_ODT(2)" )
				( pinRef "@baseboard_fab2_lib.baseboard_fab2(sch_1):page84_i14:ODT(0)" )
				( attribute "RELATIVE_PROPAGATION_DELAY_SCOPE" "G"
					( Parent
						( matchGroupRef "@crescent_city_bb_fab1_lib.crescent_city_bb_fab1(sch_1):\MG_DDR_NEAR_DIMM-CLK1_CLS_DDR_K_CAC-CLKS\" )
					)
					( Status sCSetFlattened )
					( Origin gBackEnd )
				)
				( attribute "RELATIVE_PROPAGATION_DELAY" "0.00 MIL,300.00 MIL"
					( Parent
						( matchGroupRef "@crescent_city_bb_fab1_lib.crescent_city_bb_fab1(sch_1):\MG_DDR_NEAR_DIMM-CLK1_CLS_DDR_K_CAC-CLKS\" )
					)
					( Units "uMatchProp" "ns" 1.000000)
					( Status sCSetFlattened )
					( Origin gBackEnd )
				)
				( attribute "RELATIVE_PROPAGATION_DELAY_SCOPE" "G"
					( Parent
						( matchGroupRef "@baseboard_fab2_lib.baseboard_fab2(sch_1):\MG_DDR_CTRL_NG_DDR_K_DLL_20\" )
					)
					( Status sCSetFlattened )
					( Origin gBackEnd )
				)
				( attribute "RELATIVE_PROPAGATION_DELAY" "0.00 MIL,25.00 MIL"
					( Parent
						( matchGroupRef "@baseboard_fab2_lib.baseboard_fab2(sch_1):\MG_DDR_CTRL_NG_DDR_K_DLL_20\" )
					)
					( Units "uMatchProp" "ns" 1.000000)
					( Status sCSetFlattened )
					( Origin gBackEnd )
				)
			)
			( pinPair "@baseboard_fab2_lib.baseboard_fab2(sch_1):\PP3404\"
				( pinRef "@baseboard_fab2_lib.baseboard_fab2(sch_1):page60_i172:DDR3_CKE(2)" )
				( pinRef "@baseboard_fab2_lib.baseboard_fab2(sch_1):page84_i14:CKE(0)" )
				( attribute "RELATIVE_PROPAGATION_DELAY_SCOPE" "G"
					( Parent
						( matchGroupRef "@crescent_city_bb_fab1_lib.crescent_city_bb_fab1(sch_1):\MG_DDR_NEAR_DIMM-CLK1_CLS_DDR_K_CAC-CLKS\" )
					)
					( Status sCSetFlattened )
					( Origin gBackEnd )
				)
				( attribute "RELATIVE_PROPAGATION_DELAY" "0.00 MIL,300.00 MIL"
					( Parent
						( matchGroupRef "@crescent_city_bb_fab1_lib.crescent_city_bb_fab1(sch_1):\MG_DDR_NEAR_DIMM-CLK1_CLS_DDR_K_CAC-CLKS\" )
					)
					( Units "uMatchProp" "ns" 1.000000)
					( Status sCSetFlattened )
					( Origin gBackEnd )
				)
				( attribute "RELATIVE_PROPAGATION_DELAY_SCOPE" "G"
					( Parent
						( matchGroupRef "@baseboard_fab2_lib.baseboard_fab2(sch_1):\MG_DDR_CTRL_NG_DDR_K_DLL_21\" )
					)
					( Status sCSetFlattened )
					( Origin gBackEnd )
				)
				( attribute "RELATIVE_PROPAGATION_DELAY" "0.00 MIL,25.00 MIL"
					( Parent
						( matchGroupRef "@baseboard_fab2_lib.baseboard_fab2(sch_1):\MG_DDR_CTRL_NG_DDR_K_DLL_21\" )
					)
					( Units "uMatchProp" "ns" 1.000000)
					( Status sCSetFlattened )
					( Origin gBackEnd )
				)
			)
			( pinPair "@baseboard_fab2_lib.baseboard_fab2(sch_1):\PP3402\"
				( pinRef "@baseboard_fab2_lib.baseboard_fab2(sch_1):page60_i172:DDR3_CS_N(6)" )
				( pinRef "@baseboard_fab2_lib.baseboard_fab2(sch_1):page84_i14:S2_N_C(0)" )
				( attribute "RELATIVE_PROPAGATION_DELAY_SCOPE" "G"
					( Parent
						( matchGroupRef "@crescent_city_bb_fab1_lib.crescent_city_bb_fab1(sch_1):\MG_DDR_NEAR_DIMM-CLK1_CLS_DDR_K_CAC-CLKS\" )
					)
					( Status sCSetFlattened )
					( Origin gBackEnd )
				)
				( attribute "RELATIVE_PROPAGATION_DELAY" "0.00 MIL,300.00 MIL"
					( Parent
						( matchGroupRef "@crescent_city_bb_fab1_lib.crescent_city_bb_fab1(sch_1):\MG_DDR_NEAR_DIMM-CLK1_CLS_DDR_K_CAC-CLKS\" )
					)
					( Units "uMatchProp" "ns" 1.000000)
					( Status sCSetFlattened )
					( Origin gBackEnd )
				)
				( attribute "RELATIVE_PROPAGATION_DELAY_SCOPE" "G"
					( Parent
						( matchGroupRef "@baseboard_fab2_lib.baseboard_fab2(sch_1):\MG_DDR_CTRL_NG_DDR_K_DLL_22\" )
					)
					( Status sCSetFlattened )
					( Origin gBackEnd )
				)
				( attribute "RELATIVE_PROPAGATION_DELAY" "0.00 MIL,25.00 MIL"
					( Parent
						( matchGroupRef "@baseboard_fab2_lib.baseboard_fab2(sch_1):\MG_DDR_CTRL_NG_DDR_K_DLL_22\" )
					)
					( Units "uMatchProp" "ns" 1.000000)
					( Status sCSetFlattened )
					( Origin gBackEnd )
				)
			)
			( pinPair "@baseboard_fab2_lib.baseboard_fab2(sch_1):\PP3403\"
				( pinRef "@baseboard_fab2_lib.baseboard_fab2(sch_1):page60_i172:DDR3_CS_N(7)" )
				( pinRef "@baseboard_fab2_lib.baseboard_fab2(sch_1):page84_i14:S3_N_C(1)" )
				( attribute "RELATIVE_PROPAGATION_DELAY_SCOPE" "G"
					( Parent
						( matchGroupRef "@crescent_city_bb_fab1_lib.crescent_city_bb_fab1(sch_1):\MG_DDR_NEAR_DIMM-CLK1_CLS_DDR_K_CAC-CLKS\" )
					)
					( Status sCSetFlattened )
					( Origin gBackEnd )
				)
				( attribute "RELATIVE_PROPAGATION_DELAY" "0.00 MIL,300.00 MIL"
					( Parent
						( matchGroupRef "@crescent_city_bb_fab1_lib.crescent_city_bb_fab1(sch_1):\MG_DDR_NEAR_DIMM-CLK1_CLS_DDR_K_CAC-CLKS\" )
					)
					( Units "uMatchProp" "ns" 1.000000)
					( Status sCSetFlattened )
					( Origin gBackEnd )
				)
				( attribute "RELATIVE_PROPAGATION_DELAY_SCOPE" "G"
					( Parent
						( matchGroupRef "@baseboard_fab2_lib.baseboard_fab2(sch_1):\MG_DDR_CTRL_NG_DDR_K_DLL_22\" )
					)
					( Status sCSetFlattened )
					( Origin gBackEnd )
				)
				( attribute "RELATIVE_PROPAGATION_DELAY" "0.00 MIL,25.00 MIL"
					( Parent
						( matchGroupRef "@baseboard_fab2_lib.baseboard_fab2(sch_1):\MG_DDR_CTRL_NG_DDR_K_DLL_22\" )
					)
					( Units "uMatchProp" "ns" 1.000000)
					( Status sCSetFlattened )
					( Origin gBackEnd )
				)
			)
			( pinPair "@baseboard_fab2_lib.baseboard_fab2(sch_1):\PP3400\"
				( pinRef "@baseboard_fab2_lib.baseboard_fab2(sch_1):page60_i172:DDR3_CS_N(5)" )
				( pinRef "@baseboard_fab2_lib.baseboard_fab2(sch_1):page84_i14:S1_N" )
				( attribute "RELATIVE_PROPAGATION_DELAY_SCOPE" "G"
					( Parent
						( matchGroupRef "@crescent_city_bb_fab1_lib.crescent_city_bb_fab1(sch_1):\MG_DDR_NEAR_DIMM-CLK1_CLS_DDR_K_CAC-CLKS\" )
					)
					( Status sCSetFlattened )
					( Origin gBackEnd )
				)
				( attribute "RELATIVE_PROPAGATION_DELAY" "0.00 MIL,300.00 MIL"
					( Parent
						( matchGroupRef "@crescent_city_bb_fab1_lib.crescent_city_bb_fab1(sch_1):\MG_DDR_NEAR_DIMM-CLK1_CLS_DDR_K_CAC-CLKS\" )
					)
					( Units "uMatchProp" "ns" 1.000000)
					( Status sCSetFlattened )
					( Origin gBackEnd )
				)
				( attribute "RELATIVE_PROPAGATION_DELAY_SCOPE" "G"
					( Parent
						( matchGroupRef "@baseboard_fab2_lib.baseboard_fab2(sch_1):\MG_DDR_CTRL_NG_DDR_K_DLL_23\" )
					)
					( Status sCSetFlattened )
					( Origin gBackEnd )
				)
				( attribute "RELATIVE_PROPAGATION_DELAY" "0.00 MIL,25.00 MIL"
					( Parent
						( matchGroupRef "@baseboard_fab2_lib.baseboard_fab2(sch_1):\MG_DDR_CTRL_NG_DDR_K_DLL_23\" )
					)
					( Units "uMatchProp" "ns" 1.000000)
					( Status sCSetFlattened )
					( Origin gBackEnd )
				)
			)
			( pinPair "@baseboard_fab2_lib.baseboard_fab2(sch_1):\PP3401\"
				( pinRef "@baseboard_fab2_lib.baseboard_fab2(sch_1):page60_i172:DDR3_ODT(3)" )
				( pinRef "@baseboard_fab2_lib.baseboard_fab2(sch_1):page84_i14:ODT(1)" )
				( attribute "RELATIVE_PROPAGATION_DELAY_SCOPE" "G"
					( Parent
						( matchGroupRef "@crescent_city_bb_fab1_lib.crescent_city_bb_fab1(sch_1):\MG_DDR_NEAR_DIMM-CLK1_CLS_DDR_K_CAC-CLKS\" )
					)
					( Status sCSetFlattened )
					( Origin gBackEnd )
				)
				( attribute "RELATIVE_PROPAGATION_DELAY" "0.00 MIL,300.00 MIL"
					( Parent
						( matchGroupRef "@crescent_city_bb_fab1_lib.crescent_city_bb_fab1(sch_1):\MG_DDR_NEAR_DIMM-CLK1_CLS_DDR_K_CAC-CLKS\" )
					)
					( Units "uMatchProp" "ns" 1.000000)
					( Status sCSetFlattened )
					( Origin gBackEnd )
				)
				( attribute "RELATIVE_PROPAGATION_DELAY_SCOPE" "G"
					( Parent
						( matchGroupRef "@baseboard_fab2_lib.baseboard_fab2(sch_1):\MG_DDR_CTRL_NG_DDR_K_DLL_23\" )
					)
					( Status sCSetFlattened )
					( Origin gBackEnd )
				)
				( attribute "RELATIVE_PROPAGATION_DELAY" "0.00 MIL,25.00 MIL"
					( Parent
						( matchGroupRef "@baseboard_fab2_lib.baseboard_fab2(sch_1):\MG_DDR_CTRL_NG_DDR_K_DLL_23\" )
					)
					( Units "uMatchProp" "ns" 1.000000)
					( Status sCSetFlattened )
					( Origin gBackEnd )
				)
			)
			( pinPair "@baseboard_fab2_lib.baseboard_fab2(sch_1):\PP3399\"
				( pinRef "@baseboard_fab2_lib.baseboard_fab2(sch_1):page60_i172:DDR3_CKE(3)" )
				( pinRef "@baseboard_fab2_lib.baseboard_fab2(sch_1):page84_i14:CKE(1)" )
				( attribute "RELATIVE_PROPAGATION_DELAY_SCOPE" "G"
					( Parent
						( matchGroupRef "@crescent_city_bb_fab1_lib.crescent_city_bb_fab1(sch_1):\MG_DDR_NEAR_DIMM-CLK1_CLS_DDR_K_CAC-CLKS\" )
					)
					( Status sCSetFlattened )
					( Origin gBackEnd )
				)
				( attribute "RELATIVE_PROPAGATION_DELAY" "0.00 MIL,300.00 MIL"
					( Parent
						( matchGroupRef "@crescent_city_bb_fab1_lib.crescent_city_bb_fab1(sch_1):\MG_DDR_NEAR_DIMM-CLK1_CLS_DDR_K_CAC-CLKS\" )
					)
					( Units "uMatchProp" "ns" 1.000000)
					( Status sCSetFlattened )
					( Origin gBackEnd )
				)
				( attribute "RELATIVE_PROPAGATION_DELAY_SCOPE" "G"
					( Parent
						( matchGroupRef "@baseboard_fab2_lib.baseboard_fab2(sch_1):\MG_DDR_CTRL_NG_DDR_K_DLL_24\" )
					)
					( Status sCSetFlattened )
					( Origin gBackEnd )
				)
				( attribute "RELATIVE_PROPAGATION_DELAY" "0.00 MIL,25.00 MIL"
					( Parent
						( matchGroupRef "@baseboard_fab2_lib.baseboard_fab2(sch_1):\MG_DDR_CTRL_NG_DDR_K_DLL_24\" )
					)
					( Units "uMatchProp" "ns" 1.000000)
					( Status sCSetFlattened )
					( Origin gBackEnd )
				)
			)
			( pinPair "@baseboard_fab2_lib.baseboard_fab2(sch_1):\PP3527\"
				( pinRef "@baseboard_fab2_lib.baseboard_fab2(sch_1):page59_i172:DDR2_CID(2)" )
				( pinRef "@baseboard_fab2_lib.baseboard_fab2(sch_1):page81_i186:C(2)" )
				( attribute "RELATIVE_PROPAGATION_DELAY_SCOPE" "G"
					( Parent
						( matchGroupRef "@baseboard_fab2_lib.baseboard_fab2(sch_1):\MG_DDR_FAR_DIMM_CMD_NG_DDR_J_DLL_1\" )
					)
					( Status sCSetFlattened )
					( Origin gBackEnd )
				)
				( attribute "RELATIVE_PROPAGATION_DELAY" "0.00 MIL,25.00 MIL"
					( Parent
						( matchGroupRef "@baseboard_fab2_lib.baseboard_fab2(sch_1):\MG_DDR_FAR_DIMM_CMD_NG_DDR_J_DLL_1\" )
					)
					( Units "uMatchProp" "ns" 1.000000)
					( Status sCSetFlattened )
					( Origin gBackEnd )
				)
				( attribute "RELATIVE_PROPAGATION_DELAY_SCOPE" "G"
					( Parent
						( matchGroupRef "@crescent_city_bb_fab1_lib.crescent_city_bb_fab1(sch_1):\MG_DDR_FAR_DIMM-CLK0_CLS_DDR_J_CAC-CLKS\" )
					)
					( Status sCSetFlattened )
					( Origin gBackEnd )
				)
				( attribute "RELATIVE_PROPAGATION_DELAY" "0.00 MIL,700.00 MIL"
					( Parent
						( matchGroupRef "@crescent_city_bb_fab1_lib.crescent_city_bb_fab1(sch_1):\MG_DDR_FAR_DIMM-CLK0_CLS_DDR_J_CAC-CLKS\" )
					)
					( Units "uMatchProp" "ns" 1.000000)
					( Status sCSetFlattened )
					( Origin gBackEnd )
				)
			)
			( pinPair "@baseboard_fab2_lib.baseboard_fab2(sch_1):\PP3528\"
				( pinRef "@baseboard_fab2_lib.baseboard_fab2(sch_1):page82_i187:C(2)" )
				( pinRef "@baseboard_fab2_lib.baseboard_fab2(sch_1):page59_i172:DDR2_CID(2)" )
				( attribute "RELATIVE_PROPAGATION_DELAY_SCOPE" "G"
					( Parent
						( matchGroupRef "@crescent_city_bb_fab1_lib.crescent_city_bb_fab1(sch_1):\MG_DDR_NEAR_DIMM-CLK1_CLS_DDR_J_CAC-CLKS\" )
					)
					( Status sCSetFlattened )
					( Origin gBackEnd )
				)
				( attribute "RELATIVE_PROPAGATION_DELAY" "0.00 MIL,700.00 MIL"
					( Parent
						( matchGroupRef "@crescent_city_bb_fab1_lib.crescent_city_bb_fab1(sch_1):\MG_DDR_NEAR_DIMM-CLK1_CLS_DDR_J_CAC-CLKS\" )
					)
					( Units "uMatchProp" "ns" 1.000000)
					( Status sCSetFlattened )
					( Origin gBackEnd )
				)
				( attribute "RELATIVE_PROPAGATION_DELAY_SCOPE" "G"
					( Parent
						( matchGroupRef "@baseboard_fab2_lib.baseboard_fab2(sch_1):\MG_DDR_CMD_NEAR_DIMM_NG_DDR_J_DLL_1\" )
					)
					( Status sCSetFlattened )
					( Origin gBackEnd )
				)
				( attribute "RELATIVE_PROPAGATION_DELAY" "0.00 MIL,25.00 MIL"
					( Parent
						( matchGroupRef "@baseboard_fab2_lib.baseboard_fab2(sch_1):\MG_DDR_CMD_NEAR_DIMM_NG_DDR_J_DLL_1\" )
					)
					( Units "uMatchProp" "ns" 1.000000)
					( Status sCSetFlattened )
					( Origin gBackEnd )
				)
			)
			( pinPair "@baseboard_fab2_lib.baseboard_fab2(sch_1):\PP3529\"
				( pinRef "@baseboard_fab2_lib.baseboard_fab2(sch_1):page59_i172:DDR2_MA(17)" )
				( pinRef "@baseboard_fab2_lib.baseboard_fab2(sch_1):page81_i186:A17" )
				( attribute "RELATIVE_PROPAGATION_DELAY_SCOPE" "G"
					( Parent
						( matchGroupRef "@baseboard_fab2_lib.baseboard_fab2(sch_1):\MG_DDR_FAR_DIMM_CMD_NG_DDR_J_DLL_1\" )
					)
					( Status sCSetFlattened )
					( Origin gBackEnd )
				)
				( attribute "RELATIVE_PROPAGATION_DELAY" "0.00 MIL,25.00 MIL"
					( Parent
						( matchGroupRef "@baseboard_fab2_lib.baseboard_fab2(sch_1):\MG_DDR_FAR_DIMM_CMD_NG_DDR_J_DLL_1\" )
					)
					( Units "uMatchProp" "ns" 1.000000)
					( Status sCSetFlattened )
					( Origin gBackEnd )
				)
				( attribute "RELATIVE_PROPAGATION_DELAY_SCOPE" "G"
					( Parent
						( matchGroupRef "@crescent_city_bb_fab1_lib.crescent_city_bb_fab1(sch_1):\MG_DDR_FAR_DIMM-CLK0_CLS_DDR_J_CAC-CLKS\" )
					)
					( Status sCSetFlattened )
					( Origin gBackEnd )
				)
				( attribute "RELATIVE_PROPAGATION_DELAY" "0.00 MIL,700.00 MIL"
					( Parent
						( matchGroupRef "@crescent_city_bb_fab1_lib.crescent_city_bb_fab1(sch_1):\MG_DDR_FAR_DIMM-CLK0_CLS_DDR_J_CAC-CLKS\" )
					)
					( Units "uMatchProp" "ns" 1.000000)
					( Status sCSetFlattened )
					( Origin gBackEnd )
				)
			)
			( pinPair "@baseboard_fab2_lib.baseboard_fab2(sch_1):\PP3530\"
				( pinRef "@baseboard_fab2_lib.baseboard_fab2(sch_1):page82_i187:A17" )
				( pinRef "@baseboard_fab2_lib.baseboard_fab2(sch_1):page59_i172:DDR2_MA(17)" )
				( attribute "RELATIVE_PROPAGATION_DELAY_SCOPE" "G"
					( Parent
						( matchGroupRef "@crescent_city_bb_fab1_lib.crescent_city_bb_fab1(sch_1):\MG_DDR_NEAR_DIMM-CLK1_CLS_DDR_J_CAC-CLKS\" )
					)
					( Status sCSetFlattened )
					( Origin gBackEnd )
				)
				( attribute "RELATIVE_PROPAGATION_DELAY" "0.00 MIL,700.00 MIL"
					( Parent
						( matchGroupRef "@crescent_city_bb_fab1_lib.crescent_city_bb_fab1(sch_1):\MG_DDR_NEAR_DIMM-CLK1_CLS_DDR_J_CAC-CLKS\" )
					)
					( Units "uMatchProp" "ns" 1.000000)
					( Status sCSetFlattened )
					( Origin gBackEnd )
				)
				( attribute "RELATIVE_PROPAGATION_DELAY_SCOPE" "G"
					( Parent
						( matchGroupRef "@baseboard_fab2_lib.baseboard_fab2(sch_1):\MG_DDR_CMD_NEAR_DIMM_NG_DDR_J_DLL_1\" )
					)
					( Status sCSetFlattened )
					( Origin gBackEnd )
				)
				( attribute "RELATIVE_PROPAGATION_DELAY" "0.00 MIL,25.00 MIL"
					( Parent
						( matchGroupRef "@baseboard_fab2_lib.baseboard_fab2(sch_1):\MG_DDR_CMD_NEAR_DIMM_NG_DDR_J_DLL_1\" )
					)
					( Units "uMatchProp" "ns" 1.000000)
					( Status sCSetFlattened )
					( Origin gBackEnd )
				)
			)
			( pinPair "@baseboard_fab2_lib.baseboard_fab2(sch_1):\PP3523\"
				( pinRef "@baseboard_fab2_lib.baseboard_fab2(sch_1):page59_i172:DDR2_MA(13)" )
				( pinRef "@baseboard_fab2_lib.baseboard_fab2(sch_1):page81_i186:A13" )
				( attribute "RELATIVE_PROPAGATION_DELAY_SCOPE" "G"
					( Parent
						( matchGroupRef "@crescent_city_bb_fab1_lib.crescent_city_bb_fab1(sch_1):\MG_DDR_FAR_DIMM-CLK0_CLS_DDR_J_CAC-CLKS\" )
					)
					( Status sCSetFlattened )
					( Origin gBackEnd )
				)
				( attribute "RELATIVE_PROPAGATION_DELAY" "0.00 MIL,700.00 MIL"
					( Parent
						( matchGroupRef "@crescent_city_bb_fab1_lib.crescent_city_bb_fab1(sch_1):\MG_DDR_FAR_DIMM-CLK0_CLS_DDR_J_CAC-CLKS\" )
					)
					( Units "uMatchProp" "ns" 1.000000)
					( Status sCSetFlattened )
					( Origin gBackEnd )
				)
				( attribute "RELATIVE_PROPAGATION_DELAY_SCOPE" "G"
					( Parent
						( matchGroupRef "@baseboard_fab2_lib.baseboard_fab2(sch_1):\MG_DDR_FAR_DIMM_CMD_NG_DDR_J_DLL_2\" )
					)
					( Status sCSetFlattened )
					( Origin gBackEnd )
				)
				( attribute "RELATIVE_PROPAGATION_DELAY" "0.00 MIL,25.00 MIL"
					( Parent
						( matchGroupRef "@baseboard_fab2_lib.baseboard_fab2(sch_1):\MG_DDR_FAR_DIMM_CMD_NG_DDR_J_DLL_2\" )
					)
					( Units "uMatchProp" "ns" 1.000000)
					( Status sCSetFlattened )
					( Origin gBackEnd )
				)
			)
			( pinPair "@baseboard_fab2_lib.baseboard_fab2(sch_1):\PP3524\"
				( pinRef "@baseboard_fab2_lib.baseboard_fab2(sch_1):page82_i187:A13" )
				( pinRef "@baseboard_fab2_lib.baseboard_fab2(sch_1):page59_i172:DDR2_MA(13)" )
				( attribute "RELATIVE_PROPAGATION_DELAY_SCOPE" "G"
					( Parent
						( matchGroupRef "@crescent_city_bb_fab1_lib.crescent_city_bb_fab1(sch_1):\MG_DDR_NEAR_DIMM-CLK1_CLS_DDR_J_CAC-CLKS\" )
					)
					( Status sCSetFlattened )
					( Origin gBackEnd )
				)
				( attribute "RELATIVE_PROPAGATION_DELAY" "0.00 MIL,700.00 MIL"
					( Parent
						( matchGroupRef "@crescent_city_bb_fab1_lib.crescent_city_bb_fab1(sch_1):\MG_DDR_NEAR_DIMM-CLK1_CLS_DDR_J_CAC-CLKS\" )
					)
					( Units "uMatchProp" "ns" 1.000000)
					( Status sCSetFlattened )
					( Origin gBackEnd )
				)
				( attribute "RELATIVE_PROPAGATION_DELAY_SCOPE" "G"
					( Parent
						( matchGroupRef "@baseboard_fab2_lib.baseboard_fab2(sch_1):\MG_DDR_CMD_NEAR_DIMM_NG_DDR_J_DLL_2\" )
					)
					( Status sCSetFlattened )
					( Origin gBackEnd )
				)
				( attribute "RELATIVE_PROPAGATION_DELAY" "0.00 MIL,25.00 MIL"
					( Parent
						( matchGroupRef "@baseboard_fab2_lib.baseboard_fab2(sch_1):\MG_DDR_CMD_NEAR_DIMM_NG_DDR_J_DLL_2\" )
					)
					( Units "uMatchProp" "ns" 1.000000)
					( Status sCSetFlattened )
					( Origin gBackEnd )
				)
			)
			( pinPair "@baseboard_fab2_lib.baseboard_fab2(sch_1):\PP3525\"
				( pinRef "@baseboard_fab2_lib.baseboard_fab2(sch_1):page59_i172:DDR2_MA(15)" )
				( pinRef "@baseboard_fab2_lib.baseboard_fab2(sch_1):page81_i186:A15_CAS_N" )
				( attribute "RELATIVE_PROPAGATION_DELAY_SCOPE" "G"
					( Parent
						( matchGroupRef "@crescent_city_bb_fab1_lib.crescent_city_bb_fab1(sch_1):\MG_DDR_FAR_DIMM-CLK0_CLS_DDR_J_CAC-CLKS\" )
					)
					( Status sCSetFlattened )
					( Origin gBackEnd )
				)
				( attribute "RELATIVE_PROPAGATION_DELAY" "0.00 MIL,700.00 MIL"
					( Parent
						( matchGroupRef "@crescent_city_bb_fab1_lib.crescent_city_bb_fab1(sch_1):\MG_DDR_FAR_DIMM-CLK0_CLS_DDR_J_CAC-CLKS\" )
					)
					( Units "uMatchProp" "ns" 1.000000)
					( Status sCSetFlattened )
					( Origin gBackEnd )
				)
				( attribute "RELATIVE_PROPAGATION_DELAY_SCOPE" "G"
					( Parent
						( matchGroupRef "@baseboard_fab2_lib.baseboard_fab2(sch_1):\MG_DDR_FAR_DIMM_CMD_NG_DDR_J_DLL_2\" )
					)
					( Status sCSetFlattened )
					( Origin gBackEnd )
				)
				( attribute "RELATIVE_PROPAGATION_DELAY" "0.00 MIL,25.00 MIL"
					( Parent
						( matchGroupRef "@baseboard_fab2_lib.baseboard_fab2(sch_1):\MG_DDR_FAR_DIMM_CMD_NG_DDR_J_DLL_2\" )
					)
					( Units "uMatchProp" "ns" 1.000000)
					( Status sCSetFlattened )
					( Origin gBackEnd )
				)
			)
			( pinPair "@baseboard_fab2_lib.baseboard_fab2(sch_1):\PP3526\"
				( pinRef "@baseboard_fab2_lib.baseboard_fab2(sch_1):page82_i187:A15_CAS_N" )
				( pinRef "@baseboard_fab2_lib.baseboard_fab2(sch_1):page59_i172:DDR2_MA(15)" )
				( attribute "RELATIVE_PROPAGATION_DELAY_SCOPE" "G"
					( Parent
						( matchGroupRef "@crescent_city_bb_fab1_lib.crescent_city_bb_fab1(sch_1):\MG_DDR_NEAR_DIMM-CLK1_CLS_DDR_J_CAC-CLKS\" )
					)
					( Status sCSetFlattened )
					( Origin gBackEnd )
				)
				( attribute "RELATIVE_PROPAGATION_DELAY" "0.00 MIL,700.00 MIL"
					( Parent
						( matchGroupRef "@crescent_city_bb_fab1_lib.crescent_city_bb_fab1(sch_1):\MG_DDR_NEAR_DIMM-CLK1_CLS_DDR_J_CAC-CLKS\" )
					)
					( Units "uMatchProp" "ns" 1.000000)
					( Status sCSetFlattened )
					( Origin gBackEnd )
				)
				( attribute "RELATIVE_PROPAGATION_DELAY_SCOPE" "G"
					( Parent
						( matchGroupRef "@baseboard_fab2_lib.baseboard_fab2(sch_1):\MG_DDR_CMD_NEAR_DIMM_NG_DDR_J_DLL_2\" )
					)
					( Status sCSetFlattened )
					( Origin gBackEnd )
				)
				( attribute "RELATIVE_PROPAGATION_DELAY" "0.00 MIL,25.00 MIL"
					( Parent
						( matchGroupRef "@baseboard_fab2_lib.baseboard_fab2(sch_1):\MG_DDR_CMD_NEAR_DIMM_NG_DDR_J_DLL_2\" )
					)
					( Units "uMatchProp" "ns" 1.000000)
					( Status sCSetFlattened )
					( Origin gBackEnd )
				)
			)
			( pinPair "@baseboard_fab2_lib.baseboard_fab2(sch_1):\PP3519\"
				( pinRef "@baseboard_fab2_lib.baseboard_fab2(sch_1):page59_i172:DDR2_MA(14)" )
				( pinRef "@baseboard_fab2_lib.baseboard_fab2(sch_1):page81_i186:A14_WE_N" )
				( attribute "RELATIVE_PROPAGATION_DELAY_SCOPE" "G"
					( Parent
						( matchGroupRef "@crescent_city_bb_fab1_lib.crescent_city_bb_fab1(sch_1):\MG_DDR_FAR_DIMM-CLK0_CLS_DDR_J_CAC-CLKS\" )
					)
					( Status sCSetFlattened )
					( Origin gBackEnd )
				)
				( attribute "RELATIVE_PROPAGATION_DELAY" "0.00 MIL,700.00 MIL"
					( Parent
						( matchGroupRef "@crescent_city_bb_fab1_lib.crescent_city_bb_fab1(sch_1):\MG_DDR_FAR_DIMM-CLK0_CLS_DDR_J_CAC-CLKS\" )
					)
					( Units "uMatchProp" "ns" 1.000000)
					( Status sCSetFlattened )
					( Origin gBackEnd )
				)
				( attribute "RELATIVE_PROPAGATION_DELAY_SCOPE" "G"
					( Parent
						( matchGroupRef "@baseboard_fab2_lib.baseboard_fab2(sch_1):\MG_DDR_FAR_DIMM_CMD_NG_DDR_J_DLL_3\" )
					)
					( Status sCSetFlattened )
					( Origin gBackEnd )
				)
				( attribute "RELATIVE_PROPAGATION_DELAY" "0.00 MIL,25.00 MIL"
					( Parent
						( matchGroupRef "@baseboard_fab2_lib.baseboard_fab2(sch_1):\MG_DDR_FAR_DIMM_CMD_NG_DDR_J_DLL_3\" )
					)
					( Units "uMatchProp" "ns" 1.000000)
					( Status sCSetFlattened )
					( Origin gBackEnd )
				)
			)
			( pinPair "@baseboard_fab2_lib.baseboard_fab2(sch_1):\PP3520\"
				( pinRef "@baseboard_fab2_lib.baseboard_fab2(sch_1):page82_i187:A14_WE_N" )
				( pinRef "@baseboard_fab2_lib.baseboard_fab2(sch_1):page59_i172:DDR2_MA(14)" )
				( attribute "RELATIVE_PROPAGATION_DELAY_SCOPE" "G"
					( Parent
						( matchGroupRef "@crescent_city_bb_fab1_lib.crescent_city_bb_fab1(sch_1):\MG_DDR_NEAR_DIMM-CLK1_CLS_DDR_J_CAC-CLKS\" )
					)
					( Status sCSetFlattened )
					( Origin gBackEnd )
				)
				( attribute "RELATIVE_PROPAGATION_DELAY" "0.00 MIL,700.00 MIL"
					( Parent
						( matchGroupRef "@crescent_city_bb_fab1_lib.crescent_city_bb_fab1(sch_1):\MG_DDR_NEAR_DIMM-CLK1_CLS_DDR_J_CAC-CLKS\" )
					)
					( Units "uMatchProp" "ns" 1.000000)
					( Status sCSetFlattened )
					( Origin gBackEnd )
				)
				( attribute "RELATIVE_PROPAGATION_DELAY_SCOPE" "G"
					( Parent
						( matchGroupRef "@baseboard_fab2_lib.baseboard_fab2(sch_1):\MG_DDR_CMD_NEAR_DIMM_NG_DDR_J_DLL_3\" )
					)
					( Status sCSetFlattened )
					( Origin gBackEnd )
				)
				( attribute "RELATIVE_PROPAGATION_DELAY" "0.00 MIL,25.00 MIL"
					( Parent
						( matchGroupRef "@baseboard_fab2_lib.baseboard_fab2(sch_1):\MG_DDR_CMD_NEAR_DIMM_NG_DDR_J_DLL_3\" )
					)
					( Units "uMatchProp" "ns" 1.000000)
					( Status sCSetFlattened )
					( Origin gBackEnd )
				)
			)
			( pinPair "@baseboard_fab2_lib.baseboard_fab2(sch_1):\PP3521\"
				( pinRef "@baseboard_fab2_lib.baseboard_fab2(sch_1):page59_i172:DDR2_MA(16)" )
				( pinRef "@baseboard_fab2_lib.baseboard_fab2(sch_1):page81_i186:A16_RAS_N" )
				( attribute "RELATIVE_PROPAGATION_DELAY_SCOPE" "G"
					( Parent
						( matchGroupRef "@crescent_city_bb_fab1_lib.crescent_city_bb_fab1(sch_1):\MG_DDR_FAR_DIMM-CLK0_CLS_DDR_J_CAC-CLKS\" )
					)
					( Status sCSetFlattened )
					( Origin gBackEnd )
				)
				( attribute "RELATIVE_PROPAGATION_DELAY" "0.00 MIL,700.00 MIL"
					( Parent
						( matchGroupRef "@crescent_city_bb_fab1_lib.crescent_city_bb_fab1(sch_1):\MG_DDR_FAR_DIMM-CLK0_CLS_DDR_J_CAC-CLKS\" )
					)
					( Units "uMatchProp" "ns" 1.000000)
					( Status sCSetFlattened )
					( Origin gBackEnd )
				)
				( attribute "RELATIVE_PROPAGATION_DELAY_SCOPE" "G"
					( Parent
						( matchGroupRef "@baseboard_fab2_lib.baseboard_fab2(sch_1):\MG_DDR_FAR_DIMM_CMD_NG_DDR_J_DLL_3\" )
					)
					( Status sCSetFlattened )
					( Origin gBackEnd )
				)
				( attribute "RELATIVE_PROPAGATION_DELAY" "0.00 MIL,25.00 MIL"
					( Parent
						( matchGroupRef "@baseboard_fab2_lib.baseboard_fab2(sch_1):\MG_DDR_FAR_DIMM_CMD_NG_DDR_J_DLL_3\" )
					)
					( Units "uMatchProp" "ns" 1.000000)
					( Status sCSetFlattened )
					( Origin gBackEnd )
				)
			)
			( pinPair "@baseboard_fab2_lib.baseboard_fab2(sch_1):\PP3522\"
				( pinRef "@baseboard_fab2_lib.baseboard_fab2(sch_1):page82_i187:A16_RAS_N" )
				( pinRef "@baseboard_fab2_lib.baseboard_fab2(sch_1):page59_i172:DDR2_MA(16)" )
				( attribute "RELATIVE_PROPAGATION_DELAY_SCOPE" "G"
					( Parent
						( matchGroupRef "@crescent_city_bb_fab1_lib.crescent_city_bb_fab1(sch_1):\MG_DDR_NEAR_DIMM-CLK1_CLS_DDR_J_CAC-CLKS\" )
					)
					( Status sCSetFlattened )
					( Origin gBackEnd )
				)
				( attribute "RELATIVE_PROPAGATION_DELAY" "0.00 MIL,700.00 MIL"
					( Parent
						( matchGroupRef "@crescent_city_bb_fab1_lib.crescent_city_bb_fab1(sch_1):\MG_DDR_NEAR_DIMM-CLK1_CLS_DDR_J_CAC-CLKS\" )
					)
					( Units "uMatchProp" "ns" 1.000000)
					( Status sCSetFlattened )
					( Origin gBackEnd )
				)
				( attribute "RELATIVE_PROPAGATION_DELAY_SCOPE" "G"
					( Parent
						( matchGroupRef "@baseboard_fab2_lib.baseboard_fab2(sch_1):\MG_DDR_CMD_NEAR_DIMM_NG_DDR_J_DLL_3\" )
					)
					( Status sCSetFlattened )
					( Origin gBackEnd )
				)
				( attribute "RELATIVE_PROPAGATION_DELAY" "0.00 MIL,25.00 MIL"
					( Parent
						( matchGroupRef "@baseboard_fab2_lib.baseboard_fab2(sch_1):\MG_DDR_CMD_NEAR_DIMM_NG_DDR_J_DLL_3\" )
					)
					( Units "uMatchProp" "ns" 1.000000)
					( Status sCSetFlattened )
					( Origin gBackEnd )
				)
			)
			( pinPair "@baseboard_fab2_lib.baseboard_fab2(sch_1):\PP3515\"
				( pinRef "@baseboard_fab2_lib.baseboard_fab2(sch_1):page59_i172:DDR2_BA(1)" )
				( pinRef "@baseboard_fab2_lib.baseboard_fab2(sch_1):page81_i186:BA(1)" )
				( attribute "RELATIVE_PROPAGATION_DELAY_SCOPE" "G"
					( Parent
						( matchGroupRef "@crescent_city_bb_fab1_lib.crescent_city_bb_fab1(sch_1):\MG_DDR_FAR_DIMM-CLK0_CLS_DDR_J_CAC-CLKS\" )
					)
					( Status sCSetFlattened )
					( Origin gBackEnd )
				)
				( attribute "RELATIVE_PROPAGATION_DELAY" "0.00 MIL,700.00 MIL"
					( Parent
						( matchGroupRef "@crescent_city_bb_fab1_lib.crescent_city_bb_fab1(sch_1):\MG_DDR_FAR_DIMM-CLK0_CLS_DDR_J_CAC-CLKS\" )
					)
					( Units "uMatchProp" "ns" 1.000000)
					( Status sCSetFlattened )
					( Origin gBackEnd )
				)
				( attribute "RELATIVE_PROPAGATION_DELAY_SCOPE" "G"
					( Parent
						( matchGroupRef "@baseboard_fab2_lib.baseboard_fab2(sch_1):\MG_DDR_FAR_DIMM_CMD_NG_DDR_J_DLL_4\" )
					)
					( Status sCSetFlattened )
					( Origin gBackEnd )
				)
				( attribute "RELATIVE_PROPAGATION_DELAY" "0.00 MIL,25.00 MIL"
					( Parent
						( matchGroupRef "@baseboard_fab2_lib.baseboard_fab2(sch_1):\MG_DDR_FAR_DIMM_CMD_NG_DDR_J_DLL_4\" )
					)
					( Units "uMatchProp" "ns" 1.000000)
					( Status sCSetFlattened )
					( Origin gBackEnd )
				)
			)
			( pinPair "@baseboard_fab2_lib.baseboard_fab2(sch_1):\PP3516\"
				( pinRef "@baseboard_fab2_lib.baseboard_fab2(sch_1):page82_i187:BA(1)" )
				( pinRef "@baseboard_fab2_lib.baseboard_fab2(sch_1):page59_i172:DDR2_BA(1)" )
				( attribute "RELATIVE_PROPAGATION_DELAY_SCOPE" "G"
					( Parent
						( matchGroupRef "@crescent_city_bb_fab1_lib.crescent_city_bb_fab1(sch_1):\MG_DDR_NEAR_DIMM-CLK1_CLS_DDR_J_CAC-CLKS\" )
					)
					( Status sCSetFlattened )
					( Origin gBackEnd )
				)
				( attribute "RELATIVE_PROPAGATION_DELAY" "0.00 MIL,700.00 MIL"
					( Parent
						( matchGroupRef "@crescent_city_bb_fab1_lib.crescent_city_bb_fab1(sch_1):\MG_DDR_NEAR_DIMM-CLK1_CLS_DDR_J_CAC-CLKS\" )
					)
					( Units "uMatchProp" "ns" 1.000000)
					( Status sCSetFlattened )
					( Origin gBackEnd )
				)
				( attribute "RELATIVE_PROPAGATION_DELAY_SCOPE" "G"
					( Parent
						( matchGroupRef "@baseboard_fab2_lib.baseboard_fab2(sch_1):\MG_DDR_CMD_NEAR_DIMM_NG_DDR_J_DLL_4\" )
					)
					( Status sCSetFlattened )
					( Origin gBackEnd )
				)
				( attribute "RELATIVE_PROPAGATION_DELAY" "0.00 MIL,25.00 MIL"
					( Parent
						( matchGroupRef "@baseboard_fab2_lib.baseboard_fab2(sch_1):\MG_DDR_CMD_NEAR_DIMM_NG_DDR_J_DLL_4\" )
					)
					( Units "uMatchProp" "ns" 1.000000)
					( Status sCSetFlattened )
					( Origin gBackEnd )
				)
			)
			( pinPair "@baseboard_fab2_lib.baseboard_fab2(sch_1):\PP3517\"
				( pinRef "@baseboard_fab2_lib.baseboard_fab2(sch_1):page59_i172:DDR2_MA(10)" )
				( pinRef "@baseboard_fab2_lib.baseboard_fab2(sch_1):page81_i186:A10" )
				( attribute "RELATIVE_PROPAGATION_DELAY_SCOPE" "G"
					( Parent
						( matchGroupRef "@crescent_city_bb_fab1_lib.crescent_city_bb_fab1(sch_1):\MG_DDR_FAR_DIMM-CLK0_CLS_DDR_J_CAC-CLKS\" )
					)
					( Status sCSetFlattened )
					( Origin gBackEnd )
				)
				( attribute "RELATIVE_PROPAGATION_DELAY" "0.00 MIL,700.00 MIL"
					( Parent
						( matchGroupRef "@crescent_city_bb_fab1_lib.crescent_city_bb_fab1(sch_1):\MG_DDR_FAR_DIMM-CLK0_CLS_DDR_J_CAC-CLKS\" )
					)
					( Units "uMatchProp" "ns" 1.000000)
					( Status sCSetFlattened )
					( Origin gBackEnd )
				)
				( attribute "RELATIVE_PROPAGATION_DELAY_SCOPE" "G"
					( Parent
						( matchGroupRef "@baseboard_fab2_lib.baseboard_fab2(sch_1):\MG_DDR_FAR_DIMM_CMD_NG_DDR_J_DLL_4\" )
					)
					( Status sCSetFlattened )
					( Origin gBackEnd )
				)
				( attribute "RELATIVE_PROPAGATION_DELAY" "0.00 MIL,25.00 MIL"
					( Parent
						( matchGroupRef "@baseboard_fab2_lib.baseboard_fab2(sch_1):\MG_DDR_FAR_DIMM_CMD_NG_DDR_J_DLL_4\" )
					)
					( Units "uMatchProp" "ns" 1.000000)
					( Status sCSetFlattened )
					( Origin gBackEnd )
				)
			)
			( pinPair "@baseboard_fab2_lib.baseboard_fab2(sch_1):\PP3518\"
				( pinRef "@baseboard_fab2_lib.baseboard_fab2(sch_1):page82_i187:A10" )
				( pinRef "@baseboard_fab2_lib.baseboard_fab2(sch_1):page59_i172:DDR2_MA(10)" )
				( attribute "RELATIVE_PROPAGATION_DELAY_SCOPE" "G"
					( Parent
						( matchGroupRef "@crescent_city_bb_fab1_lib.crescent_city_bb_fab1(sch_1):\MG_DDR_NEAR_DIMM-CLK1_CLS_DDR_J_CAC-CLKS\" )
					)
					( Status sCSetFlattened )
					( Origin gBackEnd )
				)
				( attribute "RELATIVE_PROPAGATION_DELAY" "0.00 MIL,700.00 MIL"
					( Parent
						( matchGroupRef "@crescent_city_bb_fab1_lib.crescent_city_bb_fab1(sch_1):\MG_DDR_NEAR_DIMM-CLK1_CLS_DDR_J_CAC-CLKS\" )
					)
					( Units "uMatchProp" "ns" 1.000000)
					( Status sCSetFlattened )
					( Origin gBackEnd )
				)
				( attribute "RELATIVE_PROPAGATION_DELAY_SCOPE" "G"
					( Parent
						( matchGroupRef "@baseboard_fab2_lib.baseboard_fab2(sch_1):\MG_DDR_CMD_NEAR_DIMM_NG_DDR_J_DLL_4\" )
					)
					( Status sCSetFlattened )
					( Origin gBackEnd )
				)
				( attribute "RELATIVE_PROPAGATION_DELAY" "0.00 MIL,25.00 MIL"
					( Parent
						( matchGroupRef "@baseboard_fab2_lib.baseboard_fab2(sch_1):\MG_DDR_CMD_NEAR_DIMM_NG_DDR_J_DLL_4\" )
					)
					( Units "uMatchProp" "ns" 1.000000)
					( Status sCSetFlattened )
					( Origin gBackEnd )
				)
			)
			( pinPair "@baseboard_fab2_lib.baseboard_fab2(sch_1):\PP3511\"
				( pinRef "@baseboard_fab2_lib.baseboard_fab2(sch_1):page59_i172:DDR2_BA(0)" )
				( pinRef "@baseboard_fab2_lib.baseboard_fab2(sch_1):page81_i186:BA(0)" )
				( attribute "RELATIVE_PROPAGATION_DELAY_SCOPE" "G"
					( Parent
						( matchGroupRef "@crescent_city_bb_fab1_lib.crescent_city_bb_fab1(sch_1):\MG_DDR_FAR_DIMM-CLK0_CLS_DDR_J_CAC-CLKS\" )
					)
					( Status sCSetFlattened )
					( Origin gBackEnd )
				)
				( attribute "RELATIVE_PROPAGATION_DELAY" "0.00 MIL,700.00 MIL"
					( Parent
						( matchGroupRef "@crescent_city_bb_fab1_lib.crescent_city_bb_fab1(sch_1):\MG_DDR_FAR_DIMM-CLK0_CLS_DDR_J_CAC-CLKS\" )
					)
					( Units "uMatchProp" "ns" 1.000000)
					( Status sCSetFlattened )
					( Origin gBackEnd )
				)
				( attribute "RELATIVE_PROPAGATION_DELAY_SCOPE" "G"
					( Parent
						( matchGroupRef "@baseboard_fab2_lib.baseboard_fab2(sch_1):\MG_DDR_FAR_DIMM_CMD_NG_DDR_J_DLL_5\" )
					)
					( Status sCSetFlattened )
					( Origin gBackEnd )
				)
				( attribute "RELATIVE_PROPAGATION_DELAY" "0.00 MIL,25.00 MIL"
					( Parent
						( matchGroupRef "@baseboard_fab2_lib.baseboard_fab2(sch_1):\MG_DDR_FAR_DIMM_CMD_NG_DDR_J_DLL_5\" )
					)
					( Units "uMatchProp" "ns" 1.000000)
					( Status sCSetFlattened )
					( Origin gBackEnd )
				)
			)
			( pinPair "@baseboard_fab2_lib.baseboard_fab2(sch_1):\PP3512\"
				( pinRef "@baseboard_fab2_lib.baseboard_fab2(sch_1):page82_i187:BA(0)" )
				( pinRef "@baseboard_fab2_lib.baseboard_fab2(sch_1):page59_i172:DDR2_BA(0)" )
				( attribute "RELATIVE_PROPAGATION_DELAY_SCOPE" "G"
					( Parent
						( matchGroupRef "@crescent_city_bb_fab1_lib.crescent_city_bb_fab1(sch_1):\MG_DDR_NEAR_DIMM-CLK1_CLS_DDR_J_CAC-CLKS\" )
					)
					( Status sCSetFlattened )
					( Origin gBackEnd )
				)
				( attribute "RELATIVE_PROPAGATION_DELAY" "0.00 MIL,700.00 MIL"
					( Parent
						( matchGroupRef "@crescent_city_bb_fab1_lib.crescent_city_bb_fab1(sch_1):\MG_DDR_NEAR_DIMM-CLK1_CLS_DDR_J_CAC-CLKS\" )
					)
					( Units "uMatchProp" "ns" 1.000000)
					( Status sCSetFlattened )
					( Origin gBackEnd )
				)
				( attribute "RELATIVE_PROPAGATION_DELAY_SCOPE" "G"
					( Parent
						( matchGroupRef "@baseboard_fab2_lib.baseboard_fab2(sch_1):\MG_DDR_CMD_NEAR_DIMM_NG_DDR_J_DLL_5\" )
					)
					( Status sCSetFlattened )
					( Origin gBackEnd )
				)
				( attribute "RELATIVE_PROPAGATION_DELAY" "0.00 MIL,25.00 MIL"
					( Parent
						( matchGroupRef "@baseboard_fab2_lib.baseboard_fab2(sch_1):\MG_DDR_CMD_NEAR_DIMM_NG_DDR_J_DLL_5\" )
					)
					( Units "uMatchProp" "ns" 1.000000)
					( Status sCSetFlattened )
					( Origin gBackEnd )
				)
			)
			( pinPair "@baseboard_fab2_lib.baseboard_fab2(sch_1):\PP3513\"
				( pinRef "@baseboard_fab2_lib.baseboard_fab2(sch_1):page59_i172:DDR2_MA(0)" )
				( pinRef "@baseboard_fab2_lib.baseboard_fab2(sch_1):page81_i186:A0" )
				( attribute "RELATIVE_PROPAGATION_DELAY_SCOPE" "G"
					( Parent
						( matchGroupRef "@crescent_city_bb_fab1_lib.crescent_city_bb_fab1(sch_1):\MG_DDR_FAR_DIMM-CLK0_CLS_DDR_J_CAC-CLKS\" )
					)
					( Status sCSetFlattened )
					( Origin gBackEnd )
				)
				( attribute "RELATIVE_PROPAGATION_DELAY" "0.00 MIL,700.00 MIL"
					( Parent
						( matchGroupRef "@crescent_city_bb_fab1_lib.crescent_city_bb_fab1(sch_1):\MG_DDR_FAR_DIMM-CLK0_CLS_DDR_J_CAC-CLKS\" )
					)
					( Units "uMatchProp" "ns" 1.000000)
					( Status sCSetFlattened )
					( Origin gBackEnd )
				)
				( attribute "RELATIVE_PROPAGATION_DELAY_SCOPE" "G"
					( Parent
						( matchGroupRef "@baseboard_fab2_lib.baseboard_fab2(sch_1):\MG_DDR_FAR_DIMM_CMD_NG_DDR_J_DLL_5\" )
					)
					( Status sCSetFlattened )
					( Origin gBackEnd )
				)
				( attribute "RELATIVE_PROPAGATION_DELAY" "0.00 MIL,25.00 MIL"
					( Parent
						( matchGroupRef "@baseboard_fab2_lib.baseboard_fab2(sch_1):\MG_DDR_FAR_DIMM_CMD_NG_DDR_J_DLL_5\" )
					)
					( Units "uMatchProp" "ns" 1.000000)
					( Status sCSetFlattened )
					( Origin gBackEnd )
				)
			)
			( pinPair "@baseboard_fab2_lib.baseboard_fab2(sch_1):\PP3514\"
				( pinRef "@baseboard_fab2_lib.baseboard_fab2(sch_1):page82_i187:A0" )
				( pinRef "@baseboard_fab2_lib.baseboard_fab2(sch_1):page59_i172:DDR2_MA(0)" )
				( attribute "RELATIVE_PROPAGATION_DELAY_SCOPE" "G"
					( Parent
						( matchGroupRef "@crescent_city_bb_fab1_lib.crescent_city_bb_fab1(sch_1):\MG_DDR_NEAR_DIMM-CLK1_CLS_DDR_J_CAC-CLKS\" )
					)
					( Status sCSetFlattened )
					( Origin gBackEnd )
				)
				( attribute "RELATIVE_PROPAGATION_DELAY" "0.00 MIL,700.00 MIL"
					( Parent
						( matchGroupRef "@crescent_city_bb_fab1_lib.crescent_city_bb_fab1(sch_1):\MG_DDR_NEAR_DIMM-CLK1_CLS_DDR_J_CAC-CLKS\" )
					)
					( Units "uMatchProp" "ns" 1.000000)
					( Status sCSetFlattened )
					( Origin gBackEnd )
				)
				( attribute "RELATIVE_PROPAGATION_DELAY_SCOPE" "G"
					( Parent
						( matchGroupRef "@baseboard_fab2_lib.baseboard_fab2(sch_1):\MG_DDR_CMD_NEAR_DIMM_NG_DDR_J_DLL_5\" )
					)
					( Status sCSetFlattened )
					( Origin gBackEnd )
				)
				( attribute "RELATIVE_PROPAGATION_DELAY" "0.00 MIL,25.00 MIL"
					( Parent
						( matchGroupRef "@baseboard_fab2_lib.baseboard_fab2(sch_1):\MG_DDR_CMD_NEAR_DIMM_NG_DDR_J_DLL_5\" )
					)
					( Units "uMatchProp" "ns" 1.000000)
					( Status sCSetFlattened )
					( Origin gBackEnd )
				)
			)
			( pinPair "@baseboard_fab2_lib.baseboard_fab2(sch_1):\PP3509\"
				( pinRef "@baseboard_fab2_lib.baseboard_fab2(sch_1):page59_i172:DDR2_PAR" )
				( pinRef "@baseboard_fab2_lib.baseboard_fab2(sch_1):page81_i186:PAR" )
				( attribute "RELATIVE_PROPAGATION_DELAY_SCOPE" "G"
					( Parent
						( matchGroupRef "@crescent_city_bb_fab1_lib.crescent_city_bb_fab1(sch_1):\MG_DDR_FAR_DIMM-CLK0_CLS_DDR_J_CAC-CLKS\" )
					)
					( Status sCSetFlattened )
					( Origin gBackEnd )
				)
				( attribute "RELATIVE_PROPAGATION_DELAY" "0.00 MIL,700.00 MIL"
					( Parent
						( matchGroupRef "@crescent_city_bb_fab1_lib.crescent_city_bb_fab1(sch_1):\MG_DDR_FAR_DIMM-CLK0_CLS_DDR_J_CAC-CLKS\" )
					)
					( Units "uMatchProp" "ns" 1.000000)
					( Status sCSetFlattened )
					( Origin gBackEnd )
				)
				( attribute "RELATIVE_PROPAGATION_DELAY_SCOPE" "G"
					( Parent
						( matchGroupRef "@baseboard_fab2_lib.baseboard_fab2(sch_1):\MG_DDR_FAR_DIMM_CMD_NG_DDR_J_DLL_6\" )
					)
					( Status sCSetFlattened )
					( Origin gBackEnd )
				)
				( attribute "RELATIVE_PROPAGATION_DELAY" "0.00 MIL,25.00 MIL"
					( Parent
						( matchGroupRef "@baseboard_fab2_lib.baseboard_fab2(sch_1):\MG_DDR_FAR_DIMM_CMD_NG_DDR_J_DLL_6\" )
					)
					( Units "uMatchProp" "ns" 1.000000)
					( Status sCSetFlattened )
					( Origin gBackEnd )
				)
			)
			( pinPair "@baseboard_fab2_lib.baseboard_fab2(sch_1):\PP3510\"
				( pinRef "@baseboard_fab2_lib.baseboard_fab2(sch_1):page82_i187:PAR" )
				( pinRef "@baseboard_fab2_lib.baseboard_fab2(sch_1):page59_i172:DDR2_PAR" )
				( attribute "RELATIVE_PROPAGATION_DELAY_SCOPE" "G"
					( Parent
						( matchGroupRef "@crescent_city_bb_fab1_lib.crescent_city_bb_fab1(sch_1):\MG_DDR_NEAR_DIMM-CLK1_CLS_DDR_J_CAC-CLKS\" )
					)
					( Status sCSetFlattened )
					( Origin gBackEnd )
				)
				( attribute "RELATIVE_PROPAGATION_DELAY" "0.00 MIL,700.00 MIL"
					( Parent
						( matchGroupRef "@crescent_city_bb_fab1_lib.crescent_city_bb_fab1(sch_1):\MG_DDR_NEAR_DIMM-CLK1_CLS_DDR_J_CAC-CLKS\" )
					)
					( Units "uMatchProp" "ns" 1.000000)
					( Status sCSetFlattened )
					( Origin gBackEnd )
				)
				( attribute "RELATIVE_PROPAGATION_DELAY_SCOPE" "G"
					( Parent
						( matchGroupRef "@baseboard_fab2_lib.baseboard_fab2(sch_1):\MG_DDR_CMD_NEAR_DIMM_NG_DDR_J_DLL_6\" )
					)
					( Status sCSetFlattened )
					( Origin gBackEnd )
				)
				( attribute "RELATIVE_PROPAGATION_DELAY" "0.00 MIL,25.00 MIL"
					( Parent
						( matchGroupRef "@baseboard_fab2_lib.baseboard_fab2(sch_1):\MG_DDR_CMD_NEAR_DIMM_NG_DDR_J_DLL_6\" )
					)
					( Units "uMatchProp" "ns" 1.000000)
					( Status sCSetFlattened )
					( Origin gBackEnd )
				)
			)
			( pinPair "@baseboard_fab2_lib.baseboard_fab2(sch_1):\PP3505\"
				( pinRef "@baseboard_fab2_lib.baseboard_fab2(sch_1):page59_i172:DDR2_MA(1)" )
				( pinRef "@baseboard_fab2_lib.baseboard_fab2(sch_1):page81_i186:A1" )
				( attribute "RELATIVE_PROPAGATION_DELAY_SCOPE" "G"
					( Parent
						( matchGroupRef "@crescent_city_bb_fab1_lib.crescent_city_bb_fab1(sch_1):\MG_DDR_FAR_DIMM-CLK0_CLS_DDR_J_CAC-CLKS\" )
					)
					( Status sCSetFlattened )
					( Origin gBackEnd )
				)
				( attribute "RELATIVE_PROPAGATION_DELAY" "0.00 MIL,700.00 MIL"
					( Parent
						( matchGroupRef "@crescent_city_bb_fab1_lib.crescent_city_bb_fab1(sch_1):\MG_DDR_FAR_DIMM-CLK0_CLS_DDR_J_CAC-CLKS\" )
					)
					( Units "uMatchProp" "ns" 1.000000)
					( Status sCSetFlattened )
					( Origin gBackEnd )
				)
				( attribute "RELATIVE_PROPAGATION_DELAY_SCOPE" "G"
					( Parent
						( matchGroupRef "@baseboard_fab2_lib.baseboard_fab2(sch_1):\MG_DDR_FAR_DIMM_CMD_NG_DDR_J_DLL_7\" )
					)
					( Status sCSetFlattened )
					( Origin gBackEnd )
				)
				( attribute "RELATIVE_PROPAGATION_DELAY" "0.00 MIL,25.00 MIL"
					( Parent
						( matchGroupRef "@baseboard_fab2_lib.baseboard_fab2(sch_1):\MG_DDR_FAR_DIMM_CMD_NG_DDR_J_DLL_7\" )
					)
					( Units "uMatchProp" "ns" 1.000000)
					( Status sCSetFlattened )
					( Origin gBackEnd )
				)
			)
			( pinPair "@baseboard_fab2_lib.baseboard_fab2(sch_1):\PP3506\"
				( pinRef "@baseboard_fab2_lib.baseboard_fab2(sch_1):page82_i187:A1" )
				( pinRef "@baseboard_fab2_lib.baseboard_fab2(sch_1):page59_i172:DDR2_MA(1)" )
				( attribute "RELATIVE_PROPAGATION_DELAY_SCOPE" "G"
					( Parent
						( matchGroupRef "@crescent_city_bb_fab1_lib.crescent_city_bb_fab1(sch_1):\MG_DDR_NEAR_DIMM-CLK1_CLS_DDR_J_CAC-CLKS\" )
					)
					( Status sCSetFlattened )
					( Origin gBackEnd )
				)
				( attribute "RELATIVE_PROPAGATION_DELAY" "0.00 MIL,700.00 MIL"
					( Parent
						( matchGroupRef "@crescent_city_bb_fab1_lib.crescent_city_bb_fab1(sch_1):\MG_DDR_NEAR_DIMM-CLK1_CLS_DDR_J_CAC-CLKS\" )
					)
					( Units "uMatchProp" "ns" 1.000000)
					( Status sCSetFlattened )
					( Origin gBackEnd )
				)
				( attribute "RELATIVE_PROPAGATION_DELAY_SCOPE" "G"
					( Parent
						( matchGroupRef "@baseboard_fab2_lib.baseboard_fab2(sch_1):\MG_DDR_CMD_NEAR_DIMM_NG_DDR_J_DLL_7\" )
					)
					( Status sCSetFlattened )
					( Origin gBackEnd )
				)
				( attribute "RELATIVE_PROPAGATION_DELAY" "0.00 MIL,25.00 MIL"
					( Parent
						( matchGroupRef "@baseboard_fab2_lib.baseboard_fab2(sch_1):\MG_DDR_CMD_NEAR_DIMM_NG_DDR_J_DLL_7\" )
					)
					( Units "uMatchProp" "ns" 1.000000)
					( Status sCSetFlattened )
					( Origin gBackEnd )
				)
			)
			( pinPair "@baseboard_fab2_lib.baseboard_fab2(sch_1):\PP3507\"
				( pinRef "@baseboard_fab2_lib.baseboard_fab2(sch_1):page59_i172:DDR2_MA(3)" )
				( pinRef "@baseboard_fab2_lib.baseboard_fab2(sch_1):page81_i186:A3" )
				( attribute "RELATIVE_PROPAGATION_DELAY_SCOPE" "G"
					( Parent
						( matchGroupRef "@crescent_city_bb_fab1_lib.crescent_city_bb_fab1(sch_1):\MG_DDR_FAR_DIMM-CLK0_CLS_DDR_J_CAC-CLKS\" )
					)
					( Status sCSetFlattened )
					( Origin gBackEnd )
				)
				( attribute "RELATIVE_PROPAGATION_DELAY" "0.00 MIL,700.00 MIL"
					( Parent
						( matchGroupRef "@crescent_city_bb_fab1_lib.crescent_city_bb_fab1(sch_1):\MG_DDR_FAR_DIMM-CLK0_CLS_DDR_J_CAC-CLKS\" )
					)
					( Units "uMatchProp" "ns" 1.000000)
					( Status sCSetFlattened )
					( Origin gBackEnd )
				)
				( attribute "RELATIVE_PROPAGATION_DELAY_SCOPE" "G"
					( Parent
						( matchGroupRef "@baseboard_fab2_lib.baseboard_fab2(sch_1):\MG_DDR_FAR_DIMM_CMD_NG_DDR_J_DLL_7\" )
					)
					( Status sCSetFlattened )
					( Origin gBackEnd )
				)
				( attribute "RELATIVE_PROPAGATION_DELAY" "0.00 MIL,25.00 MIL"
					( Parent
						( matchGroupRef "@baseboard_fab2_lib.baseboard_fab2(sch_1):\MG_DDR_FAR_DIMM_CMD_NG_DDR_J_DLL_7\" )
					)
					( Units "uMatchProp" "ns" 1.000000)
					( Status sCSetFlattened )
					( Origin gBackEnd )
				)
			)
			( pinPair "@baseboard_fab2_lib.baseboard_fab2(sch_1):\PP3508\"
				( pinRef "@baseboard_fab2_lib.baseboard_fab2(sch_1):page82_i187:A3" )
				( pinRef "@baseboard_fab2_lib.baseboard_fab2(sch_1):page59_i172:DDR2_MA(3)" )
				( attribute "RELATIVE_PROPAGATION_DELAY_SCOPE" "G"
					( Parent
						( matchGroupRef "@crescent_city_bb_fab1_lib.crescent_city_bb_fab1(sch_1):\MG_DDR_NEAR_DIMM-CLK1_CLS_DDR_J_CAC-CLKS\" )
					)
					( Status sCSetFlattened )
					( Origin gBackEnd )
				)
				( attribute "RELATIVE_PROPAGATION_DELAY" "0.00 MIL,700.00 MIL"
					( Parent
						( matchGroupRef "@crescent_city_bb_fab1_lib.crescent_city_bb_fab1(sch_1):\MG_DDR_NEAR_DIMM-CLK1_CLS_DDR_J_CAC-CLKS\" )
					)
					( Units "uMatchProp" "ns" 1.000000)
					( Status sCSetFlattened )
					( Origin gBackEnd )
				)
				( attribute "RELATIVE_PROPAGATION_DELAY_SCOPE" "G"
					( Parent
						( matchGroupRef "@baseboard_fab2_lib.baseboard_fab2(sch_1):\MG_DDR_CMD_NEAR_DIMM_NG_DDR_J_DLL_7\" )
					)
					( Status sCSetFlattened )
					( Origin gBackEnd )
				)
				( attribute "RELATIVE_PROPAGATION_DELAY" "0.00 MIL,25.00 MIL"
					( Parent
						( matchGroupRef "@baseboard_fab2_lib.baseboard_fab2(sch_1):\MG_DDR_CMD_NEAR_DIMM_NG_DDR_J_DLL_7\" )
					)
					( Units "uMatchProp" "ns" 1.000000)
					( Status sCSetFlattened )
					( Origin gBackEnd )
				)
			)
			( pinPair "@baseboard_fab2_lib.baseboard_fab2(sch_1):\PP3501\"
				( pinRef "@baseboard_fab2_lib.baseboard_fab2(sch_1):page59_i172:DDR2_MA(2)" )
				( pinRef "@baseboard_fab2_lib.baseboard_fab2(sch_1):page81_i186:A2" )
				( attribute "RELATIVE_PROPAGATION_DELAY_SCOPE" "G"
					( Parent
						( matchGroupRef "@crescent_city_bb_fab1_lib.crescent_city_bb_fab1(sch_1):\MG_DDR_FAR_DIMM-CLK0_CLS_DDR_J_CAC-CLKS\" )
					)
					( Status sCSetFlattened )
					( Origin gBackEnd )
				)
				( attribute "RELATIVE_PROPAGATION_DELAY" "0.00 MIL,700.00 MIL"
					( Parent
						( matchGroupRef "@crescent_city_bb_fab1_lib.crescent_city_bb_fab1(sch_1):\MG_DDR_FAR_DIMM-CLK0_CLS_DDR_J_CAC-CLKS\" )
					)
					( Units "uMatchProp" "ns" 1.000000)
					( Status sCSetFlattened )
					( Origin gBackEnd )
				)
				( attribute "RELATIVE_PROPAGATION_DELAY_SCOPE" "G"
					( Parent
						( matchGroupRef "@baseboard_fab2_lib.baseboard_fab2(sch_1):\MG_DDR_FAR_DIMM_CMD_NG_DDR_J_DLL_8\" )
					)
					( Status sCSetFlattened )
					( Origin gBackEnd )
				)
				( attribute "RELATIVE_PROPAGATION_DELAY" "0.00 MIL,25.00 MIL"
					( Parent
						( matchGroupRef "@baseboard_fab2_lib.baseboard_fab2(sch_1):\MG_DDR_FAR_DIMM_CMD_NG_DDR_J_DLL_8\" )
					)
					( Units "uMatchProp" "ns" 1.000000)
					( Status sCSetFlattened )
					( Origin gBackEnd )
				)
			)
			( pinPair "@baseboard_fab2_lib.baseboard_fab2(sch_1):\PP3502\"
				( pinRef "@baseboard_fab2_lib.baseboard_fab2(sch_1):page82_i187:A2" )
				( pinRef "@baseboard_fab2_lib.baseboard_fab2(sch_1):page59_i172:DDR2_MA(2)" )
				( attribute "RELATIVE_PROPAGATION_DELAY_SCOPE" "G"
					( Parent
						( matchGroupRef "@crescent_city_bb_fab1_lib.crescent_city_bb_fab1(sch_1):\MG_DDR_NEAR_DIMM-CLK1_CLS_DDR_J_CAC-CLKS\" )
					)
					( Status sCSetFlattened )
					( Origin gBackEnd )
				)
				( attribute "RELATIVE_PROPAGATION_DELAY" "0.00 MIL,700.00 MIL"
					( Parent
						( matchGroupRef "@crescent_city_bb_fab1_lib.crescent_city_bb_fab1(sch_1):\MG_DDR_NEAR_DIMM-CLK1_CLS_DDR_J_CAC-CLKS\" )
					)
					( Units "uMatchProp" "ns" 1.000000)
					( Status sCSetFlattened )
					( Origin gBackEnd )
				)
				( attribute "RELATIVE_PROPAGATION_DELAY_SCOPE" "G"
					( Parent
						( matchGroupRef "@baseboard_fab2_lib.baseboard_fab2(sch_1):\MG_DDR_CMD_NEAR_DIMM_NG_DDR_J_DLL_8\" )
					)
					( Status sCSetFlattened )
					( Origin gBackEnd )
				)
				( attribute "RELATIVE_PROPAGATION_DELAY" "0.00 MIL,25.00 MIL"
					( Parent
						( matchGroupRef "@baseboard_fab2_lib.baseboard_fab2(sch_1):\MG_DDR_CMD_NEAR_DIMM_NG_DDR_J_DLL_8\" )
					)
					( Units "uMatchProp" "ns" 1.000000)
					( Status sCSetFlattened )
					( Origin gBackEnd )
				)
			)
			( pinPair "@baseboard_fab2_lib.baseboard_fab2(sch_1):\PP3503\"
				( pinRef "@baseboard_fab2_lib.baseboard_fab2(sch_1):page59_i172:DDR2_MA(4)" )
				( pinRef "@baseboard_fab2_lib.baseboard_fab2(sch_1):page81_i186:A4" )
				( attribute "RELATIVE_PROPAGATION_DELAY_SCOPE" "G"
					( Parent
						( matchGroupRef "@crescent_city_bb_fab1_lib.crescent_city_bb_fab1(sch_1):\MG_DDR_FAR_DIMM-CLK0_CLS_DDR_J_CAC-CLKS\" )
					)
					( Status sCSetFlattened )
					( Origin gBackEnd )
				)
				( attribute "RELATIVE_PROPAGATION_DELAY" "0.00 MIL,700.00 MIL"
					( Parent
						( matchGroupRef "@crescent_city_bb_fab1_lib.crescent_city_bb_fab1(sch_1):\MG_DDR_FAR_DIMM-CLK0_CLS_DDR_J_CAC-CLKS\" )
					)
					( Units "uMatchProp" "ns" 1.000000)
					( Status sCSetFlattened )
					( Origin gBackEnd )
				)
				( attribute "RELATIVE_PROPAGATION_DELAY_SCOPE" "G"
					( Parent
						( matchGroupRef "@baseboard_fab2_lib.baseboard_fab2(sch_1):\MG_DDR_FAR_DIMM_CMD_NG_DDR_J_DLL_8\" )
					)
					( Status sCSetFlattened )
					( Origin gBackEnd )
				)
				( attribute "RELATIVE_PROPAGATION_DELAY" "0.00 MIL,25.00 MIL"
					( Parent
						( matchGroupRef "@baseboard_fab2_lib.baseboard_fab2(sch_1):\MG_DDR_FAR_DIMM_CMD_NG_DDR_J_DLL_8\" )
					)
					( Units "uMatchProp" "ns" 1.000000)
					( Status sCSetFlattened )
					( Origin gBackEnd )
				)
			)
			( pinPair "@baseboard_fab2_lib.baseboard_fab2(sch_1):\PP3504\"
				( pinRef "@baseboard_fab2_lib.baseboard_fab2(sch_1):page82_i187:A4" )
				( pinRef "@baseboard_fab2_lib.baseboard_fab2(sch_1):page59_i172:DDR2_MA(4)" )
				( attribute "RELATIVE_PROPAGATION_DELAY_SCOPE" "G"
					( Parent
						( matchGroupRef "@crescent_city_bb_fab1_lib.crescent_city_bb_fab1(sch_1):\MG_DDR_NEAR_DIMM-CLK1_CLS_DDR_J_CAC-CLKS\" )
					)
					( Status sCSetFlattened )
					( Origin gBackEnd )
				)
				( attribute "RELATIVE_PROPAGATION_DELAY" "0.00 MIL,700.00 MIL"
					( Parent
						( matchGroupRef "@crescent_city_bb_fab1_lib.crescent_city_bb_fab1(sch_1):\MG_DDR_NEAR_DIMM-CLK1_CLS_DDR_J_CAC-CLKS\" )
					)
					( Units "uMatchProp" "ns" 1.000000)
					( Status sCSetFlattened )
					( Origin gBackEnd )
				)
				( attribute "RELATIVE_PROPAGATION_DELAY_SCOPE" "G"
					( Parent
						( matchGroupRef "@baseboard_fab2_lib.baseboard_fab2(sch_1):\MG_DDR_CMD_NEAR_DIMM_NG_DDR_J_DLL_8\" )
					)
					( Status sCSetFlattened )
					( Origin gBackEnd )
				)
				( attribute "RELATIVE_PROPAGATION_DELAY" "0.00 MIL,25.00 MIL"
					( Parent
						( matchGroupRef "@baseboard_fab2_lib.baseboard_fab2(sch_1):\MG_DDR_CMD_NEAR_DIMM_NG_DDR_J_DLL_8\" )
					)
					( Units "uMatchProp" "ns" 1.000000)
					( Status sCSetFlattened )
					( Origin gBackEnd )
				)
			)
			( pinPair "@baseboard_fab2_lib.baseboard_fab2(sch_1):\PP3497\"
				( pinRef "@baseboard_fab2_lib.baseboard_fab2(sch_1):page59_i172:DDR2_MA(5)" )
				( pinRef "@baseboard_fab2_lib.baseboard_fab2(sch_1):page81_i186:A5" )
				( attribute "RELATIVE_PROPAGATION_DELAY_SCOPE" "G"
					( Parent
						( matchGroupRef "@crescent_city_bb_fab1_lib.crescent_city_bb_fab1(sch_1):\MG_DDR_FAR_DIMM-CLK0_CLS_DDR_J_CAC-CLKS\" )
					)
					( Status sCSetFlattened )
					( Origin gBackEnd )
				)
				( attribute "RELATIVE_PROPAGATION_DELAY" "0.00 MIL,700.00 MIL"
					( Parent
						( matchGroupRef "@crescent_city_bb_fab1_lib.crescent_city_bb_fab1(sch_1):\MG_DDR_FAR_DIMM-CLK0_CLS_DDR_J_CAC-CLKS\" )
					)
					( Units "uMatchProp" "ns" 1.000000)
					( Status sCSetFlattened )
					( Origin gBackEnd )
				)
				( attribute "RELATIVE_PROPAGATION_DELAY_SCOPE" "G"
					( Parent
						( matchGroupRef "@baseboard_fab2_lib.baseboard_fab2(sch_1):\MG_DDR_FAR_DIMM_CMD_NG_DDR_J_DLL_9\" )
					)
					( Status sCSetFlattened )
					( Origin gBackEnd )
				)
				( attribute "RELATIVE_PROPAGATION_DELAY" "0.00 MIL,25.00 MIL"
					( Parent
						( matchGroupRef "@baseboard_fab2_lib.baseboard_fab2(sch_1):\MG_DDR_FAR_DIMM_CMD_NG_DDR_J_DLL_9\" )
					)
					( Units "uMatchProp" "ns" 1.000000)
					( Status sCSetFlattened )
					( Origin gBackEnd )
				)
			)
			( pinPair "@baseboard_fab2_lib.baseboard_fab2(sch_1):\PP3498\"
				( pinRef "@baseboard_fab2_lib.baseboard_fab2(sch_1):page82_i187:A5" )
				( pinRef "@baseboard_fab2_lib.baseboard_fab2(sch_1):page59_i172:DDR2_MA(5)" )
				( attribute "RELATIVE_PROPAGATION_DELAY_SCOPE" "G"
					( Parent
						( matchGroupRef "@crescent_city_bb_fab1_lib.crescent_city_bb_fab1(sch_1):\MG_DDR_NEAR_DIMM-CLK1_CLS_DDR_J_CAC-CLKS\" )
					)
					( Status sCSetFlattened )
					( Origin gBackEnd )
				)
				( attribute "RELATIVE_PROPAGATION_DELAY" "0.00 MIL,700.00 MIL"
					( Parent
						( matchGroupRef "@crescent_city_bb_fab1_lib.crescent_city_bb_fab1(sch_1):\MG_DDR_NEAR_DIMM-CLK1_CLS_DDR_J_CAC-CLKS\" )
					)
					( Units "uMatchProp" "ns" 1.000000)
					( Status sCSetFlattened )
					( Origin gBackEnd )
				)
				( attribute "RELATIVE_PROPAGATION_DELAY_SCOPE" "G"
					( Parent
						( matchGroupRef "@baseboard_fab2_lib.baseboard_fab2(sch_1):\MG_DDR_CMD_NEAR_DIMM_NG_DDR_J_DLL_9\" )
					)
					( Status sCSetFlattened )
					( Origin gBackEnd )
				)
				( attribute "RELATIVE_PROPAGATION_DELAY" "0.00 MIL,25.00 MIL"
					( Parent
						( matchGroupRef "@baseboard_fab2_lib.baseboard_fab2(sch_1):\MG_DDR_CMD_NEAR_DIMM_NG_DDR_J_DLL_9\" )
					)
					( Units "uMatchProp" "ns" 1.000000)
					( Status sCSetFlattened )
					( Origin gBackEnd )
				)
			)
			( pinPair "@baseboard_fab2_lib.baseboard_fab2(sch_1):\PP3499\"
				( pinRef "@baseboard_fab2_lib.baseboard_fab2(sch_1):page59_i172:DDR2_MA(6)" )
				( pinRef "@baseboard_fab2_lib.baseboard_fab2(sch_1):page81_i186:A6" )
				( attribute "RELATIVE_PROPAGATION_DELAY_SCOPE" "G"
					( Parent
						( matchGroupRef "@crescent_city_bb_fab1_lib.crescent_city_bb_fab1(sch_1):\MG_DDR_FAR_DIMM-CLK0_CLS_DDR_J_CAC-CLKS\" )
					)
					( Status sCSetFlattened )
					( Origin gBackEnd )
				)
				( attribute "RELATIVE_PROPAGATION_DELAY" "0.00 MIL,700.00 MIL"
					( Parent
						( matchGroupRef "@crescent_city_bb_fab1_lib.crescent_city_bb_fab1(sch_1):\MG_DDR_FAR_DIMM-CLK0_CLS_DDR_J_CAC-CLKS\" )
					)
					( Units "uMatchProp" "ns" 1.000000)
					( Status sCSetFlattened )
					( Origin gBackEnd )
				)
				( attribute "RELATIVE_PROPAGATION_DELAY_SCOPE" "G"
					( Parent
						( matchGroupRef "@baseboard_fab2_lib.baseboard_fab2(sch_1):\MG_DDR_FAR_DIMM_CMD_NG_DDR_J_DLL_9\" )
					)
					( Status sCSetFlattened )
					( Origin gBackEnd )
				)
				( attribute "RELATIVE_PROPAGATION_DELAY" "0.00 MIL,25.00 MIL"
					( Parent
						( matchGroupRef "@baseboard_fab2_lib.baseboard_fab2(sch_1):\MG_DDR_FAR_DIMM_CMD_NG_DDR_J_DLL_9\" )
					)
					( Units "uMatchProp" "ns" 1.000000)
					( Status sCSetFlattened )
					( Origin gBackEnd )
				)
			)
			( pinPair "@baseboard_fab2_lib.baseboard_fab2(sch_1):\PP3500\"
				( pinRef "@baseboard_fab2_lib.baseboard_fab2(sch_1):page82_i187:A6" )
				( pinRef "@baseboard_fab2_lib.baseboard_fab2(sch_1):page59_i172:DDR2_MA(6)" )
				( attribute "RELATIVE_PROPAGATION_DELAY_SCOPE" "G"
					( Parent
						( matchGroupRef "@crescent_city_bb_fab1_lib.crescent_city_bb_fab1(sch_1):\MG_DDR_NEAR_DIMM-CLK1_CLS_DDR_J_CAC-CLKS\" )
					)
					( Status sCSetFlattened )
					( Origin gBackEnd )
				)
				( attribute "RELATIVE_PROPAGATION_DELAY" "0.00 MIL,700.00 MIL"
					( Parent
						( matchGroupRef "@crescent_city_bb_fab1_lib.crescent_city_bb_fab1(sch_1):\MG_DDR_NEAR_DIMM-CLK1_CLS_DDR_J_CAC-CLKS\" )
					)
					( Units "uMatchProp" "ns" 1.000000)
					( Status sCSetFlattened )
					( Origin gBackEnd )
				)
				( attribute "RELATIVE_PROPAGATION_DELAY_SCOPE" "G"
					( Parent
						( matchGroupRef "@baseboard_fab2_lib.baseboard_fab2(sch_1):\MG_DDR_CMD_NEAR_DIMM_NG_DDR_J_DLL_9\" )
					)
					( Status sCSetFlattened )
					( Origin gBackEnd )
				)
				( attribute "RELATIVE_PROPAGATION_DELAY" "0.00 MIL,25.00 MIL"
					( Parent
						( matchGroupRef "@baseboard_fab2_lib.baseboard_fab2(sch_1):\MG_DDR_CMD_NEAR_DIMM_NG_DDR_J_DLL_9\" )
					)
					( Units "uMatchProp" "ns" 1.000000)
					( Status sCSetFlattened )
					( Origin gBackEnd )
				)
			)
			( pinPair "@baseboard_fab2_lib.baseboard_fab2(sch_1):\PP3493\"
				( pinRef "@baseboard_fab2_lib.baseboard_fab2(sch_1):page59_i172:DDR2_MA(7)" )
				( pinRef "@baseboard_fab2_lib.baseboard_fab2(sch_1):page81_i186:A7" )
				( attribute "RELATIVE_PROPAGATION_DELAY_SCOPE" "G"
					( Parent
						( matchGroupRef "@crescent_city_bb_fab1_lib.crescent_city_bb_fab1(sch_1):\MG_DDR_FAR_DIMM-CLK0_CLS_DDR_J_CAC-CLKS\" )
					)
					( Status sCSetFlattened )
					( Origin gBackEnd )
				)
				( attribute "RELATIVE_PROPAGATION_DELAY" "0.00 MIL,700.00 MIL"
					( Parent
						( matchGroupRef "@crescent_city_bb_fab1_lib.crescent_city_bb_fab1(sch_1):\MG_DDR_FAR_DIMM-CLK0_CLS_DDR_J_CAC-CLKS\" )
					)
					( Units "uMatchProp" "ns" 1.000000)
					( Status sCSetFlattened )
					( Origin gBackEnd )
				)
				( attribute "RELATIVE_PROPAGATION_DELAY_SCOPE" "G"
					( Parent
						( matchGroupRef "@baseboard_fab2_lib.baseboard_fab2(sch_1):\MG_DDR_FAR_DIMM_CMD_NG_DDR_J_DLL_10\" )
					)
					( Status sCSetFlattened )
					( Origin gBackEnd )
				)
				( attribute "RELATIVE_PROPAGATION_DELAY" "0.00 MIL,25.00 MIL"
					( Parent
						( matchGroupRef "@baseboard_fab2_lib.baseboard_fab2(sch_1):\MG_DDR_FAR_DIMM_CMD_NG_DDR_J_DLL_10\" )
					)
					( Units "uMatchProp" "ns" 1.000000)
					( Status sCSetFlattened )
					( Origin gBackEnd )
				)
			)
			( pinPair "@baseboard_fab2_lib.baseboard_fab2(sch_1):\PP3494\"
				( pinRef "@baseboard_fab2_lib.baseboard_fab2(sch_1):page82_i187:A7" )
				( pinRef "@baseboard_fab2_lib.baseboard_fab2(sch_1):page59_i172:DDR2_MA(7)" )
				( attribute "RELATIVE_PROPAGATION_DELAY_SCOPE" "G"
					( Parent
						( matchGroupRef "@crescent_city_bb_fab1_lib.crescent_city_bb_fab1(sch_1):\MG_DDR_NEAR_DIMM-CLK1_CLS_DDR_J_CAC-CLKS\" )
					)
					( Status sCSetFlattened )
					( Origin gBackEnd )
				)
				( attribute "RELATIVE_PROPAGATION_DELAY" "0.00 MIL,700.00 MIL"
					( Parent
						( matchGroupRef "@crescent_city_bb_fab1_lib.crescent_city_bb_fab1(sch_1):\MG_DDR_NEAR_DIMM-CLK1_CLS_DDR_J_CAC-CLKS\" )
					)
					( Units "uMatchProp" "ns" 1.000000)
					( Status sCSetFlattened )
					( Origin gBackEnd )
				)
				( attribute "RELATIVE_PROPAGATION_DELAY_SCOPE" "G"
					( Parent
						( matchGroupRef "@baseboard_fab2_lib.baseboard_fab2(sch_1):\MG_DDR_CMD_NEAR_DIMM_NG_DDR_J_DLL_10\" )
					)
					( Status sCSetFlattened )
					( Origin gBackEnd )
				)
				( attribute "RELATIVE_PROPAGATION_DELAY" "0.00 MIL,25.00 MIL"
					( Parent
						( matchGroupRef "@baseboard_fab2_lib.baseboard_fab2(sch_1):\MG_DDR_CMD_NEAR_DIMM_NG_DDR_J_DLL_10\" )
					)
					( Units "uMatchProp" "ns" 1.000000)
					( Status sCSetFlattened )
					( Origin gBackEnd )
				)
			)
			( pinPair "@baseboard_fab2_lib.baseboard_fab2(sch_1):\PP3495\"
				( pinRef "@baseboard_fab2_lib.baseboard_fab2(sch_1):page59_i172:DDR2_MA(8)" )
				( pinRef "@baseboard_fab2_lib.baseboard_fab2(sch_1):page81_i186:A8" )
				( attribute "RELATIVE_PROPAGATION_DELAY_SCOPE" "G"
					( Parent
						( matchGroupRef "@crescent_city_bb_fab1_lib.crescent_city_bb_fab1(sch_1):\MG_DDR_FAR_DIMM-CLK0_CLS_DDR_J_CAC-CLKS\" )
					)
					( Status sCSetFlattened )
					( Origin gBackEnd )
				)
				( attribute "RELATIVE_PROPAGATION_DELAY" "0.00 MIL,700.00 MIL"
					( Parent
						( matchGroupRef "@crescent_city_bb_fab1_lib.crescent_city_bb_fab1(sch_1):\MG_DDR_FAR_DIMM-CLK0_CLS_DDR_J_CAC-CLKS\" )
					)
					( Units "uMatchProp" "ns" 1.000000)
					( Status sCSetFlattened )
					( Origin gBackEnd )
				)
				( attribute "RELATIVE_PROPAGATION_DELAY_SCOPE" "G"
					( Parent
						( matchGroupRef "@baseboard_fab2_lib.baseboard_fab2(sch_1):\MG_DDR_FAR_DIMM_CMD_NG_DDR_J_DLL_10\" )
					)
					( Status sCSetFlattened )
					( Origin gBackEnd )
				)
				( attribute "RELATIVE_PROPAGATION_DELAY" "0.00 MIL,25.00 MIL"
					( Parent
						( matchGroupRef "@baseboard_fab2_lib.baseboard_fab2(sch_1):\MG_DDR_FAR_DIMM_CMD_NG_DDR_J_DLL_10\" )
					)
					( Units "uMatchProp" "ns" 1.000000)
					( Status sCSetFlattened )
					( Origin gBackEnd )
				)
			)
			( pinPair "@baseboard_fab2_lib.baseboard_fab2(sch_1):\PP3496\"
				( pinRef "@baseboard_fab2_lib.baseboard_fab2(sch_1):page82_i187:A8" )
				( pinRef "@baseboard_fab2_lib.baseboard_fab2(sch_1):page59_i172:DDR2_MA(8)" )
				( attribute "RELATIVE_PROPAGATION_DELAY_SCOPE" "G"
					( Parent
						( matchGroupRef "@crescent_city_bb_fab1_lib.crescent_city_bb_fab1(sch_1):\MG_DDR_NEAR_DIMM-CLK1_CLS_DDR_J_CAC-CLKS\" )
					)
					( Status sCSetFlattened )
					( Origin gBackEnd )
				)
				( attribute "RELATIVE_PROPAGATION_DELAY" "0.00 MIL,700.00 MIL"
					( Parent
						( matchGroupRef "@crescent_city_bb_fab1_lib.crescent_city_bb_fab1(sch_1):\MG_DDR_NEAR_DIMM-CLK1_CLS_DDR_J_CAC-CLKS\" )
					)
					( Units "uMatchProp" "ns" 1.000000)
					( Status sCSetFlattened )
					( Origin gBackEnd )
				)
				( attribute "RELATIVE_PROPAGATION_DELAY_SCOPE" "G"
					( Parent
						( matchGroupRef "@baseboard_fab2_lib.baseboard_fab2(sch_1):\MG_DDR_CMD_NEAR_DIMM_NG_DDR_J_DLL_10\" )
					)
					( Status sCSetFlattened )
					( Origin gBackEnd )
				)
				( attribute "RELATIVE_PROPAGATION_DELAY" "0.00 MIL,25.00 MIL"
					( Parent
						( matchGroupRef "@baseboard_fab2_lib.baseboard_fab2(sch_1):\MG_DDR_CMD_NEAR_DIMM_NG_DDR_J_DLL_10\" )
					)
					( Units "uMatchProp" "ns" 1.000000)
					( Status sCSetFlattened )
					( Origin gBackEnd )
				)
			)
			( pinPair "@baseboard_fab2_lib.baseboard_fab2(sch_1):\PP3489\"
				( pinRef "@baseboard_fab2_lib.baseboard_fab2(sch_1):page59_i172:DDR2_MA(9)" )
				( pinRef "@baseboard_fab2_lib.baseboard_fab2(sch_1):page81_i186:A9" )
				( attribute "RELATIVE_PROPAGATION_DELAY_SCOPE" "G"
					( Parent
						( matchGroupRef "@crescent_city_bb_fab1_lib.crescent_city_bb_fab1(sch_1):\MG_DDR_FAR_DIMM-CLK0_CLS_DDR_J_CAC-CLKS\" )
					)
					( Status sCSetFlattened )
					( Origin gBackEnd )
				)
				( attribute "RELATIVE_PROPAGATION_DELAY" "0.00 MIL,700.00 MIL"
					( Parent
						( matchGroupRef "@crescent_city_bb_fab1_lib.crescent_city_bb_fab1(sch_1):\MG_DDR_FAR_DIMM-CLK0_CLS_DDR_J_CAC-CLKS\" )
					)
					( Units "uMatchProp" "ns" 1.000000)
					( Status sCSetFlattened )
					( Origin gBackEnd )
				)
				( attribute "RELATIVE_PROPAGATION_DELAY_SCOPE" "G"
					( Parent
						( matchGroupRef "@baseboard_fab2_lib.baseboard_fab2(sch_1):\MG_DDR_FAR_DIMM_CMD_NG_DDR_J_DLL_11\" )
					)
					( Status sCSetFlattened )
					( Origin gBackEnd )
				)
				( attribute "RELATIVE_PROPAGATION_DELAY" "0.00 MIL,25.00 MIL"
					( Parent
						( matchGroupRef "@baseboard_fab2_lib.baseboard_fab2(sch_1):\MG_DDR_FAR_DIMM_CMD_NG_DDR_J_DLL_11\" )
					)
					( Units "uMatchProp" "ns" 1.000000)
					( Status sCSetFlattened )
					( Origin gBackEnd )
				)
			)
			( pinPair "@baseboard_fab2_lib.baseboard_fab2(sch_1):\PP3490\"
				( pinRef "@baseboard_fab2_lib.baseboard_fab2(sch_1):page82_i187:A9" )
				( pinRef "@baseboard_fab2_lib.baseboard_fab2(sch_1):page59_i172:DDR2_MA(9)" )
				( attribute "RELATIVE_PROPAGATION_DELAY_SCOPE" "G"
					( Parent
						( matchGroupRef "@crescent_city_bb_fab1_lib.crescent_city_bb_fab1(sch_1):\MG_DDR_NEAR_DIMM-CLK1_CLS_DDR_J_CAC-CLKS\" )
					)
					( Status sCSetFlattened )
					( Origin gBackEnd )
				)
				( attribute "RELATIVE_PROPAGATION_DELAY" "0.00 MIL,700.00 MIL"
					( Parent
						( matchGroupRef "@crescent_city_bb_fab1_lib.crescent_city_bb_fab1(sch_1):\MG_DDR_NEAR_DIMM-CLK1_CLS_DDR_J_CAC-CLKS\" )
					)
					( Units "uMatchProp" "ns" 1.000000)
					( Status sCSetFlattened )
					( Origin gBackEnd )
				)
				( attribute "RELATIVE_PROPAGATION_DELAY_SCOPE" "G"
					( Parent
						( matchGroupRef "@baseboard_fab2_lib.baseboard_fab2(sch_1):\MG_DDR_CMD_NEAR_DIMM_NG_DDR_J_DLL_11\" )
					)
					( Status sCSetFlattened )
					( Origin gBackEnd )
				)
				( attribute "RELATIVE_PROPAGATION_DELAY" "0.00 MIL,25.00 MIL"
					( Parent
						( matchGroupRef "@baseboard_fab2_lib.baseboard_fab2(sch_1):\MG_DDR_CMD_NEAR_DIMM_NG_DDR_J_DLL_11\" )
					)
					( Units "uMatchProp" "ns" 1.000000)
					( Status sCSetFlattened )
					( Origin gBackEnd )
				)
			)
			( pinPair "@baseboard_fab2_lib.baseboard_fab2(sch_1):\PP3491\"
				( pinRef "@baseboard_fab2_lib.baseboard_fab2(sch_1):page59_i172:DDR2_MA(12)" )
				( pinRef "@baseboard_fab2_lib.baseboard_fab2(sch_1):page81_i186:A12" )
				( attribute "RELATIVE_PROPAGATION_DELAY_SCOPE" "G"
					( Parent
						( matchGroupRef "@crescent_city_bb_fab1_lib.crescent_city_bb_fab1(sch_1):\MG_DDR_FAR_DIMM-CLK0_CLS_DDR_J_CAC-CLKS\" )
					)
					( Status sCSetFlattened )
					( Origin gBackEnd )
				)
				( attribute "RELATIVE_PROPAGATION_DELAY" "0.00 MIL,700.00 MIL"
					( Parent
						( matchGroupRef "@crescent_city_bb_fab1_lib.crescent_city_bb_fab1(sch_1):\MG_DDR_FAR_DIMM-CLK0_CLS_DDR_J_CAC-CLKS\" )
					)
					( Units "uMatchProp" "ns" 1.000000)
					( Status sCSetFlattened )
					( Origin gBackEnd )
				)
				( attribute "RELATIVE_PROPAGATION_DELAY_SCOPE" "G"
					( Parent
						( matchGroupRef "@baseboard_fab2_lib.baseboard_fab2(sch_1):\MG_DDR_FAR_DIMM_CMD_NG_DDR_J_DLL_11\" )
					)
					( Status sCSetFlattened )
					( Origin gBackEnd )
				)
				( attribute "RELATIVE_PROPAGATION_DELAY" "0.00 MIL,25.00 MIL"
					( Parent
						( matchGroupRef "@baseboard_fab2_lib.baseboard_fab2(sch_1):\MG_DDR_FAR_DIMM_CMD_NG_DDR_J_DLL_11\" )
					)
					( Units "uMatchProp" "ns" 1.000000)
					( Status sCSetFlattened )
					( Origin gBackEnd )
				)
			)
			( pinPair "@baseboard_fab2_lib.baseboard_fab2(sch_1):\PP3492\"
				( pinRef "@baseboard_fab2_lib.baseboard_fab2(sch_1):page82_i187:A12" )
				( pinRef "@baseboard_fab2_lib.baseboard_fab2(sch_1):page59_i172:DDR2_MA(12)" )
				( attribute "RELATIVE_PROPAGATION_DELAY_SCOPE" "G"
					( Parent
						( matchGroupRef "@crescent_city_bb_fab1_lib.crescent_city_bb_fab1(sch_1):\MG_DDR_NEAR_DIMM-CLK1_CLS_DDR_J_CAC-CLKS\" )
					)
					( Status sCSetFlattened )
					( Origin gBackEnd )
				)
				( attribute "RELATIVE_PROPAGATION_DELAY" "0.00 MIL,700.00 MIL"
					( Parent
						( matchGroupRef "@crescent_city_bb_fab1_lib.crescent_city_bb_fab1(sch_1):\MG_DDR_NEAR_DIMM-CLK1_CLS_DDR_J_CAC-CLKS\" )
					)
					( Units "uMatchProp" "ns" 1.000000)
					( Status sCSetFlattened )
					( Origin gBackEnd )
				)
				( attribute "RELATIVE_PROPAGATION_DELAY_SCOPE" "G"
					( Parent
						( matchGroupRef "@baseboard_fab2_lib.baseboard_fab2(sch_1):\MG_DDR_CMD_NEAR_DIMM_NG_DDR_J_DLL_11\" )
					)
					( Status sCSetFlattened )
					( Origin gBackEnd )
				)
				( attribute "RELATIVE_PROPAGATION_DELAY" "0.00 MIL,25.00 MIL"
					( Parent
						( matchGroupRef "@baseboard_fab2_lib.baseboard_fab2(sch_1):\MG_DDR_CMD_NEAR_DIMM_NG_DDR_J_DLL_11\" )
					)
					( Units "uMatchProp" "ns" 1.000000)
					( Status sCSetFlattened )
					( Origin gBackEnd )
				)
			)
			( pinPair "@baseboard_fab2_lib.baseboard_fab2(sch_1):\PP3485\"
				( pinRef "@baseboard_fab2_lib.baseboard_fab2(sch_1):page59_i172:DDR2_BG(1)" )
				( pinRef "@baseboard_fab2_lib.baseboard_fab2(sch_1):page81_i186:BG(1)" )
				( attribute "RELATIVE_PROPAGATION_DELAY_SCOPE" "G"
					( Parent
						( matchGroupRef "@crescent_city_bb_fab1_lib.crescent_city_bb_fab1(sch_1):\MG_DDR_FAR_DIMM-CLK0_CLS_DDR_J_CAC-CLKS\" )
					)
					( Status sCSetFlattened )
					( Origin gBackEnd )
				)
				( attribute "RELATIVE_PROPAGATION_DELAY" "0.00 MIL,700.00 MIL"
					( Parent
						( matchGroupRef "@crescent_city_bb_fab1_lib.crescent_city_bb_fab1(sch_1):\MG_DDR_FAR_DIMM-CLK0_CLS_DDR_J_CAC-CLKS\" )
					)
					( Units "uMatchProp" "ns" 1.000000)
					( Status sCSetFlattened )
					( Origin gBackEnd )
				)
				( attribute "RELATIVE_PROPAGATION_DELAY_SCOPE" "G"
					( Parent
						( matchGroupRef "@baseboard_fab2_lib.baseboard_fab2(sch_1):\MG_DDR_FAR_DIMM_CMD_NG_DDR_J_DLL_12\" )
					)
					( Status sCSetFlattened )
					( Origin gBackEnd )
				)
				( attribute "RELATIVE_PROPAGATION_DELAY" "0.00 MIL,25.00 MIL"
					( Parent
						( matchGroupRef "@baseboard_fab2_lib.baseboard_fab2(sch_1):\MG_DDR_FAR_DIMM_CMD_NG_DDR_J_DLL_12\" )
					)
					( Units "uMatchProp" "ns" 1.000000)
					( Status sCSetFlattened )
					( Origin gBackEnd )
				)
			)
			( pinPair "@baseboard_fab2_lib.baseboard_fab2(sch_1):\PP3486\"
				( pinRef "@baseboard_fab2_lib.baseboard_fab2(sch_1):page82_i187:BG(1)" )
				( pinRef "@baseboard_fab2_lib.baseboard_fab2(sch_1):page59_i172:DDR2_BG(1)" )
				( attribute "RELATIVE_PROPAGATION_DELAY_SCOPE" "G"
					( Parent
						( matchGroupRef "@crescent_city_bb_fab1_lib.crescent_city_bb_fab1(sch_1):\MG_DDR_NEAR_DIMM-CLK1_CLS_DDR_J_CAC-CLKS\" )
					)
					( Status sCSetFlattened )
					( Origin gBackEnd )
				)
				( attribute "RELATIVE_PROPAGATION_DELAY" "0.00 MIL,700.00 MIL"
					( Parent
						( matchGroupRef "@crescent_city_bb_fab1_lib.crescent_city_bb_fab1(sch_1):\MG_DDR_NEAR_DIMM-CLK1_CLS_DDR_J_CAC-CLKS\" )
					)
					( Units "uMatchProp" "ns" 1.000000)
					( Status sCSetFlattened )
					( Origin gBackEnd )
				)
				( attribute "RELATIVE_PROPAGATION_DELAY_SCOPE" "G"
					( Parent
						( matchGroupRef "@baseboard_fab2_lib.baseboard_fab2(sch_1):\MG_DDR_CMD_NEAR_DIMM_NG_DDR_J_DLL_12\" )
					)
					( Status sCSetFlattened )
					( Origin gBackEnd )
				)
				( attribute "RELATIVE_PROPAGATION_DELAY" "0.00 MIL,25.00 MIL"
					( Parent
						( matchGroupRef "@baseboard_fab2_lib.baseboard_fab2(sch_1):\MG_DDR_CMD_NEAR_DIMM_NG_DDR_J_DLL_12\" )
					)
					( Units "uMatchProp" "ns" 1.000000)
					( Status sCSetFlattened )
					( Origin gBackEnd )
				)
			)
			( pinPair "@baseboard_fab2_lib.baseboard_fab2(sch_1):\PP3487\"
				( pinRef "@baseboard_fab2_lib.baseboard_fab2(sch_1):page59_i172:DDR2_MA(11)" )
				( pinRef "@baseboard_fab2_lib.baseboard_fab2(sch_1):page81_i186:A11" )
				( attribute "RELATIVE_PROPAGATION_DELAY_SCOPE" "G"
					( Parent
						( matchGroupRef "@crescent_city_bb_fab1_lib.crescent_city_bb_fab1(sch_1):\MG_DDR_FAR_DIMM-CLK0_CLS_DDR_J_CAC-CLKS\" )
					)
					( Status sCSetFlattened )
					( Origin gBackEnd )
				)
				( attribute "RELATIVE_PROPAGATION_DELAY" "0.00 MIL,700.00 MIL"
					( Parent
						( matchGroupRef "@crescent_city_bb_fab1_lib.crescent_city_bb_fab1(sch_1):\MG_DDR_FAR_DIMM-CLK0_CLS_DDR_J_CAC-CLKS\" )
					)
					( Units "uMatchProp" "ns" 1.000000)
					( Status sCSetFlattened )
					( Origin gBackEnd )
				)
				( attribute "RELATIVE_PROPAGATION_DELAY_SCOPE" "G"
					( Parent
						( matchGroupRef "@baseboard_fab2_lib.baseboard_fab2(sch_1):\MG_DDR_FAR_DIMM_CMD_NG_DDR_J_DLL_12\" )
					)
					( Status sCSetFlattened )
					( Origin gBackEnd )
				)
				( attribute "RELATIVE_PROPAGATION_DELAY" "0.00 MIL,25.00 MIL"
					( Parent
						( matchGroupRef "@baseboard_fab2_lib.baseboard_fab2(sch_1):\MG_DDR_FAR_DIMM_CMD_NG_DDR_J_DLL_12\" )
					)
					( Units "uMatchProp" "ns" 1.000000)
					( Status sCSetFlattened )
					( Origin gBackEnd )
				)
			)
			( pinPair "@baseboard_fab2_lib.baseboard_fab2(sch_1):\PP3488\"
				( pinRef "@baseboard_fab2_lib.baseboard_fab2(sch_1):page82_i187:A11" )
				( pinRef "@baseboard_fab2_lib.baseboard_fab2(sch_1):page59_i172:DDR2_MA(11)" )
				( attribute "RELATIVE_PROPAGATION_DELAY_SCOPE" "G"
					( Parent
						( matchGroupRef "@crescent_city_bb_fab1_lib.crescent_city_bb_fab1(sch_1):\MG_DDR_NEAR_DIMM-CLK1_CLS_DDR_J_CAC-CLKS\" )
					)
					( Status sCSetFlattened )
					( Origin gBackEnd )
				)
				( attribute "RELATIVE_PROPAGATION_DELAY" "0.00 MIL,700.00 MIL"
					( Parent
						( matchGroupRef "@crescent_city_bb_fab1_lib.crescent_city_bb_fab1(sch_1):\MG_DDR_NEAR_DIMM-CLK1_CLS_DDR_J_CAC-CLKS\" )
					)
					( Units "uMatchProp" "ns" 1.000000)
					( Status sCSetFlattened )
					( Origin gBackEnd )
				)
				( attribute "RELATIVE_PROPAGATION_DELAY_SCOPE" "G"
					( Parent
						( matchGroupRef "@baseboard_fab2_lib.baseboard_fab2(sch_1):\MG_DDR_CMD_NEAR_DIMM_NG_DDR_J_DLL_12\" )
					)
					( Status sCSetFlattened )
					( Origin gBackEnd )
				)
				( attribute "RELATIVE_PROPAGATION_DELAY" "0.00 MIL,25.00 MIL"
					( Parent
						( matchGroupRef "@baseboard_fab2_lib.baseboard_fab2(sch_1):\MG_DDR_CMD_NEAR_DIMM_NG_DDR_J_DLL_12\" )
					)
					( Units "uMatchProp" "ns" 1.000000)
					( Status sCSetFlattened )
					( Origin gBackEnd )
				)
			)
			( pinPair "@baseboard_fab2_lib.baseboard_fab2(sch_1):\PP3481\"
				( pinRef "@baseboard_fab2_lib.baseboard_fab2(sch_1):page59_i172:DDR2_ACT_N" )
				( pinRef "@baseboard_fab2_lib.baseboard_fab2(sch_1):page81_i186:ACT_N" )
				( attribute "RELATIVE_PROPAGATION_DELAY_SCOPE" "G"
					( Parent
						( matchGroupRef "@crescent_city_bb_fab1_lib.crescent_city_bb_fab1(sch_1):\MG_DDR_FAR_DIMM-CLK0_CLS_DDR_J_CAC-CLKS\" )
					)
					( Status sCSetFlattened )
					( Origin gBackEnd )
				)
				( attribute "RELATIVE_PROPAGATION_DELAY" "0.00 MIL,700.00 MIL"
					( Parent
						( matchGroupRef "@crescent_city_bb_fab1_lib.crescent_city_bb_fab1(sch_1):\MG_DDR_FAR_DIMM-CLK0_CLS_DDR_J_CAC-CLKS\" )
					)
					( Units "uMatchProp" "ns" 1.000000)
					( Status sCSetFlattened )
					( Origin gBackEnd )
				)
				( attribute "RELATIVE_PROPAGATION_DELAY_SCOPE" "G"
					( Parent
						( matchGroupRef "@baseboard_fab2_lib.baseboard_fab2(sch_1):\MG_DDR_FAR_DIMM_CMD_NG_DDR_J_DLL_13\" )
					)
					( Status sCSetFlattened )
					( Origin gBackEnd )
				)
				( attribute "RELATIVE_PROPAGATION_DELAY" "0.00 MIL,25.00 MIL"
					( Parent
						( matchGroupRef "@baseboard_fab2_lib.baseboard_fab2(sch_1):\MG_DDR_FAR_DIMM_CMD_NG_DDR_J_DLL_13\" )
					)
					( Units "uMatchProp" "ns" 1.000000)
					( Status sCSetFlattened )
					( Origin gBackEnd )
				)
			)
			( pinPair "@baseboard_fab2_lib.baseboard_fab2(sch_1):\PP3482\"
				( pinRef "@baseboard_fab2_lib.baseboard_fab2(sch_1):page59_i172:DDR2_ACT_N" )
				( pinRef "@baseboard_fab2_lib.baseboard_fab2(sch_1):page82_i187:ACT_N" )
				( attribute "RELATIVE_PROPAGATION_DELAY_SCOPE" "G"
					( Parent
						( matchGroupRef "@crescent_city_bb_fab1_lib.crescent_city_bb_fab1(sch_1):\MG_DDR_NEAR_DIMM-CLK1_CLS_DDR_J_CAC-CLKS\" )
					)
					( Status sCSetFlattened )
					( Origin gBackEnd )
				)
				( attribute "RELATIVE_PROPAGATION_DELAY" "0.00 MIL,700.00 MIL"
					( Parent
						( matchGroupRef "@crescent_city_bb_fab1_lib.crescent_city_bb_fab1(sch_1):\MG_DDR_NEAR_DIMM-CLK1_CLS_DDR_J_CAC-CLKS\" )
					)
					( Units "uMatchProp" "ns" 1.000000)
					( Status sCSetFlattened )
					( Origin gBackEnd )
				)
				( attribute "RELATIVE_PROPAGATION_DELAY_SCOPE" "G"
					( Parent
						( matchGroupRef "@baseboard_fab2_lib.baseboard_fab2(sch_1):\MG_DDR_CMD_NEAR_DIMM_NG_DDR_J_DLL_13\" )
					)
					( Status sCSetFlattened )
					( Origin gBackEnd )
				)
				( attribute "RELATIVE_PROPAGATION_DELAY" "0.00 MIL,25.00 MIL"
					( Parent
						( matchGroupRef "@baseboard_fab2_lib.baseboard_fab2(sch_1):\MG_DDR_CMD_NEAR_DIMM_NG_DDR_J_DLL_13\" )
					)
					( Units "uMatchProp" "ns" 1.000000)
					( Status sCSetFlattened )
					( Origin gBackEnd )
				)
			)
			( pinPair "@baseboard_fab2_lib.baseboard_fab2(sch_1):\PP3483\"
				( pinRef "@baseboard_fab2_lib.baseboard_fab2(sch_1):page59_i172:DDR2_BG(0)" )
				( pinRef "@baseboard_fab2_lib.baseboard_fab2(sch_1):page81_i186:BG(0)" )
				( attribute "RELATIVE_PROPAGATION_DELAY_SCOPE" "G"
					( Parent
						( matchGroupRef "@crescent_city_bb_fab1_lib.crescent_city_bb_fab1(sch_1):\MG_DDR_FAR_DIMM-CLK0_CLS_DDR_J_CAC-CLKS\" )
					)
					( Status sCSetFlattened )
					( Origin gBackEnd )
				)
				( attribute "RELATIVE_PROPAGATION_DELAY" "0.00 MIL,700.00 MIL"
					( Parent
						( matchGroupRef "@crescent_city_bb_fab1_lib.crescent_city_bb_fab1(sch_1):\MG_DDR_FAR_DIMM-CLK0_CLS_DDR_J_CAC-CLKS\" )
					)
					( Units "uMatchProp" "ns" 1.000000)
					( Status sCSetFlattened )
					( Origin gBackEnd )
				)
				( attribute "RELATIVE_PROPAGATION_DELAY_SCOPE" "G"
					( Parent
						( matchGroupRef "@baseboard_fab2_lib.baseboard_fab2(sch_1):\MG_DDR_FAR_DIMM_CMD_NG_DDR_J_DLL_13\" )
					)
					( Status sCSetFlattened )
					( Origin gBackEnd )
				)
				( attribute "RELATIVE_PROPAGATION_DELAY" "0.00 MIL,25.00 MIL"
					( Parent
						( matchGroupRef "@baseboard_fab2_lib.baseboard_fab2(sch_1):\MG_DDR_FAR_DIMM_CMD_NG_DDR_J_DLL_13\" )
					)
					( Units "uMatchProp" "ns" 1.000000)
					( Status sCSetFlattened )
					( Origin gBackEnd )
				)
			)
			( pinPair "@baseboard_fab2_lib.baseboard_fab2(sch_1):\PP3484\"
				( pinRef "@baseboard_fab2_lib.baseboard_fab2(sch_1):page82_i187:BG(0)" )
				( pinRef "@baseboard_fab2_lib.baseboard_fab2(sch_1):page59_i172:DDR2_BG(0)" )
				( attribute "RELATIVE_PROPAGATION_DELAY_SCOPE" "G"
					( Parent
						( matchGroupRef "@crescent_city_bb_fab1_lib.crescent_city_bb_fab1(sch_1):\MG_DDR_NEAR_DIMM-CLK1_CLS_DDR_J_CAC-CLKS\" )
					)
					( Status sCSetFlattened )
					( Origin gBackEnd )
				)
				( attribute "RELATIVE_PROPAGATION_DELAY" "0.00 MIL,700.00 MIL"
					( Parent
						( matchGroupRef "@crescent_city_bb_fab1_lib.crescent_city_bb_fab1(sch_1):\MG_DDR_NEAR_DIMM-CLK1_CLS_DDR_J_CAC-CLKS\" )
					)
					( Units "uMatchProp" "ns" 1.000000)
					( Status sCSetFlattened )
					( Origin gBackEnd )
				)
				( attribute "RELATIVE_PROPAGATION_DELAY_SCOPE" "G"
					( Parent
						( matchGroupRef "@baseboard_fab2_lib.baseboard_fab2(sch_1):\MG_DDR_CMD_NEAR_DIMM_NG_DDR_J_DLL_13\" )
					)
					( Status sCSetFlattened )
					( Origin gBackEnd )
				)
				( attribute "RELATIVE_PROPAGATION_DELAY" "0.00 MIL,25.00 MIL"
					( Parent
						( matchGroupRef "@baseboard_fab2_lib.baseboard_fab2(sch_1):\MG_DDR_CMD_NEAR_DIMM_NG_DDR_J_DLL_13\" )
					)
					( Units "uMatchProp" "ns" 1.000000)
					( Status sCSetFlattened )
					( Origin gBackEnd )
				)
			)
			( pinPair "@baseboard_fab2_lib.baseboard_fab2(sch_1):\PP3479\"
				( pinRef "@baseboard_fab2_lib.baseboard_fab2(sch_1):page81_i186:S0_N" )
				( pinRef "@baseboard_fab2_lib.baseboard_fab2(sch_1):page59_i172:DDR2_CS_N(0)" )
				( attribute "RELATIVE_PROPAGATION_DELAY_SCOPE" "G"
					( Parent
						( matchGroupRef "@crescent_city_bb_fab1_lib.crescent_city_bb_fab1(sch_1):\MG_DDR_FAR_DIMM-CLK0_CLS_DDR_J_CAC-CLKS\" )
					)
					( Status sCSetFlattened )
					( Origin gBackEnd )
				)
				( attribute "RELATIVE_PROPAGATION_DELAY" "0.00 MIL,300.00 MIL"
					( Parent
						( matchGroupRef "@crescent_city_bb_fab1_lib.crescent_city_bb_fab1(sch_1):\MG_DDR_FAR_DIMM-CLK0_CLS_DDR_J_CAC-CLKS\" )
					)
					( Units "uMatchProp" "ns" 1.000000)
					( Status sCSetFlattened )
					( Origin gBackEnd )
				)
				( attribute "RELATIVE_PROPAGATION_DELAY_SCOPE" "G"
					( Parent
						( matchGroupRef "@baseboard_fab2_lib.baseboard_fab2(sch_1):\MG_DDR_CTRL_NG_DDR_J_DLL_14\" )
					)
					( Status sCSetFlattened )
					( Origin gBackEnd )
				)
				( attribute "RELATIVE_PROPAGATION_DELAY" "0.00 MIL,25.00 MIL"
					( Parent
						( matchGroupRef "@baseboard_fab2_lib.baseboard_fab2(sch_1):\MG_DDR_CTRL_NG_DDR_J_DLL_14\" )
					)
					( Units "uMatchProp" "ns" 1.000000)
					( Status sCSetFlattened )
					( Origin gBackEnd )
				)
			)
			( pinPair "@baseboard_fab2_lib.baseboard_fab2(sch_1):\PP3480\"
				( pinRef "@baseboard_fab2_lib.baseboard_fab2(sch_1):page81_i186:ODT(0)" )
				( pinRef "@baseboard_fab2_lib.baseboard_fab2(sch_1):page59_i172:DDR2_ODT(0)" )
				( attribute "RELATIVE_PROPAGATION_DELAY_SCOPE" "G"
					( Parent
						( matchGroupRef "@crescent_city_bb_fab1_lib.crescent_city_bb_fab1(sch_1):\MG_DDR_FAR_DIMM-CLK0_CLS_DDR_J_CAC-CLKS\" )
					)
					( Status sCSetFlattened )
					( Origin gBackEnd )
				)
				( attribute "RELATIVE_PROPAGATION_DELAY" "0.00 MIL,300.00 MIL"
					( Parent
						( matchGroupRef "@crescent_city_bb_fab1_lib.crescent_city_bb_fab1(sch_1):\MG_DDR_FAR_DIMM-CLK0_CLS_DDR_J_CAC-CLKS\" )
					)
					( Units "uMatchProp" "ns" 1.000000)
					( Status sCSetFlattened )
					( Origin gBackEnd )
				)
				( attribute "RELATIVE_PROPAGATION_DELAY_SCOPE" "G"
					( Parent
						( matchGroupRef "@baseboard_fab2_lib.baseboard_fab2(sch_1):\MG_DDR_CTRL_NG_DDR_J_DLL_14\" )
					)
					( Status sCSetFlattened )
					( Origin gBackEnd )
				)
				( attribute "RELATIVE_PROPAGATION_DELAY" "0.00 MIL,25.00 MIL"
					( Parent
						( matchGroupRef "@baseboard_fab2_lib.baseboard_fab2(sch_1):\MG_DDR_CTRL_NG_DDR_J_DLL_14\" )
					)
					( Units "uMatchProp" "ns" 1.000000)
					( Status sCSetFlattened )
					( Origin gBackEnd )
				)
			)
			( pinPair "@baseboard_fab2_lib.baseboard_fab2(sch_1):\PP3478\"
				( pinRef "@baseboard_fab2_lib.baseboard_fab2(sch_1):page81_i186:CKE(0)" )
				( pinRef "@baseboard_fab2_lib.baseboard_fab2(sch_1):page59_i172:DDR2_CKE(0)" )
				( attribute "RELATIVE_PROPAGATION_DELAY_SCOPE" "G"
					( Parent
						( matchGroupRef "@crescent_city_bb_fab1_lib.crescent_city_bb_fab1(sch_1):\MG_DDR_FAR_DIMM-CLK0_CLS_DDR_J_CAC-CLKS\" )
					)
					( Status sCSetFlattened )
					( Origin gBackEnd )
				)
				( attribute "RELATIVE_PROPAGATION_DELAY" "0.00 MIL,300.00 MIL"
					( Parent
						( matchGroupRef "@crescent_city_bb_fab1_lib.crescent_city_bb_fab1(sch_1):\MG_DDR_FAR_DIMM-CLK0_CLS_DDR_J_CAC-CLKS\" )
					)
					( Units "uMatchProp" "ns" 1.000000)
					( Status sCSetFlattened )
					( Origin gBackEnd )
				)
				( attribute "RELATIVE_PROPAGATION_DELAY_SCOPE" "G"
					( Parent
						( matchGroupRef "@baseboard_fab2_lib.baseboard_fab2(sch_1):\MG_DDR_CTRL_NG_DDR_J_DLL_15\" )
					)
					( Status sCSetFlattened )
					( Origin gBackEnd )
				)
				( attribute "RELATIVE_PROPAGATION_DELAY" "0.00 MIL,25.00 MIL"
					( Parent
						( matchGroupRef "@baseboard_fab2_lib.baseboard_fab2(sch_1):\MG_DDR_CTRL_NG_DDR_J_DLL_15\" )
					)
					( Units "uMatchProp" "ns" 1.000000)
					( Status sCSetFlattened )
					( Origin gBackEnd )
				)
			)
			( pinPair "@baseboard_fab2_lib.baseboard_fab2(sch_1):\PP3477\"
				( pinRef "@baseboard_fab2_lib.baseboard_fab2(sch_1):page81_i186:S2_N_C(0)" )
				( pinRef "@baseboard_fab2_lib.baseboard_fab2(sch_1):page59_i172:DDR2_CS_N(2)" )
				( attribute "RELATIVE_PROPAGATION_DELAY_SCOPE" "G"
					( Parent
						( matchGroupRef "@crescent_city_bb_fab1_lib.crescent_city_bb_fab1(sch_1):\MG_DDR_FAR_DIMM-CLK0_CLS_DDR_J_CAC-CLKS\" )
					)
					( Status sCSetFlattened )
					( Origin gBackEnd )
				)
				( attribute "RELATIVE_PROPAGATION_DELAY" "0.00 MIL,300.00 MIL"
					( Parent
						( matchGroupRef "@crescent_city_bb_fab1_lib.crescent_city_bb_fab1(sch_1):\MG_DDR_FAR_DIMM-CLK0_CLS_DDR_J_CAC-CLKS\" )
					)
					( Units "uMatchProp" "ns" 1.000000)
					( Status sCSetFlattened )
					( Origin gBackEnd )
				)
				( attribute "RELATIVE_PROPAGATION_DELAY_SCOPE" "G"
					( Parent
						( matchGroupRef "@baseboard_fab2_lib.baseboard_fab2(sch_1):\MG_DDR_CTRL_NG_DDR_J_DLL_16\" )
					)
					( Status sCSetFlattened )
					( Origin gBackEnd )
				)
				( attribute "RELATIVE_PROPAGATION_DELAY" "0.00 MIL,25.00 MIL"
					( Parent
						( matchGroupRef "@baseboard_fab2_lib.baseboard_fab2(sch_1):\MG_DDR_CTRL_NG_DDR_J_DLL_16\" )
					)
					( Units "uMatchProp" "ns" 1.000000)
					( Status sCSetFlattened )
					( Origin gBackEnd )
				)
			)
			( pinPair "@baseboard_fab2_lib.baseboard_fab2(sch_1):\PP3476\"
				( pinRef "@baseboard_fab2_lib.baseboard_fab2(sch_1):page81_i186:S3_N_C(1)" )
				( pinRef "@baseboard_fab2_lib.baseboard_fab2(sch_1):page59_i172:DDR2_CS_N(3)" )
				( attribute "RELATIVE_PROPAGATION_DELAY_SCOPE" "G"
					( Parent
						( matchGroupRef "@crescent_city_bb_fab1_lib.crescent_city_bb_fab1(sch_1):\MG_DDR_FAR_DIMM-CLK0_CLS_DDR_J_CAC-CLKS\" )
					)
					( Status sCSetFlattened )
					( Origin gBackEnd )
				)
				( attribute "RELATIVE_PROPAGATION_DELAY" "0.00 MIL,300.00 MIL"
					( Parent
						( matchGroupRef "@crescent_city_bb_fab1_lib.crescent_city_bb_fab1(sch_1):\MG_DDR_FAR_DIMM-CLK0_CLS_DDR_J_CAC-CLKS\" )
					)
					( Units "uMatchProp" "ns" 1.000000)
					( Status sCSetFlattened )
					( Origin gBackEnd )
				)
				( attribute "RELATIVE_PROPAGATION_DELAY_SCOPE" "G"
					( Parent
						( matchGroupRef "@baseboard_fab2_lib.baseboard_fab2(sch_1):\MG_DDR_CTRL_NG_DDR_J_DLL_17\" )
					)
					( Status sCSetFlattened )
					( Origin gBackEnd )
				)
				( attribute "RELATIVE_PROPAGATION_DELAY" "0.00 MIL,25.00 MIL"
					( Parent
						( matchGroupRef "@baseboard_fab2_lib.baseboard_fab2(sch_1):\MG_DDR_CTRL_NG_DDR_J_DLL_17\" )
					)
					( Units "uMatchProp" "ns" 1.000000)
					( Status sCSetFlattened )
					( Origin gBackEnd )
				)
			)
			( pinPair "@baseboard_fab2_lib.baseboard_fab2(sch_1):\PP3474\"
				( pinRef "@baseboard_fab2_lib.baseboard_fab2(sch_1):page81_i186:S1_N" )
				( pinRef "@baseboard_fab2_lib.baseboard_fab2(sch_1):page59_i172:DDR2_CS_N(1)" )
				( attribute "RELATIVE_PROPAGATION_DELAY_SCOPE" "G"
					( Parent
						( matchGroupRef "@crescent_city_bb_fab1_lib.crescent_city_bb_fab1(sch_1):\MG_DDR_FAR_DIMM-CLK0_CLS_DDR_J_CAC-CLKS\" )
					)
					( Status sCSetFlattened )
					( Origin gBackEnd )
				)
				( attribute "RELATIVE_PROPAGATION_DELAY" "0.00 MIL,300.00 MIL"
					( Parent
						( matchGroupRef "@crescent_city_bb_fab1_lib.crescent_city_bb_fab1(sch_1):\MG_DDR_FAR_DIMM-CLK0_CLS_DDR_J_CAC-CLKS\" )
					)
					( Units "uMatchProp" "ns" 1.000000)
					( Status sCSetFlattened )
					( Origin gBackEnd )
				)
				( attribute "RELATIVE_PROPAGATION_DELAY_SCOPE" "G"
					( Parent
						( matchGroupRef "@baseboard_fab2_lib.baseboard_fab2(sch_1):\MG_DDR_CTRL_NG_DDR_J_DLL_18\" )
					)
					( Status sCSetFlattened )
					( Origin gBackEnd )
				)
				( attribute "RELATIVE_PROPAGATION_DELAY" "0.00 MIL,25.00 MIL"
					( Parent
						( matchGroupRef "@baseboard_fab2_lib.baseboard_fab2(sch_1):\MG_DDR_CTRL_NG_DDR_J_DLL_18\" )
					)
					( Units "uMatchProp" "ns" 1.000000)
					( Status sCSetFlattened )
					( Origin gBackEnd )
				)
			)
			( pinPair "@baseboard_fab2_lib.baseboard_fab2(sch_1):\PP3475\"
				( pinRef "@baseboard_fab2_lib.baseboard_fab2(sch_1):page81_i186:ODT(1)" )
				( pinRef "@baseboard_fab2_lib.baseboard_fab2(sch_1):page59_i172:DDR2_ODT(1)" )
				( attribute "RELATIVE_PROPAGATION_DELAY_SCOPE" "G"
					( Parent
						( matchGroupRef "@crescent_city_bb_fab1_lib.crescent_city_bb_fab1(sch_1):\MG_DDR_FAR_DIMM-CLK0_CLS_DDR_J_CAC-CLKS\" )
					)
					( Status sCSetFlattened )
					( Origin gBackEnd )
				)
				( attribute "RELATIVE_PROPAGATION_DELAY" "0.00 MIL,300.00 MIL"
					( Parent
						( matchGroupRef "@crescent_city_bb_fab1_lib.crescent_city_bb_fab1(sch_1):\MG_DDR_FAR_DIMM-CLK0_CLS_DDR_J_CAC-CLKS\" )
					)
					( Units "uMatchProp" "ns" 1.000000)
					( Status sCSetFlattened )
					( Origin gBackEnd )
				)
				( attribute "RELATIVE_PROPAGATION_DELAY_SCOPE" "G"
					( Parent
						( matchGroupRef "@baseboard_fab2_lib.baseboard_fab2(sch_1):\MG_DDR_CTRL_NG_DDR_J_DLL_18\" )
					)
					( Status sCSetFlattened )
					( Origin gBackEnd )
				)
				( attribute "RELATIVE_PROPAGATION_DELAY" "0.00 MIL,25.00 MIL"
					( Parent
						( matchGroupRef "@baseboard_fab2_lib.baseboard_fab2(sch_1):\MG_DDR_CTRL_NG_DDR_J_DLL_18\" )
					)
					( Units "uMatchProp" "ns" 1.000000)
					( Status sCSetFlattened )
					( Origin gBackEnd )
				)
			)
			( pinPair "@baseboard_fab2_lib.baseboard_fab2(sch_1):\PP3473\"
				( pinRef "@baseboard_fab2_lib.baseboard_fab2(sch_1):page81_i186:CKE(1)" )
				( pinRef "@baseboard_fab2_lib.baseboard_fab2(sch_1):page59_i172:DDR2_CKE(1)" )
				( attribute "RELATIVE_PROPAGATION_DELAY_SCOPE" "G"
					( Parent
						( matchGroupRef "@crescent_city_bb_fab1_lib.crescent_city_bb_fab1(sch_1):\MG_DDR_FAR_DIMM-CLK0_CLS_DDR_J_CAC-CLKS\" )
					)
					( Status sCSetFlattened )
					( Origin gBackEnd )
				)
				( attribute "RELATIVE_PROPAGATION_DELAY" "0.00 MIL,300.00 MIL"
					( Parent
						( matchGroupRef "@crescent_city_bb_fab1_lib.crescent_city_bb_fab1(sch_1):\MG_DDR_FAR_DIMM-CLK0_CLS_DDR_J_CAC-CLKS\" )
					)
					( Units "uMatchProp" "ns" 1.000000)
					( Status sCSetFlattened )
					( Origin gBackEnd )
				)
				( attribute "RELATIVE_PROPAGATION_DELAY_SCOPE" "G"
					( Parent
						( matchGroupRef "@baseboard_fab2_lib.baseboard_fab2(sch_1):\MG_DDR_CTRL_NG_DDR_J_DLL_19\" )
					)
					( Status sCSetFlattened )
					( Origin gBackEnd )
				)
				( attribute "RELATIVE_PROPAGATION_DELAY" "0.00 MIL,25.00 MIL"
					( Parent
						( matchGroupRef "@baseboard_fab2_lib.baseboard_fab2(sch_1):\MG_DDR_CTRL_NG_DDR_J_DLL_19\" )
					)
					( Units "uMatchProp" "ns" 1.000000)
					( Status sCSetFlattened )
					( Origin gBackEnd )
				)
			)
			( pinPair "@baseboard_fab2_lib.baseboard_fab2(sch_1):\PP3471\"
				( pinRef "@baseboard_fab2_lib.baseboard_fab2(sch_1):page59_i172:DDR2_CS_N(4)" )
				( pinRef "@baseboard_fab2_lib.baseboard_fab2(sch_1):page82_i187:S0_N" )
				( attribute "RELATIVE_PROPAGATION_DELAY_SCOPE" "G"
					( Parent
						( matchGroupRef "@crescent_city_bb_fab1_lib.crescent_city_bb_fab1(sch_1):\MG_DDR_NEAR_DIMM-CLK1_CLS_DDR_J_CAC-CLKS\" )
					)
					( Status sCSetFlattened )
					( Origin gBackEnd )
				)
				( attribute "RELATIVE_PROPAGATION_DELAY" "0.00 MIL,300.00 MIL"
					( Parent
						( matchGroupRef "@crescent_city_bb_fab1_lib.crescent_city_bb_fab1(sch_1):\MG_DDR_NEAR_DIMM-CLK1_CLS_DDR_J_CAC-CLKS\" )
					)
					( Units "uMatchProp" "ns" 1.000000)
					( Status sCSetFlattened )
					( Origin gBackEnd )
				)
				( attribute "RELATIVE_PROPAGATION_DELAY_SCOPE" "G"
					( Parent
						( matchGroupRef "@baseboard_fab2_lib.baseboard_fab2(sch_1):\MG_DDR_CTRL_NG_DDR_J_DLL_20\" )
					)
					( Status sCSetFlattened )
					( Origin gBackEnd )
				)
				( attribute "RELATIVE_PROPAGATION_DELAY" "0.00 MIL,25.00 MIL"
					( Parent
						( matchGroupRef "@baseboard_fab2_lib.baseboard_fab2(sch_1):\MG_DDR_CTRL_NG_DDR_J_DLL_20\" )
					)
					( Units "uMatchProp" "ns" 1.000000)
					( Status sCSetFlattened )
					( Origin gBackEnd )
				)
			)
			( pinPair "@baseboard_fab2_lib.baseboard_fab2(sch_1):\PP3472\"
				( pinRef "@baseboard_fab2_lib.baseboard_fab2(sch_1):page59_i172:DDR2_ODT(2)" )
				( pinRef "@baseboard_fab2_lib.baseboard_fab2(sch_1):page82_i187:ODT(0)" )
				( attribute "RELATIVE_PROPAGATION_DELAY_SCOPE" "G"
					( Parent
						( matchGroupRef "@crescent_city_bb_fab1_lib.crescent_city_bb_fab1(sch_1):\MG_DDR_NEAR_DIMM-CLK1_CLS_DDR_J_CAC-CLKS\" )
					)
					( Status sCSetFlattened )
					( Origin gBackEnd )
				)
				( attribute "RELATIVE_PROPAGATION_DELAY" "0.00 MIL,300.00 MIL"
					( Parent
						( matchGroupRef "@crescent_city_bb_fab1_lib.crescent_city_bb_fab1(sch_1):\MG_DDR_NEAR_DIMM-CLK1_CLS_DDR_J_CAC-CLKS\" )
					)
					( Units "uMatchProp" "ns" 1.000000)
					( Status sCSetFlattened )
					( Origin gBackEnd )
				)
				( attribute "RELATIVE_PROPAGATION_DELAY_SCOPE" "G"
					( Parent
						( matchGroupRef "@baseboard_fab2_lib.baseboard_fab2(sch_1):\MG_DDR_CTRL_NG_DDR_J_DLL_20\" )
					)
					( Status sCSetFlattened )
					( Origin gBackEnd )
				)
				( attribute "RELATIVE_PROPAGATION_DELAY" "0.00 MIL,25.00 MIL"
					( Parent
						( matchGroupRef "@baseboard_fab2_lib.baseboard_fab2(sch_1):\MG_DDR_CTRL_NG_DDR_J_DLL_20\" )
					)
					( Units "uMatchProp" "ns" 1.000000)
					( Status sCSetFlattened )
					( Origin gBackEnd )
				)
			)
			( pinPair "@baseboard_fab2_lib.baseboard_fab2(sch_1):\PP3470\"
				( pinRef "@baseboard_fab2_lib.baseboard_fab2(sch_1):page59_i172:DDR2_CKE(2)" )
				( pinRef "@baseboard_fab2_lib.baseboard_fab2(sch_1):page82_i187:CKE(0)" )
				( attribute "RELATIVE_PROPAGATION_DELAY_SCOPE" "G"
					( Parent
						( matchGroupRef "@crescent_city_bb_fab1_lib.crescent_city_bb_fab1(sch_1):\MG_DDR_NEAR_DIMM-CLK1_CLS_DDR_J_CAC-CLKS\" )
					)
					( Status sCSetFlattened )
					( Origin gBackEnd )
				)
				( attribute "RELATIVE_PROPAGATION_DELAY" "0.00 MIL,300.00 MIL"
					( Parent
						( matchGroupRef "@crescent_city_bb_fab1_lib.crescent_city_bb_fab1(sch_1):\MG_DDR_NEAR_DIMM-CLK1_CLS_DDR_J_CAC-CLKS\" )
					)
					( Units "uMatchProp" "ns" 1.000000)
					( Status sCSetFlattened )
					( Origin gBackEnd )
				)
				( attribute "RELATIVE_PROPAGATION_DELAY_SCOPE" "G"
					( Parent
						( matchGroupRef "@baseboard_fab2_lib.baseboard_fab2(sch_1):\MG_DDR_CTRL_NG_DDR_J_DLL_21\" )
					)
					( Status sCSetFlattened )
					( Origin gBackEnd )
				)
				( attribute "RELATIVE_PROPAGATION_DELAY" "0.00 MIL,25.00 MIL"
					( Parent
						( matchGroupRef "@baseboard_fab2_lib.baseboard_fab2(sch_1):\MG_DDR_CTRL_NG_DDR_J_DLL_21\" )
					)
					( Units "uMatchProp" "ns" 1.000000)
					( Status sCSetFlattened )
					( Origin gBackEnd )
				)
			)
			( pinPair "@baseboard_fab2_lib.baseboard_fab2(sch_1):\PP3468\"
				( pinRef "@baseboard_fab2_lib.baseboard_fab2(sch_1):page59_i172:DDR2_CS_N(6)" )
				( pinRef "@baseboard_fab2_lib.baseboard_fab2(sch_1):page82_i187:S2_N_C(0)" )
				( attribute "RELATIVE_PROPAGATION_DELAY_SCOPE" "G"
					( Parent
						( matchGroupRef "@crescent_city_bb_fab1_lib.crescent_city_bb_fab1(sch_1):\MG_DDR_NEAR_DIMM-CLK1_CLS_DDR_J_CAC-CLKS\" )
					)
					( Status sCSetFlattened )
					( Origin gBackEnd )
				)
				( attribute "RELATIVE_PROPAGATION_DELAY" "0.00 MIL,300.00 MIL"
					( Parent
						( matchGroupRef "@crescent_city_bb_fab1_lib.crescent_city_bb_fab1(sch_1):\MG_DDR_NEAR_DIMM-CLK1_CLS_DDR_J_CAC-CLKS\" )
					)
					( Units "uMatchProp" "ns" 1.000000)
					( Status sCSetFlattened )
					( Origin gBackEnd )
				)
				( attribute "RELATIVE_PROPAGATION_DELAY_SCOPE" "G"
					( Parent
						( matchGroupRef "@baseboard_fab2_lib.baseboard_fab2(sch_1):\MG_DDR_CTRL_NG_DDR_J_DLL_22\" )
					)
					( Status sCSetFlattened )
					( Origin gBackEnd )
				)
				( attribute "RELATIVE_PROPAGATION_DELAY" "0.00 MIL,25.00 MIL"
					( Parent
						( matchGroupRef "@baseboard_fab2_lib.baseboard_fab2(sch_1):\MG_DDR_CTRL_NG_DDR_J_DLL_22\" )
					)
					( Units "uMatchProp" "ns" 1.000000)
					( Status sCSetFlattened )
					( Origin gBackEnd )
				)
			)
			( pinPair "@baseboard_fab2_lib.baseboard_fab2(sch_1):\PP3469\"
				( pinRef "@baseboard_fab2_lib.baseboard_fab2(sch_1):page59_i172:DDR2_CS_N(7)" )
				( pinRef "@baseboard_fab2_lib.baseboard_fab2(sch_1):page82_i187:S3_N_C(1)" )
				( attribute "RELATIVE_PROPAGATION_DELAY_SCOPE" "G"
					( Parent
						( matchGroupRef "@crescent_city_bb_fab1_lib.crescent_city_bb_fab1(sch_1):\MG_DDR_NEAR_DIMM-CLK1_CLS_DDR_J_CAC-CLKS\" )
					)
					( Status sCSetFlattened )
					( Origin gBackEnd )
				)
				( attribute "RELATIVE_PROPAGATION_DELAY" "0.00 MIL,300.00 MIL"
					( Parent
						( matchGroupRef "@crescent_city_bb_fab1_lib.crescent_city_bb_fab1(sch_1):\MG_DDR_NEAR_DIMM-CLK1_CLS_DDR_J_CAC-CLKS\" )
					)
					( Units "uMatchProp" "ns" 1.000000)
					( Status sCSetFlattened )
					( Origin gBackEnd )
				)
				( attribute "RELATIVE_PROPAGATION_DELAY_SCOPE" "G"
					( Parent
						( matchGroupRef "@baseboard_fab2_lib.baseboard_fab2(sch_1):\MG_DDR_CTRL_NG_DDR_J_DLL_22\" )
					)
					( Status sCSetFlattened )
					( Origin gBackEnd )
				)
				( attribute "RELATIVE_PROPAGATION_DELAY" "0.00 MIL,25.00 MIL"
					( Parent
						( matchGroupRef "@baseboard_fab2_lib.baseboard_fab2(sch_1):\MG_DDR_CTRL_NG_DDR_J_DLL_22\" )
					)
					( Units "uMatchProp" "ns" 1.000000)
					( Status sCSetFlattened )
					( Origin gBackEnd )
				)
			)
			( pinPair "@baseboard_fab2_lib.baseboard_fab2(sch_1):\PP3466\"
				( pinRef "@baseboard_fab2_lib.baseboard_fab2(sch_1):page59_i172:DDR2_CS_N(5)" )
				( pinRef "@baseboard_fab2_lib.baseboard_fab2(sch_1):page82_i187:S1_N" )
				( attribute "RELATIVE_PROPAGATION_DELAY_SCOPE" "G"
					( Parent
						( matchGroupRef "@crescent_city_bb_fab1_lib.crescent_city_bb_fab1(sch_1):\MG_DDR_NEAR_DIMM-CLK1_CLS_DDR_J_CAC-CLKS\" )
					)
					( Status sCSetFlattened )
					( Origin gBackEnd )
				)
				( attribute "RELATIVE_PROPAGATION_DELAY" "0.00 MIL,300.00 MIL"
					( Parent
						( matchGroupRef "@crescent_city_bb_fab1_lib.crescent_city_bb_fab1(sch_1):\MG_DDR_NEAR_DIMM-CLK1_CLS_DDR_J_CAC-CLKS\" )
					)
					( Units "uMatchProp" "ns" 1.000000)
					( Status sCSetFlattened )
					( Origin gBackEnd )
				)
				( attribute "RELATIVE_PROPAGATION_DELAY_SCOPE" "G"
					( Parent
						( matchGroupRef "@baseboard_fab2_lib.baseboard_fab2(sch_1):\MG_DDR_CTRL_NG_DDR_J_DLL_23\" )
					)
					( Status sCSetFlattened )
					( Origin gBackEnd )
				)
				( attribute "RELATIVE_PROPAGATION_DELAY" "0.00 MIL,25.00 MIL"
					( Parent
						( matchGroupRef "@baseboard_fab2_lib.baseboard_fab2(sch_1):\MG_DDR_CTRL_NG_DDR_J_DLL_23\" )
					)
					( Units "uMatchProp" "ns" 1.000000)
					( Status sCSetFlattened )
					( Origin gBackEnd )
				)
			)
			( pinPair "@baseboard_fab2_lib.baseboard_fab2(sch_1):\PP3467\"
				( pinRef "@baseboard_fab2_lib.baseboard_fab2(sch_1):page59_i172:DDR2_ODT(3)" )
				( pinRef "@baseboard_fab2_lib.baseboard_fab2(sch_1):page82_i187:ODT(1)" )
				( attribute "RELATIVE_PROPAGATION_DELAY_SCOPE" "G"
					( Parent
						( matchGroupRef "@crescent_city_bb_fab1_lib.crescent_city_bb_fab1(sch_1):\MG_DDR_NEAR_DIMM-CLK1_CLS_DDR_J_CAC-CLKS\" )
					)
					( Status sCSetFlattened )
					( Origin gBackEnd )
				)
				( attribute "RELATIVE_PROPAGATION_DELAY" "0.00 MIL,300.00 MIL"
					( Parent
						( matchGroupRef "@crescent_city_bb_fab1_lib.crescent_city_bb_fab1(sch_1):\MG_DDR_NEAR_DIMM-CLK1_CLS_DDR_J_CAC-CLKS\" )
					)
					( Units "uMatchProp" "ns" 1.000000)
					( Status sCSetFlattened )
					( Origin gBackEnd )
				)
				( attribute "RELATIVE_PROPAGATION_DELAY_SCOPE" "G"
					( Parent
						( matchGroupRef "@baseboard_fab2_lib.baseboard_fab2(sch_1):\MG_DDR_CTRL_NG_DDR_J_DLL_23\" )
					)
					( Status sCSetFlattened )
					( Origin gBackEnd )
				)
				( attribute "RELATIVE_PROPAGATION_DELAY" "0.00 MIL,25.00 MIL"
					( Parent
						( matchGroupRef "@baseboard_fab2_lib.baseboard_fab2(sch_1):\MG_DDR_CTRL_NG_DDR_J_DLL_23\" )
					)
					( Units "uMatchProp" "ns" 1.000000)
					( Status sCSetFlattened )
					( Origin gBackEnd )
				)
			)
			( pinPair "@baseboard_fab2_lib.baseboard_fab2(sch_1):\PP3465\"
				( pinRef "@baseboard_fab2_lib.baseboard_fab2(sch_1):page59_i172:DDR2_CKE(3)" )
				( pinRef "@baseboard_fab2_lib.baseboard_fab2(sch_1):page82_i187:CKE(1)" )
				( attribute "RELATIVE_PROPAGATION_DELAY_SCOPE" "G"
					( Parent
						( matchGroupRef "@crescent_city_bb_fab1_lib.crescent_city_bb_fab1(sch_1):\MG_DDR_NEAR_DIMM-CLK1_CLS_DDR_J_CAC-CLKS\" )
					)
					( Status sCSetFlattened )
					( Origin gBackEnd )
				)
				( attribute "RELATIVE_PROPAGATION_DELAY" "0.00 MIL,300.00 MIL"
					( Parent
						( matchGroupRef "@crescent_city_bb_fab1_lib.crescent_city_bb_fab1(sch_1):\MG_DDR_NEAR_DIMM-CLK1_CLS_DDR_J_CAC-CLKS\" )
					)
					( Units "uMatchProp" "ns" 1.000000)
					( Status sCSetFlattened )
					( Origin gBackEnd )
				)
				( attribute "RELATIVE_PROPAGATION_DELAY_SCOPE" "G"
					( Parent
						( matchGroupRef "@baseboard_fab2_lib.baseboard_fab2(sch_1):\MG_DDR_CTRL_NG_DDR_J_DLL_24\" )
					)
					( Status sCSetFlattened )
					( Origin gBackEnd )
				)
				( attribute "RELATIVE_PROPAGATION_DELAY" "0.00 MIL,25.00 MIL"
					( Parent
						( matchGroupRef "@baseboard_fab2_lib.baseboard_fab2(sch_1):\MG_DDR_CTRL_NG_DDR_J_DLL_24\" )
					)
					( Units "uMatchProp" "ns" 1.000000)
					( Status sCSetFlattened )
					( Origin gBackEnd )
				)
			)
			( pinPair "@baseboard_fab2_lib.baseboard_fab2(sch_1):\PP3593\"
				( pinRef "@baseboard_fab2_lib.baseboard_fab2(sch_1):page58_i172:DDR1_CID(2)" )
				( pinRef "@baseboard_fab2_lib.baseboard_fab2(sch_1):page79_i111:C(2)" )
				( attribute "RELATIVE_PROPAGATION_DELAY_SCOPE" "G"
					( Parent
						( matchGroupRef "@baseboard_fab2_lib.baseboard_fab2(sch_1):\MG_DDR_FAR_DIMM_CMD_NG_DDR_H_DLL_1\" )
					)
					( Status sCSetFlattened )
					( Origin gBackEnd )
				)
				( attribute "RELATIVE_PROPAGATION_DELAY" "0.00 MIL,25.00 MIL"
					( Parent
						( matchGroupRef "@baseboard_fab2_lib.baseboard_fab2(sch_1):\MG_DDR_FAR_DIMM_CMD_NG_DDR_H_DLL_1\" )
					)
					( Units "uMatchProp" "ns" 1.000000)
					( Status sCSetFlattened )
					( Origin gBackEnd )
				)
				( attribute "RELATIVE_PROPAGATION_DELAY_SCOPE" "G"
					( Parent
						( matchGroupRef "@crescent_city_bb_fab1_lib.crescent_city_bb_fab1(sch_1):\MG_DDR_FAR_DIMM-CLK0_CLS_DDR_H_CAC-CLKS\" )
					)
					( Status sCSetFlattened )
					( Origin gBackEnd )
				)
				( attribute "RELATIVE_PROPAGATION_DELAY" "0.00 MIL,700.00 MIL"
					( Parent
						( matchGroupRef "@crescent_city_bb_fab1_lib.crescent_city_bb_fab1(sch_1):\MG_DDR_FAR_DIMM-CLK0_CLS_DDR_H_CAC-CLKS\" )
					)
					( Units "uMatchProp" "ns" 1.000000)
					( Status sCSetFlattened )
					( Origin gBackEnd )
				)
			)
			( pinPair "@baseboard_fab2_lib.baseboard_fab2(sch_1):\PP3594\"
				( pinRef "@baseboard_fab2_lib.baseboard_fab2(sch_1):page80_i24:C(2)" )
				( pinRef "@baseboard_fab2_lib.baseboard_fab2(sch_1):page58_i172:DDR1_CID(2)" )
				( attribute "RELATIVE_PROPAGATION_DELAY_SCOPE" "G"
					( Parent
						( matchGroupRef "@crescent_city_bb_fab1_lib.crescent_city_bb_fab1(sch_1):\MG_DDR_NEAR_DIMM-CLK1_CLS_DDR_H_CAC-CLKS\" )
					)
					( Status sCSetFlattened )
					( Origin gBackEnd )
				)
				( attribute "RELATIVE_PROPAGATION_DELAY" "0.00 MIL,700.00 MIL"
					( Parent
						( matchGroupRef "@crescent_city_bb_fab1_lib.crescent_city_bb_fab1(sch_1):\MG_DDR_NEAR_DIMM-CLK1_CLS_DDR_H_CAC-CLKS\" )
					)
					( Units "uMatchProp" "ns" 1.000000)
					( Status sCSetFlattened )
					( Origin gBackEnd )
				)
				( attribute "RELATIVE_PROPAGATION_DELAY_SCOPE" "G"
					( Parent
						( matchGroupRef "@baseboard_fab2_lib.baseboard_fab2(sch_1):\MG_DDR_CMD_NEAR_DIMM_NG_DDR_H_DLL_1\" )
					)
					( Status sCSetFlattened )
					( Origin gBackEnd )
				)
				( attribute "RELATIVE_PROPAGATION_DELAY" "0.00 MIL,25.00 MIL"
					( Parent
						( matchGroupRef "@baseboard_fab2_lib.baseboard_fab2(sch_1):\MG_DDR_CMD_NEAR_DIMM_NG_DDR_H_DLL_1\" )
					)
					( Units "uMatchProp" "ns" 1.000000)
					( Status sCSetFlattened )
					( Origin gBackEnd )
				)
			)
			( pinPair "@baseboard_fab2_lib.baseboard_fab2(sch_1):\PP3595\"
				( pinRef "@baseboard_fab2_lib.baseboard_fab2(sch_1):page58_i172:DDR1_MA(17)" )
				( pinRef "@baseboard_fab2_lib.baseboard_fab2(sch_1):page79_i111:A17" )
				( attribute "RELATIVE_PROPAGATION_DELAY_SCOPE" "G"
					( Parent
						( matchGroupRef "@baseboard_fab2_lib.baseboard_fab2(sch_1):\MG_DDR_FAR_DIMM_CMD_NG_DDR_H_DLL_1\" )
					)
					( Status sCSetFlattened )
					( Origin gBackEnd )
				)
				( attribute "RELATIVE_PROPAGATION_DELAY" "0.00 MIL,25.00 MIL"
					( Parent
						( matchGroupRef "@baseboard_fab2_lib.baseboard_fab2(sch_1):\MG_DDR_FAR_DIMM_CMD_NG_DDR_H_DLL_1\" )
					)
					( Units "uMatchProp" "ns" 1.000000)
					( Status sCSetFlattened )
					( Origin gBackEnd )
				)
				( attribute "RELATIVE_PROPAGATION_DELAY_SCOPE" "G"
					( Parent
						( matchGroupRef "@crescent_city_bb_fab1_lib.crescent_city_bb_fab1(sch_1):\MG_DDR_FAR_DIMM-CLK0_CLS_DDR_H_CAC-CLKS\" )
					)
					( Status sCSetFlattened )
					( Origin gBackEnd )
				)
				( attribute "RELATIVE_PROPAGATION_DELAY" "0.00 MIL,700.00 MIL"
					( Parent
						( matchGroupRef "@crescent_city_bb_fab1_lib.crescent_city_bb_fab1(sch_1):\MG_DDR_FAR_DIMM-CLK0_CLS_DDR_H_CAC-CLKS\" )
					)
					( Units "uMatchProp" "ns" 1.000000)
					( Status sCSetFlattened )
					( Origin gBackEnd )
				)
			)
			( pinPair "@baseboard_fab2_lib.baseboard_fab2(sch_1):\PP3596\"
				( pinRef "@baseboard_fab2_lib.baseboard_fab2(sch_1):page80_i24:A17" )
				( pinRef "@baseboard_fab2_lib.baseboard_fab2(sch_1):page58_i172:DDR1_MA(17)" )
				( attribute "RELATIVE_PROPAGATION_DELAY_SCOPE" "G"
					( Parent
						( matchGroupRef "@crescent_city_bb_fab1_lib.crescent_city_bb_fab1(sch_1):\MG_DDR_NEAR_DIMM-CLK1_CLS_DDR_H_CAC-CLKS\" )
					)
					( Status sCSetFlattened )
					( Origin gBackEnd )
				)
				( attribute "RELATIVE_PROPAGATION_DELAY" "0.00 MIL,700.00 MIL"
					( Parent
						( matchGroupRef "@crescent_city_bb_fab1_lib.crescent_city_bb_fab1(sch_1):\MG_DDR_NEAR_DIMM-CLK1_CLS_DDR_H_CAC-CLKS\" )
					)
					( Units "uMatchProp" "ns" 1.000000)
					( Status sCSetFlattened )
					( Origin gBackEnd )
				)
				( attribute "RELATIVE_PROPAGATION_DELAY_SCOPE" "G"
					( Parent
						( matchGroupRef "@baseboard_fab2_lib.baseboard_fab2(sch_1):\MG_DDR_CMD_NEAR_DIMM_NG_DDR_H_DLL_1\" )
					)
					( Status sCSetFlattened )
					( Origin gBackEnd )
				)
				( attribute "RELATIVE_PROPAGATION_DELAY" "0.00 MIL,25.00 MIL"
					( Parent
						( matchGroupRef "@baseboard_fab2_lib.baseboard_fab2(sch_1):\MG_DDR_CMD_NEAR_DIMM_NG_DDR_H_DLL_1\" )
					)
					( Units "uMatchProp" "ns" 1.000000)
					( Status sCSetFlattened )
					( Origin gBackEnd )
				)
			)
			( pinPair "@baseboard_fab2_lib.baseboard_fab2(sch_1):\PP3589\"
				( pinRef "@baseboard_fab2_lib.baseboard_fab2(sch_1):page58_i172:DDR1_MA(13)" )
				( pinRef "@baseboard_fab2_lib.baseboard_fab2(sch_1):page79_i111:A13" )
				( attribute "RELATIVE_PROPAGATION_DELAY_SCOPE" "G"
					( Parent
						( matchGroupRef "@crescent_city_bb_fab1_lib.crescent_city_bb_fab1(sch_1):\MG_DDR_FAR_DIMM-CLK0_CLS_DDR_H_CAC-CLKS\" )
					)
					( Status sCSetFlattened )
					( Origin gBackEnd )
				)
				( attribute "RELATIVE_PROPAGATION_DELAY" "0.00 MIL,700.00 MIL"
					( Parent
						( matchGroupRef "@crescent_city_bb_fab1_lib.crescent_city_bb_fab1(sch_1):\MG_DDR_FAR_DIMM-CLK0_CLS_DDR_H_CAC-CLKS\" )
					)
					( Units "uMatchProp" "ns" 1.000000)
					( Status sCSetFlattened )
					( Origin gBackEnd )
				)
				( attribute "RELATIVE_PROPAGATION_DELAY_SCOPE" "G"
					( Parent
						( matchGroupRef "@baseboard_fab2_lib.baseboard_fab2(sch_1):\MG_DDR_FAR_DIMM_CMD_NG_DDR_H_DLL_2\" )
					)
					( Status sCSetFlattened )
					( Origin gBackEnd )
				)
				( attribute "RELATIVE_PROPAGATION_DELAY" "0.00 MIL,25.00 MIL"
					( Parent
						( matchGroupRef "@baseboard_fab2_lib.baseboard_fab2(sch_1):\MG_DDR_FAR_DIMM_CMD_NG_DDR_H_DLL_2\" )
					)
					( Units "uMatchProp" "ns" 1.000000)
					( Status sCSetFlattened )
					( Origin gBackEnd )
				)
			)
			( pinPair "@baseboard_fab2_lib.baseboard_fab2(sch_1):\PP3590\"
				( pinRef "@baseboard_fab2_lib.baseboard_fab2(sch_1):page58_i172:DDR1_MA(13)" )
				( pinRef "@baseboard_fab2_lib.baseboard_fab2(sch_1):page80_i24:A13" )
				( attribute "RELATIVE_PROPAGATION_DELAY_SCOPE" "G"
					( Parent
						( matchGroupRef "@crescent_city_bb_fab1_lib.crescent_city_bb_fab1(sch_1):\MG_DDR_NEAR_DIMM-CLK1_CLS_DDR_H_CAC-CLKS\" )
					)
					( Status sCSetFlattened )
					( Origin gBackEnd )
				)
				( attribute "RELATIVE_PROPAGATION_DELAY" "0.00 MIL,700.00 MIL"
					( Parent
						( matchGroupRef "@crescent_city_bb_fab1_lib.crescent_city_bb_fab1(sch_1):\MG_DDR_NEAR_DIMM-CLK1_CLS_DDR_H_CAC-CLKS\" )
					)
					( Units "uMatchProp" "ns" 1.000000)
					( Status sCSetFlattened )
					( Origin gBackEnd )
				)
				( attribute "RELATIVE_PROPAGATION_DELAY_SCOPE" "G"
					( Parent
						( matchGroupRef "@baseboard_fab2_lib.baseboard_fab2(sch_1):\MG_DDR_CMD_NEAR_DIMM_NG_DDR_H_DLL_2\" )
					)
					( Status sCSetFlattened )
					( Origin gBackEnd )
				)
				( attribute "RELATIVE_PROPAGATION_DELAY" "0.00 MIL,25.00 MIL"
					( Parent
						( matchGroupRef "@baseboard_fab2_lib.baseboard_fab2(sch_1):\MG_DDR_CMD_NEAR_DIMM_NG_DDR_H_DLL_2\" )
					)
					( Units "uMatchProp" "ns" 1.000000)
					( Status sCSetFlattened )
					( Origin gBackEnd )
				)
			)
			( pinPair "@baseboard_fab2_lib.baseboard_fab2(sch_1):\PP3591\"
				( pinRef "@baseboard_fab2_lib.baseboard_fab2(sch_1):page58_i172:DDR1_MA(14)" )
				( pinRef "@baseboard_fab2_lib.baseboard_fab2(sch_1):page79_i111:A14_WE_N" )
				( attribute "RELATIVE_PROPAGATION_DELAY_SCOPE" "G"
					( Parent
						( matchGroupRef "@crescent_city_bb_fab1_lib.crescent_city_bb_fab1(sch_1):\MG_DDR_FAR_DIMM-CLK0_CLS_DDR_H_CAC-CLKS\" )
					)
					( Status sCSetFlattened )
					( Origin gBackEnd )
				)
				( attribute "RELATIVE_PROPAGATION_DELAY" "0.00 MIL,700.00 MIL"
					( Parent
						( matchGroupRef "@crescent_city_bb_fab1_lib.crescent_city_bb_fab1(sch_1):\MG_DDR_FAR_DIMM-CLK0_CLS_DDR_H_CAC-CLKS\" )
					)
					( Units "uMatchProp" "ns" 1.000000)
					( Status sCSetFlattened )
					( Origin gBackEnd )
				)
				( attribute "RELATIVE_PROPAGATION_DELAY_SCOPE" "G"
					( Parent
						( matchGroupRef "@baseboard_fab2_lib.baseboard_fab2(sch_1):\MG_DDR_FAR_DIMM_CMD_NG_DDR_H_DLL_2\" )
					)
					( Status sCSetFlattened )
					( Origin gBackEnd )
				)
				( attribute "RELATIVE_PROPAGATION_DELAY" "0.00 MIL,25.00 MIL"
					( Parent
						( matchGroupRef "@baseboard_fab2_lib.baseboard_fab2(sch_1):\MG_DDR_FAR_DIMM_CMD_NG_DDR_H_DLL_2\" )
					)
					( Units "uMatchProp" "ns" 1.000000)
					( Status sCSetFlattened )
					( Origin gBackEnd )
				)
			)
			( pinPair "@baseboard_fab2_lib.baseboard_fab2(sch_1):\PP3592\"
				( pinRef "@baseboard_fab2_lib.baseboard_fab2(sch_1):page58_i172:DDR1_MA(14)" )
				( pinRef "@baseboard_fab2_lib.baseboard_fab2(sch_1):page80_i24:A14_WE_N" )
				( attribute "RELATIVE_PROPAGATION_DELAY_SCOPE" "G"
					( Parent
						( matchGroupRef "@crescent_city_bb_fab1_lib.crescent_city_bb_fab1(sch_1):\MG_DDR_NEAR_DIMM-CLK1_CLS_DDR_H_CAC-CLKS\" )
					)
					( Status sCSetFlattened )
					( Origin gBackEnd )
				)
				( attribute "RELATIVE_PROPAGATION_DELAY" "0.00 MIL,700.00 MIL"
					( Parent
						( matchGroupRef "@crescent_city_bb_fab1_lib.crescent_city_bb_fab1(sch_1):\MG_DDR_NEAR_DIMM-CLK1_CLS_DDR_H_CAC-CLKS\" )
					)
					( Units "uMatchProp" "ns" 1.000000)
					( Status sCSetFlattened )
					( Origin gBackEnd )
				)
				( attribute "RELATIVE_PROPAGATION_DELAY_SCOPE" "G"
					( Parent
						( matchGroupRef "@baseboard_fab2_lib.baseboard_fab2(sch_1):\MG_DDR_CMD_NEAR_DIMM_NG_DDR_H_DLL_2\" )
					)
					( Status sCSetFlattened )
					( Origin gBackEnd )
				)
				( attribute "RELATIVE_PROPAGATION_DELAY" "0.00 MIL,25.00 MIL"
					( Parent
						( matchGroupRef "@baseboard_fab2_lib.baseboard_fab2(sch_1):\MG_DDR_CMD_NEAR_DIMM_NG_DDR_H_DLL_2\" )
					)
					( Units "uMatchProp" "ns" 1.000000)
					( Status sCSetFlattened )
					( Origin gBackEnd )
				)
			)
			( pinPair "@baseboard_fab2_lib.baseboard_fab2(sch_1):\PP3585\"
				( pinRef "@baseboard_fab2_lib.baseboard_fab2(sch_1):page58_i172:DDR1_MA(15)" )
				( pinRef "@baseboard_fab2_lib.baseboard_fab2(sch_1):page79_i111:A15_CAS_N" )
				( attribute "RELATIVE_PROPAGATION_DELAY_SCOPE" "G"
					( Parent
						( matchGroupRef "@crescent_city_bb_fab1_lib.crescent_city_bb_fab1(sch_1):\MG_DDR_FAR_DIMM-CLK0_CLS_DDR_H_CAC-CLKS\" )
					)
					( Status sCSetFlattened )
					( Origin gBackEnd )
				)
				( attribute "RELATIVE_PROPAGATION_DELAY" "0.00 MIL,700.00 MIL"
					( Parent
						( matchGroupRef "@crescent_city_bb_fab1_lib.crescent_city_bb_fab1(sch_1):\MG_DDR_FAR_DIMM-CLK0_CLS_DDR_H_CAC-CLKS\" )
					)
					( Units "uMatchProp" "ns" 1.000000)
					( Status sCSetFlattened )
					( Origin gBackEnd )
				)
				( attribute "RELATIVE_PROPAGATION_DELAY_SCOPE" "G"
					( Parent
						( matchGroupRef "@baseboard_fab2_lib.baseboard_fab2(sch_1):\MG_DDR_FAR_DIMM_CMD_NG_DDR_H_DLL_3\" )
					)
					( Status sCSetFlattened )
					( Origin gBackEnd )
				)
				( attribute "RELATIVE_PROPAGATION_DELAY" "0.00 MIL,25.00 MIL"
					( Parent
						( matchGroupRef "@baseboard_fab2_lib.baseboard_fab2(sch_1):\MG_DDR_FAR_DIMM_CMD_NG_DDR_H_DLL_3\" )
					)
					( Units "uMatchProp" "ns" 1.000000)
					( Status sCSetFlattened )
					( Origin gBackEnd )
				)
			)
			( pinPair "@baseboard_fab2_lib.baseboard_fab2(sch_1):\PP3586\"
				( pinRef "@baseboard_fab2_lib.baseboard_fab2(sch_1):page58_i172:DDR1_MA(15)" )
				( pinRef "@baseboard_fab2_lib.baseboard_fab2(sch_1):page80_i24:A15_CAS_N" )
				( attribute "RELATIVE_PROPAGATION_DELAY_SCOPE" "G"
					( Parent
						( matchGroupRef "@crescent_city_bb_fab1_lib.crescent_city_bb_fab1(sch_1):\MG_DDR_NEAR_DIMM-CLK1_CLS_DDR_H_CAC-CLKS\" )
					)
					( Status sCSetFlattened )
					( Origin gBackEnd )
				)
				( attribute "RELATIVE_PROPAGATION_DELAY" "0.00 MIL,700.00 MIL"
					( Parent
						( matchGroupRef "@crescent_city_bb_fab1_lib.crescent_city_bb_fab1(sch_1):\MG_DDR_NEAR_DIMM-CLK1_CLS_DDR_H_CAC-CLKS\" )
					)
					( Units "uMatchProp" "ns" 1.000000)
					( Status sCSetFlattened )
					( Origin gBackEnd )
				)
				( attribute "RELATIVE_PROPAGATION_DELAY_SCOPE" "G"
					( Parent
						( matchGroupRef "@baseboard_fab2_lib.baseboard_fab2(sch_1):\MG_DDR_CMD_NEAR_DIMM_NG_DDR_H_DLL_3\" )
					)
					( Status sCSetFlattened )
					( Origin gBackEnd )
				)
				( attribute "RELATIVE_PROPAGATION_DELAY" "0.00 MIL,25.00 MIL"
					( Parent
						( matchGroupRef "@baseboard_fab2_lib.baseboard_fab2(sch_1):\MG_DDR_CMD_NEAR_DIMM_NG_DDR_H_DLL_3\" )
					)
					( Units "uMatchProp" "ns" 1.000000)
					( Status sCSetFlattened )
					( Origin gBackEnd )
				)
			)
			( pinPair "@baseboard_fab2_lib.baseboard_fab2(sch_1):\PP3587\"
				( pinRef "@baseboard_fab2_lib.baseboard_fab2(sch_1):page58_i172:DDR1_MA(16)" )
				( pinRef "@baseboard_fab2_lib.baseboard_fab2(sch_1):page79_i111:A16_RAS_N" )
				( attribute "RELATIVE_PROPAGATION_DELAY_SCOPE" "G"
					( Parent
						( matchGroupRef "@crescent_city_bb_fab1_lib.crescent_city_bb_fab1(sch_1):\MG_DDR_FAR_DIMM-CLK0_CLS_DDR_H_CAC-CLKS\" )
					)
					( Status sCSetFlattened )
					( Origin gBackEnd )
				)
				( attribute "RELATIVE_PROPAGATION_DELAY" "0.00 MIL,700.00 MIL"
					( Parent
						( matchGroupRef "@crescent_city_bb_fab1_lib.crescent_city_bb_fab1(sch_1):\MG_DDR_FAR_DIMM-CLK0_CLS_DDR_H_CAC-CLKS\" )
					)
					( Units "uMatchProp" "ns" 1.000000)
					( Status sCSetFlattened )
					( Origin gBackEnd )
				)
				( attribute "RELATIVE_PROPAGATION_DELAY_SCOPE" "G"
					( Parent
						( matchGroupRef "@baseboard_fab2_lib.baseboard_fab2(sch_1):\MG_DDR_FAR_DIMM_CMD_NG_DDR_H_DLL_3\" )
					)
					( Status sCSetFlattened )
					( Origin gBackEnd )
				)
				( attribute "RELATIVE_PROPAGATION_DELAY" "0.00 MIL,25.00 MIL"
					( Parent
						( matchGroupRef "@baseboard_fab2_lib.baseboard_fab2(sch_1):\MG_DDR_FAR_DIMM_CMD_NG_DDR_H_DLL_3\" )
					)
					( Units "uMatchProp" "ns" 1.000000)
					( Status sCSetFlattened )
					( Origin gBackEnd )
				)
			)
			( pinPair "@baseboard_fab2_lib.baseboard_fab2(sch_1):\PP3588\"
				( pinRef "@baseboard_fab2_lib.baseboard_fab2(sch_1):page58_i172:DDR1_MA(16)" )
				( pinRef "@baseboard_fab2_lib.baseboard_fab2(sch_1):page80_i24:A16_RAS_N" )
				( attribute "RELATIVE_PROPAGATION_DELAY_SCOPE" "G"
					( Parent
						( matchGroupRef "@crescent_city_bb_fab1_lib.crescent_city_bb_fab1(sch_1):\MG_DDR_NEAR_DIMM-CLK1_CLS_DDR_H_CAC-CLKS\" )
					)
					( Status sCSetFlattened )
					( Origin gBackEnd )
				)
				( attribute "RELATIVE_PROPAGATION_DELAY" "0.00 MIL,700.00 MIL"
					( Parent
						( matchGroupRef "@crescent_city_bb_fab1_lib.crescent_city_bb_fab1(sch_1):\MG_DDR_NEAR_DIMM-CLK1_CLS_DDR_H_CAC-CLKS\" )
					)
					( Units "uMatchProp" "ns" 1.000000)
					( Status sCSetFlattened )
					( Origin gBackEnd )
				)
				( attribute "RELATIVE_PROPAGATION_DELAY_SCOPE" "G"
					( Parent
						( matchGroupRef "@baseboard_fab2_lib.baseboard_fab2(sch_1):\MG_DDR_CMD_NEAR_DIMM_NG_DDR_H_DLL_3\" )
					)
					( Status sCSetFlattened )
					( Origin gBackEnd )
				)
				( attribute "RELATIVE_PROPAGATION_DELAY" "0.00 MIL,25.00 MIL"
					( Parent
						( matchGroupRef "@baseboard_fab2_lib.baseboard_fab2(sch_1):\MG_DDR_CMD_NEAR_DIMM_NG_DDR_H_DLL_3\" )
					)
					( Units "uMatchProp" "ns" 1.000000)
					( Status sCSetFlattened )
					( Origin gBackEnd )
				)
			)
			( pinPair "@baseboard_fab2_lib.baseboard_fab2(sch_1):\PP3581\"
				( pinRef "@baseboard_fab2_lib.baseboard_fab2(sch_1):page58_i172:DDR1_BA(1)" )
				( pinRef "@baseboard_fab2_lib.baseboard_fab2(sch_1):page79_i111:BA(1)" )
				( attribute "RELATIVE_PROPAGATION_DELAY_SCOPE" "G"
					( Parent
						( matchGroupRef "@crescent_city_bb_fab1_lib.crescent_city_bb_fab1(sch_1):\MG_DDR_FAR_DIMM-CLK0_CLS_DDR_H_CAC-CLKS\" )
					)
					( Status sCSetFlattened )
					( Origin gBackEnd )
				)
				( attribute "RELATIVE_PROPAGATION_DELAY" "0.00 MIL,700.00 MIL"
					( Parent
						( matchGroupRef "@crescent_city_bb_fab1_lib.crescent_city_bb_fab1(sch_1):\MG_DDR_FAR_DIMM-CLK0_CLS_DDR_H_CAC-CLKS\" )
					)
					( Units "uMatchProp" "ns" 1.000000)
					( Status sCSetFlattened )
					( Origin gBackEnd )
				)
				( attribute "RELATIVE_PROPAGATION_DELAY_SCOPE" "G"
					( Parent
						( matchGroupRef "@baseboard_fab2_lib.baseboard_fab2(sch_1):\MG_DDR_FAR_DIMM_CMD_NG_DDR_H_DLL_4\" )
					)
					( Status sCSetFlattened )
					( Origin gBackEnd )
				)
				( attribute "RELATIVE_PROPAGATION_DELAY" "0.00 MIL,25.00 MIL"
					( Parent
						( matchGroupRef "@baseboard_fab2_lib.baseboard_fab2(sch_1):\MG_DDR_FAR_DIMM_CMD_NG_DDR_H_DLL_4\" )
					)
					( Units "uMatchProp" "ns" 1.000000)
					( Status sCSetFlattened )
					( Origin gBackEnd )
				)
			)
			( pinPair "@baseboard_fab2_lib.baseboard_fab2(sch_1):\PP3582\"
				( pinRef "@baseboard_fab2_lib.baseboard_fab2(sch_1):page80_i24:BA(1)" )
				( pinRef "@baseboard_fab2_lib.baseboard_fab2(sch_1):page58_i172:DDR1_BA(1)" )
				( attribute "RELATIVE_PROPAGATION_DELAY_SCOPE" "G"
					( Parent
						( matchGroupRef "@crescent_city_bb_fab1_lib.crescent_city_bb_fab1(sch_1):\MG_DDR_NEAR_DIMM-CLK1_CLS_DDR_H_CAC-CLKS\" )
					)
					( Status sCSetFlattened )
					( Origin gBackEnd )
				)
				( attribute "RELATIVE_PROPAGATION_DELAY" "0.00 MIL,700.00 MIL"
					( Parent
						( matchGroupRef "@crescent_city_bb_fab1_lib.crescent_city_bb_fab1(sch_1):\MG_DDR_NEAR_DIMM-CLK1_CLS_DDR_H_CAC-CLKS\" )
					)
					( Units "uMatchProp" "ns" 1.000000)
					( Status sCSetFlattened )
					( Origin gBackEnd )
				)
				( attribute "RELATIVE_PROPAGATION_DELAY_SCOPE" "G"
					( Parent
						( matchGroupRef "@baseboard_fab2_lib.baseboard_fab2(sch_1):\MG_DDR_CMD_NEAR_DIMM_NG_DDR_H_DLL_4\" )
					)
					( Status sCSetFlattened )
					( Origin gBackEnd )
				)
				( attribute "RELATIVE_PROPAGATION_DELAY" "0.00 MIL,25.00 MIL"
					( Parent
						( matchGroupRef "@baseboard_fab2_lib.baseboard_fab2(sch_1):\MG_DDR_CMD_NEAR_DIMM_NG_DDR_H_DLL_4\" )
					)
					( Units "uMatchProp" "ns" 1.000000)
					( Status sCSetFlattened )
					( Origin gBackEnd )
				)
			)
			( pinPair "@baseboard_fab2_lib.baseboard_fab2(sch_1):\PP3583\"
				( pinRef "@baseboard_fab2_lib.baseboard_fab2(sch_1):page58_i172:DDR1_MA(10)" )
				( pinRef "@baseboard_fab2_lib.baseboard_fab2(sch_1):page79_i111:A10" )
				( attribute "RELATIVE_PROPAGATION_DELAY_SCOPE" "G"
					( Parent
						( matchGroupRef "@crescent_city_bb_fab1_lib.crescent_city_bb_fab1(sch_1):\MG_DDR_FAR_DIMM-CLK0_CLS_DDR_H_CAC-CLKS\" )
					)
					( Status sCSetFlattened )
					( Origin gBackEnd )
				)
				( attribute "RELATIVE_PROPAGATION_DELAY" "0.00 MIL,700.00 MIL"
					( Parent
						( matchGroupRef "@crescent_city_bb_fab1_lib.crescent_city_bb_fab1(sch_1):\MG_DDR_FAR_DIMM-CLK0_CLS_DDR_H_CAC-CLKS\" )
					)
					( Units "uMatchProp" "ns" 1.000000)
					( Status sCSetFlattened )
					( Origin gBackEnd )
				)
				( attribute "RELATIVE_PROPAGATION_DELAY_SCOPE" "G"
					( Parent
						( matchGroupRef "@baseboard_fab2_lib.baseboard_fab2(sch_1):\MG_DDR_FAR_DIMM_CMD_NG_DDR_H_DLL_4\" )
					)
					( Status sCSetFlattened )
					( Origin gBackEnd )
				)
				( attribute "RELATIVE_PROPAGATION_DELAY" "0.00 MIL,25.00 MIL"
					( Parent
						( matchGroupRef "@baseboard_fab2_lib.baseboard_fab2(sch_1):\MG_DDR_FAR_DIMM_CMD_NG_DDR_H_DLL_4\" )
					)
					( Units "uMatchProp" "ns" 1.000000)
					( Status sCSetFlattened )
					( Origin gBackEnd )
				)
			)
			( pinPair "@baseboard_fab2_lib.baseboard_fab2(sch_1):\PP3584\"
				( pinRef "@baseboard_fab2_lib.baseboard_fab2(sch_1):page80_i24:A10" )
				( pinRef "@baseboard_fab2_lib.baseboard_fab2(sch_1):page58_i172:DDR1_MA(10)" )
				( attribute "RELATIVE_PROPAGATION_DELAY_SCOPE" "G"
					( Parent
						( matchGroupRef "@crescent_city_bb_fab1_lib.crescent_city_bb_fab1(sch_1):\MG_DDR_NEAR_DIMM-CLK1_CLS_DDR_H_CAC-CLKS\" )
					)
					( Status sCSetFlattened )
					( Origin gBackEnd )
				)
				( attribute "RELATIVE_PROPAGATION_DELAY" "0.00 MIL,700.00 MIL"
					( Parent
						( matchGroupRef "@crescent_city_bb_fab1_lib.crescent_city_bb_fab1(sch_1):\MG_DDR_NEAR_DIMM-CLK1_CLS_DDR_H_CAC-CLKS\" )
					)
					( Units "uMatchProp" "ns" 1.000000)
					( Status sCSetFlattened )
					( Origin gBackEnd )
				)
				( attribute "RELATIVE_PROPAGATION_DELAY_SCOPE" "G"
					( Parent
						( matchGroupRef "@baseboard_fab2_lib.baseboard_fab2(sch_1):\MG_DDR_CMD_NEAR_DIMM_NG_DDR_H_DLL_4\" )
					)
					( Status sCSetFlattened )
					( Origin gBackEnd )
				)
				( attribute "RELATIVE_PROPAGATION_DELAY" "0.00 MIL,25.00 MIL"
					( Parent
						( matchGroupRef "@baseboard_fab2_lib.baseboard_fab2(sch_1):\MG_DDR_CMD_NEAR_DIMM_NG_DDR_H_DLL_4\" )
					)
					( Units "uMatchProp" "ns" 1.000000)
					( Status sCSetFlattened )
					( Origin gBackEnd )
				)
			)
			( pinPair "@baseboard_fab2_lib.baseboard_fab2(sch_1):\PP3577\"
				( pinRef "@baseboard_fab2_lib.baseboard_fab2(sch_1):page58_i172:DDR1_BA(0)" )
				( pinRef "@baseboard_fab2_lib.baseboard_fab2(sch_1):page79_i111:BA(0)" )
				( attribute "RELATIVE_PROPAGATION_DELAY_SCOPE" "G"
					( Parent
						( matchGroupRef "@crescent_city_bb_fab1_lib.crescent_city_bb_fab1(sch_1):\MG_DDR_FAR_DIMM-CLK0_CLS_DDR_H_CAC-CLKS\" )
					)
					( Status sCSetFlattened )
					( Origin gBackEnd )
				)
				( attribute "RELATIVE_PROPAGATION_DELAY" "0.00 MIL,700.00 MIL"
					( Parent
						( matchGroupRef "@crescent_city_bb_fab1_lib.crescent_city_bb_fab1(sch_1):\MG_DDR_FAR_DIMM-CLK0_CLS_DDR_H_CAC-CLKS\" )
					)
					( Units "uMatchProp" "ns" 1.000000)
					( Status sCSetFlattened )
					( Origin gBackEnd )
				)
				( attribute "RELATIVE_PROPAGATION_DELAY_SCOPE" "G"
					( Parent
						( matchGroupRef "@baseboard_fab2_lib.baseboard_fab2(sch_1):\MG_DDR_FAR_DIMM_CMD_NG_DDR_H_DLL_5\" )
					)
					( Status sCSetFlattened )
					( Origin gBackEnd )
				)
				( attribute "RELATIVE_PROPAGATION_DELAY" "0.00 MIL,25.00 MIL"
					( Parent
						( matchGroupRef "@baseboard_fab2_lib.baseboard_fab2(sch_1):\MG_DDR_FAR_DIMM_CMD_NG_DDR_H_DLL_5\" )
					)
					( Units "uMatchProp" "ns" 1.000000)
					( Status sCSetFlattened )
					( Origin gBackEnd )
				)
			)
			( pinPair "@baseboard_fab2_lib.baseboard_fab2(sch_1):\PP3578\"
				( pinRef "@baseboard_fab2_lib.baseboard_fab2(sch_1):page80_i24:BA(0)" )
				( pinRef "@baseboard_fab2_lib.baseboard_fab2(sch_1):page58_i172:DDR1_BA(0)" )
				( attribute "RELATIVE_PROPAGATION_DELAY_SCOPE" "G"
					( Parent
						( matchGroupRef "@crescent_city_bb_fab1_lib.crescent_city_bb_fab1(sch_1):\MG_DDR_NEAR_DIMM-CLK1_CLS_DDR_H_CAC-CLKS\" )
					)
					( Status sCSetFlattened )
					( Origin gBackEnd )
				)
				( attribute "RELATIVE_PROPAGATION_DELAY" "0.00 MIL,700.00 MIL"
					( Parent
						( matchGroupRef "@crescent_city_bb_fab1_lib.crescent_city_bb_fab1(sch_1):\MG_DDR_NEAR_DIMM-CLK1_CLS_DDR_H_CAC-CLKS\" )
					)
					( Units "uMatchProp" "ns" 1.000000)
					( Status sCSetFlattened )
					( Origin gBackEnd )
				)
				( attribute "RELATIVE_PROPAGATION_DELAY_SCOPE" "G"
					( Parent
						( matchGroupRef "@baseboard_fab2_lib.baseboard_fab2(sch_1):\MG_DDR_CMD_NEAR_DIMM_NG_DDR_H_DLL_5\" )
					)
					( Status sCSetFlattened )
					( Origin gBackEnd )
				)
				( attribute "RELATIVE_PROPAGATION_DELAY" "0.00 MIL,25.00 MIL"
					( Parent
						( matchGroupRef "@baseboard_fab2_lib.baseboard_fab2(sch_1):\MG_DDR_CMD_NEAR_DIMM_NG_DDR_H_DLL_5\" )
					)
					( Units "uMatchProp" "ns" 1.000000)
					( Status sCSetFlattened )
					( Origin gBackEnd )
				)
			)
			( pinPair "@baseboard_fab2_lib.baseboard_fab2(sch_1):\PP3579\"
				( pinRef "@baseboard_fab2_lib.baseboard_fab2(sch_1):page58_i172:DDR1_MA(0)" )
				( pinRef "@baseboard_fab2_lib.baseboard_fab2(sch_1):page79_i111:A0" )
				( attribute "RELATIVE_PROPAGATION_DELAY_SCOPE" "G"
					( Parent
						( matchGroupRef "@crescent_city_bb_fab1_lib.crescent_city_bb_fab1(sch_1):\MG_DDR_FAR_DIMM-CLK0_CLS_DDR_H_CAC-CLKS\" )
					)
					( Status sCSetFlattened )
					( Origin gBackEnd )
				)
				( attribute "RELATIVE_PROPAGATION_DELAY" "0.00 MIL,700.00 MIL"
					( Parent
						( matchGroupRef "@crescent_city_bb_fab1_lib.crescent_city_bb_fab1(sch_1):\MG_DDR_FAR_DIMM-CLK0_CLS_DDR_H_CAC-CLKS\" )
					)
					( Units "uMatchProp" "ns" 1.000000)
					( Status sCSetFlattened )
					( Origin gBackEnd )
				)
				( attribute "RELATIVE_PROPAGATION_DELAY_SCOPE" "G"
					( Parent
						( matchGroupRef "@baseboard_fab2_lib.baseboard_fab2(sch_1):\MG_DDR_FAR_DIMM_CMD_NG_DDR_H_DLL_5\" )
					)
					( Status sCSetFlattened )
					( Origin gBackEnd )
				)
				( attribute "RELATIVE_PROPAGATION_DELAY" "0.00 MIL,25.00 MIL"
					( Parent
						( matchGroupRef "@baseboard_fab2_lib.baseboard_fab2(sch_1):\MG_DDR_FAR_DIMM_CMD_NG_DDR_H_DLL_5\" )
					)
					( Units "uMatchProp" "ns" 1.000000)
					( Status sCSetFlattened )
					( Origin gBackEnd )
				)
			)
			( pinPair "@baseboard_fab2_lib.baseboard_fab2(sch_1):\PP3580\"
				( pinRef "@baseboard_fab2_lib.baseboard_fab2(sch_1):page80_i24:A0" )
				( pinRef "@baseboard_fab2_lib.baseboard_fab2(sch_1):page58_i172:DDR1_MA(0)" )
				( attribute "RELATIVE_PROPAGATION_DELAY_SCOPE" "G"
					( Parent
						( matchGroupRef "@crescent_city_bb_fab1_lib.crescent_city_bb_fab1(sch_1):\MG_DDR_NEAR_DIMM-CLK1_CLS_DDR_H_CAC-CLKS\" )
					)
					( Status sCSetFlattened )
					( Origin gBackEnd )
				)
				( attribute "RELATIVE_PROPAGATION_DELAY" "0.00 MIL,700.00 MIL"
					( Parent
						( matchGroupRef "@crescent_city_bb_fab1_lib.crescent_city_bb_fab1(sch_1):\MG_DDR_NEAR_DIMM-CLK1_CLS_DDR_H_CAC-CLKS\" )
					)
					( Units "uMatchProp" "ns" 1.000000)
					( Status sCSetFlattened )
					( Origin gBackEnd )
				)
				( attribute "RELATIVE_PROPAGATION_DELAY_SCOPE" "G"
					( Parent
						( matchGroupRef "@baseboard_fab2_lib.baseboard_fab2(sch_1):\MG_DDR_CMD_NEAR_DIMM_NG_DDR_H_DLL_5\" )
					)
					( Status sCSetFlattened )
					( Origin gBackEnd )
				)
				( attribute "RELATIVE_PROPAGATION_DELAY" "0.00 MIL,25.00 MIL"
					( Parent
						( matchGroupRef "@baseboard_fab2_lib.baseboard_fab2(sch_1):\MG_DDR_CMD_NEAR_DIMM_NG_DDR_H_DLL_5\" )
					)
					( Units "uMatchProp" "ns" 1.000000)
					( Status sCSetFlattened )
					( Origin gBackEnd )
				)
			)
			( pinPair "@baseboard_fab2_lib.baseboard_fab2(sch_1):\PP3575\"
				( pinRef "@baseboard_fab2_lib.baseboard_fab2(sch_1):page58_i172:DDR1_PAR" )
				( pinRef "@baseboard_fab2_lib.baseboard_fab2(sch_1):page79_i111:PAR" )
				( attribute "RELATIVE_PROPAGATION_DELAY_SCOPE" "G"
					( Parent
						( matchGroupRef "@crescent_city_bb_fab1_lib.crescent_city_bb_fab1(sch_1):\MG_DDR_FAR_DIMM-CLK0_CLS_DDR_H_CAC-CLKS\" )
					)
					( Status sCSetFlattened )
					( Origin gBackEnd )
				)
				( attribute "RELATIVE_PROPAGATION_DELAY" "0.00 MIL,700.00 MIL"
					( Parent
						( matchGroupRef "@crescent_city_bb_fab1_lib.crescent_city_bb_fab1(sch_1):\MG_DDR_FAR_DIMM-CLK0_CLS_DDR_H_CAC-CLKS\" )
					)
					( Units "uMatchProp" "ns" 1.000000)
					( Status sCSetFlattened )
					( Origin gBackEnd )
				)
				( attribute "RELATIVE_PROPAGATION_DELAY_SCOPE" "G"
					( Parent
						( matchGroupRef "@baseboard_fab2_lib.baseboard_fab2(sch_1):\MG_DDR_FAR_DIMM_CMD_NG_DDR_H_DLL_6\" )
					)
					( Status sCSetFlattened )
					( Origin gBackEnd )
				)
				( attribute "RELATIVE_PROPAGATION_DELAY" "0.00 MIL,25.00 MIL"
					( Parent
						( matchGroupRef "@baseboard_fab2_lib.baseboard_fab2(sch_1):\MG_DDR_FAR_DIMM_CMD_NG_DDR_H_DLL_6\" )
					)
					( Units "uMatchProp" "ns" 1.000000)
					( Status sCSetFlattened )
					( Origin gBackEnd )
				)
			)
			( pinPair "@baseboard_fab2_lib.baseboard_fab2(sch_1):\PP3576\"
				( pinRef "@baseboard_fab2_lib.baseboard_fab2(sch_1):page80_i24:PAR" )
				( pinRef "@baseboard_fab2_lib.baseboard_fab2(sch_1):page58_i172:DDR1_PAR" )
				( attribute "RELATIVE_PROPAGATION_DELAY_SCOPE" "G"
					( Parent
						( matchGroupRef "@crescent_city_bb_fab1_lib.crescent_city_bb_fab1(sch_1):\MG_DDR_NEAR_DIMM-CLK1_CLS_DDR_H_CAC-CLKS\" )
					)
					( Status sCSetFlattened )
					( Origin gBackEnd )
				)
				( attribute "RELATIVE_PROPAGATION_DELAY" "0.00 MIL,700.00 MIL"
					( Parent
						( matchGroupRef "@crescent_city_bb_fab1_lib.crescent_city_bb_fab1(sch_1):\MG_DDR_NEAR_DIMM-CLK1_CLS_DDR_H_CAC-CLKS\" )
					)
					( Units "uMatchProp" "ns" 1.000000)
					( Status sCSetFlattened )
					( Origin gBackEnd )
				)
				( attribute "RELATIVE_PROPAGATION_DELAY_SCOPE" "G"
					( Parent
						( matchGroupRef "@baseboard_fab2_lib.baseboard_fab2(sch_1):\MG_DDR_CMD_NEAR_DIMM_NG_DDR_H_DLL_6\" )
					)
					( Status sCSetFlattened )
					( Origin gBackEnd )
				)
				( attribute "RELATIVE_PROPAGATION_DELAY" "0.00 MIL,25.00 MIL"
					( Parent
						( matchGroupRef "@baseboard_fab2_lib.baseboard_fab2(sch_1):\MG_DDR_CMD_NEAR_DIMM_NG_DDR_H_DLL_6\" )
					)
					( Units "uMatchProp" "ns" 1.000000)
					( Status sCSetFlattened )
					( Origin gBackEnd )
				)
			)
			( pinPair "@baseboard_fab2_lib.baseboard_fab2(sch_1):\PP3571\"
				( pinRef "@baseboard_fab2_lib.baseboard_fab2(sch_1):page58_i172:DDR1_MA(1)" )
				( pinRef "@baseboard_fab2_lib.baseboard_fab2(sch_1):page79_i111:A1" )
				( attribute "RELATIVE_PROPAGATION_DELAY_SCOPE" "G"
					( Parent
						( matchGroupRef "@crescent_city_bb_fab1_lib.crescent_city_bb_fab1(sch_1):\MG_DDR_FAR_DIMM-CLK0_CLS_DDR_H_CAC-CLKS\" )
					)
					( Status sCSetFlattened )
					( Origin gBackEnd )
				)
				( attribute "RELATIVE_PROPAGATION_DELAY" "0.00 MIL,700.00 MIL"
					( Parent
						( matchGroupRef "@crescent_city_bb_fab1_lib.crescent_city_bb_fab1(sch_1):\MG_DDR_FAR_DIMM-CLK0_CLS_DDR_H_CAC-CLKS\" )
					)
					( Units "uMatchProp" "ns" 1.000000)
					( Status sCSetFlattened )
					( Origin gBackEnd )
				)
				( attribute "RELATIVE_PROPAGATION_DELAY_SCOPE" "G"
					( Parent
						( matchGroupRef "@baseboard_fab2_lib.baseboard_fab2(sch_1):\MG_DDR_FAR_DIMM_CMD_NG_DDR_H_DLL_7\" )
					)
					( Status sCSetFlattened )
					( Origin gBackEnd )
				)
				( attribute "RELATIVE_PROPAGATION_DELAY" "0.00 MIL,25.00 MIL"
					( Parent
						( matchGroupRef "@baseboard_fab2_lib.baseboard_fab2(sch_1):\MG_DDR_FAR_DIMM_CMD_NG_DDR_H_DLL_7\" )
					)
					( Units "uMatchProp" "ns" 1.000000)
					( Status sCSetFlattened )
					( Origin gBackEnd )
				)
			)
			( pinPair "@baseboard_fab2_lib.baseboard_fab2(sch_1):\PP3572\"
				( pinRef "@baseboard_fab2_lib.baseboard_fab2(sch_1):page80_i24:A1" )
				( pinRef "@baseboard_fab2_lib.baseboard_fab2(sch_1):page58_i172:DDR1_MA(1)" )
				( attribute "RELATIVE_PROPAGATION_DELAY_SCOPE" "G"
					( Parent
						( matchGroupRef "@crescent_city_bb_fab1_lib.crescent_city_bb_fab1(sch_1):\MG_DDR_NEAR_DIMM-CLK1_CLS_DDR_H_CAC-CLKS\" )
					)
					( Status sCSetFlattened )
					( Origin gBackEnd )
				)
				( attribute "RELATIVE_PROPAGATION_DELAY" "0.00 MIL,700.00 MIL"
					( Parent
						( matchGroupRef "@crescent_city_bb_fab1_lib.crescent_city_bb_fab1(sch_1):\MG_DDR_NEAR_DIMM-CLK1_CLS_DDR_H_CAC-CLKS\" )
					)
					( Units "uMatchProp" "ns" 1.000000)
					( Status sCSetFlattened )
					( Origin gBackEnd )
				)
				( attribute "RELATIVE_PROPAGATION_DELAY_SCOPE" "G"
					( Parent
						( matchGroupRef "@baseboard_fab2_lib.baseboard_fab2(sch_1):\MG_DDR_CMD_NEAR_DIMM_NG_DDR_H_DLL_7\" )
					)
					( Status sCSetFlattened )
					( Origin gBackEnd )
				)
				( attribute "RELATIVE_PROPAGATION_DELAY" "0.00 MIL,25.00 MIL"
					( Parent
						( matchGroupRef "@baseboard_fab2_lib.baseboard_fab2(sch_1):\MG_DDR_CMD_NEAR_DIMM_NG_DDR_H_DLL_7\" )
					)
					( Units "uMatchProp" "ns" 1.000000)
					( Status sCSetFlattened )
					( Origin gBackEnd )
				)
			)
			( pinPair "@baseboard_fab2_lib.baseboard_fab2(sch_1):\PP3573\"
				( pinRef "@baseboard_fab2_lib.baseboard_fab2(sch_1):page58_i172:DDR1_MA(3)" )
				( pinRef "@baseboard_fab2_lib.baseboard_fab2(sch_1):page79_i111:A3" )
				( attribute "RELATIVE_PROPAGATION_DELAY_SCOPE" "G"
					( Parent
						( matchGroupRef "@crescent_city_bb_fab1_lib.crescent_city_bb_fab1(sch_1):\MG_DDR_FAR_DIMM-CLK0_CLS_DDR_H_CAC-CLKS\" )
					)
					( Status sCSetFlattened )
					( Origin gBackEnd )
				)
				( attribute "RELATIVE_PROPAGATION_DELAY" "0.00 MIL,700.00 MIL"
					( Parent
						( matchGroupRef "@crescent_city_bb_fab1_lib.crescent_city_bb_fab1(sch_1):\MG_DDR_FAR_DIMM-CLK0_CLS_DDR_H_CAC-CLKS\" )
					)
					( Units "uMatchProp" "ns" 1.000000)
					( Status sCSetFlattened )
					( Origin gBackEnd )
				)
				( attribute "RELATIVE_PROPAGATION_DELAY_SCOPE" "G"
					( Parent
						( matchGroupRef "@baseboard_fab2_lib.baseboard_fab2(sch_1):\MG_DDR_FAR_DIMM_CMD_NG_DDR_H_DLL_7\" )
					)
					( Status sCSetFlattened )
					( Origin gBackEnd )
				)
				( attribute "RELATIVE_PROPAGATION_DELAY" "0.00 MIL,25.00 MIL"
					( Parent
						( matchGroupRef "@baseboard_fab2_lib.baseboard_fab2(sch_1):\MG_DDR_FAR_DIMM_CMD_NG_DDR_H_DLL_7\" )
					)
					( Units "uMatchProp" "ns" 1.000000)
					( Status sCSetFlattened )
					( Origin gBackEnd )
				)
			)
			( pinPair "@baseboard_fab2_lib.baseboard_fab2(sch_1):\PP3574\"
				( pinRef "@baseboard_fab2_lib.baseboard_fab2(sch_1):page80_i24:A3" )
				( pinRef "@baseboard_fab2_lib.baseboard_fab2(sch_1):page58_i172:DDR1_MA(3)" )
				( attribute "RELATIVE_PROPAGATION_DELAY_SCOPE" "G"
					( Parent
						( matchGroupRef "@crescent_city_bb_fab1_lib.crescent_city_bb_fab1(sch_1):\MG_DDR_NEAR_DIMM-CLK1_CLS_DDR_H_CAC-CLKS\" )
					)
					( Status sCSetFlattened )
					( Origin gBackEnd )
				)
				( attribute "RELATIVE_PROPAGATION_DELAY" "0.00 MIL,700.00 MIL"
					( Parent
						( matchGroupRef "@crescent_city_bb_fab1_lib.crescent_city_bb_fab1(sch_1):\MG_DDR_NEAR_DIMM-CLK1_CLS_DDR_H_CAC-CLKS\" )
					)
					( Units "uMatchProp" "ns" 1.000000)
					( Status sCSetFlattened )
					( Origin gBackEnd )
				)
				( attribute "RELATIVE_PROPAGATION_DELAY_SCOPE" "G"
					( Parent
						( matchGroupRef "@baseboard_fab2_lib.baseboard_fab2(sch_1):\MG_DDR_CMD_NEAR_DIMM_NG_DDR_H_DLL_7\" )
					)
					( Status sCSetFlattened )
					( Origin gBackEnd )
				)
				( attribute "RELATIVE_PROPAGATION_DELAY" "0.00 MIL,25.00 MIL"
					( Parent
						( matchGroupRef "@baseboard_fab2_lib.baseboard_fab2(sch_1):\MG_DDR_CMD_NEAR_DIMM_NG_DDR_H_DLL_7\" )
					)
					( Units "uMatchProp" "ns" 1.000000)
					( Status sCSetFlattened )
					( Origin gBackEnd )
				)
			)
			( pinPair "@baseboard_fab2_lib.baseboard_fab2(sch_1):\PP3567\"
				( pinRef "@baseboard_fab2_lib.baseboard_fab2(sch_1):page58_i172:DDR1_MA(2)" )
				( pinRef "@baseboard_fab2_lib.baseboard_fab2(sch_1):page79_i111:A2" )
				( attribute "RELATIVE_PROPAGATION_DELAY_SCOPE" "G"
					( Parent
						( matchGroupRef "@crescent_city_bb_fab1_lib.crescent_city_bb_fab1(sch_1):\MG_DDR_FAR_DIMM-CLK0_CLS_DDR_H_CAC-CLKS\" )
					)
					( Status sCSetFlattened )
					( Origin gBackEnd )
				)
				( attribute "RELATIVE_PROPAGATION_DELAY" "0.00 MIL,700.00 MIL"
					( Parent
						( matchGroupRef "@crescent_city_bb_fab1_lib.crescent_city_bb_fab1(sch_1):\MG_DDR_FAR_DIMM-CLK0_CLS_DDR_H_CAC-CLKS\" )
					)
					( Units "uMatchProp" "ns" 1.000000)
					( Status sCSetFlattened )
					( Origin gBackEnd )
				)
				( attribute "RELATIVE_PROPAGATION_DELAY_SCOPE" "G"
					( Parent
						( matchGroupRef "@baseboard_fab2_lib.baseboard_fab2(sch_1):\MG_DDR_FAR_DIMM_CMD_NG_DDR_H_DLL_8\" )
					)
					( Status sCSetFlattened )
					( Origin gBackEnd )
				)
				( attribute "RELATIVE_PROPAGATION_DELAY" "0.00 MIL,25.00 MIL"
					( Parent
						( matchGroupRef "@baseboard_fab2_lib.baseboard_fab2(sch_1):\MG_DDR_FAR_DIMM_CMD_NG_DDR_H_DLL_8\" )
					)
					( Units "uMatchProp" "ns" 1.000000)
					( Status sCSetFlattened )
					( Origin gBackEnd )
				)
			)
			( pinPair "@baseboard_fab2_lib.baseboard_fab2(sch_1):\PP3568\"
				( pinRef "@baseboard_fab2_lib.baseboard_fab2(sch_1):page80_i24:A2" )
				( pinRef "@baseboard_fab2_lib.baseboard_fab2(sch_1):page58_i172:DDR1_MA(2)" )
				( attribute "RELATIVE_PROPAGATION_DELAY_SCOPE" "G"
					( Parent
						( matchGroupRef "@crescent_city_bb_fab1_lib.crescent_city_bb_fab1(sch_1):\MG_DDR_NEAR_DIMM-CLK1_CLS_DDR_H_CAC-CLKS\" )
					)
					( Status sCSetFlattened )
					( Origin gBackEnd )
				)
				( attribute "RELATIVE_PROPAGATION_DELAY" "0.00 MIL,700.00 MIL"
					( Parent
						( matchGroupRef "@crescent_city_bb_fab1_lib.crescent_city_bb_fab1(sch_1):\MG_DDR_NEAR_DIMM-CLK1_CLS_DDR_H_CAC-CLKS\" )
					)
					( Units "uMatchProp" "ns" 1.000000)
					( Status sCSetFlattened )
					( Origin gBackEnd )
				)
				( attribute "RELATIVE_PROPAGATION_DELAY_SCOPE" "G"
					( Parent
						( matchGroupRef "@baseboard_fab2_lib.baseboard_fab2(sch_1):\MG_DDR_CMD_NEAR_DIMM_NG_DDR_H_DLL_8\" )
					)
					( Status sCSetFlattened )
					( Origin gBackEnd )
				)
				( attribute "RELATIVE_PROPAGATION_DELAY" "0.00 MIL,25.00 MIL"
					( Parent
						( matchGroupRef "@baseboard_fab2_lib.baseboard_fab2(sch_1):\MG_DDR_CMD_NEAR_DIMM_NG_DDR_H_DLL_8\" )
					)
					( Units "uMatchProp" "ns" 1.000000)
					( Status sCSetFlattened )
					( Origin gBackEnd )
				)
			)
			( pinPair "@baseboard_fab2_lib.baseboard_fab2(sch_1):\PP3569\"
				( pinRef "@baseboard_fab2_lib.baseboard_fab2(sch_1):page58_i172:DDR1_MA(4)" )
				( pinRef "@baseboard_fab2_lib.baseboard_fab2(sch_1):page79_i111:A4" )
				( attribute "RELATIVE_PROPAGATION_DELAY_SCOPE" "G"
					( Parent
						( matchGroupRef "@crescent_city_bb_fab1_lib.crescent_city_bb_fab1(sch_1):\MG_DDR_FAR_DIMM-CLK0_CLS_DDR_H_CAC-CLKS\" )
					)
					( Status sCSetFlattened )
					( Origin gBackEnd )
				)
				( attribute "RELATIVE_PROPAGATION_DELAY" "0.00 MIL,700.00 MIL"
					( Parent
						( matchGroupRef "@crescent_city_bb_fab1_lib.crescent_city_bb_fab1(sch_1):\MG_DDR_FAR_DIMM-CLK0_CLS_DDR_H_CAC-CLKS\" )
					)
					( Units "uMatchProp" "ns" 1.000000)
					( Status sCSetFlattened )
					( Origin gBackEnd )
				)
				( attribute "RELATIVE_PROPAGATION_DELAY_SCOPE" "G"
					( Parent
						( matchGroupRef "@baseboard_fab2_lib.baseboard_fab2(sch_1):\MG_DDR_FAR_DIMM_CMD_NG_DDR_H_DLL_8\" )
					)
					( Status sCSetFlattened )
					( Origin gBackEnd )
				)
				( attribute "RELATIVE_PROPAGATION_DELAY" "0.00 MIL,25.00 MIL"
					( Parent
						( matchGroupRef "@baseboard_fab2_lib.baseboard_fab2(sch_1):\MG_DDR_FAR_DIMM_CMD_NG_DDR_H_DLL_8\" )
					)
					( Units "uMatchProp" "ns" 1.000000)
					( Status sCSetFlattened )
					( Origin gBackEnd )
				)
			)
			( pinPair "@baseboard_fab2_lib.baseboard_fab2(sch_1):\PP3570\"
				( pinRef "@baseboard_fab2_lib.baseboard_fab2(sch_1):page80_i24:A4" )
				( pinRef "@baseboard_fab2_lib.baseboard_fab2(sch_1):page58_i172:DDR1_MA(4)" )
				( attribute "RELATIVE_PROPAGATION_DELAY_SCOPE" "G"
					( Parent
						( matchGroupRef "@crescent_city_bb_fab1_lib.crescent_city_bb_fab1(sch_1):\MG_DDR_NEAR_DIMM-CLK1_CLS_DDR_H_CAC-CLKS\" )
					)
					( Status sCSetFlattened )
					( Origin gBackEnd )
				)
				( attribute "RELATIVE_PROPAGATION_DELAY" "0.00 MIL,700.00 MIL"
					( Parent
						( matchGroupRef "@crescent_city_bb_fab1_lib.crescent_city_bb_fab1(sch_1):\MG_DDR_NEAR_DIMM-CLK1_CLS_DDR_H_CAC-CLKS\" )
					)
					( Units "uMatchProp" "ns" 1.000000)
					( Status sCSetFlattened )
					( Origin gBackEnd )
				)
				( attribute "RELATIVE_PROPAGATION_DELAY_SCOPE" "G"
					( Parent
						( matchGroupRef "@baseboard_fab2_lib.baseboard_fab2(sch_1):\MG_DDR_CMD_NEAR_DIMM_NG_DDR_H_DLL_8\" )
					)
					( Status sCSetFlattened )
					( Origin gBackEnd )
				)
				( attribute "RELATIVE_PROPAGATION_DELAY" "0.00 MIL,25.00 MIL"
					( Parent
						( matchGroupRef "@baseboard_fab2_lib.baseboard_fab2(sch_1):\MG_DDR_CMD_NEAR_DIMM_NG_DDR_H_DLL_8\" )
					)
					( Units "uMatchProp" "ns" 1.000000)
					( Status sCSetFlattened )
					( Origin gBackEnd )
				)
			)
			( pinPair "@baseboard_fab2_lib.baseboard_fab2(sch_1):\PP3563\"
				( pinRef "@baseboard_fab2_lib.baseboard_fab2(sch_1):page58_i172:DDR1_MA(5)" )
				( pinRef "@baseboard_fab2_lib.baseboard_fab2(sch_1):page79_i111:A5" )
				( attribute "RELATIVE_PROPAGATION_DELAY_SCOPE" "G"
					( Parent
						( matchGroupRef "@crescent_city_bb_fab1_lib.crescent_city_bb_fab1(sch_1):\MG_DDR_FAR_DIMM-CLK0_CLS_DDR_H_CAC-CLKS\" )
					)
					( Status sCSetFlattened )
					( Origin gBackEnd )
				)
				( attribute "RELATIVE_PROPAGATION_DELAY" "0.00 MIL,700.00 MIL"
					( Parent
						( matchGroupRef "@crescent_city_bb_fab1_lib.crescent_city_bb_fab1(sch_1):\MG_DDR_FAR_DIMM-CLK0_CLS_DDR_H_CAC-CLKS\" )
					)
					( Units "uMatchProp" "ns" 1.000000)
					( Status sCSetFlattened )
					( Origin gBackEnd )
				)
				( attribute "RELATIVE_PROPAGATION_DELAY_SCOPE" "G"
					( Parent
						( matchGroupRef "@baseboard_fab2_lib.baseboard_fab2(sch_1):\MG_DDR_FAR_DIMM_CMD_NG_DDR_H_DLL_9\" )
					)
					( Status sCSetFlattened )
					( Origin gBackEnd )
				)
				( attribute "RELATIVE_PROPAGATION_DELAY" "0.00 MIL,25.00 MIL"
					( Parent
						( matchGroupRef "@baseboard_fab2_lib.baseboard_fab2(sch_1):\MG_DDR_FAR_DIMM_CMD_NG_DDR_H_DLL_9\" )
					)
					( Units "uMatchProp" "ns" 1.000000)
					( Status sCSetFlattened )
					( Origin gBackEnd )
				)
			)
			( pinPair "@baseboard_fab2_lib.baseboard_fab2(sch_1):\PP3564\"
				( pinRef "@baseboard_fab2_lib.baseboard_fab2(sch_1):page80_i24:A5" )
				( pinRef "@baseboard_fab2_lib.baseboard_fab2(sch_1):page58_i172:DDR1_MA(5)" )
				( attribute "RELATIVE_PROPAGATION_DELAY_SCOPE" "G"
					( Parent
						( matchGroupRef "@crescent_city_bb_fab1_lib.crescent_city_bb_fab1(sch_1):\MG_DDR_NEAR_DIMM-CLK1_CLS_DDR_H_CAC-CLKS\" )
					)
					( Status sCSetFlattened )
					( Origin gBackEnd )
				)
				( attribute "RELATIVE_PROPAGATION_DELAY" "0.00 MIL,700.00 MIL"
					( Parent
						( matchGroupRef "@crescent_city_bb_fab1_lib.crescent_city_bb_fab1(sch_1):\MG_DDR_NEAR_DIMM-CLK1_CLS_DDR_H_CAC-CLKS\" )
					)
					( Units "uMatchProp" "ns" 1.000000)
					( Status sCSetFlattened )
					( Origin gBackEnd )
				)
				( attribute "RELATIVE_PROPAGATION_DELAY_SCOPE" "G"
					( Parent
						( matchGroupRef "@baseboard_fab2_lib.baseboard_fab2(sch_1):\MG_DDR_CMD_NEAR_DIMM_NG_DDR_H_DLL_9\" )
					)
					( Status sCSetFlattened )
					( Origin gBackEnd )
				)
				( attribute "RELATIVE_PROPAGATION_DELAY" "0.00 MIL,25.00 MIL"
					( Parent
						( matchGroupRef "@baseboard_fab2_lib.baseboard_fab2(sch_1):\MG_DDR_CMD_NEAR_DIMM_NG_DDR_H_DLL_9\" )
					)
					( Units "uMatchProp" "ns" 1.000000)
					( Status sCSetFlattened )
					( Origin gBackEnd )
				)
			)
			( pinPair "@baseboard_fab2_lib.baseboard_fab2(sch_1):\PP3565\"
				( pinRef "@baseboard_fab2_lib.baseboard_fab2(sch_1):page58_i172:DDR1_MA(6)" )
				( pinRef "@baseboard_fab2_lib.baseboard_fab2(sch_1):page79_i111:A6" )
				( attribute "RELATIVE_PROPAGATION_DELAY_SCOPE" "G"
					( Parent
						( matchGroupRef "@crescent_city_bb_fab1_lib.crescent_city_bb_fab1(sch_1):\MG_DDR_FAR_DIMM-CLK0_CLS_DDR_H_CAC-CLKS\" )
					)
					( Status sCSetFlattened )
					( Origin gBackEnd )
				)
				( attribute "RELATIVE_PROPAGATION_DELAY" "0.00 MIL,700.00 MIL"
					( Parent
						( matchGroupRef "@crescent_city_bb_fab1_lib.crescent_city_bb_fab1(sch_1):\MG_DDR_FAR_DIMM-CLK0_CLS_DDR_H_CAC-CLKS\" )
					)
					( Units "uMatchProp" "ns" 1.000000)
					( Status sCSetFlattened )
					( Origin gBackEnd )
				)
				( attribute "RELATIVE_PROPAGATION_DELAY_SCOPE" "G"
					( Parent
						( matchGroupRef "@baseboard_fab2_lib.baseboard_fab2(sch_1):\MG_DDR_FAR_DIMM_CMD_NG_DDR_H_DLL_9\" )
					)
					( Status sCSetFlattened )
					( Origin gBackEnd )
				)
				( attribute "RELATIVE_PROPAGATION_DELAY" "0.00 MIL,25.00 MIL"
					( Parent
						( matchGroupRef "@baseboard_fab2_lib.baseboard_fab2(sch_1):\MG_DDR_FAR_DIMM_CMD_NG_DDR_H_DLL_9\" )
					)
					( Units "uMatchProp" "ns" 1.000000)
					( Status sCSetFlattened )
					( Origin gBackEnd )
				)
			)
			( pinPair "@baseboard_fab2_lib.baseboard_fab2(sch_1):\PP3566\"
				( pinRef "@baseboard_fab2_lib.baseboard_fab2(sch_1):page80_i24:A6" )
				( pinRef "@baseboard_fab2_lib.baseboard_fab2(sch_1):page58_i172:DDR1_MA(6)" )
				( attribute "RELATIVE_PROPAGATION_DELAY_SCOPE" "G"
					( Parent
						( matchGroupRef "@crescent_city_bb_fab1_lib.crescent_city_bb_fab1(sch_1):\MG_DDR_NEAR_DIMM-CLK1_CLS_DDR_H_CAC-CLKS\" )
					)
					( Status sCSetFlattened )
					( Origin gBackEnd )
				)
				( attribute "RELATIVE_PROPAGATION_DELAY" "0.00 MIL,700.00 MIL"
					( Parent
						( matchGroupRef "@crescent_city_bb_fab1_lib.crescent_city_bb_fab1(sch_1):\MG_DDR_NEAR_DIMM-CLK1_CLS_DDR_H_CAC-CLKS\" )
					)
					( Units "uMatchProp" "ns" 1.000000)
					( Status sCSetFlattened )
					( Origin gBackEnd )
				)
				( attribute "RELATIVE_PROPAGATION_DELAY_SCOPE" "G"
					( Parent
						( matchGroupRef "@baseboard_fab2_lib.baseboard_fab2(sch_1):\MG_DDR_CMD_NEAR_DIMM_NG_DDR_H_DLL_9\" )
					)
					( Status sCSetFlattened )
					( Origin gBackEnd )
				)
				( attribute "RELATIVE_PROPAGATION_DELAY" "0.00 MIL,25.00 MIL"
					( Parent
						( matchGroupRef "@baseboard_fab2_lib.baseboard_fab2(sch_1):\MG_DDR_CMD_NEAR_DIMM_NG_DDR_H_DLL_9\" )
					)
					( Units "uMatchProp" "ns" 1.000000)
					( Status sCSetFlattened )
					( Origin gBackEnd )
				)
			)
			( pinPair "@baseboard_fab2_lib.baseboard_fab2(sch_1):\PP3559\"
				( pinRef "@baseboard_fab2_lib.baseboard_fab2(sch_1):page58_i172:DDR1_MA(7)" )
				( pinRef "@baseboard_fab2_lib.baseboard_fab2(sch_1):page79_i111:A7" )
				( attribute "RELATIVE_PROPAGATION_DELAY_SCOPE" "G"
					( Parent
						( matchGroupRef "@crescent_city_bb_fab1_lib.crescent_city_bb_fab1(sch_1):\MG_DDR_FAR_DIMM-CLK0_CLS_DDR_H_CAC-CLKS\" )
					)
					( Status sCSetFlattened )
					( Origin gBackEnd )
				)
				( attribute "RELATIVE_PROPAGATION_DELAY" "0.00 MIL,700.00 MIL"
					( Parent
						( matchGroupRef "@crescent_city_bb_fab1_lib.crescent_city_bb_fab1(sch_1):\MG_DDR_FAR_DIMM-CLK0_CLS_DDR_H_CAC-CLKS\" )
					)
					( Units "uMatchProp" "ns" 1.000000)
					( Status sCSetFlattened )
					( Origin gBackEnd )
				)
				( attribute "RELATIVE_PROPAGATION_DELAY_SCOPE" "G"
					( Parent
						( matchGroupRef "@baseboard_fab2_lib.baseboard_fab2(sch_1):\MG_DDR_FAR_DIMM_CMD_NG_DDR_H_DLL_10\" )
					)
					( Status sCSetFlattened )
					( Origin gBackEnd )
				)
				( attribute "RELATIVE_PROPAGATION_DELAY" "0.00 MIL,25.00 MIL"
					( Parent
						( matchGroupRef "@baseboard_fab2_lib.baseboard_fab2(sch_1):\MG_DDR_FAR_DIMM_CMD_NG_DDR_H_DLL_10\" )
					)
					( Units "uMatchProp" "ns" 1.000000)
					( Status sCSetFlattened )
					( Origin gBackEnd )
				)
			)
			( pinPair "@baseboard_fab2_lib.baseboard_fab2(sch_1):\PP3560\"
				( pinRef "@baseboard_fab2_lib.baseboard_fab2(sch_1):page80_i24:A7" )
				( pinRef "@baseboard_fab2_lib.baseboard_fab2(sch_1):page58_i172:DDR1_MA(7)" )
				( attribute "RELATIVE_PROPAGATION_DELAY_SCOPE" "G"
					( Parent
						( matchGroupRef "@crescent_city_bb_fab1_lib.crescent_city_bb_fab1(sch_1):\MG_DDR_NEAR_DIMM-CLK1_CLS_DDR_H_CAC-CLKS\" )
					)
					( Status sCSetFlattened )
					( Origin gBackEnd )
				)
				( attribute "RELATIVE_PROPAGATION_DELAY" "0.00 MIL,700.00 MIL"
					( Parent
						( matchGroupRef "@crescent_city_bb_fab1_lib.crescent_city_bb_fab1(sch_1):\MG_DDR_NEAR_DIMM-CLK1_CLS_DDR_H_CAC-CLKS\" )
					)
					( Units "uMatchProp" "ns" 1.000000)
					( Status sCSetFlattened )
					( Origin gBackEnd )
				)
				( attribute "RELATIVE_PROPAGATION_DELAY_SCOPE" "G"
					( Parent
						( matchGroupRef "@baseboard_fab2_lib.baseboard_fab2(sch_1):\MG_DDR_CMD_NEAR_DIMM_NG_DDR_H_DLL_10\" )
					)
					( Status sCSetFlattened )
					( Origin gBackEnd )
				)
				( attribute "RELATIVE_PROPAGATION_DELAY" "0.00 MIL,25.00 MIL"
					( Parent
						( matchGroupRef "@baseboard_fab2_lib.baseboard_fab2(sch_1):\MG_DDR_CMD_NEAR_DIMM_NG_DDR_H_DLL_10\" )
					)
					( Units "uMatchProp" "ns" 1.000000)
					( Status sCSetFlattened )
					( Origin gBackEnd )
				)
			)
			( pinPair "@baseboard_fab2_lib.baseboard_fab2(sch_1):\PP3561\"
				( pinRef "@baseboard_fab2_lib.baseboard_fab2(sch_1):page58_i172:DDR1_MA(8)" )
				( pinRef "@baseboard_fab2_lib.baseboard_fab2(sch_1):page79_i111:A8" )
				( attribute "RELATIVE_PROPAGATION_DELAY_SCOPE" "G"
					( Parent
						( matchGroupRef "@crescent_city_bb_fab1_lib.crescent_city_bb_fab1(sch_1):\MG_DDR_FAR_DIMM-CLK0_CLS_DDR_H_CAC-CLKS\" )
					)
					( Status sCSetFlattened )
					( Origin gBackEnd )
				)
				( attribute "RELATIVE_PROPAGATION_DELAY" "0.00 MIL,700.00 MIL"
					( Parent
						( matchGroupRef "@crescent_city_bb_fab1_lib.crescent_city_bb_fab1(sch_1):\MG_DDR_FAR_DIMM-CLK0_CLS_DDR_H_CAC-CLKS\" )
					)
					( Units "uMatchProp" "ns" 1.000000)
					( Status sCSetFlattened )
					( Origin gBackEnd )
				)
				( attribute "RELATIVE_PROPAGATION_DELAY_SCOPE" "G"
					( Parent
						( matchGroupRef "@baseboard_fab2_lib.baseboard_fab2(sch_1):\MG_DDR_FAR_DIMM_CMD_NG_DDR_H_DLL_10\" )
					)
					( Status sCSetFlattened )
					( Origin gBackEnd )
				)
				( attribute "RELATIVE_PROPAGATION_DELAY" "0.00 MIL,25.00 MIL"
					( Parent
						( matchGroupRef "@baseboard_fab2_lib.baseboard_fab2(sch_1):\MG_DDR_FAR_DIMM_CMD_NG_DDR_H_DLL_10\" )
					)
					( Units "uMatchProp" "ns" 1.000000)
					( Status sCSetFlattened )
					( Origin gBackEnd )
				)
			)
			( pinPair "@baseboard_fab2_lib.baseboard_fab2(sch_1):\PP3562\"
				( pinRef "@baseboard_fab2_lib.baseboard_fab2(sch_1):page80_i24:A8" )
				( pinRef "@baseboard_fab2_lib.baseboard_fab2(sch_1):page58_i172:DDR1_MA(8)" )
				( attribute "RELATIVE_PROPAGATION_DELAY_SCOPE" "G"
					( Parent
						( matchGroupRef "@crescent_city_bb_fab1_lib.crescent_city_bb_fab1(sch_1):\MG_DDR_NEAR_DIMM-CLK1_CLS_DDR_H_CAC-CLKS\" )
					)
					( Status sCSetFlattened )
					( Origin gBackEnd )
				)
				( attribute "RELATIVE_PROPAGATION_DELAY" "0.00 MIL,700.00 MIL"
					( Parent
						( matchGroupRef "@crescent_city_bb_fab1_lib.crescent_city_bb_fab1(sch_1):\MG_DDR_NEAR_DIMM-CLK1_CLS_DDR_H_CAC-CLKS\" )
					)
					( Units "uMatchProp" "ns" 1.000000)
					( Status sCSetFlattened )
					( Origin gBackEnd )
				)
				( attribute "RELATIVE_PROPAGATION_DELAY_SCOPE" "G"
					( Parent
						( matchGroupRef "@baseboard_fab2_lib.baseboard_fab2(sch_1):\MG_DDR_CMD_NEAR_DIMM_NG_DDR_H_DLL_10\" )
					)
					( Status sCSetFlattened )
					( Origin gBackEnd )
				)
				( attribute "RELATIVE_PROPAGATION_DELAY" "0.00 MIL,25.00 MIL"
					( Parent
						( matchGroupRef "@baseboard_fab2_lib.baseboard_fab2(sch_1):\MG_DDR_CMD_NEAR_DIMM_NG_DDR_H_DLL_10\" )
					)
					( Units "uMatchProp" "ns" 1.000000)
					( Status sCSetFlattened )
					( Origin gBackEnd )
				)
			)
			( pinPair "@baseboard_fab2_lib.baseboard_fab2(sch_1):\PP3555\"
				( pinRef "@baseboard_fab2_lib.baseboard_fab2(sch_1):page58_i172:DDR1_MA(9)" )
				( pinRef "@baseboard_fab2_lib.baseboard_fab2(sch_1):page79_i111:A9" )
				( attribute "RELATIVE_PROPAGATION_DELAY_SCOPE" "G"
					( Parent
						( matchGroupRef "@crescent_city_bb_fab1_lib.crescent_city_bb_fab1(sch_1):\MG_DDR_FAR_DIMM-CLK0_CLS_DDR_H_CAC-CLKS\" )
					)
					( Status sCSetFlattened )
					( Origin gBackEnd )
				)
				( attribute "RELATIVE_PROPAGATION_DELAY" "0.00 MIL,700.00 MIL"
					( Parent
						( matchGroupRef "@crescent_city_bb_fab1_lib.crescent_city_bb_fab1(sch_1):\MG_DDR_FAR_DIMM-CLK0_CLS_DDR_H_CAC-CLKS\" )
					)
					( Units "uMatchProp" "ns" 1.000000)
					( Status sCSetFlattened )
					( Origin gBackEnd )
				)
				( attribute "RELATIVE_PROPAGATION_DELAY_SCOPE" "G"
					( Parent
						( matchGroupRef "@baseboard_fab2_lib.baseboard_fab2(sch_1):\MG_DDR_FAR_DIMM_CMD_NG_DDR_H_DLL_11\" )
					)
					( Status sCSetFlattened )
					( Origin gBackEnd )
				)
				( attribute "RELATIVE_PROPAGATION_DELAY" "0.00 MIL,25.00 MIL"
					( Parent
						( matchGroupRef "@baseboard_fab2_lib.baseboard_fab2(sch_1):\MG_DDR_FAR_DIMM_CMD_NG_DDR_H_DLL_11\" )
					)
					( Units "uMatchProp" "ns" 1.000000)
					( Status sCSetFlattened )
					( Origin gBackEnd )
				)
			)
			( pinPair "@baseboard_fab2_lib.baseboard_fab2(sch_1):\PP3556\"
				( pinRef "@baseboard_fab2_lib.baseboard_fab2(sch_1):page80_i24:A9" )
				( pinRef "@baseboard_fab2_lib.baseboard_fab2(sch_1):page58_i172:DDR1_MA(9)" )
				( attribute "RELATIVE_PROPAGATION_DELAY_SCOPE" "G"
					( Parent
						( matchGroupRef "@crescent_city_bb_fab1_lib.crescent_city_bb_fab1(sch_1):\MG_DDR_NEAR_DIMM-CLK1_CLS_DDR_H_CAC-CLKS\" )
					)
					( Status sCSetFlattened )
					( Origin gBackEnd )
				)
				( attribute "RELATIVE_PROPAGATION_DELAY" "0.00 MIL,700.00 MIL"
					( Parent
						( matchGroupRef "@crescent_city_bb_fab1_lib.crescent_city_bb_fab1(sch_1):\MG_DDR_NEAR_DIMM-CLK1_CLS_DDR_H_CAC-CLKS\" )
					)
					( Units "uMatchProp" "ns" 1.000000)
					( Status sCSetFlattened )
					( Origin gBackEnd )
				)
				( attribute "RELATIVE_PROPAGATION_DELAY_SCOPE" "G"
					( Parent
						( matchGroupRef "@baseboard_fab2_lib.baseboard_fab2(sch_1):\MG_DDR_CMD_NEAR_DIMM_NG_DDR_H_DLL_11\" )
					)
					( Status sCSetFlattened )
					( Origin gBackEnd )
				)
				( attribute "RELATIVE_PROPAGATION_DELAY" "0.00 MIL,25.00 MIL"
					( Parent
						( matchGroupRef "@baseboard_fab2_lib.baseboard_fab2(sch_1):\MG_DDR_CMD_NEAR_DIMM_NG_DDR_H_DLL_11\" )
					)
					( Units "uMatchProp" "ns" 1.000000)
					( Status sCSetFlattened )
					( Origin gBackEnd )
				)
			)
			( pinPair "@baseboard_fab2_lib.baseboard_fab2(sch_1):\PP3557\"
				( pinRef "@baseboard_fab2_lib.baseboard_fab2(sch_1):page58_i172:DDR1_MA(12)" )
				( pinRef "@baseboard_fab2_lib.baseboard_fab2(sch_1):page79_i111:A12" )
				( attribute "RELATIVE_PROPAGATION_DELAY_SCOPE" "G"
					( Parent
						( matchGroupRef "@crescent_city_bb_fab1_lib.crescent_city_bb_fab1(sch_1):\MG_DDR_FAR_DIMM-CLK0_CLS_DDR_H_CAC-CLKS\" )
					)
					( Status sCSetFlattened )
					( Origin gBackEnd )
				)
				( attribute "RELATIVE_PROPAGATION_DELAY" "0.00 MIL,700.00 MIL"
					( Parent
						( matchGroupRef "@crescent_city_bb_fab1_lib.crescent_city_bb_fab1(sch_1):\MG_DDR_FAR_DIMM-CLK0_CLS_DDR_H_CAC-CLKS\" )
					)
					( Units "uMatchProp" "ns" 1.000000)
					( Status sCSetFlattened )
					( Origin gBackEnd )
				)
				( attribute "RELATIVE_PROPAGATION_DELAY_SCOPE" "G"
					( Parent
						( matchGroupRef "@baseboard_fab2_lib.baseboard_fab2(sch_1):\MG_DDR_FAR_DIMM_CMD_NG_DDR_H_DLL_11\" )
					)
					( Status sCSetFlattened )
					( Origin gBackEnd )
				)
				( attribute "RELATIVE_PROPAGATION_DELAY" "0.00 MIL,25.00 MIL"
					( Parent
						( matchGroupRef "@baseboard_fab2_lib.baseboard_fab2(sch_1):\MG_DDR_FAR_DIMM_CMD_NG_DDR_H_DLL_11\" )
					)
					( Units "uMatchProp" "ns" 1.000000)
					( Status sCSetFlattened )
					( Origin gBackEnd )
				)
			)
			( pinPair "@baseboard_fab2_lib.baseboard_fab2(sch_1):\PP3558\"
				( pinRef "@baseboard_fab2_lib.baseboard_fab2(sch_1):page80_i24:A12" )
				( pinRef "@baseboard_fab2_lib.baseboard_fab2(sch_1):page58_i172:DDR1_MA(12)" )
				( attribute "RELATIVE_PROPAGATION_DELAY_SCOPE" "G"
					( Parent
						( matchGroupRef "@crescent_city_bb_fab1_lib.crescent_city_bb_fab1(sch_1):\MG_DDR_NEAR_DIMM-CLK1_CLS_DDR_H_CAC-CLKS\" )
					)
					( Status sCSetFlattened )
					( Origin gBackEnd )
				)
				( attribute "RELATIVE_PROPAGATION_DELAY" "0.00 MIL,700.00 MIL"
					( Parent
						( matchGroupRef "@crescent_city_bb_fab1_lib.crescent_city_bb_fab1(sch_1):\MG_DDR_NEAR_DIMM-CLK1_CLS_DDR_H_CAC-CLKS\" )
					)
					( Units "uMatchProp" "ns" 1.000000)
					( Status sCSetFlattened )
					( Origin gBackEnd )
				)
				( attribute "RELATIVE_PROPAGATION_DELAY_SCOPE" "G"
					( Parent
						( matchGroupRef "@baseboard_fab2_lib.baseboard_fab2(sch_1):\MG_DDR_CMD_NEAR_DIMM_NG_DDR_H_DLL_11\" )
					)
					( Status sCSetFlattened )
					( Origin gBackEnd )
				)
				( attribute "RELATIVE_PROPAGATION_DELAY" "0.00 MIL,25.00 MIL"
					( Parent
						( matchGroupRef "@baseboard_fab2_lib.baseboard_fab2(sch_1):\MG_DDR_CMD_NEAR_DIMM_NG_DDR_H_DLL_11\" )
					)
					( Units "uMatchProp" "ns" 1.000000)
					( Status sCSetFlattened )
					( Origin gBackEnd )
				)
			)
			( pinPair "@baseboard_fab2_lib.baseboard_fab2(sch_1):\PP3551\"
				( pinRef "@baseboard_fab2_lib.baseboard_fab2(sch_1):page58_i172:DDR1_BG(1)" )
				( pinRef "@baseboard_fab2_lib.baseboard_fab2(sch_1):page79_i111:BG(1)" )
				( attribute "RELATIVE_PROPAGATION_DELAY_SCOPE" "G"
					( Parent
						( matchGroupRef "@crescent_city_bb_fab1_lib.crescent_city_bb_fab1(sch_1):\MG_DDR_FAR_DIMM-CLK0_CLS_DDR_H_CAC-CLKS\" )
					)
					( Status sCSetFlattened )
					( Origin gBackEnd )
				)
				( attribute "RELATIVE_PROPAGATION_DELAY" "0.00 MIL,700.00 MIL"
					( Parent
						( matchGroupRef "@crescent_city_bb_fab1_lib.crescent_city_bb_fab1(sch_1):\MG_DDR_FAR_DIMM-CLK0_CLS_DDR_H_CAC-CLKS\" )
					)
					( Units "uMatchProp" "ns" 1.000000)
					( Status sCSetFlattened )
					( Origin gBackEnd )
				)
				( attribute "RELATIVE_PROPAGATION_DELAY_SCOPE" "G"
					( Parent
						( matchGroupRef "@baseboard_fab2_lib.baseboard_fab2(sch_1):\MG_DDR_FAR_DIMM_CMD_NG_DDR_H_DLL_12\" )
					)
					( Status sCSetFlattened )
					( Origin gBackEnd )
				)
				( attribute "RELATIVE_PROPAGATION_DELAY" "0.00 MIL,25.00 MIL"
					( Parent
						( matchGroupRef "@baseboard_fab2_lib.baseboard_fab2(sch_1):\MG_DDR_FAR_DIMM_CMD_NG_DDR_H_DLL_12\" )
					)
					( Units "uMatchProp" "ns" 1.000000)
					( Status sCSetFlattened )
					( Origin gBackEnd )
				)
			)
			( pinPair "@baseboard_fab2_lib.baseboard_fab2(sch_1):\PP3552\"
				( pinRef "@baseboard_fab2_lib.baseboard_fab2(sch_1):page80_i24:BG(1)" )
				( pinRef "@baseboard_fab2_lib.baseboard_fab2(sch_1):page58_i172:DDR1_BG(1)" )
				( attribute "RELATIVE_PROPAGATION_DELAY_SCOPE" "G"
					( Parent
						( matchGroupRef "@crescent_city_bb_fab1_lib.crescent_city_bb_fab1(sch_1):\MG_DDR_NEAR_DIMM-CLK1_CLS_DDR_H_CAC-CLKS\" )
					)
					( Status sCSetFlattened )
					( Origin gBackEnd )
				)
				( attribute "RELATIVE_PROPAGATION_DELAY" "0.00 MIL,700.00 MIL"
					( Parent
						( matchGroupRef "@crescent_city_bb_fab1_lib.crescent_city_bb_fab1(sch_1):\MG_DDR_NEAR_DIMM-CLK1_CLS_DDR_H_CAC-CLKS\" )
					)
					( Units "uMatchProp" "ns" 1.000000)
					( Status sCSetFlattened )
					( Origin gBackEnd )
				)
				( attribute "RELATIVE_PROPAGATION_DELAY_SCOPE" "G"
					( Parent
						( matchGroupRef "@baseboard_fab2_lib.baseboard_fab2(sch_1):\MG_DDR_CMD_NEAR_DIMM_NG_DDR_H_DLL_12\" )
					)
					( Status sCSetFlattened )
					( Origin gBackEnd )
				)
				( attribute "RELATIVE_PROPAGATION_DELAY" "0.00 MIL,25.00 MIL"
					( Parent
						( matchGroupRef "@baseboard_fab2_lib.baseboard_fab2(sch_1):\MG_DDR_CMD_NEAR_DIMM_NG_DDR_H_DLL_12\" )
					)
					( Units "uMatchProp" "ns" 1.000000)
					( Status sCSetFlattened )
					( Origin gBackEnd )
				)
			)
			( pinPair "@baseboard_fab2_lib.baseboard_fab2(sch_1):\PP3553\"
				( pinRef "@baseboard_fab2_lib.baseboard_fab2(sch_1):page58_i172:DDR1_MA(11)" )
				( pinRef "@baseboard_fab2_lib.baseboard_fab2(sch_1):page79_i111:A11" )
				( attribute "RELATIVE_PROPAGATION_DELAY_SCOPE" "G"
					( Parent
						( matchGroupRef "@crescent_city_bb_fab1_lib.crescent_city_bb_fab1(sch_1):\MG_DDR_FAR_DIMM-CLK0_CLS_DDR_H_CAC-CLKS\" )
					)
					( Status sCSetFlattened )
					( Origin gBackEnd )
				)
				( attribute "RELATIVE_PROPAGATION_DELAY" "0.00 MIL,700.00 MIL"
					( Parent
						( matchGroupRef "@crescent_city_bb_fab1_lib.crescent_city_bb_fab1(sch_1):\MG_DDR_FAR_DIMM-CLK0_CLS_DDR_H_CAC-CLKS\" )
					)
					( Units "uMatchProp" "ns" 1.000000)
					( Status sCSetFlattened )
					( Origin gBackEnd )
				)
				( attribute "RELATIVE_PROPAGATION_DELAY_SCOPE" "G"
					( Parent
						( matchGroupRef "@baseboard_fab2_lib.baseboard_fab2(sch_1):\MG_DDR_FAR_DIMM_CMD_NG_DDR_H_DLL_12\" )
					)
					( Status sCSetFlattened )
					( Origin gBackEnd )
				)
				( attribute "RELATIVE_PROPAGATION_DELAY" "0.00 MIL,25.00 MIL"
					( Parent
						( matchGroupRef "@baseboard_fab2_lib.baseboard_fab2(sch_1):\MG_DDR_FAR_DIMM_CMD_NG_DDR_H_DLL_12\" )
					)
					( Units "uMatchProp" "ns" 1.000000)
					( Status sCSetFlattened )
					( Origin gBackEnd )
				)
			)
			( pinPair "@baseboard_fab2_lib.baseboard_fab2(sch_1):\PP3554\"
				( pinRef "@baseboard_fab2_lib.baseboard_fab2(sch_1):page80_i24:A11" )
				( pinRef "@baseboard_fab2_lib.baseboard_fab2(sch_1):page58_i172:DDR1_MA(11)" )
				( attribute "RELATIVE_PROPAGATION_DELAY_SCOPE" "G"
					( Parent
						( matchGroupRef "@crescent_city_bb_fab1_lib.crescent_city_bb_fab1(sch_1):\MG_DDR_NEAR_DIMM-CLK1_CLS_DDR_H_CAC-CLKS\" )
					)
					( Status sCSetFlattened )
					( Origin gBackEnd )
				)
				( attribute "RELATIVE_PROPAGATION_DELAY" "0.00 MIL,700.00 MIL"
					( Parent
						( matchGroupRef "@crescent_city_bb_fab1_lib.crescent_city_bb_fab1(sch_1):\MG_DDR_NEAR_DIMM-CLK1_CLS_DDR_H_CAC-CLKS\" )
					)
					( Units "uMatchProp" "ns" 1.000000)
					( Status sCSetFlattened )
					( Origin gBackEnd )
				)
				( attribute "RELATIVE_PROPAGATION_DELAY_SCOPE" "G"
					( Parent
						( matchGroupRef "@baseboard_fab2_lib.baseboard_fab2(sch_1):\MG_DDR_CMD_NEAR_DIMM_NG_DDR_H_DLL_12\" )
					)
					( Status sCSetFlattened )
					( Origin gBackEnd )
				)
				( attribute "RELATIVE_PROPAGATION_DELAY" "0.00 MIL,25.00 MIL"
					( Parent
						( matchGroupRef "@baseboard_fab2_lib.baseboard_fab2(sch_1):\MG_DDR_CMD_NEAR_DIMM_NG_DDR_H_DLL_12\" )
					)
					( Units "uMatchProp" "ns" 1.000000)
					( Status sCSetFlattened )
					( Origin gBackEnd )
				)
			)
			( pinPair "@baseboard_fab2_lib.baseboard_fab2(sch_1):\PP3547\"
				( pinRef "@baseboard_fab2_lib.baseboard_fab2(sch_1):page58_i172:DDR1_ACT_N" )
				( pinRef "@baseboard_fab2_lib.baseboard_fab2(sch_1):page79_i111:ACT_N" )
				( attribute "RELATIVE_PROPAGATION_DELAY_SCOPE" "G"
					( Parent
						( matchGroupRef "@crescent_city_bb_fab1_lib.crescent_city_bb_fab1(sch_1):\MG_DDR_FAR_DIMM-CLK0_CLS_DDR_H_CAC-CLKS\" )
					)
					( Status sCSetFlattened )
					( Origin gBackEnd )
				)
				( attribute "RELATIVE_PROPAGATION_DELAY" "0.00 MIL,700.00 MIL"
					( Parent
						( matchGroupRef "@crescent_city_bb_fab1_lib.crescent_city_bb_fab1(sch_1):\MG_DDR_FAR_DIMM-CLK0_CLS_DDR_H_CAC-CLKS\" )
					)
					( Units "uMatchProp" "ns" 1.000000)
					( Status sCSetFlattened )
					( Origin gBackEnd )
				)
				( attribute "RELATIVE_PROPAGATION_DELAY_SCOPE" "G"
					( Parent
						( matchGroupRef "@baseboard_fab2_lib.baseboard_fab2(sch_1):\MG_DDR_FAR_DIMM_CMD_NG_DDR_H_DLL_13\" )
					)
					( Status sCSetFlattened )
					( Origin gBackEnd )
				)
				( attribute "RELATIVE_PROPAGATION_DELAY" "0.00 MIL,25.00 MIL"
					( Parent
						( matchGroupRef "@baseboard_fab2_lib.baseboard_fab2(sch_1):\MG_DDR_FAR_DIMM_CMD_NG_DDR_H_DLL_13\" )
					)
					( Units "uMatchProp" "ns" 1.000000)
					( Status sCSetFlattened )
					( Origin gBackEnd )
				)
			)
			( pinPair "@baseboard_fab2_lib.baseboard_fab2(sch_1):\PP3548\"
				( pinRef "@baseboard_fab2_lib.baseboard_fab2(sch_1):page80_i24:ACT_N" )
				( pinRef "@baseboard_fab2_lib.baseboard_fab2(sch_1):page58_i172:DDR1_ACT_N" )
				( attribute "RELATIVE_PROPAGATION_DELAY_SCOPE" "G"
					( Parent
						( matchGroupRef "@crescent_city_bb_fab1_lib.crescent_city_bb_fab1(sch_1):\MG_DDR_NEAR_DIMM-CLK1_CLS_DDR_H_CAC-CLKS\" )
					)
					( Status sCSetFlattened )
					( Origin gBackEnd )
				)
				( attribute "RELATIVE_PROPAGATION_DELAY" "0.00 MIL,700.00 MIL"
					( Parent
						( matchGroupRef "@crescent_city_bb_fab1_lib.crescent_city_bb_fab1(sch_1):\MG_DDR_NEAR_DIMM-CLK1_CLS_DDR_H_CAC-CLKS\" )
					)
					( Units "uMatchProp" "ns" 1.000000)
					( Status sCSetFlattened )
					( Origin gBackEnd )
				)
				( attribute "RELATIVE_PROPAGATION_DELAY_SCOPE" "G"
					( Parent
						( matchGroupRef "@baseboard_fab2_lib.baseboard_fab2(sch_1):\MG_DDR_CMD_NEAR_DIMM_NG_DDR_H_DLL_13\" )
					)
					( Status sCSetFlattened )
					( Origin gBackEnd )
				)
				( attribute "RELATIVE_PROPAGATION_DELAY" "0.00 MIL,25.00 MIL"
					( Parent
						( matchGroupRef "@baseboard_fab2_lib.baseboard_fab2(sch_1):\MG_DDR_CMD_NEAR_DIMM_NG_DDR_H_DLL_13\" )
					)
					( Units "uMatchProp" "ns" 1.000000)
					( Status sCSetFlattened )
					( Origin gBackEnd )
				)
			)
			( pinPair "@baseboard_fab2_lib.baseboard_fab2(sch_1):\PP3549\"
				( pinRef "@baseboard_fab2_lib.baseboard_fab2(sch_1):page58_i172:DDR1_BG(0)" )
				( pinRef "@baseboard_fab2_lib.baseboard_fab2(sch_1):page79_i111:BG(0)" )
				( attribute "RELATIVE_PROPAGATION_DELAY_SCOPE" "G"
					( Parent
						( matchGroupRef "@crescent_city_bb_fab1_lib.crescent_city_bb_fab1(sch_1):\MG_DDR_FAR_DIMM-CLK0_CLS_DDR_H_CAC-CLKS\" )
					)
					( Status sCSetFlattened )
					( Origin gBackEnd )
				)
				( attribute "RELATIVE_PROPAGATION_DELAY" "0.00 MIL,700.00 MIL"
					( Parent
						( matchGroupRef "@crescent_city_bb_fab1_lib.crescent_city_bb_fab1(sch_1):\MG_DDR_FAR_DIMM-CLK0_CLS_DDR_H_CAC-CLKS\" )
					)
					( Units "uMatchProp" "ns" 1.000000)
					( Status sCSetFlattened )
					( Origin gBackEnd )
				)
				( attribute "RELATIVE_PROPAGATION_DELAY_SCOPE" "G"
					( Parent
						( matchGroupRef "@baseboard_fab2_lib.baseboard_fab2(sch_1):\MG_DDR_FAR_DIMM_CMD_NG_DDR_H_DLL_13\" )
					)
					( Status sCSetFlattened )
					( Origin gBackEnd )
				)
				( attribute "RELATIVE_PROPAGATION_DELAY" "0.00 MIL,25.00 MIL"
					( Parent
						( matchGroupRef "@baseboard_fab2_lib.baseboard_fab2(sch_1):\MG_DDR_FAR_DIMM_CMD_NG_DDR_H_DLL_13\" )
					)
					( Units "uMatchProp" "ns" 1.000000)
					( Status sCSetFlattened )
					( Origin gBackEnd )
				)
			)
			( pinPair "@baseboard_fab2_lib.baseboard_fab2(sch_1):\PP3550\"
				( pinRef "@baseboard_fab2_lib.baseboard_fab2(sch_1):page80_i24:BG(0)" )
				( pinRef "@baseboard_fab2_lib.baseboard_fab2(sch_1):page58_i172:DDR1_BG(0)" )
				( attribute "RELATIVE_PROPAGATION_DELAY_SCOPE" "G"
					( Parent
						( matchGroupRef "@crescent_city_bb_fab1_lib.crescent_city_bb_fab1(sch_1):\MG_DDR_NEAR_DIMM-CLK1_CLS_DDR_H_CAC-CLKS\" )
					)
					( Status sCSetFlattened )
					( Origin gBackEnd )
				)
				( attribute "RELATIVE_PROPAGATION_DELAY" "0.00 MIL,700.00 MIL"
					( Parent
						( matchGroupRef "@crescent_city_bb_fab1_lib.crescent_city_bb_fab1(sch_1):\MG_DDR_NEAR_DIMM-CLK1_CLS_DDR_H_CAC-CLKS\" )
					)
					( Units "uMatchProp" "ns" 1.000000)
					( Status sCSetFlattened )
					( Origin gBackEnd )
				)
				( attribute "RELATIVE_PROPAGATION_DELAY_SCOPE" "G"
					( Parent
						( matchGroupRef "@baseboard_fab2_lib.baseboard_fab2(sch_1):\MG_DDR_CMD_NEAR_DIMM_NG_DDR_H_DLL_13\" )
					)
					( Status sCSetFlattened )
					( Origin gBackEnd )
				)
				( attribute "RELATIVE_PROPAGATION_DELAY" "0.00 MIL,25.00 MIL"
					( Parent
						( matchGroupRef "@baseboard_fab2_lib.baseboard_fab2(sch_1):\MG_DDR_CMD_NEAR_DIMM_NG_DDR_H_DLL_13\" )
					)
					( Units "uMatchProp" "ns" 1.000000)
					( Status sCSetFlattened )
					( Origin gBackEnd )
				)
			)
			( pinPair "@baseboard_fab2_lib.baseboard_fab2(sch_1):\PP3545\"
				( pinRef "@baseboard_fab2_lib.baseboard_fab2(sch_1):page79_i111:S0_N" )
				( pinRef "@baseboard_fab2_lib.baseboard_fab2(sch_1):page58_i172:DDR1_CS_N(0)" )
				( attribute "RELATIVE_PROPAGATION_DELAY_SCOPE" "G"
					( Parent
						( matchGroupRef "@crescent_city_bb_fab1_lib.crescent_city_bb_fab1(sch_1):\MG_DDR_FAR_DIMM-CLK0_CLS_DDR_H_CAC-CLKS\" )
					)
					( Status sCSetFlattened )
					( Origin gBackEnd )
				)
				( attribute "RELATIVE_PROPAGATION_DELAY" "0.00 MIL,300.00 MIL"
					( Parent
						( matchGroupRef "@crescent_city_bb_fab1_lib.crescent_city_bb_fab1(sch_1):\MG_DDR_FAR_DIMM-CLK0_CLS_DDR_H_CAC-CLKS\" )
					)
					( Units "uMatchProp" "ns" 1.000000)
					( Status sCSetFlattened )
					( Origin gBackEnd )
				)
				( attribute "RELATIVE_PROPAGATION_DELAY_SCOPE" "G"
					( Parent
						( matchGroupRef "@baseboard_fab2_lib.baseboard_fab2(sch_1):\MG_DDR_CTRL_NG_DDR_H_DLL_14\" )
					)
					( Status sCSetFlattened )
					( Origin gBackEnd )
				)
				( attribute "RELATIVE_PROPAGATION_DELAY" "0.00 MIL,25.00 MIL"
					( Parent
						( matchGroupRef "@baseboard_fab2_lib.baseboard_fab2(sch_1):\MG_DDR_CTRL_NG_DDR_H_DLL_14\" )
					)
					( Units "uMatchProp" "ns" 1.000000)
					( Status sCSetFlattened )
					( Origin gBackEnd )
				)
			)
			( pinPair "@baseboard_fab2_lib.baseboard_fab2(sch_1):\PP3546\"
				( pinRef "@baseboard_fab2_lib.baseboard_fab2(sch_1):page79_i111:ODT(0)" )
				( pinRef "@baseboard_fab2_lib.baseboard_fab2(sch_1):page58_i172:DDR1_ODT(0)" )
				( attribute "RELATIVE_PROPAGATION_DELAY_SCOPE" "G"
					( Parent
						( matchGroupRef "@crescent_city_bb_fab1_lib.crescent_city_bb_fab1(sch_1):\MG_DDR_FAR_DIMM-CLK0_CLS_DDR_H_CAC-CLKS\" )
					)
					( Status sCSetFlattened )
					( Origin gBackEnd )
				)
				( attribute "RELATIVE_PROPAGATION_DELAY" "0.00 MIL,300.00 MIL"
					( Parent
						( matchGroupRef "@crescent_city_bb_fab1_lib.crescent_city_bb_fab1(sch_1):\MG_DDR_FAR_DIMM-CLK0_CLS_DDR_H_CAC-CLKS\" )
					)
					( Units "uMatchProp" "ns" 1.000000)
					( Status sCSetFlattened )
					( Origin gBackEnd )
				)
				( attribute "RELATIVE_PROPAGATION_DELAY_SCOPE" "G"
					( Parent
						( matchGroupRef "@baseboard_fab2_lib.baseboard_fab2(sch_1):\MG_DDR_CTRL_NG_DDR_H_DLL_14\" )
					)
					( Status sCSetFlattened )
					( Origin gBackEnd )
				)
				( attribute "RELATIVE_PROPAGATION_DELAY" "0.00 MIL,25.00 MIL"
					( Parent
						( matchGroupRef "@baseboard_fab2_lib.baseboard_fab2(sch_1):\MG_DDR_CTRL_NG_DDR_H_DLL_14\" )
					)
					( Units "uMatchProp" "ns" 1.000000)
					( Status sCSetFlattened )
					( Origin gBackEnd )
				)
			)
			( pinPair "@baseboard_fab2_lib.baseboard_fab2(sch_1):\PP3544\"
				( pinRef "@baseboard_fab2_lib.baseboard_fab2(sch_1):page79_i111:CKE(0)" )
				( pinRef "@baseboard_fab2_lib.baseboard_fab2(sch_1):page58_i172:DDR1_CKE(0)" )
				( attribute "RELATIVE_PROPAGATION_DELAY_SCOPE" "G"
					( Parent
						( matchGroupRef "@crescent_city_bb_fab1_lib.crescent_city_bb_fab1(sch_1):\MG_DDR_FAR_DIMM-CLK0_CLS_DDR_H_CAC-CLKS\" )
					)
					( Status sCSetFlattened )
					( Origin gBackEnd )
				)
				( attribute "RELATIVE_PROPAGATION_DELAY" "0.00 MIL,300.00 MIL"
					( Parent
						( matchGroupRef "@crescent_city_bb_fab1_lib.crescent_city_bb_fab1(sch_1):\MG_DDR_FAR_DIMM-CLK0_CLS_DDR_H_CAC-CLKS\" )
					)
					( Units "uMatchProp" "ns" 1.000000)
					( Status sCSetFlattened )
					( Origin gBackEnd )
				)
				( attribute "RELATIVE_PROPAGATION_DELAY_SCOPE" "G"
					( Parent
						( matchGroupRef "@baseboard_fab2_lib.baseboard_fab2(sch_1):\MG_DDR_CTRL_NG_DDR_H_DLL_15\" )
					)
					( Status sCSetFlattened )
					( Origin gBackEnd )
				)
				( attribute "RELATIVE_PROPAGATION_DELAY" "0.00 MIL,25.00 MIL"
					( Parent
						( matchGroupRef "@baseboard_fab2_lib.baseboard_fab2(sch_1):\MG_DDR_CTRL_NG_DDR_H_DLL_15\" )
					)
					( Units "uMatchProp" "ns" 1.000000)
					( Status sCSetFlattened )
					( Origin gBackEnd )
				)
			)
			( pinPair "@baseboard_fab2_lib.baseboard_fab2(sch_1):\PP3543\"
				( pinRef "@baseboard_fab2_lib.baseboard_fab2(sch_1):page79_i111:S2_N_C(0)" )
				( pinRef "@baseboard_fab2_lib.baseboard_fab2(sch_1):page58_i172:DDR1_CS_N(2)" )
				( attribute "RELATIVE_PROPAGATION_DELAY_SCOPE" "G"
					( Parent
						( matchGroupRef "@crescent_city_bb_fab1_lib.crescent_city_bb_fab1(sch_1):\MG_DDR_FAR_DIMM-CLK0_CLS_DDR_H_CAC-CLKS\" )
					)
					( Status sCSetFlattened )
					( Origin gBackEnd )
				)
				( attribute "RELATIVE_PROPAGATION_DELAY" "0.00 MIL,300.00 MIL"
					( Parent
						( matchGroupRef "@crescent_city_bb_fab1_lib.crescent_city_bb_fab1(sch_1):\MG_DDR_FAR_DIMM-CLK0_CLS_DDR_H_CAC-CLKS\" )
					)
					( Units "uMatchProp" "ns" 1.000000)
					( Status sCSetFlattened )
					( Origin gBackEnd )
				)
				( attribute "RELATIVE_PROPAGATION_DELAY_SCOPE" "G"
					( Parent
						( matchGroupRef "@baseboard_fab2_lib.baseboard_fab2(sch_1):\MG_DDR_CTRL_NG_DDR_H_DLL_16\" )
					)
					( Status sCSetFlattened )
					( Origin gBackEnd )
				)
				( attribute "RELATIVE_PROPAGATION_DELAY" "0.00 MIL,25.00 MIL"
					( Parent
						( matchGroupRef "@baseboard_fab2_lib.baseboard_fab2(sch_1):\MG_DDR_CTRL_NG_DDR_H_DLL_16\" )
					)
					( Units "uMatchProp" "ns" 1.000000)
					( Status sCSetFlattened )
					( Origin gBackEnd )
				)
			)
			( pinPair "@baseboard_fab2_lib.baseboard_fab2(sch_1):\PP3542\"
				( pinRef "@baseboard_fab2_lib.baseboard_fab2(sch_1):page79_i111:S3_N_C(1)" )
				( pinRef "@baseboard_fab2_lib.baseboard_fab2(sch_1):page58_i172:DDR1_CS_N(3)" )
				( attribute "RELATIVE_PROPAGATION_DELAY_SCOPE" "G"
					( Parent
						( matchGroupRef "@crescent_city_bb_fab1_lib.crescent_city_bb_fab1(sch_1):\MG_DDR_FAR_DIMM-CLK0_CLS_DDR_H_CAC-CLKS\" )
					)
					( Status sCSetFlattened )
					( Origin gBackEnd )
				)
				( attribute "RELATIVE_PROPAGATION_DELAY" "0.00 MIL,300.00 MIL"
					( Parent
						( matchGroupRef "@crescent_city_bb_fab1_lib.crescent_city_bb_fab1(sch_1):\MG_DDR_FAR_DIMM-CLK0_CLS_DDR_H_CAC-CLKS\" )
					)
					( Units "uMatchProp" "ns" 1.000000)
					( Status sCSetFlattened )
					( Origin gBackEnd )
				)
				( attribute "RELATIVE_PROPAGATION_DELAY_SCOPE" "G"
					( Parent
						( matchGroupRef "@baseboard_fab2_lib.baseboard_fab2(sch_1):\MG_DDR_CTRL_NG_DDR_H_DLL_17\" )
					)
					( Status sCSetFlattened )
					( Origin gBackEnd )
				)
				( attribute "RELATIVE_PROPAGATION_DELAY" "0.00 MIL,25.00 MIL"
					( Parent
						( matchGroupRef "@baseboard_fab2_lib.baseboard_fab2(sch_1):\MG_DDR_CTRL_NG_DDR_H_DLL_17\" )
					)
					( Units "uMatchProp" "ns" 1.000000)
					( Status sCSetFlattened )
					( Origin gBackEnd )
				)
			)
			( pinPair "@baseboard_fab2_lib.baseboard_fab2(sch_1):\PP3540\"
				( pinRef "@baseboard_fab2_lib.baseboard_fab2(sch_1):page79_i111:S1_N" )
				( pinRef "@baseboard_fab2_lib.baseboard_fab2(sch_1):page58_i172:DDR1_CS_N(1)" )
				( attribute "RELATIVE_PROPAGATION_DELAY_SCOPE" "G"
					( Parent
						( matchGroupRef "@crescent_city_bb_fab1_lib.crescent_city_bb_fab1(sch_1):\MG_DDR_FAR_DIMM-CLK0_CLS_DDR_H_CAC-CLKS\" )
					)
					( Status sCSetFlattened )
					( Origin gBackEnd )
				)
				( attribute "RELATIVE_PROPAGATION_DELAY" "0.00 MIL,300.00 MIL"
					( Parent
						( matchGroupRef "@crescent_city_bb_fab1_lib.crescent_city_bb_fab1(sch_1):\MG_DDR_FAR_DIMM-CLK0_CLS_DDR_H_CAC-CLKS\" )
					)
					( Units "uMatchProp" "ns" 1.000000)
					( Status sCSetFlattened )
					( Origin gBackEnd )
				)
				( attribute "RELATIVE_PROPAGATION_DELAY_SCOPE" "G"
					( Parent
						( matchGroupRef "@baseboard_fab2_lib.baseboard_fab2(sch_1):\MG_DDR_CTRL_NG_DDR_H_DLL_18\" )
					)
					( Status sCSetFlattened )
					( Origin gBackEnd )
				)
				( attribute "RELATIVE_PROPAGATION_DELAY" "0.00 MIL,25.00 MIL"
					( Parent
						( matchGroupRef "@baseboard_fab2_lib.baseboard_fab2(sch_1):\MG_DDR_CTRL_NG_DDR_H_DLL_18\" )
					)
					( Units "uMatchProp" "ns" 1.000000)
					( Status sCSetFlattened )
					( Origin gBackEnd )
				)
			)
			( pinPair "@baseboard_fab2_lib.baseboard_fab2(sch_1):\PP3541\"
				( pinRef "@baseboard_fab2_lib.baseboard_fab2(sch_1):page79_i111:ODT(1)" )
				( pinRef "@baseboard_fab2_lib.baseboard_fab2(sch_1):page58_i172:DDR1_ODT(1)" )
				( attribute "RELATIVE_PROPAGATION_DELAY_SCOPE" "G"
					( Parent
						( matchGroupRef "@crescent_city_bb_fab1_lib.crescent_city_bb_fab1(sch_1):\MG_DDR_FAR_DIMM-CLK0_CLS_DDR_H_CAC-CLKS\" )
					)
					( Status sCSetFlattened )
					( Origin gBackEnd )
				)
				( attribute "RELATIVE_PROPAGATION_DELAY" "0.00 MIL,300.00 MIL"
					( Parent
						( matchGroupRef "@crescent_city_bb_fab1_lib.crescent_city_bb_fab1(sch_1):\MG_DDR_FAR_DIMM-CLK0_CLS_DDR_H_CAC-CLKS\" )
					)
					( Units "uMatchProp" "ns" 1.000000)
					( Status sCSetFlattened )
					( Origin gBackEnd )
				)
				( attribute "RELATIVE_PROPAGATION_DELAY_SCOPE" "G"
					( Parent
						( matchGroupRef "@baseboard_fab2_lib.baseboard_fab2(sch_1):\MG_DDR_CTRL_NG_DDR_H_DLL_18\" )
					)
					( Status sCSetFlattened )
					( Origin gBackEnd )
				)
				( attribute "RELATIVE_PROPAGATION_DELAY" "0.00 MIL,25.00 MIL"
					( Parent
						( matchGroupRef "@baseboard_fab2_lib.baseboard_fab2(sch_1):\MG_DDR_CTRL_NG_DDR_H_DLL_18\" )
					)
					( Units "uMatchProp" "ns" 1.000000)
					( Status sCSetFlattened )
					( Origin gBackEnd )
				)
			)
			( pinPair "@baseboard_fab2_lib.baseboard_fab2(sch_1):\PP3539\"
				( pinRef "@baseboard_fab2_lib.baseboard_fab2(sch_1):page79_i111:CKE(1)" )
				( pinRef "@baseboard_fab2_lib.baseboard_fab2(sch_1):page58_i172:DDR1_CKE(1)" )
				( attribute "RELATIVE_PROPAGATION_DELAY_SCOPE" "G"
					( Parent
						( matchGroupRef "@crescent_city_bb_fab1_lib.crescent_city_bb_fab1(sch_1):\MG_DDR_FAR_DIMM-CLK0_CLS_DDR_H_CAC-CLKS\" )
					)
					( Status sCSetFlattened )
					( Origin gBackEnd )
				)
				( attribute "RELATIVE_PROPAGATION_DELAY" "0.00 MIL,300.00 MIL"
					( Parent
						( matchGroupRef "@crescent_city_bb_fab1_lib.crescent_city_bb_fab1(sch_1):\MG_DDR_FAR_DIMM-CLK0_CLS_DDR_H_CAC-CLKS\" )
					)
					( Units "uMatchProp" "ns" 1.000000)
					( Status sCSetFlattened )
					( Origin gBackEnd )
				)
				( attribute "RELATIVE_PROPAGATION_DELAY_SCOPE" "G"
					( Parent
						( matchGroupRef "@baseboard_fab2_lib.baseboard_fab2(sch_1):\MG_DDR_CTRL_NG_DDR_H_DLL_19\" )
					)
					( Status sCSetFlattened )
					( Origin gBackEnd )
				)
				( attribute "RELATIVE_PROPAGATION_DELAY" "0.00 MIL,25.00 MIL"
					( Parent
						( matchGroupRef "@baseboard_fab2_lib.baseboard_fab2(sch_1):\MG_DDR_CTRL_NG_DDR_H_DLL_19\" )
					)
					( Units "uMatchProp" "ns" 1.000000)
					( Status sCSetFlattened )
					( Origin gBackEnd )
				)
			)
			( pinPair "@baseboard_fab2_lib.baseboard_fab2(sch_1):\PP3537\"
				( pinRef "@baseboard_fab2_lib.baseboard_fab2(sch_1):page58_i172:DDR1_CS_N(4)" )
				( pinRef "@baseboard_fab2_lib.baseboard_fab2(sch_1):page80_i24:S0_N" )
				( attribute "RELATIVE_PROPAGATION_DELAY_SCOPE" "G"
					( Parent
						( matchGroupRef "@crescent_city_bb_fab1_lib.crescent_city_bb_fab1(sch_1):\MG_DDR_NEAR_DIMM-CLK1_CLS_DDR_H_CAC-CLKS\" )
					)
					( Status sCSetFlattened )
					( Origin gBackEnd )
				)
				( attribute "RELATIVE_PROPAGATION_DELAY" "0.00 MIL,300.00 MIL"
					( Parent
						( matchGroupRef "@crescent_city_bb_fab1_lib.crescent_city_bb_fab1(sch_1):\MG_DDR_NEAR_DIMM-CLK1_CLS_DDR_H_CAC-CLKS\" )
					)
					( Units "uMatchProp" "ns" 1.000000)
					( Status sCSetFlattened )
					( Origin gBackEnd )
				)
				( attribute "RELATIVE_PROPAGATION_DELAY_SCOPE" "G"
					( Parent
						( matchGroupRef "@baseboard_fab2_lib.baseboard_fab2(sch_1):\MG_DDR_CTRL_NG_DDR_H_DLL_20\" )
					)
					( Status sCSetFlattened )
					( Origin gBackEnd )
				)
				( attribute "RELATIVE_PROPAGATION_DELAY" "0.00 MIL,25.00 MIL"
					( Parent
						( matchGroupRef "@baseboard_fab2_lib.baseboard_fab2(sch_1):\MG_DDR_CTRL_NG_DDR_H_DLL_20\" )
					)
					( Units "uMatchProp" "ns" 1.000000)
					( Status sCSetFlattened )
					( Origin gBackEnd )
				)
			)
			( pinPair "@baseboard_fab2_lib.baseboard_fab2(sch_1):\PP3538\"
				( pinRef "@baseboard_fab2_lib.baseboard_fab2(sch_1):page58_i172:DDR1_ODT(2)" )
				( pinRef "@baseboard_fab2_lib.baseboard_fab2(sch_1):page80_i24:ODT(0)" )
				( attribute "RELATIVE_PROPAGATION_DELAY_SCOPE" "G"
					( Parent
						( matchGroupRef "@crescent_city_bb_fab1_lib.crescent_city_bb_fab1(sch_1):\MG_DDR_NEAR_DIMM-CLK1_CLS_DDR_H_CAC-CLKS\" )
					)
					( Status sCSetFlattened )
					( Origin gBackEnd )
				)
				( attribute "RELATIVE_PROPAGATION_DELAY" "0.00 MIL,300.00 MIL"
					( Parent
						( matchGroupRef "@crescent_city_bb_fab1_lib.crescent_city_bb_fab1(sch_1):\MG_DDR_NEAR_DIMM-CLK1_CLS_DDR_H_CAC-CLKS\" )
					)
					( Units "uMatchProp" "ns" 1.000000)
					( Status sCSetFlattened )
					( Origin gBackEnd )
				)
				( attribute "RELATIVE_PROPAGATION_DELAY_SCOPE" "G"
					( Parent
						( matchGroupRef "@baseboard_fab2_lib.baseboard_fab2(sch_1):\MG_DDR_CTRL_NG_DDR_H_DLL_20\" )
					)
					( Status sCSetFlattened )
					( Origin gBackEnd )
				)
				( attribute "RELATIVE_PROPAGATION_DELAY" "0.00 MIL,25.00 MIL"
					( Parent
						( matchGroupRef "@baseboard_fab2_lib.baseboard_fab2(sch_1):\MG_DDR_CTRL_NG_DDR_H_DLL_20\" )
					)
					( Units "uMatchProp" "ns" 1.000000)
					( Status sCSetFlattened )
					( Origin gBackEnd )
				)
			)
			( pinPair "@baseboard_fab2_lib.baseboard_fab2(sch_1):\PP3536\"
				( pinRef "@baseboard_fab2_lib.baseboard_fab2(sch_1):page58_i172:DDR1_CKE(2)" )
				( pinRef "@baseboard_fab2_lib.baseboard_fab2(sch_1):page80_i24:CKE(0)" )
				( attribute "RELATIVE_PROPAGATION_DELAY_SCOPE" "G"
					( Parent
						( matchGroupRef "@crescent_city_bb_fab1_lib.crescent_city_bb_fab1(sch_1):\MG_DDR_NEAR_DIMM-CLK1_CLS_DDR_H_CAC-CLKS\" )
					)
					( Status sCSetFlattened )
					( Origin gBackEnd )
				)
				( attribute "RELATIVE_PROPAGATION_DELAY" "0.00 MIL,300.00 MIL"
					( Parent
						( matchGroupRef "@crescent_city_bb_fab1_lib.crescent_city_bb_fab1(sch_1):\MG_DDR_NEAR_DIMM-CLK1_CLS_DDR_H_CAC-CLKS\" )
					)
					( Units "uMatchProp" "ns" 1.000000)
					( Status sCSetFlattened )
					( Origin gBackEnd )
				)
				( attribute "RELATIVE_PROPAGATION_DELAY_SCOPE" "G"
					( Parent
						( matchGroupRef "@baseboard_fab2_lib.baseboard_fab2(sch_1):\MG_DDR_CTRL_NG_DDR_H_DLL_21\" )
					)
					( Status sCSetFlattened )
					( Origin gBackEnd )
				)
				( attribute "RELATIVE_PROPAGATION_DELAY" "0.00 MIL,25.00 MIL"
					( Parent
						( matchGroupRef "@baseboard_fab2_lib.baseboard_fab2(sch_1):\MG_DDR_CTRL_NG_DDR_H_DLL_21\" )
					)
					( Units "uMatchProp" "ns" 1.000000)
					( Status sCSetFlattened )
					( Origin gBackEnd )
				)
			)
			( pinPair "@baseboard_fab2_lib.baseboard_fab2(sch_1):\PP3534\"
				( pinRef "@baseboard_fab2_lib.baseboard_fab2(sch_1):page58_i172:DDR1_CS_N(6)" )
				( pinRef "@baseboard_fab2_lib.baseboard_fab2(sch_1):page80_i24:S2_N_C(0)" )
				( attribute "RELATIVE_PROPAGATION_DELAY_SCOPE" "G"
					( Parent
						( matchGroupRef "@crescent_city_bb_fab1_lib.crescent_city_bb_fab1(sch_1):\MG_DDR_NEAR_DIMM-CLK1_CLS_DDR_H_CAC-CLKS\" )
					)
					( Status sCSetFlattened )
					( Origin gBackEnd )
				)
				( attribute "RELATIVE_PROPAGATION_DELAY" "0.00 MIL,300.00 MIL"
					( Parent
						( matchGroupRef "@crescent_city_bb_fab1_lib.crescent_city_bb_fab1(sch_1):\MG_DDR_NEAR_DIMM-CLK1_CLS_DDR_H_CAC-CLKS\" )
					)
					( Units "uMatchProp" "ns" 1.000000)
					( Status sCSetFlattened )
					( Origin gBackEnd )
				)
				( attribute "RELATIVE_PROPAGATION_DELAY_SCOPE" "G"
					( Parent
						( matchGroupRef "@baseboard_fab2_lib.baseboard_fab2(sch_1):\MG_DDR_CTRL_NG_DDR_H_DLL_22\" )
					)
					( Status sCSetFlattened )
					( Origin gBackEnd )
				)
				( attribute "RELATIVE_PROPAGATION_DELAY" "0.00 MIL,25.00 MIL"
					( Parent
						( matchGroupRef "@baseboard_fab2_lib.baseboard_fab2(sch_1):\MG_DDR_CTRL_NG_DDR_H_DLL_22\" )
					)
					( Units "uMatchProp" "ns" 1.000000)
					( Status sCSetFlattened )
					( Origin gBackEnd )
				)
			)
			( pinPair "@baseboard_fab2_lib.baseboard_fab2(sch_1):\PP3535\"
				( pinRef "@baseboard_fab2_lib.baseboard_fab2(sch_1):page58_i172:DDR1_CS_N(7)" )
				( pinRef "@baseboard_fab2_lib.baseboard_fab2(sch_1):page80_i24:S3_N_C(1)" )
				( attribute "RELATIVE_PROPAGATION_DELAY_SCOPE" "G"
					( Parent
						( matchGroupRef "@crescent_city_bb_fab1_lib.crescent_city_bb_fab1(sch_1):\MG_DDR_NEAR_DIMM-CLK1_CLS_DDR_H_CAC-CLKS\" )
					)
					( Status sCSetFlattened )
					( Origin gBackEnd )
				)
				( attribute "RELATIVE_PROPAGATION_DELAY" "0.00 MIL,300.00 MIL"
					( Parent
						( matchGroupRef "@crescent_city_bb_fab1_lib.crescent_city_bb_fab1(sch_1):\MG_DDR_NEAR_DIMM-CLK1_CLS_DDR_H_CAC-CLKS\" )
					)
					( Units "uMatchProp" "ns" 1.000000)
					( Status sCSetFlattened )
					( Origin gBackEnd )
				)
				( attribute "RELATIVE_PROPAGATION_DELAY_SCOPE" "G"
					( Parent
						( matchGroupRef "@baseboard_fab2_lib.baseboard_fab2(sch_1):\MG_DDR_CTRL_NG_DDR_H_DLL_22\" )
					)
					( Status sCSetFlattened )
					( Origin gBackEnd )
				)
				( attribute "RELATIVE_PROPAGATION_DELAY" "0.00 MIL,25.00 MIL"
					( Parent
						( matchGroupRef "@baseboard_fab2_lib.baseboard_fab2(sch_1):\MG_DDR_CTRL_NG_DDR_H_DLL_22\" )
					)
					( Units "uMatchProp" "ns" 1.000000)
					( Status sCSetFlattened )
					( Origin gBackEnd )
				)
			)
			( pinPair "@baseboard_fab2_lib.baseboard_fab2(sch_1):\PP3532\"
				( pinRef "@baseboard_fab2_lib.baseboard_fab2(sch_1):page58_i172:DDR1_CS_N(5)" )
				( pinRef "@baseboard_fab2_lib.baseboard_fab2(sch_1):page80_i24:S1_N" )
				( attribute "RELATIVE_PROPAGATION_DELAY_SCOPE" "G"
					( Parent
						( matchGroupRef "@crescent_city_bb_fab1_lib.crescent_city_bb_fab1(sch_1):\MG_DDR_NEAR_DIMM-CLK1_CLS_DDR_H_CAC-CLKS\" )
					)
					( Status sCSetFlattened )
					( Origin gBackEnd )
				)
				( attribute "RELATIVE_PROPAGATION_DELAY" "0.00 MIL,300.00 MIL"
					( Parent
						( matchGroupRef "@crescent_city_bb_fab1_lib.crescent_city_bb_fab1(sch_1):\MG_DDR_NEAR_DIMM-CLK1_CLS_DDR_H_CAC-CLKS\" )
					)
					( Units "uMatchProp" "ns" 1.000000)
					( Status sCSetFlattened )
					( Origin gBackEnd )
				)
				( attribute "RELATIVE_PROPAGATION_DELAY_SCOPE" "G"
					( Parent
						( matchGroupRef "@baseboard_fab2_lib.baseboard_fab2(sch_1):\MG_DDR_CTRL_NG_DDR_H_DLL_23\" )
					)
					( Status sCSetFlattened )
					( Origin gBackEnd )
				)
				( attribute "RELATIVE_PROPAGATION_DELAY" "0.00 MIL,25.00 MIL"
					( Parent
						( matchGroupRef "@baseboard_fab2_lib.baseboard_fab2(sch_1):\MG_DDR_CTRL_NG_DDR_H_DLL_23\" )
					)
					( Units "uMatchProp" "ns" 1.000000)
					( Status sCSetFlattened )
					( Origin gBackEnd )
				)
			)
			( pinPair "@baseboard_fab2_lib.baseboard_fab2(sch_1):\PP3533\"
				( pinRef "@baseboard_fab2_lib.baseboard_fab2(sch_1):page58_i172:DDR1_ODT(3)" )
				( pinRef "@baseboard_fab2_lib.baseboard_fab2(sch_1):page80_i24:ODT(1)" )
				( attribute "RELATIVE_PROPAGATION_DELAY_SCOPE" "G"
					( Parent
						( matchGroupRef "@crescent_city_bb_fab1_lib.crescent_city_bb_fab1(sch_1):\MG_DDR_NEAR_DIMM-CLK1_CLS_DDR_H_CAC-CLKS\" )
					)
					( Status sCSetFlattened )
					( Origin gBackEnd )
				)
				( attribute "RELATIVE_PROPAGATION_DELAY" "0.00 MIL,300.00 MIL"
					( Parent
						( matchGroupRef "@crescent_city_bb_fab1_lib.crescent_city_bb_fab1(sch_1):\MG_DDR_NEAR_DIMM-CLK1_CLS_DDR_H_CAC-CLKS\" )
					)
					( Units "uMatchProp" "ns" 1.000000)
					( Status sCSetFlattened )
					( Origin gBackEnd )
				)
				( attribute "RELATIVE_PROPAGATION_DELAY_SCOPE" "G"
					( Parent
						( matchGroupRef "@baseboard_fab2_lib.baseboard_fab2(sch_1):\MG_DDR_CTRL_NG_DDR_H_DLL_23\" )
					)
					( Status sCSetFlattened )
					( Origin gBackEnd )
				)
				( attribute "RELATIVE_PROPAGATION_DELAY" "0.00 MIL,25.00 MIL"
					( Parent
						( matchGroupRef "@baseboard_fab2_lib.baseboard_fab2(sch_1):\MG_DDR_CTRL_NG_DDR_H_DLL_23\" )
					)
					( Units "uMatchProp" "ns" 1.000000)
					( Status sCSetFlattened )
					( Origin gBackEnd )
				)
			)
			( pinPair "@baseboard_fab2_lib.baseboard_fab2(sch_1):\PP3531\"
				( pinRef "@baseboard_fab2_lib.baseboard_fab2(sch_1):page58_i172:DDR1_CKE(3)" )
				( pinRef "@baseboard_fab2_lib.baseboard_fab2(sch_1):page80_i24:CKE(1)" )
				( attribute "RELATIVE_PROPAGATION_DELAY_SCOPE" "G"
					( Parent
						( matchGroupRef "@crescent_city_bb_fab1_lib.crescent_city_bb_fab1(sch_1):\MG_DDR_NEAR_DIMM-CLK1_CLS_DDR_H_CAC-CLKS\" )
					)
					( Status sCSetFlattened )
					( Origin gBackEnd )
				)
				( attribute "RELATIVE_PROPAGATION_DELAY" "0.00 MIL,300.00 MIL"
					( Parent
						( matchGroupRef "@crescent_city_bb_fab1_lib.crescent_city_bb_fab1(sch_1):\MG_DDR_NEAR_DIMM-CLK1_CLS_DDR_H_CAC-CLKS\" )
					)
					( Units "uMatchProp" "ns" 1.000000)
					( Status sCSetFlattened )
					( Origin gBackEnd )
				)
				( attribute "RELATIVE_PROPAGATION_DELAY_SCOPE" "G"
					( Parent
						( matchGroupRef "@baseboard_fab2_lib.baseboard_fab2(sch_1):\MG_DDR_CTRL_NG_DDR_H_DLL_24\" )
					)
					( Status sCSetFlattened )
					( Origin gBackEnd )
				)
				( attribute "RELATIVE_PROPAGATION_DELAY" "0.00 MIL,25.00 MIL"
					( Parent
						( matchGroupRef "@baseboard_fab2_lib.baseboard_fab2(sch_1):\MG_DDR_CTRL_NG_DDR_H_DLL_24\" )
					)
					( Units "uMatchProp" "ns" 1.000000)
					( Status sCSetFlattened )
					( Origin gBackEnd )
				)
			)
			( pinPair "@baseboard_fab2_lib.baseboard_fab2(sch_1):\PP3659\"
				( pinRef "@baseboard_fab2_lib.baseboard_fab2(sch_1):page57_i172:DDR0_CID(2)" )
				( pinRef "@baseboard_fab2_lib.baseboard_fab2(sch_1):page77_i111:C(2)" )
				( attribute "RELATIVE_PROPAGATION_DELAY_SCOPE" "G"
					( Parent
						( matchGroupRef "@crescent_city_bb_fab1_lib.crescent_city_bb_fab1(sch_1):\MG_DDR_FAR_DIMM-CLK0_CLS_DDR_G_CAC-CLKS\" )
					)
					( Status sCSetFlattened )
					( Origin gBackEnd )
				)
				( attribute "RELATIVE_PROPAGATION_DELAY" "0.00 MIL,700.00 MIL"
					( Parent
						( matchGroupRef "@crescent_city_bb_fab1_lib.crescent_city_bb_fab1(sch_1):\MG_DDR_FAR_DIMM-CLK0_CLS_DDR_G_CAC-CLKS\" )
					)
					( Units "uMatchProp" "ns" 1.000000)
					( Status sCSetFlattened )
					( Origin gBackEnd )
				)
				( attribute "RELATIVE_PROPAGATION_DELAY_SCOPE" "G"
					( Parent
						( matchGroupRef "@baseboard_fab2_lib.baseboard_fab2(sch_1):\MG_DDR_FAR_DIMM_CMD_NG_DDR_G_DLL_1\" )
					)
					( Status sCSetFlattened )
					( Origin gBackEnd )
				)
				( attribute "RELATIVE_PROPAGATION_DELAY" "0.00 MIL,25.00 MIL"
					( Parent
						( matchGroupRef "@baseboard_fab2_lib.baseboard_fab2(sch_1):\MG_DDR_FAR_DIMM_CMD_NG_DDR_G_DLL_1\" )
					)
					( Units "uMatchProp" "ns" 1.000000)
					( Status sCSetFlattened )
					( Origin gBackEnd )
				)
			)
			( pinPair "@baseboard_fab2_lib.baseboard_fab2(sch_1):\PP3660\"
				( pinRef "@baseboard_fab2_lib.baseboard_fab2(sch_1):page78_i13:C(2)" )
				( pinRef "@baseboard_fab2_lib.baseboard_fab2(sch_1):page57_i172:DDR0_CID(2)" )
				( attribute "RELATIVE_PROPAGATION_DELAY_SCOPE" "G"
					( Parent
						( matchGroupRef "@baseboard_fab2_lib.baseboard_fab2(sch_1):\MG_DDR_CMD_NEAR_DIMM_NG_DDR_G_DLL_1\" )
					)
					( Status sCSetFlattened )
					( Origin gBackEnd )
				)
				( attribute "RELATIVE_PROPAGATION_DELAY" "0.00 MIL,25.00 MIL"
					( Parent
						( matchGroupRef "@baseboard_fab2_lib.baseboard_fab2(sch_1):\MG_DDR_CMD_NEAR_DIMM_NG_DDR_G_DLL_1\" )
					)
					( Units "uMatchProp" "ns" 1.000000)
					( Status sCSetFlattened )
					( Origin gBackEnd )
				)
				( attribute "RELATIVE_PROPAGATION_DELAY_SCOPE" "G"
					( Parent
						( matchGroupRef "@crescent_city_bb_fab1_lib.crescent_city_bb_fab1(sch_1):\MG_DDR_NEAR_DIMM-CLK1_CLS_DDR_G_CAC-CLKS\" )
					)
					( Status sCSetFlattened )
					( Origin gBackEnd )
				)
				( attribute "RELATIVE_PROPAGATION_DELAY" "0.00 MIL,700.00 MIL"
					( Parent
						( matchGroupRef "@crescent_city_bb_fab1_lib.crescent_city_bb_fab1(sch_1):\MG_DDR_NEAR_DIMM-CLK1_CLS_DDR_G_CAC-CLKS\" )
					)
					( Units "uMatchProp" "ns" 1.000000)
					( Status sCSetFlattened )
					( Origin gBackEnd )
				)
			)
			( pinPair "@baseboard_fab2_lib.baseboard_fab2(sch_1):\PP3661\"
				( pinRef "@baseboard_fab2_lib.baseboard_fab2(sch_1):page57_i172:DDR0_MA(17)" )
				( pinRef "@baseboard_fab2_lib.baseboard_fab2(sch_1):page77_i111:A17" )
				( attribute "RELATIVE_PROPAGATION_DELAY_SCOPE" "G"
					( Parent
						( matchGroupRef "@crescent_city_bb_fab1_lib.crescent_city_bb_fab1(sch_1):\MG_DDR_FAR_DIMM-CLK0_CLS_DDR_G_CAC-CLKS\" )
					)
					( Status sCSetFlattened )
					( Origin gBackEnd )
				)
				( attribute "RELATIVE_PROPAGATION_DELAY" "0.00 MIL,700.00 MIL"
					( Parent
						( matchGroupRef "@crescent_city_bb_fab1_lib.crescent_city_bb_fab1(sch_1):\MG_DDR_FAR_DIMM-CLK0_CLS_DDR_G_CAC-CLKS\" )
					)
					( Units "uMatchProp" "ns" 1.000000)
					( Status sCSetFlattened )
					( Origin gBackEnd )
				)
				( attribute "RELATIVE_PROPAGATION_DELAY_SCOPE" "G"
					( Parent
						( matchGroupRef "@baseboard_fab2_lib.baseboard_fab2(sch_1):\MG_DDR_FAR_DIMM_CMD_NG_DDR_G_DLL_1\" )
					)
					( Status sCSetFlattened )
					( Origin gBackEnd )
				)
				( attribute "RELATIVE_PROPAGATION_DELAY" "0.00 MIL,25.00 MIL"
					( Parent
						( matchGroupRef "@baseboard_fab2_lib.baseboard_fab2(sch_1):\MG_DDR_FAR_DIMM_CMD_NG_DDR_G_DLL_1\" )
					)
					( Units "uMatchProp" "ns" 1.000000)
					( Status sCSetFlattened )
					( Origin gBackEnd )
				)
			)
			( pinPair "@baseboard_fab2_lib.baseboard_fab2(sch_1):\PP3662\"
				( pinRef "@baseboard_fab2_lib.baseboard_fab2(sch_1):page78_i13:A17" )
				( pinRef "@baseboard_fab2_lib.baseboard_fab2(sch_1):page57_i172:DDR0_MA(17)" )
				( attribute "RELATIVE_PROPAGATION_DELAY_SCOPE" "G"
					( Parent
						( matchGroupRef "@baseboard_fab2_lib.baseboard_fab2(sch_1):\MG_DDR_CMD_NEAR_DIMM_NG_DDR_G_DLL_1\" )
					)
					( Status sCSetFlattened )
					( Origin gBackEnd )
				)
				( attribute "RELATIVE_PROPAGATION_DELAY" "0.00 MIL,25.00 MIL"
					( Parent
						( matchGroupRef "@baseboard_fab2_lib.baseboard_fab2(sch_1):\MG_DDR_CMD_NEAR_DIMM_NG_DDR_G_DLL_1\" )
					)
					( Units "uMatchProp" "ns" 1.000000)
					( Status sCSetFlattened )
					( Origin gBackEnd )
				)
				( attribute "RELATIVE_PROPAGATION_DELAY_SCOPE" "G"
					( Parent
						( matchGroupRef "@crescent_city_bb_fab1_lib.crescent_city_bb_fab1(sch_1):\MG_DDR_NEAR_DIMM-CLK1_CLS_DDR_G_CAC-CLKS\" )
					)
					( Status sCSetFlattened )
					( Origin gBackEnd )
				)
				( attribute "RELATIVE_PROPAGATION_DELAY" "0.00 MIL,700.00 MIL"
					( Parent
						( matchGroupRef "@crescent_city_bb_fab1_lib.crescent_city_bb_fab1(sch_1):\MG_DDR_NEAR_DIMM-CLK1_CLS_DDR_G_CAC-CLKS\" )
					)
					( Units "uMatchProp" "ns" 1.000000)
					( Status sCSetFlattened )
					( Origin gBackEnd )
				)
			)
			( pinPair "@baseboard_fab2_lib.baseboard_fab2(sch_1):\PP3655\"
				( pinRef "@baseboard_fab2_lib.baseboard_fab2(sch_1):page57_i172:DDR0_MA(13)" )
				( pinRef "@baseboard_fab2_lib.baseboard_fab2(sch_1):page77_i111:A13" )
				( attribute "RELATIVE_PROPAGATION_DELAY_SCOPE" "G"
					( Parent
						( matchGroupRef "@crescent_city_bb_fab1_lib.crescent_city_bb_fab1(sch_1):\MG_DDR_FAR_DIMM-CLK0_CLS_DDR_G_CAC-CLKS\" )
					)
					( Status sCSetFlattened )
					( Origin gBackEnd )
				)
				( attribute "RELATIVE_PROPAGATION_DELAY" "0.00 MIL,700.00 MIL"
					( Parent
						( matchGroupRef "@crescent_city_bb_fab1_lib.crescent_city_bb_fab1(sch_1):\MG_DDR_FAR_DIMM-CLK0_CLS_DDR_G_CAC-CLKS\" )
					)
					( Units "uMatchProp" "ns" 1.000000)
					( Status sCSetFlattened )
					( Origin gBackEnd )
				)
				( attribute "RELATIVE_PROPAGATION_DELAY_SCOPE" "G"
					( Parent
						( matchGroupRef "@baseboard_fab2_lib.baseboard_fab2(sch_1):\MG_DDR_FAR_DIMM_CMD_NG_DDR_G_DLL_2\" )
					)
					( Status sCSetFlattened )
					( Origin gBackEnd )
				)
				( attribute "RELATIVE_PROPAGATION_DELAY" "0.00 MIL,25.00 MIL"
					( Parent
						( matchGroupRef "@baseboard_fab2_lib.baseboard_fab2(sch_1):\MG_DDR_FAR_DIMM_CMD_NG_DDR_G_DLL_2\" )
					)
					( Units "uMatchProp" "ns" 1.000000)
					( Status sCSetFlattened )
					( Origin gBackEnd )
				)
			)
			( pinPair "@baseboard_fab2_lib.baseboard_fab2(sch_1):\PP3656\"
				( pinRef "@baseboard_fab2_lib.baseboard_fab2(sch_1):page78_i13:A13" )
				( pinRef "@baseboard_fab2_lib.baseboard_fab2(sch_1):page57_i172:DDR0_MA(13)" )
				( attribute "RELATIVE_PROPAGATION_DELAY_SCOPE" "G"
					( Parent
						( matchGroupRef "@crescent_city_bb_fab1_lib.crescent_city_bb_fab1(sch_1):\MG_DDR_NEAR_DIMM-CLK1_CLS_DDR_G_CAC-CLKS\" )
					)
					( Status sCSetFlattened )
					( Origin gBackEnd )
				)
				( attribute "RELATIVE_PROPAGATION_DELAY" "0.00 MIL,700.00 MIL"
					( Parent
						( matchGroupRef "@crescent_city_bb_fab1_lib.crescent_city_bb_fab1(sch_1):\MG_DDR_NEAR_DIMM-CLK1_CLS_DDR_G_CAC-CLKS\" )
					)
					( Units "uMatchProp" "ns" 1.000000)
					( Status sCSetFlattened )
					( Origin gBackEnd )
				)
				( attribute "RELATIVE_PROPAGATION_DELAY_SCOPE" "G"
					( Parent
						( matchGroupRef "@baseboard_fab2_lib.baseboard_fab2(sch_1):\MG_DDR_CMD_NEAR_DIMM_NG_DDR_G_DLL_2\" )
					)
					( Status sCSetFlattened )
					( Origin gBackEnd )
				)
				( attribute "RELATIVE_PROPAGATION_DELAY" "0.00 MIL,25.00 MIL"
					( Parent
						( matchGroupRef "@baseboard_fab2_lib.baseboard_fab2(sch_1):\MG_DDR_CMD_NEAR_DIMM_NG_DDR_G_DLL_2\" )
					)
					( Units "uMatchProp" "ns" 1.000000)
					( Status sCSetFlattened )
					( Origin gBackEnd )
				)
			)
			( pinPair "@baseboard_fab2_lib.baseboard_fab2(sch_1):\PP3657\"
				( pinRef "@baseboard_fab2_lib.baseboard_fab2(sch_1):page57_i172:DDR0_MA(15)" )
				( pinRef "@baseboard_fab2_lib.baseboard_fab2(sch_1):page77_i111:A15_CAS_N" )
				( attribute "RELATIVE_PROPAGATION_DELAY_SCOPE" "G"
					( Parent
						( matchGroupRef "@crescent_city_bb_fab1_lib.crescent_city_bb_fab1(sch_1):\MG_DDR_FAR_DIMM-CLK0_CLS_DDR_G_CAC-CLKS\" )
					)
					( Status sCSetFlattened )
					( Origin gBackEnd )
				)
				( attribute "RELATIVE_PROPAGATION_DELAY" "0.00 MIL,700.00 MIL"
					( Parent
						( matchGroupRef "@crescent_city_bb_fab1_lib.crescent_city_bb_fab1(sch_1):\MG_DDR_FAR_DIMM-CLK0_CLS_DDR_G_CAC-CLKS\" )
					)
					( Units "uMatchProp" "ns" 1.000000)
					( Status sCSetFlattened )
					( Origin gBackEnd )
				)
				( attribute "RELATIVE_PROPAGATION_DELAY_SCOPE" "G"
					( Parent
						( matchGroupRef "@baseboard_fab2_lib.baseboard_fab2(sch_1):\MG_DDR_FAR_DIMM_CMD_NG_DDR_G_DLL_2\" )
					)
					( Status sCSetFlattened )
					( Origin gBackEnd )
				)
				( attribute "RELATIVE_PROPAGATION_DELAY" "0.00 MIL,25.00 MIL"
					( Parent
						( matchGroupRef "@baseboard_fab2_lib.baseboard_fab2(sch_1):\MG_DDR_FAR_DIMM_CMD_NG_DDR_G_DLL_2\" )
					)
					( Units "uMatchProp" "ns" 1.000000)
					( Status sCSetFlattened )
					( Origin gBackEnd )
				)
			)
			( pinPair "@baseboard_fab2_lib.baseboard_fab2(sch_1):\PP3658\"
				( pinRef "@baseboard_fab2_lib.baseboard_fab2(sch_1):page78_i13:A15_CAS_N" )
				( pinRef "@baseboard_fab2_lib.baseboard_fab2(sch_1):page57_i172:DDR0_MA(15)" )
				( attribute "RELATIVE_PROPAGATION_DELAY_SCOPE" "G"
					( Parent
						( matchGroupRef "@crescent_city_bb_fab1_lib.crescent_city_bb_fab1(sch_1):\MG_DDR_NEAR_DIMM-CLK1_CLS_DDR_G_CAC-CLKS\" )
					)
					( Status sCSetFlattened )
					( Origin gBackEnd )
				)
				( attribute "RELATIVE_PROPAGATION_DELAY" "0.00 MIL,700.00 MIL"
					( Parent
						( matchGroupRef "@crescent_city_bb_fab1_lib.crescent_city_bb_fab1(sch_1):\MG_DDR_NEAR_DIMM-CLK1_CLS_DDR_G_CAC-CLKS\" )
					)
					( Units "uMatchProp" "ns" 1.000000)
					( Status sCSetFlattened )
					( Origin gBackEnd )
				)
				( attribute "RELATIVE_PROPAGATION_DELAY_SCOPE" "G"
					( Parent
						( matchGroupRef "@baseboard_fab2_lib.baseboard_fab2(sch_1):\MG_DDR_CMD_NEAR_DIMM_NG_DDR_G_DLL_2\" )
					)
					( Status sCSetFlattened )
					( Origin gBackEnd )
				)
				( attribute "RELATIVE_PROPAGATION_DELAY" "0.00 MIL,25.00 MIL"
					( Parent
						( matchGroupRef "@baseboard_fab2_lib.baseboard_fab2(sch_1):\MG_DDR_CMD_NEAR_DIMM_NG_DDR_G_DLL_2\" )
					)
					( Units "uMatchProp" "ns" 1.000000)
					( Status sCSetFlattened )
					( Origin gBackEnd )
				)
			)
			( pinPair "@baseboard_fab2_lib.baseboard_fab2(sch_1):\PP3651\"
				( pinRef "@baseboard_fab2_lib.baseboard_fab2(sch_1):page57_i172:DDR0_MA(14)" )
				( pinRef "@baseboard_fab2_lib.baseboard_fab2(sch_1):page77_i111:A14_WE_N" )
				( attribute "RELATIVE_PROPAGATION_DELAY_SCOPE" "G"
					( Parent
						( matchGroupRef "@crescent_city_bb_fab1_lib.crescent_city_bb_fab1(sch_1):\MG_DDR_FAR_DIMM-CLK0_CLS_DDR_G_CAC-CLKS\" )
					)
					( Status sCSetFlattened )
					( Origin gBackEnd )
				)
				( attribute "RELATIVE_PROPAGATION_DELAY" "0.00 MIL,700.00 MIL"
					( Parent
						( matchGroupRef "@crescent_city_bb_fab1_lib.crescent_city_bb_fab1(sch_1):\MG_DDR_FAR_DIMM-CLK0_CLS_DDR_G_CAC-CLKS\" )
					)
					( Units "uMatchProp" "ns" 1.000000)
					( Status sCSetFlattened )
					( Origin gBackEnd )
				)
				( attribute "RELATIVE_PROPAGATION_DELAY_SCOPE" "G"
					( Parent
						( matchGroupRef "@baseboard_fab2_lib.baseboard_fab2(sch_1):\MG_DDR_FAR_DIMM_CMD_NG_DDR_G_DLL_3\" )
					)
					( Status sCSetFlattened )
					( Origin gBackEnd )
				)
				( attribute "RELATIVE_PROPAGATION_DELAY" "0.00 MIL,25.00 MIL"
					( Parent
						( matchGroupRef "@baseboard_fab2_lib.baseboard_fab2(sch_1):\MG_DDR_FAR_DIMM_CMD_NG_DDR_G_DLL_3\" )
					)
					( Units "uMatchProp" "ns" 1.000000)
					( Status sCSetFlattened )
					( Origin gBackEnd )
				)
			)
			( pinPair "@baseboard_fab2_lib.baseboard_fab2(sch_1):\PP3652\"
				( pinRef "@baseboard_fab2_lib.baseboard_fab2(sch_1):page78_i13:A14_WE_N" )
				( pinRef "@baseboard_fab2_lib.baseboard_fab2(sch_1):page57_i172:DDR0_MA(14)" )
				( attribute "RELATIVE_PROPAGATION_DELAY_SCOPE" "G"
					( Parent
						( matchGroupRef "@crescent_city_bb_fab1_lib.crescent_city_bb_fab1(sch_1):\MG_DDR_NEAR_DIMM-CLK1_CLS_DDR_G_CAC-CLKS\" )
					)
					( Status sCSetFlattened )
					( Origin gBackEnd )
				)
				( attribute "RELATIVE_PROPAGATION_DELAY" "0.00 MIL,700.00 MIL"
					( Parent
						( matchGroupRef "@crescent_city_bb_fab1_lib.crescent_city_bb_fab1(sch_1):\MG_DDR_NEAR_DIMM-CLK1_CLS_DDR_G_CAC-CLKS\" )
					)
					( Units "uMatchProp" "ns" 1.000000)
					( Status sCSetFlattened )
					( Origin gBackEnd )
				)
				( attribute "RELATIVE_PROPAGATION_DELAY_SCOPE" "G"
					( Parent
						( matchGroupRef "@baseboard_fab2_lib.baseboard_fab2(sch_1):\MG_DDR_CMD_NEAR_DIMM_NG_DDR_G_DLL_3\" )
					)
					( Status sCSetFlattened )
					( Origin gBackEnd )
				)
				( attribute "RELATIVE_PROPAGATION_DELAY" "0.00 MIL,25.00 MIL"
					( Parent
						( matchGroupRef "@baseboard_fab2_lib.baseboard_fab2(sch_1):\MG_DDR_CMD_NEAR_DIMM_NG_DDR_G_DLL_3\" )
					)
					( Units "uMatchProp" "ns" 1.000000)
					( Status sCSetFlattened )
					( Origin gBackEnd )
				)
			)
			( pinPair "@baseboard_fab2_lib.baseboard_fab2(sch_1):\PP3653\"
				( pinRef "@baseboard_fab2_lib.baseboard_fab2(sch_1):page57_i172:DDR0_MA(16)" )
				( pinRef "@baseboard_fab2_lib.baseboard_fab2(sch_1):page77_i111:A16_RAS_N" )
				( attribute "RELATIVE_PROPAGATION_DELAY_SCOPE" "G"
					( Parent
						( matchGroupRef "@crescent_city_bb_fab1_lib.crescent_city_bb_fab1(sch_1):\MG_DDR_FAR_DIMM-CLK0_CLS_DDR_G_CAC-CLKS\" )
					)
					( Status sCSetFlattened )
					( Origin gBackEnd )
				)
				( attribute "RELATIVE_PROPAGATION_DELAY" "0.00 MIL,700.00 MIL"
					( Parent
						( matchGroupRef "@crescent_city_bb_fab1_lib.crescent_city_bb_fab1(sch_1):\MG_DDR_FAR_DIMM-CLK0_CLS_DDR_G_CAC-CLKS\" )
					)
					( Units "uMatchProp" "ns" 1.000000)
					( Status sCSetFlattened )
					( Origin gBackEnd )
				)
				( attribute "RELATIVE_PROPAGATION_DELAY_SCOPE" "G"
					( Parent
						( matchGroupRef "@baseboard_fab2_lib.baseboard_fab2(sch_1):\MG_DDR_FAR_DIMM_CMD_NG_DDR_G_DLL_3\" )
					)
					( Status sCSetFlattened )
					( Origin gBackEnd )
				)
				( attribute "RELATIVE_PROPAGATION_DELAY" "0.00 MIL,25.00 MIL"
					( Parent
						( matchGroupRef "@baseboard_fab2_lib.baseboard_fab2(sch_1):\MG_DDR_FAR_DIMM_CMD_NG_DDR_G_DLL_3\" )
					)
					( Units "uMatchProp" "ns" 1.000000)
					( Status sCSetFlattened )
					( Origin gBackEnd )
				)
			)
			( pinPair "@baseboard_fab2_lib.baseboard_fab2(sch_1):\PP3654\"
				( pinRef "@baseboard_fab2_lib.baseboard_fab2(sch_1):page78_i13:A16_RAS_N" )
				( pinRef "@baseboard_fab2_lib.baseboard_fab2(sch_1):page57_i172:DDR0_MA(16)" )
				( attribute "RELATIVE_PROPAGATION_DELAY_SCOPE" "G"
					( Parent
						( matchGroupRef "@crescent_city_bb_fab1_lib.crescent_city_bb_fab1(sch_1):\MG_DDR_NEAR_DIMM-CLK1_CLS_DDR_G_CAC-CLKS\" )
					)
					( Status sCSetFlattened )
					( Origin gBackEnd )
				)
				( attribute "RELATIVE_PROPAGATION_DELAY" "0.00 MIL,700.00 MIL"
					( Parent
						( matchGroupRef "@crescent_city_bb_fab1_lib.crescent_city_bb_fab1(sch_1):\MG_DDR_NEAR_DIMM-CLK1_CLS_DDR_G_CAC-CLKS\" )
					)
					( Units "uMatchProp" "ns" 1.000000)
					( Status sCSetFlattened )
					( Origin gBackEnd )
				)
				( attribute "RELATIVE_PROPAGATION_DELAY_SCOPE" "G"
					( Parent
						( matchGroupRef "@baseboard_fab2_lib.baseboard_fab2(sch_1):\MG_DDR_CMD_NEAR_DIMM_NG_DDR_G_DLL_3\" )
					)
					( Status sCSetFlattened )
					( Origin gBackEnd )
				)
				( attribute "RELATIVE_PROPAGATION_DELAY" "0.00 MIL,25.00 MIL"
					( Parent
						( matchGroupRef "@baseboard_fab2_lib.baseboard_fab2(sch_1):\MG_DDR_CMD_NEAR_DIMM_NG_DDR_G_DLL_3\" )
					)
					( Units "uMatchProp" "ns" 1.000000)
					( Status sCSetFlattened )
					( Origin gBackEnd )
				)
			)
			( pinPair "@baseboard_fab2_lib.baseboard_fab2(sch_1):\PP3647\"
				( pinRef "@baseboard_fab2_lib.baseboard_fab2(sch_1):page57_i172:DDR0_BA(1)" )
				( pinRef "@baseboard_fab2_lib.baseboard_fab2(sch_1):page77_i111:BA(1)" )
				( attribute "RELATIVE_PROPAGATION_DELAY_SCOPE" "G"
					( Parent
						( matchGroupRef "@crescent_city_bb_fab1_lib.crescent_city_bb_fab1(sch_1):\MG_DDR_FAR_DIMM-CLK0_CLS_DDR_G_CAC-CLKS\" )
					)
					( Status sCSetFlattened )
					( Origin gBackEnd )
				)
				( attribute "RELATIVE_PROPAGATION_DELAY" "0.00 MIL,700.00 MIL"
					( Parent
						( matchGroupRef "@crescent_city_bb_fab1_lib.crescent_city_bb_fab1(sch_1):\MG_DDR_FAR_DIMM-CLK0_CLS_DDR_G_CAC-CLKS\" )
					)
					( Units "uMatchProp" "ns" 1.000000)
					( Status sCSetFlattened )
					( Origin gBackEnd )
				)
				( attribute "RELATIVE_PROPAGATION_DELAY_SCOPE" "G"
					( Parent
						( matchGroupRef "@baseboard_fab2_lib.baseboard_fab2(sch_1):\MG_DDR_FAR_DIMM_CMD_NG_DDR_G_DLL_4\" )
					)
					( Status sCSetFlattened )
					( Origin gBackEnd )
				)
				( attribute "RELATIVE_PROPAGATION_DELAY" "0.00 MIL,25.00 MIL"
					( Parent
						( matchGroupRef "@baseboard_fab2_lib.baseboard_fab2(sch_1):\MG_DDR_FAR_DIMM_CMD_NG_DDR_G_DLL_4\" )
					)
					( Units "uMatchProp" "ns" 1.000000)
					( Status sCSetFlattened )
					( Origin gBackEnd )
				)
			)
			( pinPair "@baseboard_fab2_lib.baseboard_fab2(sch_1):\PP3648\"
				( pinRef "@baseboard_fab2_lib.baseboard_fab2(sch_1):page78_i13:BA(1)" )
				( pinRef "@baseboard_fab2_lib.baseboard_fab2(sch_1):page57_i172:DDR0_BA(1)" )
				( attribute "RELATIVE_PROPAGATION_DELAY_SCOPE" "G"
					( Parent
						( matchGroupRef "@crescent_city_bb_fab1_lib.crescent_city_bb_fab1(sch_1):\MG_DDR_NEAR_DIMM-CLK1_CLS_DDR_G_CAC-CLKS\" )
					)
					( Status sCSetFlattened )
					( Origin gBackEnd )
				)
				( attribute "RELATIVE_PROPAGATION_DELAY" "0.00 MIL,700.00 MIL"
					( Parent
						( matchGroupRef "@crescent_city_bb_fab1_lib.crescent_city_bb_fab1(sch_1):\MG_DDR_NEAR_DIMM-CLK1_CLS_DDR_G_CAC-CLKS\" )
					)
					( Units "uMatchProp" "ns" 1.000000)
					( Status sCSetFlattened )
					( Origin gBackEnd )
				)
				( attribute "RELATIVE_PROPAGATION_DELAY_SCOPE" "G"
					( Parent
						( matchGroupRef "@baseboard_fab2_lib.baseboard_fab2(sch_1):\MG_DDR_CMD_NEAR_DIMM_NG_DDR_G_DLL_4\" )
					)
					( Status sCSetFlattened )
					( Origin gBackEnd )
				)
				( attribute "RELATIVE_PROPAGATION_DELAY" "0.00 MIL,25.00 MIL"
					( Parent
						( matchGroupRef "@baseboard_fab2_lib.baseboard_fab2(sch_1):\MG_DDR_CMD_NEAR_DIMM_NG_DDR_G_DLL_4\" )
					)
					( Units "uMatchProp" "ns" 1.000000)
					( Status sCSetFlattened )
					( Origin gBackEnd )
				)
			)
			( pinPair "@baseboard_fab2_lib.baseboard_fab2(sch_1):\PP3649\"
				( pinRef "@baseboard_fab2_lib.baseboard_fab2(sch_1):page57_i172:DDR0_MA(10)" )
				( pinRef "@baseboard_fab2_lib.baseboard_fab2(sch_1):page77_i111:A10" )
				( attribute "RELATIVE_PROPAGATION_DELAY_SCOPE" "G"
					( Parent
						( matchGroupRef "@crescent_city_bb_fab1_lib.crescent_city_bb_fab1(sch_1):\MG_DDR_FAR_DIMM-CLK0_CLS_DDR_G_CAC-CLKS\" )
					)
					( Status sCSetFlattened )
					( Origin gBackEnd )
				)
				( attribute "RELATIVE_PROPAGATION_DELAY" "0.00 MIL,700.00 MIL"
					( Parent
						( matchGroupRef "@crescent_city_bb_fab1_lib.crescent_city_bb_fab1(sch_1):\MG_DDR_FAR_DIMM-CLK0_CLS_DDR_G_CAC-CLKS\" )
					)
					( Units "uMatchProp" "ns" 1.000000)
					( Status sCSetFlattened )
					( Origin gBackEnd )
				)
				( attribute "RELATIVE_PROPAGATION_DELAY_SCOPE" "G"
					( Parent
						( matchGroupRef "@baseboard_fab2_lib.baseboard_fab2(sch_1):\MG_DDR_FAR_DIMM_CMD_NG_DDR_G_DLL_4\" )
					)
					( Status sCSetFlattened )
					( Origin gBackEnd )
				)
				( attribute "RELATIVE_PROPAGATION_DELAY" "0.00 MIL,25.00 MIL"
					( Parent
						( matchGroupRef "@baseboard_fab2_lib.baseboard_fab2(sch_1):\MG_DDR_FAR_DIMM_CMD_NG_DDR_G_DLL_4\" )
					)
					( Units "uMatchProp" "ns" 1.000000)
					( Status sCSetFlattened )
					( Origin gBackEnd )
				)
			)
			( pinPair "@baseboard_fab2_lib.baseboard_fab2(sch_1):\PP3650\"
				( pinRef "@baseboard_fab2_lib.baseboard_fab2(sch_1):page57_i172:DDR0_MA(10)" )
				( pinRef "@baseboard_fab2_lib.baseboard_fab2(sch_1):page78_i13:A10" )
				( attribute "RELATIVE_PROPAGATION_DELAY_SCOPE" "G"
					( Parent
						( matchGroupRef "@crescent_city_bb_fab1_lib.crescent_city_bb_fab1(sch_1):\MG_DDR_NEAR_DIMM-CLK1_CLS_DDR_G_CAC-CLKS\" )
					)
					( Status sCSetFlattened )
					( Origin gBackEnd )
				)
				( attribute "RELATIVE_PROPAGATION_DELAY" "0.00 MIL,700.00 MIL"
					( Parent
						( matchGroupRef "@crescent_city_bb_fab1_lib.crescent_city_bb_fab1(sch_1):\MG_DDR_NEAR_DIMM-CLK1_CLS_DDR_G_CAC-CLKS\" )
					)
					( Units "uMatchProp" "ns" 1.000000)
					( Status sCSetFlattened )
					( Origin gBackEnd )
				)
				( attribute "RELATIVE_PROPAGATION_DELAY_SCOPE" "G"
					( Parent
						( matchGroupRef "@baseboard_fab2_lib.baseboard_fab2(sch_1):\MG_DDR_CMD_NEAR_DIMM_NG_DDR_G_DLL_4\" )
					)
					( Status sCSetFlattened )
					( Origin gBackEnd )
				)
				( attribute "RELATIVE_PROPAGATION_DELAY" "0.00 MIL,25.00 MIL"
					( Parent
						( matchGroupRef "@baseboard_fab2_lib.baseboard_fab2(sch_1):\MG_DDR_CMD_NEAR_DIMM_NG_DDR_G_DLL_4\" )
					)
					( Units "uMatchProp" "ns" 1.000000)
					( Status sCSetFlattened )
					( Origin gBackEnd )
				)
			)
			( pinPair "@baseboard_fab2_lib.baseboard_fab2(sch_1):\PP3643\"
				( pinRef "@baseboard_fab2_lib.baseboard_fab2(sch_1):page57_i172:DDR0_BA(0)" )
				( pinRef "@baseboard_fab2_lib.baseboard_fab2(sch_1):page77_i111:BA(0)" )
				( attribute "RELATIVE_PROPAGATION_DELAY_SCOPE" "G"
					( Parent
						( matchGroupRef "@crescent_city_bb_fab1_lib.crescent_city_bb_fab1(sch_1):\MG_DDR_FAR_DIMM-CLK0_CLS_DDR_G_CAC-CLKS\" )
					)
					( Status sCSetFlattened )
					( Origin gBackEnd )
				)
				( attribute "RELATIVE_PROPAGATION_DELAY" "0.00 MIL,700.00 MIL"
					( Parent
						( matchGroupRef "@crescent_city_bb_fab1_lib.crescent_city_bb_fab1(sch_1):\MG_DDR_FAR_DIMM-CLK0_CLS_DDR_G_CAC-CLKS\" )
					)
					( Units "uMatchProp" "ns" 1.000000)
					( Status sCSetFlattened )
					( Origin gBackEnd )
				)
				( attribute "RELATIVE_PROPAGATION_DELAY_SCOPE" "G"
					( Parent
						( matchGroupRef "@baseboard_fab2_lib.baseboard_fab2(sch_1):\MG_DDR_FAR_DIMM_CMD_NG_DDR_G_DLL_5\" )
					)
					( Status sCSetFlattened )
					( Origin gBackEnd )
				)
				( attribute "RELATIVE_PROPAGATION_DELAY" "0.00 MIL,25.00 MIL"
					( Parent
						( matchGroupRef "@baseboard_fab2_lib.baseboard_fab2(sch_1):\MG_DDR_FAR_DIMM_CMD_NG_DDR_G_DLL_5\" )
					)
					( Units "uMatchProp" "ns" 1.000000)
					( Status sCSetFlattened )
					( Origin gBackEnd )
				)
			)
			( pinPair "@baseboard_fab2_lib.baseboard_fab2(sch_1):\PP3644\"
				( pinRef "@baseboard_fab2_lib.baseboard_fab2(sch_1):page78_i13:BA(0)" )
				( pinRef "@baseboard_fab2_lib.baseboard_fab2(sch_1):page57_i172:DDR0_BA(0)" )
				( attribute "RELATIVE_PROPAGATION_DELAY_SCOPE" "G"
					( Parent
						( matchGroupRef "@crescent_city_bb_fab1_lib.crescent_city_bb_fab1(sch_1):\MG_DDR_NEAR_DIMM-CLK1_CLS_DDR_G_CAC-CLKS\" )
					)
					( Status sCSetFlattened )
					( Origin gBackEnd )
				)
				( attribute "RELATIVE_PROPAGATION_DELAY" "0.00 MIL,700.00 MIL"
					( Parent
						( matchGroupRef "@crescent_city_bb_fab1_lib.crescent_city_bb_fab1(sch_1):\MG_DDR_NEAR_DIMM-CLK1_CLS_DDR_G_CAC-CLKS\" )
					)
					( Units "uMatchProp" "ns" 1.000000)
					( Status sCSetFlattened )
					( Origin gBackEnd )
				)
				( attribute "RELATIVE_PROPAGATION_DELAY_SCOPE" "G"
					( Parent
						( matchGroupRef "@baseboard_fab2_lib.baseboard_fab2(sch_1):\MG_DDR_CMD_NEAR_DIMM_NG_DDR_G_DLL_5\" )
					)
					( Status sCSetFlattened )
					( Origin gBackEnd )
				)
				( attribute "RELATIVE_PROPAGATION_DELAY" "0.00 MIL,25.00 MIL"
					( Parent
						( matchGroupRef "@baseboard_fab2_lib.baseboard_fab2(sch_1):\MG_DDR_CMD_NEAR_DIMM_NG_DDR_G_DLL_5\" )
					)
					( Units "uMatchProp" "ns" 1.000000)
					( Status sCSetFlattened )
					( Origin gBackEnd )
				)
			)
			( pinPair "@baseboard_fab2_lib.baseboard_fab2(sch_1):\PP3645\"
				( pinRef "@baseboard_fab2_lib.baseboard_fab2(sch_1):page57_i172:DDR0_MA(0)" )
				( pinRef "@baseboard_fab2_lib.baseboard_fab2(sch_1):page77_i111:A0" )
				( attribute "RELATIVE_PROPAGATION_DELAY_SCOPE" "G"
					( Parent
						( matchGroupRef "@crescent_city_bb_fab1_lib.crescent_city_bb_fab1(sch_1):\MG_DDR_FAR_DIMM-CLK0_CLS_DDR_G_CAC-CLKS\" )
					)
					( Status sCSetFlattened )
					( Origin gBackEnd )
				)
				( attribute "RELATIVE_PROPAGATION_DELAY" "0.00 MIL,700.00 MIL"
					( Parent
						( matchGroupRef "@crescent_city_bb_fab1_lib.crescent_city_bb_fab1(sch_1):\MG_DDR_FAR_DIMM-CLK0_CLS_DDR_G_CAC-CLKS\" )
					)
					( Units "uMatchProp" "ns" 1.000000)
					( Status sCSetFlattened )
					( Origin gBackEnd )
				)
				( attribute "RELATIVE_PROPAGATION_DELAY_SCOPE" "G"
					( Parent
						( matchGroupRef "@baseboard_fab2_lib.baseboard_fab2(sch_1):\MG_DDR_FAR_DIMM_CMD_NG_DDR_G_DLL_5\" )
					)
					( Status sCSetFlattened )
					( Origin gBackEnd )
				)
				( attribute "RELATIVE_PROPAGATION_DELAY" "0.00 MIL,25.00 MIL"
					( Parent
						( matchGroupRef "@baseboard_fab2_lib.baseboard_fab2(sch_1):\MG_DDR_FAR_DIMM_CMD_NG_DDR_G_DLL_5\" )
					)
					( Units "uMatchProp" "ns" 1.000000)
					( Status sCSetFlattened )
					( Origin gBackEnd )
				)
			)
			( pinPair "@baseboard_fab2_lib.baseboard_fab2(sch_1):\PP3646\"
				( pinRef "@baseboard_fab2_lib.baseboard_fab2(sch_1):page78_i13:A0" )
				( pinRef "@baseboard_fab2_lib.baseboard_fab2(sch_1):page57_i172:DDR0_MA(0)" )
				( attribute "RELATIVE_PROPAGATION_DELAY_SCOPE" "G"
					( Parent
						( matchGroupRef "@crescent_city_bb_fab1_lib.crescent_city_bb_fab1(sch_1):\MG_DDR_NEAR_DIMM-CLK1_CLS_DDR_G_CAC-CLKS\" )
					)
					( Status sCSetFlattened )
					( Origin gBackEnd )
				)
				( attribute "RELATIVE_PROPAGATION_DELAY" "0.00 MIL,700.00 MIL"
					( Parent
						( matchGroupRef "@crescent_city_bb_fab1_lib.crescent_city_bb_fab1(sch_1):\MG_DDR_NEAR_DIMM-CLK1_CLS_DDR_G_CAC-CLKS\" )
					)
					( Units "uMatchProp" "ns" 1.000000)
					( Status sCSetFlattened )
					( Origin gBackEnd )
				)
				( attribute "RELATIVE_PROPAGATION_DELAY_SCOPE" "G"
					( Parent
						( matchGroupRef "@baseboard_fab2_lib.baseboard_fab2(sch_1):\MG_DDR_CMD_NEAR_DIMM_NG_DDR_G_DLL_5\" )
					)
					( Status sCSetFlattened )
					( Origin gBackEnd )
				)
				( attribute "RELATIVE_PROPAGATION_DELAY" "0.00 MIL,25.00 MIL"
					( Parent
						( matchGroupRef "@baseboard_fab2_lib.baseboard_fab2(sch_1):\MG_DDR_CMD_NEAR_DIMM_NG_DDR_G_DLL_5\" )
					)
					( Units "uMatchProp" "ns" 1.000000)
					( Status sCSetFlattened )
					( Origin gBackEnd )
				)
			)
			( pinPair "@baseboard_fab2_lib.baseboard_fab2(sch_1):\PP3641\"
				( pinRef "@baseboard_fab2_lib.baseboard_fab2(sch_1):page57_i172:DDR0_PAR" )
				( pinRef "@baseboard_fab2_lib.baseboard_fab2(sch_1):page77_i111:PAR" )
				( attribute "RELATIVE_PROPAGATION_DELAY_SCOPE" "G"
					( Parent
						( matchGroupRef "@crescent_city_bb_fab1_lib.crescent_city_bb_fab1(sch_1):\MG_DDR_FAR_DIMM-CLK0_CLS_DDR_G_CAC-CLKS\" )
					)
					( Status sCSetFlattened )
					( Origin gBackEnd )
				)
				( attribute "RELATIVE_PROPAGATION_DELAY" "0.00 MIL,700.00 MIL"
					( Parent
						( matchGroupRef "@crescent_city_bb_fab1_lib.crescent_city_bb_fab1(sch_1):\MG_DDR_FAR_DIMM-CLK0_CLS_DDR_G_CAC-CLKS\" )
					)
					( Units "uMatchProp" "ns" 1.000000)
					( Status sCSetFlattened )
					( Origin gBackEnd )
				)
				( attribute "RELATIVE_PROPAGATION_DELAY_SCOPE" "G"
					( Parent
						( matchGroupRef "@baseboard_fab2_lib.baseboard_fab2(sch_1):\MG_DDR_FAR_DIMM_CMD_NG_DDR_G_DLL_6\" )
					)
					( Status sCSetFlattened )
					( Origin gBackEnd )
				)
				( attribute "RELATIVE_PROPAGATION_DELAY" "0.00 MIL,25.00 MIL"
					( Parent
						( matchGroupRef "@baseboard_fab2_lib.baseboard_fab2(sch_1):\MG_DDR_FAR_DIMM_CMD_NG_DDR_G_DLL_6\" )
					)
					( Units "uMatchProp" "ns" 1.000000)
					( Status sCSetFlattened )
					( Origin gBackEnd )
				)
			)
			( pinPair "@baseboard_fab2_lib.baseboard_fab2(sch_1):\PP3642\"
				( pinRef "@baseboard_fab2_lib.baseboard_fab2(sch_1):page78_i13:PAR" )
				( pinRef "@baseboard_fab2_lib.baseboard_fab2(sch_1):page57_i172:DDR0_PAR" )
				( attribute "RELATIVE_PROPAGATION_DELAY_SCOPE" "G"
					( Parent
						( matchGroupRef "@crescent_city_bb_fab1_lib.crescent_city_bb_fab1(sch_1):\MG_DDR_NEAR_DIMM-CLK1_CLS_DDR_G_CAC-CLKS\" )
					)
					( Status sCSetFlattened )
					( Origin gBackEnd )
				)
				( attribute "RELATIVE_PROPAGATION_DELAY" "0.00 MIL,700.00 MIL"
					( Parent
						( matchGroupRef "@crescent_city_bb_fab1_lib.crescent_city_bb_fab1(sch_1):\MG_DDR_NEAR_DIMM-CLK1_CLS_DDR_G_CAC-CLKS\" )
					)
					( Units "uMatchProp" "ns" 1.000000)
					( Status sCSetFlattened )
					( Origin gBackEnd )
				)
				( attribute "RELATIVE_PROPAGATION_DELAY_SCOPE" "G"
					( Parent
						( matchGroupRef "@baseboard_fab2_lib.baseboard_fab2(sch_1):\MG_DDR_CMD_NEAR_DIMM_NG_DDR_G_DLL_6\" )
					)
					( Status sCSetFlattened )
					( Origin gBackEnd )
				)
				( attribute "RELATIVE_PROPAGATION_DELAY" "0.00 MIL,25.00 MIL"
					( Parent
						( matchGroupRef "@baseboard_fab2_lib.baseboard_fab2(sch_1):\MG_DDR_CMD_NEAR_DIMM_NG_DDR_G_DLL_6\" )
					)
					( Units "uMatchProp" "ns" 1.000000)
					( Status sCSetFlattened )
					( Origin gBackEnd )
				)
			)
			( pinPair "@baseboard_fab2_lib.baseboard_fab2(sch_1):\PP3637\"
				( pinRef "@baseboard_fab2_lib.baseboard_fab2(sch_1):page57_i172:DDR0_MA(1)" )
				( pinRef "@baseboard_fab2_lib.baseboard_fab2(sch_1):page77_i111:A1" )
				( attribute "RELATIVE_PROPAGATION_DELAY_SCOPE" "G"
					( Parent
						( matchGroupRef "@crescent_city_bb_fab1_lib.crescent_city_bb_fab1(sch_1):\MG_DDR_FAR_DIMM-CLK0_CLS_DDR_G_CAC-CLKS\" )
					)
					( Status sCSetFlattened )
					( Origin gBackEnd )
				)
				( attribute "RELATIVE_PROPAGATION_DELAY" "0.00 MIL,700.00 MIL"
					( Parent
						( matchGroupRef "@crescent_city_bb_fab1_lib.crescent_city_bb_fab1(sch_1):\MG_DDR_FAR_DIMM-CLK0_CLS_DDR_G_CAC-CLKS\" )
					)
					( Units "uMatchProp" "ns" 1.000000)
					( Status sCSetFlattened )
					( Origin gBackEnd )
				)
				( attribute "RELATIVE_PROPAGATION_DELAY_SCOPE" "G"
					( Parent
						( matchGroupRef "@baseboard_fab2_lib.baseboard_fab2(sch_1):\MG_DDR_FAR_DIMM_CMD_NG_DDR_G_DLL_7\" )
					)
					( Status sCSetFlattened )
					( Origin gBackEnd )
				)
				( attribute "RELATIVE_PROPAGATION_DELAY" "0.00 MIL,25.00 MIL"
					( Parent
						( matchGroupRef "@baseboard_fab2_lib.baseboard_fab2(sch_1):\MG_DDR_FAR_DIMM_CMD_NG_DDR_G_DLL_7\" )
					)
					( Units "uMatchProp" "ns" 1.000000)
					( Status sCSetFlattened )
					( Origin gBackEnd )
				)
			)
			( pinPair "@baseboard_fab2_lib.baseboard_fab2(sch_1):\PP3638\"
				( pinRef "@baseboard_fab2_lib.baseboard_fab2(sch_1):page78_i13:A1" )
				( pinRef "@baseboard_fab2_lib.baseboard_fab2(sch_1):page57_i172:DDR0_MA(1)" )
				( attribute "RELATIVE_PROPAGATION_DELAY_SCOPE" "G"
					( Parent
						( matchGroupRef "@crescent_city_bb_fab1_lib.crescent_city_bb_fab1(sch_1):\MG_DDR_NEAR_DIMM-CLK1_CLS_DDR_G_CAC-CLKS\" )
					)
					( Status sCSetFlattened )
					( Origin gBackEnd )
				)
				( attribute "RELATIVE_PROPAGATION_DELAY" "0.00 MIL,700.00 MIL"
					( Parent
						( matchGroupRef "@crescent_city_bb_fab1_lib.crescent_city_bb_fab1(sch_1):\MG_DDR_NEAR_DIMM-CLK1_CLS_DDR_G_CAC-CLKS\" )
					)
					( Units "uMatchProp" "ns" 1.000000)
					( Status sCSetFlattened )
					( Origin gBackEnd )
				)
				( attribute "RELATIVE_PROPAGATION_DELAY_SCOPE" "G"
					( Parent
						( matchGroupRef "@baseboard_fab2_lib.baseboard_fab2(sch_1):\MG_DDR_CMD_NEAR_DIMM_NG_DDR_G_DLL_7\" )
					)
					( Status sCSetFlattened )
					( Origin gBackEnd )
				)
				( attribute "RELATIVE_PROPAGATION_DELAY" "0.00 MIL,25.00 MIL"
					( Parent
						( matchGroupRef "@baseboard_fab2_lib.baseboard_fab2(sch_1):\MG_DDR_CMD_NEAR_DIMM_NG_DDR_G_DLL_7\" )
					)
					( Units "uMatchProp" "ns" 1.000000)
					( Status sCSetFlattened )
					( Origin gBackEnd )
				)
			)
			( pinPair "@baseboard_fab2_lib.baseboard_fab2(sch_1):\PP3639\"
				( pinRef "@baseboard_fab2_lib.baseboard_fab2(sch_1):page57_i172:DDR0_MA(3)" )
				( pinRef "@baseboard_fab2_lib.baseboard_fab2(sch_1):page77_i111:A3" )
				( attribute "RELATIVE_PROPAGATION_DELAY_SCOPE" "G"
					( Parent
						( matchGroupRef "@crescent_city_bb_fab1_lib.crescent_city_bb_fab1(sch_1):\MG_DDR_FAR_DIMM-CLK0_CLS_DDR_G_CAC-CLKS\" )
					)
					( Status sCSetFlattened )
					( Origin gBackEnd )
				)
				( attribute "RELATIVE_PROPAGATION_DELAY" "0.00 MIL,700.00 MIL"
					( Parent
						( matchGroupRef "@crescent_city_bb_fab1_lib.crescent_city_bb_fab1(sch_1):\MG_DDR_FAR_DIMM-CLK0_CLS_DDR_G_CAC-CLKS\" )
					)
					( Units "uMatchProp" "ns" 1.000000)
					( Status sCSetFlattened )
					( Origin gBackEnd )
				)
				( attribute "RELATIVE_PROPAGATION_DELAY_SCOPE" "G"
					( Parent
						( matchGroupRef "@baseboard_fab2_lib.baseboard_fab2(sch_1):\MG_DDR_FAR_DIMM_CMD_NG_DDR_G_DLL_7\" )
					)
					( Status sCSetFlattened )
					( Origin gBackEnd )
				)
				( attribute "RELATIVE_PROPAGATION_DELAY" "0.00 MIL,25.00 MIL"
					( Parent
						( matchGroupRef "@baseboard_fab2_lib.baseboard_fab2(sch_1):\MG_DDR_FAR_DIMM_CMD_NG_DDR_G_DLL_7\" )
					)
					( Units "uMatchProp" "ns" 1.000000)
					( Status sCSetFlattened )
					( Origin gBackEnd )
				)
			)
			( pinPair "@baseboard_fab2_lib.baseboard_fab2(sch_1):\PP3640\"
				( pinRef "@baseboard_fab2_lib.baseboard_fab2(sch_1):page78_i13:A3" )
				( pinRef "@baseboard_fab2_lib.baseboard_fab2(sch_1):page57_i172:DDR0_MA(3)" )
				( attribute "RELATIVE_PROPAGATION_DELAY_SCOPE" "G"
					( Parent
						( matchGroupRef "@crescent_city_bb_fab1_lib.crescent_city_bb_fab1(sch_1):\MG_DDR_NEAR_DIMM-CLK1_CLS_DDR_G_CAC-CLKS\" )
					)
					( Status sCSetFlattened )
					( Origin gBackEnd )
				)
				( attribute "RELATIVE_PROPAGATION_DELAY" "0.00 MIL,700.00 MIL"
					( Parent
						( matchGroupRef "@crescent_city_bb_fab1_lib.crescent_city_bb_fab1(sch_1):\MG_DDR_NEAR_DIMM-CLK1_CLS_DDR_G_CAC-CLKS\" )
					)
					( Units "uMatchProp" "ns" 1.000000)
					( Status sCSetFlattened )
					( Origin gBackEnd )
				)
				( attribute "RELATIVE_PROPAGATION_DELAY_SCOPE" "G"
					( Parent
						( matchGroupRef "@baseboard_fab2_lib.baseboard_fab2(sch_1):\MG_DDR_CMD_NEAR_DIMM_NG_DDR_G_DLL_7\" )
					)
					( Status sCSetFlattened )
					( Origin gBackEnd )
				)
				( attribute "RELATIVE_PROPAGATION_DELAY" "0.00 MIL,25.00 MIL"
					( Parent
						( matchGroupRef "@baseboard_fab2_lib.baseboard_fab2(sch_1):\MG_DDR_CMD_NEAR_DIMM_NG_DDR_G_DLL_7\" )
					)
					( Units "uMatchProp" "ns" 1.000000)
					( Status sCSetFlattened )
					( Origin gBackEnd )
				)
			)
			( pinPair "@baseboard_fab2_lib.baseboard_fab2(sch_1):\PP3633\"
				( pinRef "@baseboard_fab2_lib.baseboard_fab2(sch_1):page57_i172:DDR0_MA(2)" )
				( pinRef "@baseboard_fab2_lib.baseboard_fab2(sch_1):page77_i111:A2" )
				( attribute "RELATIVE_PROPAGATION_DELAY_SCOPE" "G"
					( Parent
						( matchGroupRef "@crescent_city_bb_fab1_lib.crescent_city_bb_fab1(sch_1):\MG_DDR_FAR_DIMM-CLK0_CLS_DDR_G_CAC-CLKS\" )
					)
					( Status sCSetFlattened )
					( Origin gBackEnd )
				)
				( attribute "RELATIVE_PROPAGATION_DELAY" "0.00 MIL,700.00 MIL"
					( Parent
						( matchGroupRef "@crescent_city_bb_fab1_lib.crescent_city_bb_fab1(sch_1):\MG_DDR_FAR_DIMM-CLK0_CLS_DDR_G_CAC-CLKS\" )
					)
					( Units "uMatchProp" "ns" 1.000000)
					( Status sCSetFlattened )
					( Origin gBackEnd )
				)
				( attribute "RELATIVE_PROPAGATION_DELAY_SCOPE" "G"
					( Parent
						( matchGroupRef "@baseboard_fab2_lib.baseboard_fab2(sch_1):\MG_DDR_FAR_DIMM_CMD_NG_DDR_G_DLL_8\" )
					)
					( Status sCSetFlattened )
					( Origin gBackEnd )
				)
				( attribute "RELATIVE_PROPAGATION_DELAY" "0.00 MIL,25.00 MIL"
					( Parent
						( matchGroupRef "@baseboard_fab2_lib.baseboard_fab2(sch_1):\MG_DDR_FAR_DIMM_CMD_NG_DDR_G_DLL_8\" )
					)
					( Units "uMatchProp" "ns" 1.000000)
					( Status sCSetFlattened )
					( Origin gBackEnd )
				)
			)
			( pinPair "@baseboard_fab2_lib.baseboard_fab2(sch_1):\PP3634\"
				( pinRef "@baseboard_fab2_lib.baseboard_fab2(sch_1):page78_i13:A2" )
				( pinRef "@baseboard_fab2_lib.baseboard_fab2(sch_1):page57_i172:DDR0_MA(2)" )
				( attribute "RELATIVE_PROPAGATION_DELAY_SCOPE" "G"
					( Parent
						( matchGroupRef "@crescent_city_bb_fab1_lib.crescent_city_bb_fab1(sch_1):\MG_DDR_NEAR_DIMM-CLK1_CLS_DDR_G_CAC-CLKS\" )
					)
					( Status sCSetFlattened )
					( Origin gBackEnd )
				)
				( attribute "RELATIVE_PROPAGATION_DELAY" "0.00 MIL,700.00 MIL"
					( Parent
						( matchGroupRef "@crescent_city_bb_fab1_lib.crescent_city_bb_fab1(sch_1):\MG_DDR_NEAR_DIMM-CLK1_CLS_DDR_G_CAC-CLKS\" )
					)
					( Units "uMatchProp" "ns" 1.000000)
					( Status sCSetFlattened )
					( Origin gBackEnd )
				)
				( attribute "RELATIVE_PROPAGATION_DELAY_SCOPE" "G"
					( Parent
						( matchGroupRef "@baseboard_fab2_lib.baseboard_fab2(sch_1):\MG_DDR_CMD_NEAR_DIMM_NG_DDR_G_DLL_8\" )
					)
					( Status sCSetFlattened )
					( Origin gBackEnd )
				)
				( attribute "RELATIVE_PROPAGATION_DELAY" "0.00 MIL,25.00 MIL"
					( Parent
						( matchGroupRef "@baseboard_fab2_lib.baseboard_fab2(sch_1):\MG_DDR_CMD_NEAR_DIMM_NG_DDR_G_DLL_8\" )
					)
					( Units "uMatchProp" "ns" 1.000000)
					( Status sCSetFlattened )
					( Origin gBackEnd )
				)
			)
			( pinPair "@baseboard_fab2_lib.baseboard_fab2(sch_1):\PP3635\"
				( pinRef "@baseboard_fab2_lib.baseboard_fab2(sch_1):page57_i172:DDR0_MA(4)" )
				( pinRef "@baseboard_fab2_lib.baseboard_fab2(sch_1):page77_i111:A4" )
				( attribute "RELATIVE_PROPAGATION_DELAY_SCOPE" "G"
					( Parent
						( matchGroupRef "@crescent_city_bb_fab1_lib.crescent_city_bb_fab1(sch_1):\MG_DDR_FAR_DIMM-CLK0_CLS_DDR_G_CAC-CLKS\" )
					)
					( Status sCSetFlattened )
					( Origin gBackEnd )
				)
				( attribute "RELATIVE_PROPAGATION_DELAY" "0.00 MIL,700.00 MIL"
					( Parent
						( matchGroupRef "@crescent_city_bb_fab1_lib.crescent_city_bb_fab1(sch_1):\MG_DDR_FAR_DIMM-CLK0_CLS_DDR_G_CAC-CLKS\" )
					)
					( Units "uMatchProp" "ns" 1.000000)
					( Status sCSetFlattened )
					( Origin gBackEnd )
				)
				( attribute "RELATIVE_PROPAGATION_DELAY_SCOPE" "G"
					( Parent
						( matchGroupRef "@baseboard_fab2_lib.baseboard_fab2(sch_1):\MG_DDR_FAR_DIMM_CMD_NG_DDR_G_DLL_8\" )
					)
					( Status sCSetFlattened )
					( Origin gBackEnd )
				)
				( attribute "RELATIVE_PROPAGATION_DELAY" "0.00 MIL,25.00 MIL"
					( Parent
						( matchGroupRef "@baseboard_fab2_lib.baseboard_fab2(sch_1):\MG_DDR_FAR_DIMM_CMD_NG_DDR_G_DLL_8\" )
					)
					( Units "uMatchProp" "ns" 1.000000)
					( Status sCSetFlattened )
					( Origin gBackEnd )
				)
			)
			( pinPair "@baseboard_fab2_lib.baseboard_fab2(sch_1):\PP3636\"
				( pinRef "@baseboard_fab2_lib.baseboard_fab2(sch_1):page78_i13:A4" )
				( pinRef "@baseboard_fab2_lib.baseboard_fab2(sch_1):page57_i172:DDR0_MA(4)" )
				( attribute "RELATIVE_PROPAGATION_DELAY_SCOPE" "G"
					( Parent
						( matchGroupRef "@crescent_city_bb_fab1_lib.crescent_city_bb_fab1(sch_1):\MG_DDR_NEAR_DIMM-CLK1_CLS_DDR_G_CAC-CLKS\" )
					)
					( Status sCSetFlattened )
					( Origin gBackEnd )
				)
				( attribute "RELATIVE_PROPAGATION_DELAY" "0.00 MIL,700.00 MIL"
					( Parent
						( matchGroupRef "@crescent_city_bb_fab1_lib.crescent_city_bb_fab1(sch_1):\MG_DDR_NEAR_DIMM-CLK1_CLS_DDR_G_CAC-CLKS\" )
					)
					( Units "uMatchProp" "ns" 1.000000)
					( Status sCSetFlattened )
					( Origin gBackEnd )
				)
				( attribute "RELATIVE_PROPAGATION_DELAY_SCOPE" "G"
					( Parent
						( matchGroupRef "@baseboard_fab2_lib.baseboard_fab2(sch_1):\MG_DDR_CMD_NEAR_DIMM_NG_DDR_G_DLL_8\" )
					)
					( Status sCSetFlattened )
					( Origin gBackEnd )
				)
				( attribute "RELATIVE_PROPAGATION_DELAY" "0.00 MIL,25.00 MIL"
					( Parent
						( matchGroupRef "@baseboard_fab2_lib.baseboard_fab2(sch_1):\MG_DDR_CMD_NEAR_DIMM_NG_DDR_G_DLL_8\" )
					)
					( Units "uMatchProp" "ns" 1.000000)
					( Status sCSetFlattened )
					( Origin gBackEnd )
				)
			)
			( pinPair "@baseboard_fab2_lib.baseboard_fab2(sch_1):\PP3629\"
				( pinRef "@baseboard_fab2_lib.baseboard_fab2(sch_1):page57_i172:DDR0_MA(5)" )
				( pinRef "@baseboard_fab2_lib.baseboard_fab2(sch_1):page77_i111:A5" )
				( attribute "RELATIVE_PROPAGATION_DELAY_SCOPE" "G"
					( Parent
						( matchGroupRef "@crescent_city_bb_fab1_lib.crescent_city_bb_fab1(sch_1):\MG_DDR_FAR_DIMM-CLK0_CLS_DDR_G_CAC-CLKS\" )
					)
					( Status sCSetFlattened )
					( Origin gBackEnd )
				)
				( attribute "RELATIVE_PROPAGATION_DELAY" "0.00 MIL,700.00 MIL"
					( Parent
						( matchGroupRef "@crescent_city_bb_fab1_lib.crescent_city_bb_fab1(sch_1):\MG_DDR_FAR_DIMM-CLK0_CLS_DDR_G_CAC-CLKS\" )
					)
					( Units "uMatchProp" "ns" 1.000000)
					( Status sCSetFlattened )
					( Origin gBackEnd )
				)
				( attribute "RELATIVE_PROPAGATION_DELAY_SCOPE" "G"
					( Parent
						( matchGroupRef "@baseboard_fab2_lib.baseboard_fab2(sch_1):\MG_DDR_FAR_DIMM_CMD_NG_DDR_G_DLL_9\" )
					)
					( Status sCSetFlattened )
					( Origin gBackEnd )
				)
				( attribute "RELATIVE_PROPAGATION_DELAY" "0.00 MIL,25.00 MIL"
					( Parent
						( matchGroupRef "@baseboard_fab2_lib.baseboard_fab2(sch_1):\MG_DDR_FAR_DIMM_CMD_NG_DDR_G_DLL_9\" )
					)
					( Units "uMatchProp" "ns" 1.000000)
					( Status sCSetFlattened )
					( Origin gBackEnd )
				)
			)
			( pinPair "@baseboard_fab2_lib.baseboard_fab2(sch_1):\PP3630\"
				( pinRef "@baseboard_fab2_lib.baseboard_fab2(sch_1):page78_i13:A5" )
				( pinRef "@baseboard_fab2_lib.baseboard_fab2(sch_1):page57_i172:DDR0_MA(5)" )
				( attribute "RELATIVE_PROPAGATION_DELAY_SCOPE" "G"
					( Parent
						( matchGroupRef "@crescent_city_bb_fab1_lib.crescent_city_bb_fab1(sch_1):\MG_DDR_NEAR_DIMM-CLK1_CLS_DDR_G_CAC-CLKS\" )
					)
					( Status sCSetFlattened )
					( Origin gBackEnd )
				)
				( attribute "RELATIVE_PROPAGATION_DELAY" "0.00 MIL,700.00 MIL"
					( Parent
						( matchGroupRef "@crescent_city_bb_fab1_lib.crescent_city_bb_fab1(sch_1):\MG_DDR_NEAR_DIMM-CLK1_CLS_DDR_G_CAC-CLKS\" )
					)
					( Units "uMatchProp" "ns" 1.000000)
					( Status sCSetFlattened )
					( Origin gBackEnd )
				)
				( attribute "RELATIVE_PROPAGATION_DELAY_SCOPE" "G"
					( Parent
						( matchGroupRef "@baseboard_fab2_lib.baseboard_fab2(sch_1):\MG_DDR_CMD_NEAR_DIMM_NG_DDR_G_DLL_9\" )
					)
					( Status sCSetFlattened )
					( Origin gBackEnd )
				)
				( attribute "RELATIVE_PROPAGATION_DELAY" "0.00 MIL,25.00 MIL"
					( Parent
						( matchGroupRef "@baseboard_fab2_lib.baseboard_fab2(sch_1):\MG_DDR_CMD_NEAR_DIMM_NG_DDR_G_DLL_9\" )
					)
					( Units "uMatchProp" "ns" 1.000000)
					( Status sCSetFlattened )
					( Origin gBackEnd )
				)
			)
			( pinPair "@baseboard_fab2_lib.baseboard_fab2(sch_1):\PP3631\"
				( pinRef "@baseboard_fab2_lib.baseboard_fab2(sch_1):page57_i172:DDR0_MA(6)" )
				( pinRef "@baseboard_fab2_lib.baseboard_fab2(sch_1):page77_i111:A6" )
				( attribute "RELATIVE_PROPAGATION_DELAY_SCOPE" "G"
					( Parent
						( matchGroupRef "@crescent_city_bb_fab1_lib.crescent_city_bb_fab1(sch_1):\MG_DDR_FAR_DIMM-CLK0_CLS_DDR_G_CAC-CLKS\" )
					)
					( Status sCSetFlattened )
					( Origin gBackEnd )
				)
				( attribute "RELATIVE_PROPAGATION_DELAY" "0.00 MIL,700.00 MIL"
					( Parent
						( matchGroupRef "@crescent_city_bb_fab1_lib.crescent_city_bb_fab1(sch_1):\MG_DDR_FAR_DIMM-CLK0_CLS_DDR_G_CAC-CLKS\" )
					)
					( Units "uMatchProp" "ns" 1.000000)
					( Status sCSetFlattened )
					( Origin gBackEnd )
				)
				( attribute "RELATIVE_PROPAGATION_DELAY_SCOPE" "G"
					( Parent
						( matchGroupRef "@baseboard_fab2_lib.baseboard_fab2(sch_1):\MG_DDR_FAR_DIMM_CMD_NG_DDR_G_DLL_9\" )
					)
					( Status sCSetFlattened )
					( Origin gBackEnd )
				)
				( attribute "RELATIVE_PROPAGATION_DELAY" "0.00 MIL,25.00 MIL"
					( Parent
						( matchGroupRef "@baseboard_fab2_lib.baseboard_fab2(sch_1):\MG_DDR_FAR_DIMM_CMD_NG_DDR_G_DLL_9\" )
					)
					( Units "uMatchProp" "ns" 1.000000)
					( Status sCSetFlattened )
					( Origin gBackEnd )
				)
			)
			( pinPair "@baseboard_fab2_lib.baseboard_fab2(sch_1):\PP3632\"
				( pinRef "@baseboard_fab2_lib.baseboard_fab2(sch_1):page78_i13:A6" )
				( pinRef "@baseboard_fab2_lib.baseboard_fab2(sch_1):page57_i172:DDR0_MA(6)" )
				( attribute "RELATIVE_PROPAGATION_DELAY_SCOPE" "G"
					( Parent
						( matchGroupRef "@crescent_city_bb_fab1_lib.crescent_city_bb_fab1(sch_1):\MG_DDR_NEAR_DIMM-CLK1_CLS_DDR_G_CAC-CLKS\" )
					)
					( Status sCSetFlattened )
					( Origin gBackEnd )
				)
				( attribute "RELATIVE_PROPAGATION_DELAY" "0.00 MIL,700.00 MIL"
					( Parent
						( matchGroupRef "@crescent_city_bb_fab1_lib.crescent_city_bb_fab1(sch_1):\MG_DDR_NEAR_DIMM-CLK1_CLS_DDR_G_CAC-CLKS\" )
					)
					( Units "uMatchProp" "ns" 1.000000)
					( Status sCSetFlattened )
					( Origin gBackEnd )
				)
				( attribute "RELATIVE_PROPAGATION_DELAY_SCOPE" "G"
					( Parent
						( matchGroupRef "@baseboard_fab2_lib.baseboard_fab2(sch_1):\MG_DDR_CMD_NEAR_DIMM_NG_DDR_G_DLL_9\" )
					)
					( Status sCSetFlattened )
					( Origin gBackEnd )
				)
				( attribute "RELATIVE_PROPAGATION_DELAY" "0.00 MIL,25.00 MIL"
					( Parent
						( matchGroupRef "@baseboard_fab2_lib.baseboard_fab2(sch_1):\MG_DDR_CMD_NEAR_DIMM_NG_DDR_G_DLL_9\" )
					)
					( Units "uMatchProp" "ns" 1.000000)
					( Status sCSetFlattened )
					( Origin gBackEnd )
				)
			)
			( pinPair "@baseboard_fab2_lib.baseboard_fab2(sch_1):\PP3625\"
				( pinRef "@baseboard_fab2_lib.baseboard_fab2(sch_1):page57_i172:DDR0_MA(7)" )
				( pinRef "@baseboard_fab2_lib.baseboard_fab2(sch_1):page77_i111:A7" )
				( attribute "RELATIVE_PROPAGATION_DELAY_SCOPE" "G"
					( Parent
						( matchGroupRef "@crescent_city_bb_fab1_lib.crescent_city_bb_fab1(sch_1):\MG_DDR_FAR_DIMM-CLK0_CLS_DDR_G_CAC-CLKS\" )
					)
					( Status sCSetFlattened )
					( Origin gBackEnd )
				)
				( attribute "RELATIVE_PROPAGATION_DELAY" "0.00 MIL,700.00 MIL"
					( Parent
						( matchGroupRef "@crescent_city_bb_fab1_lib.crescent_city_bb_fab1(sch_1):\MG_DDR_FAR_DIMM-CLK0_CLS_DDR_G_CAC-CLKS\" )
					)
					( Units "uMatchProp" "ns" 1.000000)
					( Status sCSetFlattened )
					( Origin gBackEnd )
				)
				( attribute "RELATIVE_PROPAGATION_DELAY_SCOPE" "G"
					( Parent
						( matchGroupRef "@baseboard_fab2_lib.baseboard_fab2(sch_1):\MG_DDR_FAR_DIMM_CMD_NG_DDR_G_DLL_10\" )
					)
					( Status sCSetFlattened )
					( Origin gBackEnd )
				)
				( attribute "RELATIVE_PROPAGATION_DELAY" "0.00 MIL,25.00 MIL"
					( Parent
						( matchGroupRef "@baseboard_fab2_lib.baseboard_fab2(sch_1):\MG_DDR_FAR_DIMM_CMD_NG_DDR_G_DLL_10\" )
					)
					( Units "uMatchProp" "ns" 1.000000)
					( Status sCSetFlattened )
					( Origin gBackEnd )
				)
			)
			( pinPair "@baseboard_fab2_lib.baseboard_fab2(sch_1):\PP3626\"
				( pinRef "@baseboard_fab2_lib.baseboard_fab2(sch_1):page78_i13:A7" )
				( pinRef "@baseboard_fab2_lib.baseboard_fab2(sch_1):page57_i172:DDR0_MA(7)" )
				( attribute "RELATIVE_PROPAGATION_DELAY_SCOPE" "G"
					( Parent
						( matchGroupRef "@crescent_city_bb_fab1_lib.crescent_city_bb_fab1(sch_1):\MG_DDR_NEAR_DIMM-CLK1_CLS_DDR_G_CAC-CLKS\" )
					)
					( Status sCSetFlattened )
					( Origin gBackEnd )
				)
				( attribute "RELATIVE_PROPAGATION_DELAY" "0.00 MIL,700.00 MIL"
					( Parent
						( matchGroupRef "@crescent_city_bb_fab1_lib.crescent_city_bb_fab1(sch_1):\MG_DDR_NEAR_DIMM-CLK1_CLS_DDR_G_CAC-CLKS\" )
					)
					( Units "uMatchProp" "ns" 1.000000)
					( Status sCSetFlattened )
					( Origin gBackEnd )
				)
				( attribute "RELATIVE_PROPAGATION_DELAY_SCOPE" "G"
					( Parent
						( matchGroupRef "@baseboard_fab2_lib.baseboard_fab2(sch_1):\MG_DDR_CMD_NEAR_DIMM_NG_DDR_G_DLL_10\" )
					)
					( Status sCSetFlattened )
					( Origin gBackEnd )
				)
				( attribute "RELATIVE_PROPAGATION_DELAY" "0.00 MIL,25.00 MIL"
					( Parent
						( matchGroupRef "@baseboard_fab2_lib.baseboard_fab2(sch_1):\MG_DDR_CMD_NEAR_DIMM_NG_DDR_G_DLL_10\" )
					)
					( Units "uMatchProp" "ns" 1.000000)
					( Status sCSetFlattened )
					( Origin gBackEnd )
				)
			)
			( pinPair "@baseboard_fab2_lib.baseboard_fab2(sch_1):\PP3627\"
				( pinRef "@baseboard_fab2_lib.baseboard_fab2(sch_1):page57_i172:DDR0_MA(8)" )
				( pinRef "@baseboard_fab2_lib.baseboard_fab2(sch_1):page77_i111:A8" )
				( attribute "RELATIVE_PROPAGATION_DELAY_SCOPE" "G"
					( Parent
						( matchGroupRef "@crescent_city_bb_fab1_lib.crescent_city_bb_fab1(sch_1):\MG_DDR_FAR_DIMM-CLK0_CLS_DDR_G_CAC-CLKS\" )
					)
					( Status sCSetFlattened )
					( Origin gBackEnd )
				)
				( attribute "RELATIVE_PROPAGATION_DELAY" "0.00 MIL,700.00 MIL"
					( Parent
						( matchGroupRef "@crescent_city_bb_fab1_lib.crescent_city_bb_fab1(sch_1):\MG_DDR_FAR_DIMM-CLK0_CLS_DDR_G_CAC-CLKS\" )
					)
					( Units "uMatchProp" "ns" 1.000000)
					( Status sCSetFlattened )
					( Origin gBackEnd )
				)
				( attribute "RELATIVE_PROPAGATION_DELAY_SCOPE" "G"
					( Parent
						( matchGroupRef "@baseboard_fab2_lib.baseboard_fab2(sch_1):\MG_DDR_FAR_DIMM_CMD_NG_DDR_G_DLL_10\" )
					)
					( Status sCSetFlattened )
					( Origin gBackEnd )
				)
				( attribute "RELATIVE_PROPAGATION_DELAY" "0.00 MIL,25.00 MIL"
					( Parent
						( matchGroupRef "@baseboard_fab2_lib.baseboard_fab2(sch_1):\MG_DDR_FAR_DIMM_CMD_NG_DDR_G_DLL_10\" )
					)
					( Units "uMatchProp" "ns" 1.000000)
					( Status sCSetFlattened )
					( Origin gBackEnd )
				)
			)
			( pinPair "@baseboard_fab2_lib.baseboard_fab2(sch_1):\PP3628\"
				( pinRef "@baseboard_fab2_lib.baseboard_fab2(sch_1):page78_i13:A8" )
				( pinRef "@baseboard_fab2_lib.baseboard_fab2(sch_1):page57_i172:DDR0_MA(8)" )
				( attribute "RELATIVE_PROPAGATION_DELAY_SCOPE" "G"
					( Parent
						( matchGroupRef "@crescent_city_bb_fab1_lib.crescent_city_bb_fab1(sch_1):\MG_DDR_NEAR_DIMM-CLK1_CLS_DDR_G_CAC-CLKS\" )
					)
					( Status sCSetFlattened )
					( Origin gBackEnd )
				)
				( attribute "RELATIVE_PROPAGATION_DELAY" "0.00 MIL,700.00 MIL"
					( Parent
						( matchGroupRef "@crescent_city_bb_fab1_lib.crescent_city_bb_fab1(sch_1):\MG_DDR_NEAR_DIMM-CLK1_CLS_DDR_G_CAC-CLKS\" )
					)
					( Units "uMatchProp" "ns" 1.000000)
					( Status sCSetFlattened )
					( Origin gBackEnd )
				)
				( attribute "RELATIVE_PROPAGATION_DELAY_SCOPE" "G"
					( Parent
						( matchGroupRef "@baseboard_fab2_lib.baseboard_fab2(sch_1):\MG_DDR_CMD_NEAR_DIMM_NG_DDR_G_DLL_10\" )
					)
					( Status sCSetFlattened )
					( Origin gBackEnd )
				)
				( attribute "RELATIVE_PROPAGATION_DELAY" "0.00 MIL,25.00 MIL"
					( Parent
						( matchGroupRef "@baseboard_fab2_lib.baseboard_fab2(sch_1):\MG_DDR_CMD_NEAR_DIMM_NG_DDR_G_DLL_10\" )
					)
					( Units "uMatchProp" "ns" 1.000000)
					( Status sCSetFlattened )
					( Origin gBackEnd )
				)
			)
			( pinPair "@baseboard_fab2_lib.baseboard_fab2(sch_1):\PP3621\"
				( pinRef "@baseboard_fab2_lib.baseboard_fab2(sch_1):page57_i172:DDR0_MA(9)" )
				( pinRef "@baseboard_fab2_lib.baseboard_fab2(sch_1):page77_i111:A9" )
				( attribute "RELATIVE_PROPAGATION_DELAY_SCOPE" "G"
					( Parent
						( matchGroupRef "@crescent_city_bb_fab1_lib.crescent_city_bb_fab1(sch_1):\MG_DDR_FAR_DIMM-CLK0_CLS_DDR_G_CAC-CLKS\" )
					)
					( Status sCSetFlattened )
					( Origin gBackEnd )
				)
				( attribute "RELATIVE_PROPAGATION_DELAY" "0.00 MIL,700.00 MIL"
					( Parent
						( matchGroupRef "@crescent_city_bb_fab1_lib.crescent_city_bb_fab1(sch_1):\MG_DDR_FAR_DIMM-CLK0_CLS_DDR_G_CAC-CLKS\" )
					)
					( Units "uMatchProp" "ns" 1.000000)
					( Status sCSetFlattened )
					( Origin gBackEnd )
				)
				( attribute "RELATIVE_PROPAGATION_DELAY_SCOPE" "G"
					( Parent
						( matchGroupRef "@baseboard_fab2_lib.baseboard_fab2(sch_1):\MG_DDR_FAR_DIMM_CMD_NG_DDR_G_DLL_11\" )
					)
					( Status sCSetFlattened )
					( Origin gBackEnd )
				)
				( attribute "RELATIVE_PROPAGATION_DELAY" "0.00 MIL,25.00 MIL"
					( Parent
						( matchGroupRef "@baseboard_fab2_lib.baseboard_fab2(sch_1):\MG_DDR_FAR_DIMM_CMD_NG_DDR_G_DLL_11\" )
					)
					( Units "uMatchProp" "ns" 1.000000)
					( Status sCSetFlattened )
					( Origin gBackEnd )
				)
			)
			( pinPair "@baseboard_fab2_lib.baseboard_fab2(sch_1):\PP3622\"
				( pinRef "@baseboard_fab2_lib.baseboard_fab2(sch_1):page78_i13:A9" )
				( pinRef "@baseboard_fab2_lib.baseboard_fab2(sch_1):page57_i172:DDR0_MA(9)" )
				( attribute "RELATIVE_PROPAGATION_DELAY_SCOPE" "G"
					( Parent
						( matchGroupRef "@crescent_city_bb_fab1_lib.crescent_city_bb_fab1(sch_1):\MG_DDR_NEAR_DIMM-CLK1_CLS_DDR_G_CAC-CLKS\" )
					)
					( Status sCSetFlattened )
					( Origin gBackEnd )
				)
				( attribute "RELATIVE_PROPAGATION_DELAY" "0.00 MIL,700.00 MIL"
					( Parent
						( matchGroupRef "@crescent_city_bb_fab1_lib.crescent_city_bb_fab1(sch_1):\MG_DDR_NEAR_DIMM-CLK1_CLS_DDR_G_CAC-CLKS\" )
					)
					( Units "uMatchProp" "ns" 1.000000)
					( Status sCSetFlattened )
					( Origin gBackEnd )
				)
				( attribute "RELATIVE_PROPAGATION_DELAY_SCOPE" "G"
					( Parent
						( matchGroupRef "@baseboard_fab2_lib.baseboard_fab2(sch_1):\MG_DDR_CMD_NEAR_DIMM_NG_DDR_G_DLL_11\" )
					)
					( Status sCSetFlattened )
					( Origin gBackEnd )
				)
				( attribute "RELATIVE_PROPAGATION_DELAY" "0.00 MIL,25.00 MIL"
					( Parent
						( matchGroupRef "@baseboard_fab2_lib.baseboard_fab2(sch_1):\MG_DDR_CMD_NEAR_DIMM_NG_DDR_G_DLL_11\" )
					)
					( Units "uMatchProp" "ns" 1.000000)
					( Status sCSetFlattened )
					( Origin gBackEnd )
				)
			)
			( pinPair "@baseboard_fab2_lib.baseboard_fab2(sch_1):\PP3623\"
				( pinRef "@baseboard_fab2_lib.baseboard_fab2(sch_1):page57_i172:DDR0_MA(12)" )
				( pinRef "@baseboard_fab2_lib.baseboard_fab2(sch_1):page77_i111:A12" )
				( attribute "RELATIVE_PROPAGATION_DELAY_SCOPE" "G"
					( Parent
						( matchGroupRef "@crescent_city_bb_fab1_lib.crescent_city_bb_fab1(sch_1):\MG_DDR_FAR_DIMM-CLK0_CLS_DDR_G_CAC-CLKS\" )
					)
					( Status sCSetFlattened )
					( Origin gBackEnd )
				)
				( attribute "RELATIVE_PROPAGATION_DELAY" "0.00 MIL,700.00 MIL"
					( Parent
						( matchGroupRef "@crescent_city_bb_fab1_lib.crescent_city_bb_fab1(sch_1):\MG_DDR_FAR_DIMM-CLK0_CLS_DDR_G_CAC-CLKS\" )
					)
					( Units "uMatchProp" "ns" 1.000000)
					( Status sCSetFlattened )
					( Origin gBackEnd )
				)
				( attribute "RELATIVE_PROPAGATION_DELAY_SCOPE" "G"
					( Parent
						( matchGroupRef "@baseboard_fab2_lib.baseboard_fab2(sch_1):\MG_DDR_FAR_DIMM_CMD_NG_DDR_G_DLL_11\" )
					)
					( Status sCSetFlattened )
					( Origin gBackEnd )
				)
				( attribute "RELATIVE_PROPAGATION_DELAY" "0.00 MIL,25.00 MIL"
					( Parent
						( matchGroupRef "@baseboard_fab2_lib.baseboard_fab2(sch_1):\MG_DDR_FAR_DIMM_CMD_NG_DDR_G_DLL_11\" )
					)
					( Units "uMatchProp" "ns" 1.000000)
					( Status sCSetFlattened )
					( Origin gBackEnd )
				)
			)
			( pinPair "@baseboard_fab2_lib.baseboard_fab2(sch_1):\PP3624\"
				( pinRef "@baseboard_fab2_lib.baseboard_fab2(sch_1):page78_i13:A12" )
				( pinRef "@baseboard_fab2_lib.baseboard_fab2(sch_1):page57_i172:DDR0_MA(12)" )
				( attribute "RELATIVE_PROPAGATION_DELAY_SCOPE" "G"
					( Parent
						( matchGroupRef "@crescent_city_bb_fab1_lib.crescent_city_bb_fab1(sch_1):\MG_DDR_NEAR_DIMM-CLK1_CLS_DDR_G_CAC-CLKS\" )
					)
					( Status sCSetFlattened )
					( Origin gBackEnd )
				)
				( attribute "RELATIVE_PROPAGATION_DELAY" "0.00 MIL,700.00 MIL"
					( Parent
						( matchGroupRef "@crescent_city_bb_fab1_lib.crescent_city_bb_fab1(sch_1):\MG_DDR_NEAR_DIMM-CLK1_CLS_DDR_G_CAC-CLKS\" )
					)
					( Units "uMatchProp" "ns" 1.000000)
					( Status sCSetFlattened )
					( Origin gBackEnd )
				)
				( attribute "RELATIVE_PROPAGATION_DELAY_SCOPE" "G"
					( Parent
						( matchGroupRef "@baseboard_fab2_lib.baseboard_fab2(sch_1):\MG_DDR_CMD_NEAR_DIMM_NG_DDR_G_DLL_11\" )
					)
					( Status sCSetFlattened )
					( Origin gBackEnd )
				)
				( attribute "RELATIVE_PROPAGATION_DELAY" "0.00 MIL,25.00 MIL"
					( Parent
						( matchGroupRef "@baseboard_fab2_lib.baseboard_fab2(sch_1):\MG_DDR_CMD_NEAR_DIMM_NG_DDR_G_DLL_11\" )
					)
					( Units "uMatchProp" "ns" 1.000000)
					( Status sCSetFlattened )
					( Origin gBackEnd )
				)
			)
			( pinPair "@baseboard_fab2_lib.baseboard_fab2(sch_1):\PP3617\"
				( pinRef "@baseboard_fab2_lib.baseboard_fab2(sch_1):page57_i172:DDR0_BG(1)" )
				( pinRef "@baseboard_fab2_lib.baseboard_fab2(sch_1):page77_i111:BG(1)" )
				( attribute "RELATIVE_PROPAGATION_DELAY_SCOPE" "G"
					( Parent
						( matchGroupRef "@crescent_city_bb_fab1_lib.crescent_city_bb_fab1(sch_1):\MG_DDR_FAR_DIMM-CLK0_CLS_DDR_G_CAC-CLKS\" )
					)
					( Status sCSetFlattened )
					( Origin gBackEnd )
				)
				( attribute "RELATIVE_PROPAGATION_DELAY" "0.00 MIL,700.00 MIL"
					( Parent
						( matchGroupRef "@crescent_city_bb_fab1_lib.crescent_city_bb_fab1(sch_1):\MG_DDR_FAR_DIMM-CLK0_CLS_DDR_G_CAC-CLKS\" )
					)
					( Units "uMatchProp" "ns" 1.000000)
					( Status sCSetFlattened )
					( Origin gBackEnd )
				)
				( attribute "RELATIVE_PROPAGATION_DELAY_SCOPE" "G"
					( Parent
						( matchGroupRef "@baseboard_fab2_lib.baseboard_fab2(sch_1):\MG_DDR_FAR_DIMM_CMD_NG_DDR_G_DLL_12\" )
					)
					( Status sCSetFlattened )
					( Origin gBackEnd )
				)
				( attribute "RELATIVE_PROPAGATION_DELAY" "0.00 MIL,25.00 MIL"
					( Parent
						( matchGroupRef "@baseboard_fab2_lib.baseboard_fab2(sch_1):\MG_DDR_FAR_DIMM_CMD_NG_DDR_G_DLL_12\" )
					)
					( Units "uMatchProp" "ns" 1.000000)
					( Status sCSetFlattened )
					( Origin gBackEnd )
				)
			)
			( pinPair "@baseboard_fab2_lib.baseboard_fab2(sch_1):\PP3618\"
				( pinRef "@baseboard_fab2_lib.baseboard_fab2(sch_1):page78_i13:BG(1)" )
				( pinRef "@baseboard_fab2_lib.baseboard_fab2(sch_1):page57_i172:DDR0_BG(1)" )
				( attribute "RELATIVE_PROPAGATION_DELAY_SCOPE" "G"
					( Parent
						( matchGroupRef "@crescent_city_bb_fab1_lib.crescent_city_bb_fab1(sch_1):\MG_DDR_NEAR_DIMM-CLK1_CLS_DDR_G_CAC-CLKS\" )
					)
					( Status sCSetFlattened )
					( Origin gBackEnd )
				)
				( attribute "RELATIVE_PROPAGATION_DELAY" "0.00 MIL,700.00 MIL"
					( Parent
						( matchGroupRef "@crescent_city_bb_fab1_lib.crescent_city_bb_fab1(sch_1):\MG_DDR_NEAR_DIMM-CLK1_CLS_DDR_G_CAC-CLKS\" )
					)
					( Units "uMatchProp" "ns" 1.000000)
					( Status sCSetFlattened )
					( Origin gBackEnd )
				)
				( attribute "RELATIVE_PROPAGATION_DELAY_SCOPE" "G"
					( Parent
						( matchGroupRef "@baseboard_fab2_lib.baseboard_fab2(sch_1):\MG_DDR_CMD_NEAR_DIMM_NG_DDR_G_DLL_12\" )
					)
					( Status sCSetFlattened )
					( Origin gBackEnd )
				)
				( attribute "RELATIVE_PROPAGATION_DELAY" "0.00 MIL,25.00 MIL"
					( Parent
						( matchGroupRef "@baseboard_fab2_lib.baseboard_fab2(sch_1):\MG_DDR_CMD_NEAR_DIMM_NG_DDR_G_DLL_12\" )
					)
					( Units "uMatchProp" "ns" 1.000000)
					( Status sCSetFlattened )
					( Origin gBackEnd )
				)
			)
			( pinPair "@baseboard_fab2_lib.baseboard_fab2(sch_1):\PP3619\"
				( pinRef "@baseboard_fab2_lib.baseboard_fab2(sch_1):page57_i172:DDR0_MA(11)" )
				( pinRef "@baseboard_fab2_lib.baseboard_fab2(sch_1):page77_i111:A11" )
				( attribute "RELATIVE_PROPAGATION_DELAY_SCOPE" "G"
					( Parent
						( matchGroupRef "@crescent_city_bb_fab1_lib.crescent_city_bb_fab1(sch_1):\MG_DDR_FAR_DIMM-CLK0_CLS_DDR_G_CAC-CLKS\" )
					)
					( Status sCSetFlattened )
					( Origin gBackEnd )
				)
				( attribute "RELATIVE_PROPAGATION_DELAY" "0.00 MIL,700.00 MIL"
					( Parent
						( matchGroupRef "@crescent_city_bb_fab1_lib.crescent_city_bb_fab1(sch_1):\MG_DDR_FAR_DIMM-CLK0_CLS_DDR_G_CAC-CLKS\" )
					)
					( Units "uMatchProp" "ns" 1.000000)
					( Status sCSetFlattened )
					( Origin gBackEnd )
				)
				( attribute "RELATIVE_PROPAGATION_DELAY_SCOPE" "G"
					( Parent
						( matchGroupRef "@baseboard_fab2_lib.baseboard_fab2(sch_1):\MG_DDR_FAR_DIMM_CMD_NG_DDR_G_DLL_12\" )
					)
					( Status sCSetFlattened )
					( Origin gBackEnd )
				)
				( attribute "RELATIVE_PROPAGATION_DELAY" "0.00 MIL,25.00 MIL"
					( Parent
						( matchGroupRef "@baseboard_fab2_lib.baseboard_fab2(sch_1):\MG_DDR_FAR_DIMM_CMD_NG_DDR_G_DLL_12\" )
					)
					( Units "uMatchProp" "ns" 1.000000)
					( Status sCSetFlattened )
					( Origin gBackEnd )
				)
			)
			( pinPair "@baseboard_fab2_lib.baseboard_fab2(sch_1):\PP3620\"
				( pinRef "@baseboard_fab2_lib.baseboard_fab2(sch_1):page78_i13:A11" )
				( pinRef "@baseboard_fab2_lib.baseboard_fab2(sch_1):page57_i172:DDR0_MA(11)" )
				( attribute "RELATIVE_PROPAGATION_DELAY_SCOPE" "G"
					( Parent
						( matchGroupRef "@crescent_city_bb_fab1_lib.crescent_city_bb_fab1(sch_1):\MG_DDR_NEAR_DIMM-CLK1_CLS_DDR_G_CAC-CLKS\" )
					)
					( Status sCSetFlattened )
					( Origin gBackEnd )
				)
				( attribute "RELATIVE_PROPAGATION_DELAY" "0.00 MIL,700.00 MIL"
					( Parent
						( matchGroupRef "@crescent_city_bb_fab1_lib.crescent_city_bb_fab1(sch_1):\MG_DDR_NEAR_DIMM-CLK1_CLS_DDR_G_CAC-CLKS\" )
					)
					( Units "uMatchProp" "ns" 1.000000)
					( Status sCSetFlattened )
					( Origin gBackEnd )
				)
				( attribute "RELATIVE_PROPAGATION_DELAY_SCOPE" "G"
					( Parent
						( matchGroupRef "@baseboard_fab2_lib.baseboard_fab2(sch_1):\MG_DDR_CMD_NEAR_DIMM_NG_DDR_G_DLL_12\" )
					)
					( Status sCSetFlattened )
					( Origin gBackEnd )
				)
				( attribute "RELATIVE_PROPAGATION_DELAY" "0.00 MIL,25.00 MIL"
					( Parent
						( matchGroupRef "@baseboard_fab2_lib.baseboard_fab2(sch_1):\MG_DDR_CMD_NEAR_DIMM_NG_DDR_G_DLL_12\" )
					)
					( Units "uMatchProp" "ns" 1.000000)
					( Status sCSetFlattened )
					( Origin gBackEnd )
				)
			)
			( pinPair "@baseboard_fab2_lib.baseboard_fab2(sch_1):\PP3613\"
				( pinRef "@baseboard_fab2_lib.baseboard_fab2(sch_1):page57_i172:DDR0_ACT_N" )
				( pinRef "@baseboard_fab2_lib.baseboard_fab2(sch_1):page77_i111:ACT_N" )
				( attribute "RELATIVE_PROPAGATION_DELAY_SCOPE" "G"
					( Parent
						( matchGroupRef "@crescent_city_bb_fab1_lib.crescent_city_bb_fab1(sch_1):\MG_DDR_FAR_DIMM-CLK0_CLS_DDR_G_CAC-CLKS\" )
					)
					( Status sCSetFlattened )
					( Origin gBackEnd )
				)
				( attribute "RELATIVE_PROPAGATION_DELAY" "0.00 MIL,700.00 MIL"
					( Parent
						( matchGroupRef "@crescent_city_bb_fab1_lib.crescent_city_bb_fab1(sch_1):\MG_DDR_FAR_DIMM-CLK0_CLS_DDR_G_CAC-CLKS\" )
					)
					( Units "uMatchProp" "ns" 1.000000)
					( Status sCSetFlattened )
					( Origin gBackEnd )
				)
				( attribute "RELATIVE_PROPAGATION_DELAY_SCOPE" "G"
					( Parent
						( matchGroupRef "@baseboard_fab2_lib.baseboard_fab2(sch_1):\MG_DDR_FAR_DIMM_CMD_NG_DDR_G_DLL_13\" )
					)
					( Status sCSetFlattened )
					( Origin gBackEnd )
				)
				( attribute "RELATIVE_PROPAGATION_DELAY" "0.00 MIL,25.00 MIL"
					( Parent
						( matchGroupRef "@baseboard_fab2_lib.baseboard_fab2(sch_1):\MG_DDR_FAR_DIMM_CMD_NG_DDR_G_DLL_13\" )
					)
					( Units "uMatchProp" "ns" 1.000000)
					( Status sCSetFlattened )
					( Origin gBackEnd )
				)
			)
			( pinPair "@baseboard_fab2_lib.baseboard_fab2(sch_1):\PP3614\"
				( pinRef "@baseboard_fab2_lib.baseboard_fab2(sch_1):page78_i13:ACT_N" )
				( pinRef "@baseboard_fab2_lib.baseboard_fab2(sch_1):page57_i172:DDR0_ACT_N" )
				( attribute "RELATIVE_PROPAGATION_DELAY_SCOPE" "G"
					( Parent
						( matchGroupRef "@crescent_city_bb_fab1_lib.crescent_city_bb_fab1(sch_1):\MG_DDR_NEAR_DIMM-CLK1_CLS_DDR_G_CAC-CLKS\" )
					)
					( Status sCSetFlattened )
					( Origin gBackEnd )
				)
				( attribute "RELATIVE_PROPAGATION_DELAY" "0.00 MIL,700.00 MIL"
					( Parent
						( matchGroupRef "@crescent_city_bb_fab1_lib.crescent_city_bb_fab1(sch_1):\MG_DDR_NEAR_DIMM-CLK1_CLS_DDR_G_CAC-CLKS\" )
					)
					( Units "uMatchProp" "ns" 1.000000)
					( Status sCSetFlattened )
					( Origin gBackEnd )
				)
				( attribute "RELATIVE_PROPAGATION_DELAY_SCOPE" "G"
					( Parent
						( matchGroupRef "@baseboard_fab2_lib.baseboard_fab2(sch_1):\MG_DDR_CMD_NEAR_DIMM_NG_DDR_G_DLL_13\" )
					)
					( Status sCSetFlattened )
					( Origin gBackEnd )
				)
				( attribute "RELATIVE_PROPAGATION_DELAY" "0.00 MIL,25.00 MIL"
					( Parent
						( matchGroupRef "@baseboard_fab2_lib.baseboard_fab2(sch_1):\MG_DDR_CMD_NEAR_DIMM_NG_DDR_G_DLL_13\" )
					)
					( Units "uMatchProp" "ns" 1.000000)
					( Status sCSetFlattened )
					( Origin gBackEnd )
				)
			)
			( pinPair "@baseboard_fab2_lib.baseboard_fab2(sch_1):\PP3615\"
				( pinRef "@baseboard_fab2_lib.baseboard_fab2(sch_1):page57_i172:DDR0_BG(0)" )
				( pinRef "@baseboard_fab2_lib.baseboard_fab2(sch_1):page77_i111:BG(0)" )
				( attribute "RELATIVE_PROPAGATION_DELAY_SCOPE" "G"
					( Parent
						( matchGroupRef "@crescent_city_bb_fab1_lib.crescent_city_bb_fab1(sch_1):\MG_DDR_FAR_DIMM-CLK0_CLS_DDR_G_CAC-CLKS\" )
					)
					( Status sCSetFlattened )
					( Origin gBackEnd )
				)
				( attribute "RELATIVE_PROPAGATION_DELAY" "0.00 MIL,700.00 MIL"
					( Parent
						( matchGroupRef "@crescent_city_bb_fab1_lib.crescent_city_bb_fab1(sch_1):\MG_DDR_FAR_DIMM-CLK0_CLS_DDR_G_CAC-CLKS\" )
					)
					( Units "uMatchProp" "ns" 1.000000)
					( Status sCSetFlattened )
					( Origin gBackEnd )
				)
				( attribute "RELATIVE_PROPAGATION_DELAY_SCOPE" "G"
					( Parent
						( matchGroupRef "@baseboard_fab2_lib.baseboard_fab2(sch_1):\MG_DDR_FAR_DIMM_CMD_NG_DDR_G_DLL_13\" )
					)
					( Status sCSetFlattened )
					( Origin gBackEnd )
				)
				( attribute "RELATIVE_PROPAGATION_DELAY" "0.00 MIL,25.00 MIL"
					( Parent
						( matchGroupRef "@baseboard_fab2_lib.baseboard_fab2(sch_1):\MG_DDR_FAR_DIMM_CMD_NG_DDR_G_DLL_13\" )
					)
					( Units "uMatchProp" "ns" 1.000000)
					( Status sCSetFlattened )
					( Origin gBackEnd )
				)
			)
			( pinPair "@baseboard_fab2_lib.baseboard_fab2(sch_1):\PP3616\"
				( pinRef "@baseboard_fab2_lib.baseboard_fab2(sch_1):page78_i13:BG(0)" )
				( pinRef "@baseboard_fab2_lib.baseboard_fab2(sch_1):page57_i172:DDR0_BG(0)" )
				( attribute "RELATIVE_PROPAGATION_DELAY_SCOPE" "G"
					( Parent
						( matchGroupRef "@crescent_city_bb_fab1_lib.crescent_city_bb_fab1(sch_1):\MG_DDR_NEAR_DIMM-CLK1_CLS_DDR_G_CAC-CLKS\" )
					)
					( Status sCSetFlattened )
					( Origin gBackEnd )
				)
				( attribute "RELATIVE_PROPAGATION_DELAY" "0.00 MIL,700.00 MIL"
					( Parent
						( matchGroupRef "@crescent_city_bb_fab1_lib.crescent_city_bb_fab1(sch_1):\MG_DDR_NEAR_DIMM-CLK1_CLS_DDR_G_CAC-CLKS\" )
					)
					( Units "uMatchProp" "ns" 1.000000)
					( Status sCSetFlattened )
					( Origin gBackEnd )
				)
				( attribute "RELATIVE_PROPAGATION_DELAY_SCOPE" "G"
					( Parent
						( matchGroupRef "@baseboard_fab2_lib.baseboard_fab2(sch_1):\MG_DDR_CMD_NEAR_DIMM_NG_DDR_G_DLL_13\" )
					)
					( Status sCSetFlattened )
					( Origin gBackEnd )
				)
				( attribute "RELATIVE_PROPAGATION_DELAY" "0.00 MIL,25.00 MIL"
					( Parent
						( matchGroupRef "@baseboard_fab2_lib.baseboard_fab2(sch_1):\MG_DDR_CMD_NEAR_DIMM_NG_DDR_G_DLL_13\" )
					)
					( Units "uMatchProp" "ns" 1.000000)
					( Status sCSetFlattened )
					( Origin gBackEnd )
				)
			)
			( pinPair "@baseboard_fab2_lib.baseboard_fab2(sch_1):\PP3611\"
				( pinRef "@baseboard_fab2_lib.baseboard_fab2(sch_1):page77_i111:S0_N" )
				( pinRef "@baseboard_fab2_lib.baseboard_fab2(sch_1):page57_i172:DDR0_CS_N(0)" )
				( attribute "RELATIVE_PROPAGATION_DELAY_SCOPE" "G"
					( Parent
						( matchGroupRef "@crescent_city_bb_fab1_lib.crescent_city_bb_fab1(sch_1):\MG_DDR_FAR_DIMM-CLK0_CLS_DDR_G_CAC-CLKS\" )
					)
					( Status sCSetFlattened )
					( Origin gBackEnd )
				)
				( attribute "RELATIVE_PROPAGATION_DELAY" "0.00 MIL,300.00 MIL"
					( Parent
						( matchGroupRef "@crescent_city_bb_fab1_lib.crescent_city_bb_fab1(sch_1):\MG_DDR_FAR_DIMM-CLK0_CLS_DDR_G_CAC-CLKS\" )
					)
					( Units "uMatchProp" "ns" 1.000000)
					( Status sCSetFlattened )
					( Origin gBackEnd )
				)
				( attribute "RELATIVE_PROPAGATION_DELAY_SCOPE" "G"
					( Parent
						( matchGroupRef "@baseboard_fab2_lib.baseboard_fab2(sch_1):\MG_DDR_CTRL_NG_DDR_G_DLL_14\" )
					)
					( Status sCSetFlattened )
					( Origin gBackEnd )
				)
				( attribute "RELATIVE_PROPAGATION_DELAY" "0.00 MIL,25.00 MIL"
					( Parent
						( matchGroupRef "@baseboard_fab2_lib.baseboard_fab2(sch_1):\MG_DDR_CTRL_NG_DDR_G_DLL_14\" )
					)
					( Units "uMatchProp" "ns" 1.000000)
					( Status sCSetFlattened )
					( Origin gBackEnd )
				)
			)
			( pinPair "@baseboard_fab2_lib.baseboard_fab2(sch_1):\PP3612\"
				( pinRef "@baseboard_fab2_lib.baseboard_fab2(sch_1):page77_i111:ODT(0)" )
				( pinRef "@baseboard_fab2_lib.baseboard_fab2(sch_1):page57_i172:DDR0_ODT(0)" )
				( attribute "RELATIVE_PROPAGATION_DELAY_SCOPE" "G"
					( Parent
						( matchGroupRef "@crescent_city_bb_fab1_lib.crescent_city_bb_fab1(sch_1):\MG_DDR_FAR_DIMM-CLK0_CLS_DDR_G_CAC-CLKS\" )
					)
					( Status sCSetFlattened )
					( Origin gBackEnd )
				)
				( attribute "RELATIVE_PROPAGATION_DELAY" "0.00 MIL,300.00 MIL"
					( Parent
						( matchGroupRef "@crescent_city_bb_fab1_lib.crescent_city_bb_fab1(sch_1):\MG_DDR_FAR_DIMM-CLK0_CLS_DDR_G_CAC-CLKS\" )
					)
					( Units "uMatchProp" "ns" 1.000000)
					( Status sCSetFlattened )
					( Origin gBackEnd )
				)
				( attribute "RELATIVE_PROPAGATION_DELAY_SCOPE" "G"
					( Parent
						( matchGroupRef "@baseboard_fab2_lib.baseboard_fab2(sch_1):\MG_DDR_CTRL_NG_DDR_G_DLL_14\" )
					)
					( Status sCSetFlattened )
					( Origin gBackEnd )
				)
				( attribute "RELATIVE_PROPAGATION_DELAY" "0.00 MIL,25.00 MIL"
					( Parent
						( matchGroupRef "@baseboard_fab2_lib.baseboard_fab2(sch_1):\MG_DDR_CTRL_NG_DDR_G_DLL_14\" )
					)
					( Units "uMatchProp" "ns" 1.000000)
					( Status sCSetFlattened )
					( Origin gBackEnd )
				)
			)
			( pinPair "@baseboard_fab2_lib.baseboard_fab2(sch_1):\PP3610\"
				( pinRef "@baseboard_fab2_lib.baseboard_fab2(sch_1):page77_i111:CKE(0)" )
				( pinRef "@baseboard_fab2_lib.baseboard_fab2(sch_1):page57_i172:DDR0_CKE(0)" )
				( attribute "RELATIVE_PROPAGATION_DELAY_SCOPE" "G"
					( Parent
						( matchGroupRef "@crescent_city_bb_fab1_lib.crescent_city_bb_fab1(sch_1):\MG_DDR_FAR_DIMM-CLK0_CLS_DDR_G_CAC-CLKS\" )
					)
					( Status sCSetFlattened )
					( Origin gBackEnd )
				)
				( attribute "RELATIVE_PROPAGATION_DELAY" "0.00 MIL,300.00 MIL"
					( Parent
						( matchGroupRef "@crescent_city_bb_fab1_lib.crescent_city_bb_fab1(sch_1):\MG_DDR_FAR_DIMM-CLK0_CLS_DDR_G_CAC-CLKS\" )
					)
					( Units "uMatchProp" "ns" 1.000000)
					( Status sCSetFlattened )
					( Origin gBackEnd )
				)
				( attribute "RELATIVE_PROPAGATION_DELAY_SCOPE" "G"
					( Parent
						( matchGroupRef "@baseboard_fab2_lib.baseboard_fab2(sch_1):\MG_DDR_CTRL_NG_DDR_G_DLL_15\" )
					)
					( Status sCSetFlattened )
					( Origin gBackEnd )
				)
				( attribute "RELATIVE_PROPAGATION_DELAY" "0.00 MIL,25.00 MIL"
					( Parent
						( matchGroupRef "@baseboard_fab2_lib.baseboard_fab2(sch_1):\MG_DDR_CTRL_NG_DDR_G_DLL_15\" )
					)
					( Units "uMatchProp" "ns" 1.000000)
					( Status sCSetFlattened )
					( Origin gBackEnd )
				)
			)
			( pinPair "@baseboard_fab2_lib.baseboard_fab2(sch_1):\PP3609\"
				( pinRef "@baseboard_fab2_lib.baseboard_fab2(sch_1):page77_i111:S2_N_C(0)" )
				( pinRef "@baseboard_fab2_lib.baseboard_fab2(sch_1):page57_i172:DDR0_CS_N(2)" )
				( attribute "RELATIVE_PROPAGATION_DELAY_SCOPE" "G"
					( Parent
						( matchGroupRef "@crescent_city_bb_fab1_lib.crescent_city_bb_fab1(sch_1):\MG_DDR_FAR_DIMM-CLK0_CLS_DDR_G_CAC-CLKS\" )
					)
					( Status sCSetFlattened )
					( Origin gBackEnd )
				)
				( attribute "RELATIVE_PROPAGATION_DELAY" "0.00 MIL,300.00 MIL"
					( Parent
						( matchGroupRef "@crescent_city_bb_fab1_lib.crescent_city_bb_fab1(sch_1):\MG_DDR_FAR_DIMM-CLK0_CLS_DDR_G_CAC-CLKS\" )
					)
					( Units "uMatchProp" "ns" 1.000000)
					( Status sCSetFlattened )
					( Origin gBackEnd )
				)
				( attribute "RELATIVE_PROPAGATION_DELAY_SCOPE" "G"
					( Parent
						( matchGroupRef "@baseboard_fab2_lib.baseboard_fab2(sch_1):\MG_DDR_CTRL_NG_DDR_G_DLL_16\" )
					)
					( Status sCSetFlattened )
					( Origin gBackEnd )
				)
				( attribute "RELATIVE_PROPAGATION_DELAY" "0.00 MIL,25.00 MIL"
					( Parent
						( matchGroupRef "@baseboard_fab2_lib.baseboard_fab2(sch_1):\MG_DDR_CTRL_NG_DDR_G_DLL_16\" )
					)
					( Units "uMatchProp" "ns" 1.000000)
					( Status sCSetFlattened )
					( Origin gBackEnd )
				)
			)
			( pinPair "@baseboard_fab2_lib.baseboard_fab2(sch_1):\PP3608\"
				( pinRef "@baseboard_fab2_lib.baseboard_fab2(sch_1):page77_i111:S3_N_C(1)" )
				( pinRef "@baseboard_fab2_lib.baseboard_fab2(sch_1):page57_i172:DDR0_CS_N(3)" )
				( attribute "RELATIVE_PROPAGATION_DELAY_SCOPE" "G"
					( Parent
						( matchGroupRef "@crescent_city_bb_fab1_lib.crescent_city_bb_fab1(sch_1):\MG_DDR_FAR_DIMM-CLK0_CLS_DDR_G_CAC-CLKS\" )
					)
					( Status sCSetFlattened )
					( Origin gBackEnd )
				)
				( attribute "RELATIVE_PROPAGATION_DELAY" "0.00 MIL,300.00 MIL"
					( Parent
						( matchGroupRef "@crescent_city_bb_fab1_lib.crescent_city_bb_fab1(sch_1):\MG_DDR_FAR_DIMM-CLK0_CLS_DDR_G_CAC-CLKS\" )
					)
					( Units "uMatchProp" "ns" 1.000000)
					( Status sCSetFlattened )
					( Origin gBackEnd )
				)
				( attribute "RELATIVE_PROPAGATION_DELAY_SCOPE" "G"
					( Parent
						( matchGroupRef "@baseboard_fab2_lib.baseboard_fab2(sch_1):\MG_DDR_CTRL_NG_DDR_G_DLL_17\" )
					)
					( Status sCSetFlattened )
					( Origin gBackEnd )
				)
				( attribute "RELATIVE_PROPAGATION_DELAY" "0.00 MIL,25.00 MIL"
					( Parent
						( matchGroupRef "@baseboard_fab2_lib.baseboard_fab2(sch_1):\MG_DDR_CTRL_NG_DDR_G_DLL_17\" )
					)
					( Units "uMatchProp" "ns" 1.000000)
					( Status sCSetFlattened )
					( Origin gBackEnd )
				)
			)
			( pinPair "@baseboard_fab2_lib.baseboard_fab2(sch_1):\PP3606\"
				( pinRef "@baseboard_fab2_lib.baseboard_fab2(sch_1):page77_i111:S1_N" )
				( pinRef "@baseboard_fab2_lib.baseboard_fab2(sch_1):page57_i172:DDR0_CS_N(1)" )
				( attribute "RELATIVE_PROPAGATION_DELAY_SCOPE" "G"
					( Parent
						( matchGroupRef "@crescent_city_bb_fab1_lib.crescent_city_bb_fab1(sch_1):\MG_DDR_FAR_DIMM-CLK0_CLS_DDR_G_CAC-CLKS\" )
					)
					( Status sCSetFlattened )
					( Origin gBackEnd )
				)
				( attribute "RELATIVE_PROPAGATION_DELAY" "0.00 MIL,300.00 MIL"
					( Parent
						( matchGroupRef "@crescent_city_bb_fab1_lib.crescent_city_bb_fab1(sch_1):\MG_DDR_FAR_DIMM-CLK0_CLS_DDR_G_CAC-CLKS\" )
					)
					( Units "uMatchProp" "ns" 1.000000)
					( Status sCSetFlattened )
					( Origin gBackEnd )
				)
				( attribute "RELATIVE_PROPAGATION_DELAY_SCOPE" "G"
					( Parent
						( matchGroupRef "@baseboard_fab2_lib.baseboard_fab2(sch_1):\MG_DDR_CTRL_NG_DDR_G_DLL_18\" )
					)
					( Status sCSetFlattened )
					( Origin gBackEnd )
				)
				( attribute "RELATIVE_PROPAGATION_DELAY" "0.00 MIL,25.00 MIL"
					( Parent
						( matchGroupRef "@baseboard_fab2_lib.baseboard_fab2(sch_1):\MG_DDR_CTRL_NG_DDR_G_DLL_18\" )
					)
					( Units "uMatchProp" "ns" 1.000000)
					( Status sCSetFlattened )
					( Origin gBackEnd )
				)
			)
			( pinPair "@baseboard_fab2_lib.baseboard_fab2(sch_1):\PP3607\"
				( pinRef "@baseboard_fab2_lib.baseboard_fab2(sch_1):page77_i111:ODT(1)" )
				( pinRef "@baseboard_fab2_lib.baseboard_fab2(sch_1):page57_i172:DDR0_ODT(1)" )
				( attribute "RELATIVE_PROPAGATION_DELAY_SCOPE" "G"
					( Parent
						( matchGroupRef "@crescent_city_bb_fab1_lib.crescent_city_bb_fab1(sch_1):\MG_DDR_FAR_DIMM-CLK0_CLS_DDR_G_CAC-CLKS\" )
					)
					( Status sCSetFlattened )
					( Origin gBackEnd )
				)
				( attribute "RELATIVE_PROPAGATION_DELAY" "0.00 MIL,300.00 MIL"
					( Parent
						( matchGroupRef "@crescent_city_bb_fab1_lib.crescent_city_bb_fab1(sch_1):\MG_DDR_FAR_DIMM-CLK0_CLS_DDR_G_CAC-CLKS\" )
					)
					( Units "uMatchProp" "ns" 1.000000)
					( Status sCSetFlattened )
					( Origin gBackEnd )
				)
				( attribute "RELATIVE_PROPAGATION_DELAY_SCOPE" "G"
					( Parent
						( matchGroupRef "@baseboard_fab2_lib.baseboard_fab2(sch_1):\MG_DDR_CTRL_NG_DDR_G_DLL_18\" )
					)
					( Status sCSetFlattened )
					( Origin gBackEnd )
				)
				( attribute "RELATIVE_PROPAGATION_DELAY" "0.00 MIL,25.00 MIL"
					( Parent
						( matchGroupRef "@baseboard_fab2_lib.baseboard_fab2(sch_1):\MG_DDR_CTRL_NG_DDR_G_DLL_18\" )
					)
					( Units "uMatchProp" "ns" 1.000000)
					( Status sCSetFlattened )
					( Origin gBackEnd )
				)
			)
			( pinPair "@baseboard_fab2_lib.baseboard_fab2(sch_1):\PP3605\"
				( pinRef "@baseboard_fab2_lib.baseboard_fab2(sch_1):page77_i111:CKE(1)" )
				( pinRef "@baseboard_fab2_lib.baseboard_fab2(sch_1):page57_i172:DDR0_CKE(1)" )
				( attribute "RELATIVE_PROPAGATION_DELAY_SCOPE" "G"
					( Parent
						( matchGroupRef "@crescent_city_bb_fab1_lib.crescent_city_bb_fab1(sch_1):\MG_DDR_FAR_DIMM-CLK0_CLS_DDR_G_CAC-CLKS\" )
					)
					( Status sCSetFlattened )
					( Origin gBackEnd )
				)
				( attribute "RELATIVE_PROPAGATION_DELAY" "0.00 MIL,300.00 MIL"
					( Parent
						( matchGroupRef "@crescent_city_bb_fab1_lib.crescent_city_bb_fab1(sch_1):\MG_DDR_FAR_DIMM-CLK0_CLS_DDR_G_CAC-CLKS\" )
					)
					( Units "uMatchProp" "ns" 1.000000)
					( Status sCSetFlattened )
					( Origin gBackEnd )
				)
				( attribute "RELATIVE_PROPAGATION_DELAY_SCOPE" "G"
					( Parent
						( matchGroupRef "@baseboard_fab2_lib.baseboard_fab2(sch_1):\MG_DDR_CTRL_NG_DDR_G_DLL_19\" )
					)
					( Status sCSetFlattened )
					( Origin gBackEnd )
				)
				( attribute "RELATIVE_PROPAGATION_DELAY" "0.00 MIL,25.00 MIL"
					( Parent
						( matchGroupRef "@baseboard_fab2_lib.baseboard_fab2(sch_1):\MG_DDR_CTRL_NG_DDR_G_DLL_19\" )
					)
					( Units "uMatchProp" "ns" 1.000000)
					( Status sCSetFlattened )
					( Origin gBackEnd )
				)
			)
			( pinPair "@baseboard_fab2_lib.baseboard_fab2(sch_1):\PP3603\"
				( pinRef "@baseboard_fab2_lib.baseboard_fab2(sch_1):page57_i172:DDR0_CS_N(4)" )
				( pinRef "@baseboard_fab2_lib.baseboard_fab2(sch_1):page78_i13:S0_N" )
				( attribute "RELATIVE_PROPAGATION_DELAY_SCOPE" "G"
					( Parent
						( matchGroupRef "@crescent_city_bb_fab1_lib.crescent_city_bb_fab1(sch_1):\MG_DDR_NEAR_DIMM-CLK1_CLS_DDR_G_CAC-CLKS\" )
					)
					( Status sCSetFlattened )
					( Origin gBackEnd )
				)
				( attribute "RELATIVE_PROPAGATION_DELAY" "0.00 MIL,300.00 MIL"
					( Parent
						( matchGroupRef "@crescent_city_bb_fab1_lib.crescent_city_bb_fab1(sch_1):\MG_DDR_NEAR_DIMM-CLK1_CLS_DDR_G_CAC-CLKS\" )
					)
					( Units "uMatchProp" "ns" 1.000000)
					( Status sCSetFlattened )
					( Origin gBackEnd )
				)
				( attribute "RELATIVE_PROPAGATION_DELAY_SCOPE" "G"
					( Parent
						( matchGroupRef "@baseboard_fab2_lib.baseboard_fab2(sch_1):\MG_DDR_CTRL_NG_DDR_G_DLL_20\" )
					)
					( Status sCSetFlattened )
					( Origin gBackEnd )
				)
				( attribute "RELATIVE_PROPAGATION_DELAY" "0.00 MIL,25.00 MIL"
					( Parent
						( matchGroupRef "@baseboard_fab2_lib.baseboard_fab2(sch_1):\MG_DDR_CTRL_NG_DDR_G_DLL_20\" )
					)
					( Units "uMatchProp" "ns" 1.000000)
					( Status sCSetFlattened )
					( Origin gBackEnd )
				)
			)
			( pinPair "@baseboard_fab2_lib.baseboard_fab2(sch_1):\PP3604\"
				( pinRef "@baseboard_fab2_lib.baseboard_fab2(sch_1):page57_i172:DDR0_ODT(2)" )
				( pinRef "@baseboard_fab2_lib.baseboard_fab2(sch_1):page78_i13:ODT(0)" )
				( attribute "RELATIVE_PROPAGATION_DELAY_SCOPE" "G"
					( Parent
						( matchGroupRef "@crescent_city_bb_fab1_lib.crescent_city_bb_fab1(sch_1):\MG_DDR_NEAR_DIMM-CLK1_CLS_DDR_G_CAC-CLKS\" )
					)
					( Status sCSetFlattened )
					( Origin gBackEnd )
				)
				( attribute "RELATIVE_PROPAGATION_DELAY" "0.00 MIL,300.00 MIL"
					( Parent
						( matchGroupRef "@crescent_city_bb_fab1_lib.crescent_city_bb_fab1(sch_1):\MG_DDR_NEAR_DIMM-CLK1_CLS_DDR_G_CAC-CLKS\" )
					)
					( Units "uMatchProp" "ns" 1.000000)
					( Status sCSetFlattened )
					( Origin gBackEnd )
				)
				( attribute "RELATIVE_PROPAGATION_DELAY_SCOPE" "G"
					( Parent
						( matchGroupRef "@baseboard_fab2_lib.baseboard_fab2(sch_1):\MG_DDR_CTRL_NG_DDR_G_DLL_20\" )
					)
					( Status sCSetFlattened )
					( Origin gBackEnd )
				)
				( attribute "RELATIVE_PROPAGATION_DELAY" "0.00 MIL,25.00 MIL"
					( Parent
						( matchGroupRef "@baseboard_fab2_lib.baseboard_fab2(sch_1):\MG_DDR_CTRL_NG_DDR_G_DLL_20\" )
					)
					( Units "uMatchProp" "ns" 1.000000)
					( Status sCSetFlattened )
					( Origin gBackEnd )
				)
			)
			( pinPair "@baseboard_fab2_lib.baseboard_fab2(sch_1):\PP3602\"
				( pinRef "@baseboard_fab2_lib.baseboard_fab2(sch_1):page57_i172:DDR0_CKE(2)" )
				( pinRef "@baseboard_fab2_lib.baseboard_fab2(sch_1):page78_i13:CKE(0)" )
				( attribute "RELATIVE_PROPAGATION_DELAY_SCOPE" "G"
					( Parent
						( matchGroupRef "@crescent_city_bb_fab1_lib.crescent_city_bb_fab1(sch_1):\MG_DDR_NEAR_DIMM-CLK1_CLS_DDR_G_CAC-CLKS\" )
					)
					( Status sCSetFlattened )
					( Origin gBackEnd )
				)
				( attribute "RELATIVE_PROPAGATION_DELAY" "0.00 MIL,300.00 MIL"
					( Parent
						( matchGroupRef "@crescent_city_bb_fab1_lib.crescent_city_bb_fab1(sch_1):\MG_DDR_NEAR_DIMM-CLK1_CLS_DDR_G_CAC-CLKS\" )
					)
					( Units "uMatchProp" "ns" 1.000000)
					( Status sCSetFlattened )
					( Origin gBackEnd )
				)
				( attribute "RELATIVE_PROPAGATION_DELAY_SCOPE" "G"
					( Parent
						( matchGroupRef "@baseboard_fab2_lib.baseboard_fab2(sch_1):\MG_DDR_CTRL_NG_DDR_G_DLL_21\" )
					)
					( Status sCSetFlattened )
					( Origin gBackEnd )
				)
				( attribute "RELATIVE_PROPAGATION_DELAY" "0.00 MIL,25.00 MIL"
					( Parent
						( matchGroupRef "@baseboard_fab2_lib.baseboard_fab2(sch_1):\MG_DDR_CTRL_NG_DDR_G_DLL_21\" )
					)
					( Units "uMatchProp" "ns" 1.000000)
					( Status sCSetFlattened )
					( Origin gBackEnd )
				)
			)
			( pinPair "@baseboard_fab2_lib.baseboard_fab2(sch_1):\PP3600\"
				( pinRef "@baseboard_fab2_lib.baseboard_fab2(sch_1):page57_i172:DDR0_CS_N(6)" )
				( pinRef "@baseboard_fab2_lib.baseboard_fab2(sch_1):page78_i13:S2_N_C(0)" )
				( attribute "RELATIVE_PROPAGATION_DELAY_SCOPE" "G"
					( Parent
						( matchGroupRef "@crescent_city_bb_fab1_lib.crescent_city_bb_fab1(sch_1):\MG_DDR_NEAR_DIMM-CLK1_CLS_DDR_G_CAC-CLKS\" )
					)
					( Status sCSetFlattened )
					( Origin gBackEnd )
				)
				( attribute "RELATIVE_PROPAGATION_DELAY" "0.00 MIL,300.00 MIL"
					( Parent
						( matchGroupRef "@crescent_city_bb_fab1_lib.crescent_city_bb_fab1(sch_1):\MG_DDR_NEAR_DIMM-CLK1_CLS_DDR_G_CAC-CLKS\" )
					)
					( Units "uMatchProp" "ns" 1.000000)
					( Status sCSetFlattened )
					( Origin gBackEnd )
				)
				( attribute "RELATIVE_PROPAGATION_DELAY_SCOPE" "G"
					( Parent
						( matchGroupRef "@baseboard_fab2_lib.baseboard_fab2(sch_1):\MG_DDR_CTRL_NG_DDR_G_DLL_22\" )
					)
					( Status sCSetFlattened )
					( Origin gBackEnd )
				)
				( attribute "RELATIVE_PROPAGATION_DELAY" "0.00 MIL,25.00 MIL"
					( Parent
						( matchGroupRef "@baseboard_fab2_lib.baseboard_fab2(sch_1):\MG_DDR_CTRL_NG_DDR_G_DLL_22\" )
					)
					( Units "uMatchProp" "ns" 1.000000)
					( Status sCSetFlattened )
					( Origin gBackEnd )
				)
			)
			( pinPair "@baseboard_fab2_lib.baseboard_fab2(sch_1):\PP3601\"
				( pinRef "@baseboard_fab2_lib.baseboard_fab2(sch_1):page57_i172:DDR0_CS_N(7)" )
				( pinRef "@baseboard_fab2_lib.baseboard_fab2(sch_1):page78_i13:S3_N_C(1)" )
				( attribute "RELATIVE_PROPAGATION_DELAY_SCOPE" "G"
					( Parent
						( matchGroupRef "@crescent_city_bb_fab1_lib.crescent_city_bb_fab1(sch_1):\MG_DDR_NEAR_DIMM-CLK1_CLS_DDR_G_CAC-CLKS\" )
					)
					( Status sCSetFlattened )
					( Origin gBackEnd )
				)
				( attribute "RELATIVE_PROPAGATION_DELAY" "0.00 MIL,300.00 MIL"
					( Parent
						( matchGroupRef "@crescent_city_bb_fab1_lib.crescent_city_bb_fab1(sch_1):\MG_DDR_NEAR_DIMM-CLK1_CLS_DDR_G_CAC-CLKS\" )
					)
					( Units "uMatchProp" "ns" 1.000000)
					( Status sCSetFlattened )
					( Origin gBackEnd )
				)
				( attribute "RELATIVE_PROPAGATION_DELAY_SCOPE" "G"
					( Parent
						( matchGroupRef "@baseboard_fab2_lib.baseboard_fab2(sch_1):\MG_DDR_CTRL_NG_DDR_G_DLL_22\" )
					)
					( Status sCSetFlattened )
					( Origin gBackEnd )
				)
				( attribute "RELATIVE_PROPAGATION_DELAY" "0.00 MIL,25.00 MIL"
					( Parent
						( matchGroupRef "@baseboard_fab2_lib.baseboard_fab2(sch_1):\MG_DDR_CTRL_NG_DDR_G_DLL_22\" )
					)
					( Units "uMatchProp" "ns" 1.000000)
					( Status sCSetFlattened )
					( Origin gBackEnd )
				)
			)
			( pinPair "@baseboard_fab2_lib.baseboard_fab2(sch_1):\PP3598\"
				( pinRef "@baseboard_fab2_lib.baseboard_fab2(sch_1):page57_i172:DDR0_CS_N(5)" )
				( pinRef "@baseboard_fab2_lib.baseboard_fab2(sch_1):page78_i13:S1_N" )
				( attribute "RELATIVE_PROPAGATION_DELAY_SCOPE" "G"
					( Parent
						( matchGroupRef "@crescent_city_bb_fab1_lib.crescent_city_bb_fab1(sch_1):\MG_DDR_NEAR_DIMM-CLK1_CLS_DDR_G_CAC-CLKS\" )
					)
					( Status sCSetFlattened )
					( Origin gBackEnd )
				)
				( attribute "RELATIVE_PROPAGATION_DELAY" "0.00 MIL,300.00 MIL"
					( Parent
						( matchGroupRef "@crescent_city_bb_fab1_lib.crescent_city_bb_fab1(sch_1):\MG_DDR_NEAR_DIMM-CLK1_CLS_DDR_G_CAC-CLKS\" )
					)
					( Units "uMatchProp" "ns" 1.000000)
					( Status sCSetFlattened )
					( Origin gBackEnd )
				)
				( attribute "RELATIVE_PROPAGATION_DELAY_SCOPE" "G"
					( Parent
						( matchGroupRef "@baseboard_fab2_lib.baseboard_fab2(sch_1):\MG_DDR_CTRL_NG_DDR_G_DLL_23\" )
					)
					( Status sCSetFlattened )
					( Origin gBackEnd )
				)
				( attribute "RELATIVE_PROPAGATION_DELAY" "0.00 MIL,25.00 MIL"
					( Parent
						( matchGroupRef "@baseboard_fab2_lib.baseboard_fab2(sch_1):\MG_DDR_CTRL_NG_DDR_G_DLL_23\" )
					)
					( Units "uMatchProp" "ns" 1.000000)
					( Status sCSetFlattened )
					( Origin gBackEnd )
				)
			)
			( pinPair "@baseboard_fab2_lib.baseboard_fab2(sch_1):\PP3599\"
				( pinRef "@baseboard_fab2_lib.baseboard_fab2(sch_1):page57_i172:DDR0_ODT(3)" )
				( pinRef "@baseboard_fab2_lib.baseboard_fab2(sch_1):page78_i13:ODT(1)" )
				( attribute "RELATIVE_PROPAGATION_DELAY_SCOPE" "G"
					( Parent
						( matchGroupRef "@crescent_city_bb_fab1_lib.crescent_city_bb_fab1(sch_1):\MG_DDR_NEAR_DIMM-CLK1_CLS_DDR_G_CAC-CLKS\" )
					)
					( Status sCSetFlattened )
					( Origin gBackEnd )
				)
				( attribute "RELATIVE_PROPAGATION_DELAY" "0.00 MIL,300.00 MIL"
					( Parent
						( matchGroupRef "@crescent_city_bb_fab1_lib.crescent_city_bb_fab1(sch_1):\MG_DDR_NEAR_DIMM-CLK1_CLS_DDR_G_CAC-CLKS\" )
					)
					( Units "uMatchProp" "ns" 1.000000)
					( Status sCSetFlattened )
					( Origin gBackEnd )
				)
				( attribute "RELATIVE_PROPAGATION_DELAY_SCOPE" "G"
					( Parent
						( matchGroupRef "@baseboard_fab2_lib.baseboard_fab2(sch_1):\MG_DDR_CTRL_NG_DDR_G_DLL_23\" )
					)
					( Status sCSetFlattened )
					( Origin gBackEnd )
				)
				( attribute "RELATIVE_PROPAGATION_DELAY" "0.00 MIL,25.00 MIL"
					( Parent
						( matchGroupRef "@baseboard_fab2_lib.baseboard_fab2(sch_1):\MG_DDR_CTRL_NG_DDR_G_DLL_23\" )
					)
					( Units "uMatchProp" "ns" 1.000000)
					( Status sCSetFlattened )
					( Origin gBackEnd )
				)
			)
			( pinPair "@baseboard_fab2_lib.baseboard_fab2(sch_1):\PP3597\"
				( pinRef "@baseboard_fab2_lib.baseboard_fab2(sch_1):page57_i172:DDR0_CKE(3)" )
				( pinRef "@baseboard_fab2_lib.baseboard_fab2(sch_1):page78_i13:CKE(1)" )
				( attribute "RELATIVE_PROPAGATION_DELAY_SCOPE" "G"
					( Parent
						( matchGroupRef "@crescent_city_bb_fab1_lib.crescent_city_bb_fab1(sch_1):\MG_DDR_NEAR_DIMM-CLK1_CLS_DDR_G_CAC-CLKS\" )
					)
					( Status sCSetFlattened )
					( Origin gBackEnd )
				)
				( attribute "RELATIVE_PROPAGATION_DELAY" "0.00 MIL,300.00 MIL"
					( Parent
						( matchGroupRef "@crescent_city_bb_fab1_lib.crescent_city_bb_fab1(sch_1):\MG_DDR_NEAR_DIMM-CLK1_CLS_DDR_G_CAC-CLKS\" )
					)
					( Units "uMatchProp" "ns" 1.000000)
					( Status sCSetFlattened )
					( Origin gBackEnd )
				)
				( attribute "RELATIVE_PROPAGATION_DELAY_SCOPE" "G"
					( Parent
						( matchGroupRef "@baseboard_fab2_lib.baseboard_fab2(sch_1):\MG_DDR_CTRL_NG_DDR_G_DLL_24\" )
					)
					( Status sCSetFlattened )
					( Origin gBackEnd )
				)
				( attribute "RELATIVE_PROPAGATION_DELAY" "0.00 MIL,25.00 MIL"
					( Parent
						( matchGroupRef "@baseboard_fab2_lib.baseboard_fab2(sch_1):\MG_DDR_CTRL_NG_DDR_G_DLL_24\" )
					)
					( Units "uMatchProp" "ns" 1.000000)
					( Status sCSetFlattened )
					( Origin gBackEnd )
				)
			)
			( pinPair "@baseboard_fab2_lib.baseboard_fab2(sch_1):\PP3725\"
				( pinRef "@baseboard_fab2_lib.baseboard_fab2(sch_1):page28_i172:DDR5_CID(2)" )
				( pinRef "@baseboard_fab2_lib.baseboard_fab2(sch_1):page53_i111:C(2)" )
				( attribute "RELATIVE_PROPAGATION_DELAY_SCOPE" "G"
					( Parent
						( matchGroupRef "@crescent_city_bb_fab1_lib.crescent_city_bb_fab1(sch_1):\MG_DDR_FAR_DIMM-CLK0_CLS_DDR_F_CAC-CLKS\" )
					)
					( Status sCSetFlattened )
					( Origin gBackEnd )
				)
				( attribute "RELATIVE_PROPAGATION_DELAY" "0.00 MIL,700.00 MIL"
					( Parent
						( matchGroupRef "@crescent_city_bb_fab1_lib.crescent_city_bb_fab1(sch_1):\MG_DDR_FAR_DIMM-CLK0_CLS_DDR_F_CAC-CLKS\" )
					)
					( Units "uMatchProp" "ns" 1.000000)
					( Status sCSetFlattened )
					( Origin gBackEnd )
				)
				( attribute "RELATIVE_PROPAGATION_DELAY_SCOPE" "G"
					( Parent
						( matchGroupRef "@baseboard_fab2_lib.baseboard_fab2(sch_1):\MG_DDR_FAR_DIMM_CMD_NG_DDR_F_DLL_1\" )
					)
					( Status sCSetFlattened )
					( Origin gBackEnd )
				)
				( attribute "RELATIVE_PROPAGATION_DELAY" "0.00 MIL,25.00 MIL"
					( Parent
						( matchGroupRef "@baseboard_fab2_lib.baseboard_fab2(sch_1):\MG_DDR_FAR_DIMM_CMD_NG_DDR_F_DLL_1\" )
					)
					( Units "uMatchProp" "ns" 1.000000)
					( Status sCSetFlattened )
					( Origin gBackEnd )
				)
			)
			( pinPair "@baseboard_fab2_lib.baseboard_fab2(sch_1):\PP3726\"
				( pinRef "@baseboard_fab2_lib.baseboard_fab2(sch_1):page54_i111:C(2)" )
				( pinRef "@baseboard_fab2_lib.baseboard_fab2(sch_1):page28_i172:DDR5_CID(2)" )
				( attribute "RELATIVE_PROPAGATION_DELAY_SCOPE" "G"
					( Parent
						( matchGroupRef "@baseboard_fab2_lib.baseboard_fab2(sch_1):\MG_DDR_CMD_NEAR_DIMM_NG_DDR_F_DLL_1\" )
					)
					( Status sCSetFlattened )
					( Origin gBackEnd )
				)
				( attribute "RELATIVE_PROPAGATION_DELAY" "0.00 MIL,25.00 MIL"
					( Parent
						( matchGroupRef "@baseboard_fab2_lib.baseboard_fab2(sch_1):\MG_DDR_CMD_NEAR_DIMM_NG_DDR_F_DLL_1\" )
					)
					( Units "uMatchProp" "ns" 1.000000)
					( Status sCSetFlattened )
					( Origin gBackEnd )
				)
				( attribute "RELATIVE_PROPAGATION_DELAY_SCOPE" "G"
					( Parent
						( matchGroupRef "@crescent_city_bb_fab1_lib.crescent_city_bb_fab1(sch_1):\MG_DDR_NEAR_DIMM-CLK1_CLS_DDR_F_CAC-CLKS\" )
					)
					( Status sCSetFlattened )
					( Origin gBackEnd )
				)
				( attribute "RELATIVE_PROPAGATION_DELAY" "0.00 MIL,700.00 MIL"
					( Parent
						( matchGroupRef "@crescent_city_bb_fab1_lib.crescent_city_bb_fab1(sch_1):\MG_DDR_NEAR_DIMM-CLK1_CLS_DDR_F_CAC-CLKS\" )
					)
					( Units "uMatchProp" "ns" 1.000000)
					( Status sCSetFlattened )
					( Origin gBackEnd )
				)
			)
			( pinPair "@baseboard_fab2_lib.baseboard_fab2(sch_1):\PP3727\"
				( pinRef "@baseboard_fab2_lib.baseboard_fab2(sch_1):page28_i172:DDR5_MA(17)" )
				( pinRef "@baseboard_fab2_lib.baseboard_fab2(sch_1):page53_i111:A17" )
				( attribute "RELATIVE_PROPAGATION_DELAY_SCOPE" "G"
					( Parent
						( matchGroupRef "@crescent_city_bb_fab1_lib.crescent_city_bb_fab1(sch_1):\MG_DDR_FAR_DIMM-CLK0_CLS_DDR_F_CAC-CLKS\" )
					)
					( Status sCSetFlattened )
					( Origin gBackEnd )
				)
				( attribute "RELATIVE_PROPAGATION_DELAY" "0.00 MIL,700.00 MIL"
					( Parent
						( matchGroupRef "@crescent_city_bb_fab1_lib.crescent_city_bb_fab1(sch_1):\MG_DDR_FAR_DIMM-CLK0_CLS_DDR_F_CAC-CLKS\" )
					)
					( Units "uMatchProp" "ns" 1.000000)
					( Status sCSetFlattened )
					( Origin gBackEnd )
				)
				( attribute "RELATIVE_PROPAGATION_DELAY_SCOPE" "G"
					( Parent
						( matchGroupRef "@baseboard_fab2_lib.baseboard_fab2(sch_1):\MG_DDR_FAR_DIMM_CMD_NG_DDR_F_DLL_1\" )
					)
					( Status sCSetFlattened )
					( Origin gBackEnd )
				)
				( attribute "RELATIVE_PROPAGATION_DELAY" "0.00 MIL,25.00 MIL"
					( Parent
						( matchGroupRef "@baseboard_fab2_lib.baseboard_fab2(sch_1):\MG_DDR_FAR_DIMM_CMD_NG_DDR_F_DLL_1\" )
					)
					( Units "uMatchProp" "ns" 1.000000)
					( Status sCSetFlattened )
					( Origin gBackEnd )
				)
			)
			( pinPair "@baseboard_fab2_lib.baseboard_fab2(sch_1):\PP3728\"
				( pinRef "@baseboard_fab2_lib.baseboard_fab2(sch_1):page54_i111:A17" )
				( pinRef "@baseboard_fab2_lib.baseboard_fab2(sch_1):page28_i172:DDR5_MA(17)" )
				( attribute "RELATIVE_PROPAGATION_DELAY_SCOPE" "G"
					( Parent
						( matchGroupRef "@baseboard_fab2_lib.baseboard_fab2(sch_1):\MG_DDR_CMD_NEAR_DIMM_NG_DDR_F_DLL_1\" )
					)
					( Status sCSetFlattened )
					( Origin gBackEnd )
				)
				( attribute "RELATIVE_PROPAGATION_DELAY" "0.00 MIL,25.00 MIL"
					( Parent
						( matchGroupRef "@baseboard_fab2_lib.baseboard_fab2(sch_1):\MG_DDR_CMD_NEAR_DIMM_NG_DDR_F_DLL_1\" )
					)
					( Units "uMatchProp" "ns" 1.000000)
					( Status sCSetFlattened )
					( Origin gBackEnd )
				)
				( attribute "RELATIVE_PROPAGATION_DELAY_SCOPE" "G"
					( Parent
						( matchGroupRef "@crescent_city_bb_fab1_lib.crescent_city_bb_fab1(sch_1):\MG_DDR_NEAR_DIMM-CLK1_CLS_DDR_F_CAC-CLKS\" )
					)
					( Status sCSetFlattened )
					( Origin gBackEnd )
				)
				( attribute "RELATIVE_PROPAGATION_DELAY" "0.00 MIL,700.00 MIL"
					( Parent
						( matchGroupRef "@crescent_city_bb_fab1_lib.crescent_city_bb_fab1(sch_1):\MG_DDR_NEAR_DIMM-CLK1_CLS_DDR_F_CAC-CLKS\" )
					)
					( Units "uMatchProp" "ns" 1.000000)
					( Status sCSetFlattened )
					( Origin gBackEnd )
				)
			)
			( pinPair "@baseboard_fab2_lib.baseboard_fab2(sch_1):\PP3721\"
				( pinRef "@baseboard_fab2_lib.baseboard_fab2(sch_1):page28_i172:DDR5_MA(13)" )
				( pinRef "@baseboard_fab2_lib.baseboard_fab2(sch_1):page53_i111:A13" )
				( attribute "RELATIVE_PROPAGATION_DELAY_SCOPE" "G"
					( Parent
						( matchGroupRef "@crescent_city_bb_fab1_lib.crescent_city_bb_fab1(sch_1):\MG_DDR_FAR_DIMM-CLK0_CLS_DDR_F_CAC-CLKS\" )
					)
					( Status sCSetFlattened )
					( Origin gBackEnd )
				)
				( attribute "RELATIVE_PROPAGATION_DELAY" "0.00 MIL,700.00 MIL"
					( Parent
						( matchGroupRef "@crescent_city_bb_fab1_lib.crescent_city_bb_fab1(sch_1):\MG_DDR_FAR_DIMM-CLK0_CLS_DDR_F_CAC-CLKS\" )
					)
					( Units "uMatchProp" "ns" 1.000000)
					( Status sCSetFlattened )
					( Origin gBackEnd )
				)
				( attribute "RELATIVE_PROPAGATION_DELAY_SCOPE" "G"
					( Parent
						( matchGroupRef "@baseboard_fab2_lib.baseboard_fab2(sch_1):\MG_DDR_FAR_DIMM_CMD_NG_DDR_F_DLL_2\" )
					)
					( Status sCSetFlattened )
					( Origin gBackEnd )
				)
				( attribute "RELATIVE_PROPAGATION_DELAY" "0.00 MIL,25.00 MIL"
					( Parent
						( matchGroupRef "@baseboard_fab2_lib.baseboard_fab2(sch_1):\MG_DDR_FAR_DIMM_CMD_NG_DDR_F_DLL_2\" )
					)
					( Units "uMatchProp" "ns" 1.000000)
					( Status sCSetFlattened )
					( Origin gBackEnd )
				)
			)
			( pinPair "@baseboard_fab2_lib.baseboard_fab2(sch_1):\PP3722\"
				( pinRef "@baseboard_fab2_lib.baseboard_fab2(sch_1):page28_i172:DDR5_MA(13)" )
				( pinRef "@baseboard_fab2_lib.baseboard_fab2(sch_1):page54_i111:A13" )
				( attribute "RELATIVE_PROPAGATION_DELAY_SCOPE" "G"
					( Parent
						( matchGroupRef "@crescent_city_bb_fab1_lib.crescent_city_bb_fab1(sch_1):\MG_DDR_NEAR_DIMM-CLK1_CLS_DDR_F_CAC-CLKS\" )
					)
					( Status sCSetFlattened )
					( Origin gBackEnd )
				)
				( attribute "RELATIVE_PROPAGATION_DELAY" "0.00 MIL,700.00 MIL"
					( Parent
						( matchGroupRef "@crescent_city_bb_fab1_lib.crescent_city_bb_fab1(sch_1):\MG_DDR_NEAR_DIMM-CLK1_CLS_DDR_F_CAC-CLKS\" )
					)
					( Units "uMatchProp" "ns" 1.000000)
					( Status sCSetFlattened )
					( Origin gBackEnd )
				)
				( attribute "RELATIVE_PROPAGATION_DELAY_SCOPE" "G"
					( Parent
						( matchGroupRef "@baseboard_fab2_lib.baseboard_fab2(sch_1):\MG_DDR_CMD_NEAR_DIMM_NG_DDR_F_DLL_2\" )
					)
					( Status sCSetFlattened )
					( Origin gBackEnd )
				)
				( attribute "RELATIVE_PROPAGATION_DELAY" "0.00 MIL,25.00 MIL"
					( Parent
						( matchGroupRef "@baseboard_fab2_lib.baseboard_fab2(sch_1):\MG_DDR_CMD_NEAR_DIMM_NG_DDR_F_DLL_2\" )
					)
					( Units "uMatchProp" "ns" 1.000000)
					( Status sCSetFlattened )
					( Origin gBackEnd )
				)
			)
			( pinPair "@baseboard_fab2_lib.baseboard_fab2(sch_1):\PP3723\"
				( pinRef "@baseboard_fab2_lib.baseboard_fab2(sch_1):page28_i172:DDR5_MA(15)" )
				( pinRef "@baseboard_fab2_lib.baseboard_fab2(sch_1):page53_i111:A15_CAS_N" )
				( attribute "RELATIVE_PROPAGATION_DELAY_SCOPE" "G"
					( Parent
						( matchGroupRef "@crescent_city_bb_fab1_lib.crescent_city_bb_fab1(sch_1):\MG_DDR_FAR_DIMM-CLK0_CLS_DDR_F_CAC-CLKS\" )
					)
					( Status sCSetFlattened )
					( Origin gBackEnd )
				)
				( attribute "RELATIVE_PROPAGATION_DELAY" "0.00 MIL,700.00 MIL"
					( Parent
						( matchGroupRef "@crescent_city_bb_fab1_lib.crescent_city_bb_fab1(sch_1):\MG_DDR_FAR_DIMM-CLK0_CLS_DDR_F_CAC-CLKS\" )
					)
					( Units "uMatchProp" "ns" 1.000000)
					( Status sCSetFlattened )
					( Origin gBackEnd )
				)
				( attribute "RELATIVE_PROPAGATION_DELAY_SCOPE" "G"
					( Parent
						( matchGroupRef "@baseboard_fab2_lib.baseboard_fab2(sch_1):\MG_DDR_FAR_DIMM_CMD_NG_DDR_F_DLL_2\" )
					)
					( Status sCSetFlattened )
					( Origin gBackEnd )
				)
				( attribute "RELATIVE_PROPAGATION_DELAY" "0.00 MIL,25.00 MIL"
					( Parent
						( matchGroupRef "@baseboard_fab2_lib.baseboard_fab2(sch_1):\MG_DDR_FAR_DIMM_CMD_NG_DDR_F_DLL_2\" )
					)
					( Units "uMatchProp" "ns" 1.000000)
					( Status sCSetFlattened )
					( Origin gBackEnd )
				)
			)
			( pinPair "@baseboard_fab2_lib.baseboard_fab2(sch_1):\PP3724\"
				( pinRef "@baseboard_fab2_lib.baseboard_fab2(sch_1):page28_i172:DDR5_MA(15)" )
				( pinRef "@baseboard_fab2_lib.baseboard_fab2(sch_1):page54_i111:A15_CAS_N" )
				( attribute "RELATIVE_PROPAGATION_DELAY_SCOPE" "G"
					( Parent
						( matchGroupRef "@crescent_city_bb_fab1_lib.crescent_city_bb_fab1(sch_1):\MG_DDR_NEAR_DIMM-CLK1_CLS_DDR_F_CAC-CLKS\" )
					)
					( Status sCSetFlattened )
					( Origin gBackEnd )
				)
				( attribute "RELATIVE_PROPAGATION_DELAY" "0.00 MIL,700.00 MIL"
					( Parent
						( matchGroupRef "@crescent_city_bb_fab1_lib.crescent_city_bb_fab1(sch_1):\MG_DDR_NEAR_DIMM-CLK1_CLS_DDR_F_CAC-CLKS\" )
					)
					( Units "uMatchProp" "ns" 1.000000)
					( Status sCSetFlattened )
					( Origin gBackEnd )
				)
				( attribute "RELATIVE_PROPAGATION_DELAY_SCOPE" "G"
					( Parent
						( matchGroupRef "@baseboard_fab2_lib.baseboard_fab2(sch_1):\MG_DDR_CMD_NEAR_DIMM_NG_DDR_F_DLL_2\" )
					)
					( Status sCSetFlattened )
					( Origin gBackEnd )
				)
				( attribute "RELATIVE_PROPAGATION_DELAY" "0.00 MIL,25.00 MIL"
					( Parent
						( matchGroupRef "@baseboard_fab2_lib.baseboard_fab2(sch_1):\MG_DDR_CMD_NEAR_DIMM_NG_DDR_F_DLL_2\" )
					)
					( Units "uMatchProp" "ns" 1.000000)
					( Status sCSetFlattened )
					( Origin gBackEnd )
				)
			)
			( pinPair "@baseboard_fab2_lib.baseboard_fab2(sch_1):\PP3717\"
				( pinRef "@baseboard_fab2_lib.baseboard_fab2(sch_1):page28_i172:DDR5_MA(14)" )
				( pinRef "@baseboard_fab2_lib.baseboard_fab2(sch_1):page53_i111:A14_WE_N" )
				( attribute "RELATIVE_PROPAGATION_DELAY_SCOPE" "G"
					( Parent
						( matchGroupRef "@crescent_city_bb_fab1_lib.crescent_city_bb_fab1(sch_1):\MG_DDR_FAR_DIMM-CLK0_CLS_DDR_F_CAC-CLKS\" )
					)
					( Status sCSetFlattened )
					( Origin gBackEnd )
				)
				( attribute "RELATIVE_PROPAGATION_DELAY" "0.00 MIL,700.00 MIL"
					( Parent
						( matchGroupRef "@crescent_city_bb_fab1_lib.crescent_city_bb_fab1(sch_1):\MG_DDR_FAR_DIMM-CLK0_CLS_DDR_F_CAC-CLKS\" )
					)
					( Units "uMatchProp" "ns" 1.000000)
					( Status sCSetFlattened )
					( Origin gBackEnd )
				)
				( attribute "RELATIVE_PROPAGATION_DELAY_SCOPE" "G"
					( Parent
						( matchGroupRef "@baseboard_fab2_lib.baseboard_fab2(sch_1):\MG_DDR_FAR_DIMM_CMD_NG_DDR_F_DLL_3\" )
					)
					( Status sCSetFlattened )
					( Origin gBackEnd )
				)
				( attribute "RELATIVE_PROPAGATION_DELAY" "0.00 MIL,25.00 MIL"
					( Parent
						( matchGroupRef "@baseboard_fab2_lib.baseboard_fab2(sch_1):\MG_DDR_FAR_DIMM_CMD_NG_DDR_F_DLL_3\" )
					)
					( Units "uMatchProp" "ns" 1.000000)
					( Status sCSetFlattened )
					( Origin gBackEnd )
				)
			)
			( pinPair "@baseboard_fab2_lib.baseboard_fab2(sch_1):\PP3718\"
				( pinRef "@baseboard_fab2_lib.baseboard_fab2(sch_1):page54_i111:A14_WE_N" )
				( pinRef "@baseboard_fab2_lib.baseboard_fab2(sch_1):page28_i172:DDR5_MA(14)" )
				( attribute "RELATIVE_PROPAGATION_DELAY_SCOPE" "G"
					( Parent
						( matchGroupRef "@crescent_city_bb_fab1_lib.crescent_city_bb_fab1(sch_1):\MG_DDR_NEAR_DIMM-CLK1_CLS_DDR_F_CAC-CLKS\" )
					)
					( Status sCSetFlattened )
					( Origin gBackEnd )
				)
				( attribute "RELATIVE_PROPAGATION_DELAY" "0.00 MIL,700.00 MIL"
					( Parent
						( matchGroupRef "@crescent_city_bb_fab1_lib.crescent_city_bb_fab1(sch_1):\MG_DDR_NEAR_DIMM-CLK1_CLS_DDR_F_CAC-CLKS\" )
					)
					( Units "uMatchProp" "ns" 1.000000)
					( Status sCSetFlattened )
					( Origin gBackEnd )
				)
				( attribute "RELATIVE_PROPAGATION_DELAY_SCOPE" "G"
					( Parent
						( matchGroupRef "@baseboard_fab2_lib.baseboard_fab2(sch_1):\MG_DDR_CMD_NEAR_DIMM_NG_DDR_F_DLL_3\" )
					)
					( Status sCSetFlattened )
					( Origin gBackEnd )
				)
				( attribute "RELATIVE_PROPAGATION_DELAY" "0.00 MIL,25.00 MIL"
					( Parent
						( matchGroupRef "@baseboard_fab2_lib.baseboard_fab2(sch_1):\MG_DDR_CMD_NEAR_DIMM_NG_DDR_F_DLL_3\" )
					)
					( Units "uMatchProp" "ns" 1.000000)
					( Status sCSetFlattened )
					( Origin gBackEnd )
				)
			)
			( pinPair "@baseboard_fab2_lib.baseboard_fab2(sch_1):\PP3719\"
				( pinRef "@baseboard_fab2_lib.baseboard_fab2(sch_1):page28_i172:DDR5_MA(16)" )
				( pinRef "@baseboard_fab2_lib.baseboard_fab2(sch_1):page53_i111:A16_RAS_N" )
				( attribute "RELATIVE_PROPAGATION_DELAY_SCOPE" "G"
					( Parent
						( matchGroupRef "@crescent_city_bb_fab1_lib.crescent_city_bb_fab1(sch_1):\MG_DDR_FAR_DIMM-CLK0_CLS_DDR_F_CAC-CLKS\" )
					)
					( Status sCSetFlattened )
					( Origin gBackEnd )
				)
				( attribute "RELATIVE_PROPAGATION_DELAY" "0.00 MIL,700.00 MIL"
					( Parent
						( matchGroupRef "@crescent_city_bb_fab1_lib.crescent_city_bb_fab1(sch_1):\MG_DDR_FAR_DIMM-CLK0_CLS_DDR_F_CAC-CLKS\" )
					)
					( Units "uMatchProp" "ns" 1.000000)
					( Status sCSetFlattened )
					( Origin gBackEnd )
				)
				( attribute "RELATIVE_PROPAGATION_DELAY_SCOPE" "G"
					( Parent
						( matchGroupRef "@baseboard_fab2_lib.baseboard_fab2(sch_1):\MG_DDR_FAR_DIMM_CMD_NG_DDR_F_DLL_3\" )
					)
					( Status sCSetFlattened )
					( Origin gBackEnd )
				)
				( attribute "RELATIVE_PROPAGATION_DELAY" "0.00 MIL,25.00 MIL"
					( Parent
						( matchGroupRef "@baseboard_fab2_lib.baseboard_fab2(sch_1):\MG_DDR_FAR_DIMM_CMD_NG_DDR_F_DLL_3\" )
					)
					( Units "uMatchProp" "ns" 1.000000)
					( Status sCSetFlattened )
					( Origin gBackEnd )
				)
			)
			( pinPair "@baseboard_fab2_lib.baseboard_fab2(sch_1):\PP3720\"
				( pinRef "@baseboard_fab2_lib.baseboard_fab2(sch_1):page54_i111:A16_RAS_N" )
				( pinRef "@baseboard_fab2_lib.baseboard_fab2(sch_1):page28_i172:DDR5_MA(16)" )
				( attribute "RELATIVE_PROPAGATION_DELAY_SCOPE" "G"
					( Parent
						( matchGroupRef "@crescent_city_bb_fab1_lib.crescent_city_bb_fab1(sch_1):\MG_DDR_NEAR_DIMM-CLK1_CLS_DDR_F_CAC-CLKS\" )
					)
					( Status sCSetFlattened )
					( Origin gBackEnd )
				)
				( attribute "RELATIVE_PROPAGATION_DELAY" "0.00 MIL,700.00 MIL"
					( Parent
						( matchGroupRef "@crescent_city_bb_fab1_lib.crescent_city_bb_fab1(sch_1):\MG_DDR_NEAR_DIMM-CLK1_CLS_DDR_F_CAC-CLKS\" )
					)
					( Units "uMatchProp" "ns" 1.000000)
					( Status sCSetFlattened )
					( Origin gBackEnd )
				)
				( attribute "RELATIVE_PROPAGATION_DELAY_SCOPE" "G"
					( Parent
						( matchGroupRef "@baseboard_fab2_lib.baseboard_fab2(sch_1):\MG_DDR_CMD_NEAR_DIMM_NG_DDR_F_DLL_3\" )
					)
					( Status sCSetFlattened )
					( Origin gBackEnd )
				)
				( attribute "RELATIVE_PROPAGATION_DELAY" "0.00 MIL,25.00 MIL"
					( Parent
						( matchGroupRef "@baseboard_fab2_lib.baseboard_fab2(sch_1):\MG_DDR_CMD_NEAR_DIMM_NG_DDR_F_DLL_3\" )
					)
					( Units "uMatchProp" "ns" 1.000000)
					( Status sCSetFlattened )
					( Origin gBackEnd )
				)
			)
			( pinPair "@baseboard_fab2_lib.baseboard_fab2(sch_1):\PP3713\"
				( pinRef "@baseboard_fab2_lib.baseboard_fab2(sch_1):page28_i172:DDR5_BA(1)" )
				( pinRef "@baseboard_fab2_lib.baseboard_fab2(sch_1):page53_i111:BA(1)" )
				( attribute "RELATIVE_PROPAGATION_DELAY_SCOPE" "G"
					( Parent
						( matchGroupRef "@crescent_city_bb_fab1_lib.crescent_city_bb_fab1(sch_1):\MG_DDR_FAR_DIMM-CLK0_CLS_DDR_F_CAC-CLKS\" )
					)
					( Status sCSetFlattened )
					( Origin gBackEnd )
				)
				( attribute "RELATIVE_PROPAGATION_DELAY" "0.00 MIL,700.00 MIL"
					( Parent
						( matchGroupRef "@crescent_city_bb_fab1_lib.crescent_city_bb_fab1(sch_1):\MG_DDR_FAR_DIMM-CLK0_CLS_DDR_F_CAC-CLKS\" )
					)
					( Units "uMatchProp" "ns" 1.000000)
					( Status sCSetFlattened )
					( Origin gBackEnd )
				)
				( attribute "RELATIVE_PROPAGATION_DELAY_SCOPE" "G"
					( Parent
						( matchGroupRef "@baseboard_fab2_lib.baseboard_fab2(sch_1):\MG_DDR_FAR_DIMM_CMD_NG_DDR_F_DLL_4\" )
					)
					( Status sCSetFlattened )
					( Origin gBackEnd )
				)
				( attribute "RELATIVE_PROPAGATION_DELAY" "0.00 MIL,25.00 MIL"
					( Parent
						( matchGroupRef "@baseboard_fab2_lib.baseboard_fab2(sch_1):\MG_DDR_FAR_DIMM_CMD_NG_DDR_F_DLL_4\" )
					)
					( Units "uMatchProp" "ns" 1.000000)
					( Status sCSetFlattened )
					( Origin gBackEnd )
				)
			)
			( pinPair "@baseboard_fab2_lib.baseboard_fab2(sch_1):\PP3714\"
				( pinRef "@baseboard_fab2_lib.baseboard_fab2(sch_1):page54_i111:BA(1)" )
				( pinRef "@baseboard_fab2_lib.baseboard_fab2(sch_1):page28_i172:DDR5_BA(1)" )
				( attribute "RELATIVE_PROPAGATION_DELAY_SCOPE" "G"
					( Parent
						( matchGroupRef "@crescent_city_bb_fab1_lib.crescent_city_bb_fab1(sch_1):\MG_DDR_NEAR_DIMM-CLK1_CLS_DDR_F_CAC-CLKS\" )
					)
					( Status sCSetFlattened )
					( Origin gBackEnd )
				)
				( attribute "RELATIVE_PROPAGATION_DELAY" "0.00 MIL,700.00 MIL"
					( Parent
						( matchGroupRef "@crescent_city_bb_fab1_lib.crescent_city_bb_fab1(sch_1):\MG_DDR_NEAR_DIMM-CLK1_CLS_DDR_F_CAC-CLKS\" )
					)
					( Units "uMatchProp" "ns" 1.000000)
					( Status sCSetFlattened )
					( Origin gBackEnd )
				)
				( attribute "RELATIVE_PROPAGATION_DELAY_SCOPE" "G"
					( Parent
						( matchGroupRef "@baseboard_fab2_lib.baseboard_fab2(sch_1):\MG_DDR_CMD_NEAR_DIMM_NG_DDR_F_DLL_4\" )
					)
					( Status sCSetFlattened )
					( Origin gBackEnd )
				)
				( attribute "RELATIVE_PROPAGATION_DELAY" "0.00 MIL,25.00 MIL"
					( Parent
						( matchGroupRef "@baseboard_fab2_lib.baseboard_fab2(sch_1):\MG_DDR_CMD_NEAR_DIMM_NG_DDR_F_DLL_4\" )
					)
					( Units "uMatchProp" "ns" 1.000000)
					( Status sCSetFlattened )
					( Origin gBackEnd )
				)
			)
			( pinPair "@baseboard_fab2_lib.baseboard_fab2(sch_1):\PP3715\"
				( pinRef "@baseboard_fab2_lib.baseboard_fab2(sch_1):page28_i172:DDR5_MA(10)" )
				( pinRef "@baseboard_fab2_lib.baseboard_fab2(sch_1):page53_i111:A10" )
				( attribute "RELATIVE_PROPAGATION_DELAY_SCOPE" "G"
					( Parent
						( matchGroupRef "@crescent_city_bb_fab1_lib.crescent_city_bb_fab1(sch_1):\MG_DDR_FAR_DIMM-CLK0_CLS_DDR_F_CAC-CLKS\" )
					)
					( Status sCSetFlattened )
					( Origin gBackEnd )
				)
				( attribute "RELATIVE_PROPAGATION_DELAY" "0.00 MIL,700.00 MIL"
					( Parent
						( matchGroupRef "@crescent_city_bb_fab1_lib.crescent_city_bb_fab1(sch_1):\MG_DDR_FAR_DIMM-CLK0_CLS_DDR_F_CAC-CLKS\" )
					)
					( Units "uMatchProp" "ns" 1.000000)
					( Status sCSetFlattened )
					( Origin gBackEnd )
				)
				( attribute "RELATIVE_PROPAGATION_DELAY_SCOPE" "G"
					( Parent
						( matchGroupRef "@baseboard_fab2_lib.baseboard_fab2(sch_1):\MG_DDR_FAR_DIMM_CMD_NG_DDR_F_DLL_4\" )
					)
					( Status sCSetFlattened )
					( Origin gBackEnd )
				)
				( attribute "RELATIVE_PROPAGATION_DELAY" "0.00 MIL,25.00 MIL"
					( Parent
						( matchGroupRef "@baseboard_fab2_lib.baseboard_fab2(sch_1):\MG_DDR_FAR_DIMM_CMD_NG_DDR_F_DLL_4\" )
					)
					( Units "uMatchProp" "ns" 1.000000)
					( Status sCSetFlattened )
					( Origin gBackEnd )
				)
			)
			( pinPair "@baseboard_fab2_lib.baseboard_fab2(sch_1):\PP3716\"
				( pinRef "@baseboard_fab2_lib.baseboard_fab2(sch_1):page54_i111:A10" )
				( pinRef "@baseboard_fab2_lib.baseboard_fab2(sch_1):page28_i172:DDR5_MA(10)" )
				( attribute "RELATIVE_PROPAGATION_DELAY_SCOPE" "G"
					( Parent
						( matchGroupRef "@crescent_city_bb_fab1_lib.crescent_city_bb_fab1(sch_1):\MG_DDR_NEAR_DIMM-CLK1_CLS_DDR_F_CAC-CLKS\" )
					)
					( Status sCSetFlattened )
					( Origin gBackEnd )
				)
				( attribute "RELATIVE_PROPAGATION_DELAY" "0.00 MIL,700.00 MIL"
					( Parent
						( matchGroupRef "@crescent_city_bb_fab1_lib.crescent_city_bb_fab1(sch_1):\MG_DDR_NEAR_DIMM-CLK1_CLS_DDR_F_CAC-CLKS\" )
					)
					( Units "uMatchProp" "ns" 1.000000)
					( Status sCSetFlattened )
					( Origin gBackEnd )
				)
				( attribute "RELATIVE_PROPAGATION_DELAY_SCOPE" "G"
					( Parent
						( matchGroupRef "@baseboard_fab2_lib.baseboard_fab2(sch_1):\MG_DDR_CMD_NEAR_DIMM_NG_DDR_F_DLL_4\" )
					)
					( Status sCSetFlattened )
					( Origin gBackEnd )
				)
				( attribute "RELATIVE_PROPAGATION_DELAY" "0.00 MIL,25.00 MIL"
					( Parent
						( matchGroupRef "@baseboard_fab2_lib.baseboard_fab2(sch_1):\MG_DDR_CMD_NEAR_DIMM_NG_DDR_F_DLL_4\" )
					)
					( Units "uMatchProp" "ns" 1.000000)
					( Status sCSetFlattened )
					( Origin gBackEnd )
				)
			)
			( pinPair "@baseboard_fab2_lib.baseboard_fab2(sch_1):\PP3709\"
				( pinRef "@baseboard_fab2_lib.baseboard_fab2(sch_1):page28_i172:DDR5_BA(0)" )
				( pinRef "@baseboard_fab2_lib.baseboard_fab2(sch_1):page53_i111:BA(0)" )
				( attribute "RELATIVE_PROPAGATION_DELAY_SCOPE" "G"
					( Parent
						( matchGroupRef "@crescent_city_bb_fab1_lib.crescent_city_bb_fab1(sch_1):\MG_DDR_FAR_DIMM-CLK0_CLS_DDR_F_CAC-CLKS\" )
					)
					( Status sCSetFlattened )
					( Origin gBackEnd )
				)
				( attribute "RELATIVE_PROPAGATION_DELAY" "0.00 MIL,700.00 MIL"
					( Parent
						( matchGroupRef "@crescent_city_bb_fab1_lib.crescent_city_bb_fab1(sch_1):\MG_DDR_FAR_DIMM-CLK0_CLS_DDR_F_CAC-CLKS\" )
					)
					( Units "uMatchProp" "ns" 1.000000)
					( Status sCSetFlattened )
					( Origin gBackEnd )
				)
				( attribute "RELATIVE_PROPAGATION_DELAY_SCOPE" "G"
					( Parent
						( matchGroupRef "@baseboard_fab2_lib.baseboard_fab2(sch_1):\MG_DDR_FAR_DIMM_CMD_NG_DDR_F_DLL_5\" )
					)
					( Status sCSetFlattened )
					( Origin gBackEnd )
				)
				( attribute "RELATIVE_PROPAGATION_DELAY" "0.00 MIL,25.00 MIL"
					( Parent
						( matchGroupRef "@baseboard_fab2_lib.baseboard_fab2(sch_1):\MG_DDR_FAR_DIMM_CMD_NG_DDR_F_DLL_5\" )
					)
					( Units "uMatchProp" "ns" 1.000000)
					( Status sCSetFlattened )
					( Origin gBackEnd )
				)
			)
			( pinPair "@baseboard_fab2_lib.baseboard_fab2(sch_1):\PP3710\"
				( pinRef "@baseboard_fab2_lib.baseboard_fab2(sch_1):page54_i111:BA(0)" )
				( pinRef "@baseboard_fab2_lib.baseboard_fab2(sch_1):page28_i172:DDR5_BA(0)" )
				( attribute "RELATIVE_PROPAGATION_DELAY_SCOPE" "G"
					( Parent
						( matchGroupRef "@crescent_city_bb_fab1_lib.crescent_city_bb_fab1(sch_1):\MG_DDR_NEAR_DIMM-CLK1_CLS_DDR_F_CAC-CLKS\" )
					)
					( Status sCSetFlattened )
					( Origin gBackEnd )
				)
				( attribute "RELATIVE_PROPAGATION_DELAY" "0.00 MIL,700.00 MIL"
					( Parent
						( matchGroupRef "@crescent_city_bb_fab1_lib.crescent_city_bb_fab1(sch_1):\MG_DDR_NEAR_DIMM-CLK1_CLS_DDR_F_CAC-CLKS\" )
					)
					( Units "uMatchProp" "ns" 1.000000)
					( Status sCSetFlattened )
					( Origin gBackEnd )
				)
				( attribute "RELATIVE_PROPAGATION_DELAY_SCOPE" "G"
					( Parent
						( matchGroupRef "@baseboard_fab2_lib.baseboard_fab2(sch_1):\MG_DDR_CMD_NEAR_DIMM_NG_DDR_F_DLL_5\" )
					)
					( Status sCSetFlattened )
					( Origin gBackEnd )
				)
				( attribute "RELATIVE_PROPAGATION_DELAY" "0.00 MIL,25.00 MIL"
					( Parent
						( matchGroupRef "@baseboard_fab2_lib.baseboard_fab2(sch_1):\MG_DDR_CMD_NEAR_DIMM_NG_DDR_F_DLL_5\" )
					)
					( Units "uMatchProp" "ns" 1.000000)
					( Status sCSetFlattened )
					( Origin gBackEnd )
				)
			)
			( pinPair "@baseboard_fab2_lib.baseboard_fab2(sch_1):\PP3711\"
				( pinRef "@baseboard_fab2_lib.baseboard_fab2(sch_1):page28_i172:DDR5_MA(0)" )
				( pinRef "@baseboard_fab2_lib.baseboard_fab2(sch_1):page53_i111:A0" )
				( attribute "RELATIVE_PROPAGATION_DELAY_SCOPE" "G"
					( Parent
						( matchGroupRef "@crescent_city_bb_fab1_lib.crescent_city_bb_fab1(sch_1):\MG_DDR_FAR_DIMM-CLK0_CLS_DDR_F_CAC-CLKS\" )
					)
					( Status sCSetFlattened )
					( Origin gBackEnd )
				)
				( attribute "RELATIVE_PROPAGATION_DELAY" "0.00 MIL,700.00 MIL"
					( Parent
						( matchGroupRef "@crescent_city_bb_fab1_lib.crescent_city_bb_fab1(sch_1):\MG_DDR_FAR_DIMM-CLK0_CLS_DDR_F_CAC-CLKS\" )
					)
					( Units "uMatchProp" "ns" 1.000000)
					( Status sCSetFlattened )
					( Origin gBackEnd )
				)
				( attribute "RELATIVE_PROPAGATION_DELAY_SCOPE" "G"
					( Parent
						( matchGroupRef "@baseboard_fab2_lib.baseboard_fab2(sch_1):\MG_DDR_FAR_DIMM_CMD_NG_DDR_F_DLL_5\" )
					)
					( Status sCSetFlattened )
					( Origin gBackEnd )
				)
				( attribute "RELATIVE_PROPAGATION_DELAY" "0.00 MIL,25.00 MIL"
					( Parent
						( matchGroupRef "@baseboard_fab2_lib.baseboard_fab2(sch_1):\MG_DDR_FAR_DIMM_CMD_NG_DDR_F_DLL_5\" )
					)
					( Units "uMatchProp" "ns" 1.000000)
					( Status sCSetFlattened )
					( Origin gBackEnd )
				)
			)
			( pinPair "@baseboard_fab2_lib.baseboard_fab2(sch_1):\PP3712\"
				( pinRef "@baseboard_fab2_lib.baseboard_fab2(sch_1):page54_i111:A0" )
				( pinRef "@baseboard_fab2_lib.baseboard_fab2(sch_1):page28_i172:DDR5_MA(0)" )
				( attribute "RELATIVE_PROPAGATION_DELAY_SCOPE" "G"
					( Parent
						( matchGroupRef "@crescent_city_bb_fab1_lib.crescent_city_bb_fab1(sch_1):\MG_DDR_NEAR_DIMM-CLK1_CLS_DDR_F_CAC-CLKS\" )
					)
					( Status sCSetFlattened )
					( Origin gBackEnd )
				)
				( attribute "RELATIVE_PROPAGATION_DELAY" "0.00 MIL,700.00 MIL"
					( Parent
						( matchGroupRef "@crescent_city_bb_fab1_lib.crescent_city_bb_fab1(sch_1):\MG_DDR_NEAR_DIMM-CLK1_CLS_DDR_F_CAC-CLKS\" )
					)
					( Units "uMatchProp" "ns" 1.000000)
					( Status sCSetFlattened )
					( Origin gBackEnd )
				)
				( attribute "RELATIVE_PROPAGATION_DELAY_SCOPE" "G"
					( Parent
						( matchGroupRef "@baseboard_fab2_lib.baseboard_fab2(sch_1):\MG_DDR_CMD_NEAR_DIMM_NG_DDR_F_DLL_5\" )
					)
					( Status sCSetFlattened )
					( Origin gBackEnd )
				)
				( attribute "RELATIVE_PROPAGATION_DELAY" "0.00 MIL,25.00 MIL"
					( Parent
						( matchGroupRef "@baseboard_fab2_lib.baseboard_fab2(sch_1):\MG_DDR_CMD_NEAR_DIMM_NG_DDR_F_DLL_5\" )
					)
					( Units "uMatchProp" "ns" 1.000000)
					( Status sCSetFlattened )
					( Origin gBackEnd )
				)
			)
			( pinPair "@baseboard_fab2_lib.baseboard_fab2(sch_1):\PP3707\"
				( pinRef "@baseboard_fab2_lib.baseboard_fab2(sch_1):page28_i172:DDR5_PAR" )
				( pinRef "@baseboard_fab2_lib.baseboard_fab2(sch_1):page53_i111:PAR" )
				( attribute "RELATIVE_PROPAGATION_DELAY_SCOPE" "G"
					( Parent
						( matchGroupRef "@crescent_city_bb_fab1_lib.crescent_city_bb_fab1(sch_1):\MG_DDR_FAR_DIMM-CLK0_CLS_DDR_F_CAC-CLKS\" )
					)
					( Status sCSetFlattened )
					( Origin gBackEnd )
				)
				( attribute "RELATIVE_PROPAGATION_DELAY" "0.00 MIL,700.00 MIL"
					( Parent
						( matchGroupRef "@crescent_city_bb_fab1_lib.crescent_city_bb_fab1(sch_1):\MG_DDR_FAR_DIMM-CLK0_CLS_DDR_F_CAC-CLKS\" )
					)
					( Units "uMatchProp" "ns" 1.000000)
					( Status sCSetFlattened )
					( Origin gBackEnd )
				)
				( attribute "RELATIVE_PROPAGATION_DELAY_SCOPE" "G"
					( Parent
						( matchGroupRef "@baseboard_fab2_lib.baseboard_fab2(sch_1):\MG_DDR_FAR_DIMM_CMD_NG_DDR_F_DLL_6\" )
					)
					( Status sCSetFlattened )
					( Origin gBackEnd )
				)
				( attribute "RELATIVE_PROPAGATION_DELAY" "0.00 MIL,25.00 MIL"
					( Parent
						( matchGroupRef "@baseboard_fab2_lib.baseboard_fab2(sch_1):\MG_DDR_FAR_DIMM_CMD_NG_DDR_F_DLL_6\" )
					)
					( Units "uMatchProp" "ns" 1.000000)
					( Status sCSetFlattened )
					( Origin gBackEnd )
				)
			)
			( pinPair "@baseboard_fab2_lib.baseboard_fab2(sch_1):\PP3708\"
				( pinRef "@baseboard_fab2_lib.baseboard_fab2(sch_1):page54_i111:PAR" )
				( pinRef "@baseboard_fab2_lib.baseboard_fab2(sch_1):page28_i172:DDR5_PAR" )
				( attribute "RELATIVE_PROPAGATION_DELAY_SCOPE" "G"
					( Parent
						( matchGroupRef "@crescent_city_bb_fab1_lib.crescent_city_bb_fab1(sch_1):\MG_DDR_NEAR_DIMM-CLK1_CLS_DDR_F_CAC-CLKS\" )
					)
					( Status sCSetFlattened )
					( Origin gBackEnd )
				)
				( attribute "RELATIVE_PROPAGATION_DELAY" "0.00 MIL,700.00 MIL"
					( Parent
						( matchGroupRef "@crescent_city_bb_fab1_lib.crescent_city_bb_fab1(sch_1):\MG_DDR_NEAR_DIMM-CLK1_CLS_DDR_F_CAC-CLKS\" )
					)
					( Units "uMatchProp" "ns" 1.000000)
					( Status sCSetFlattened )
					( Origin gBackEnd )
				)
				( attribute "RELATIVE_PROPAGATION_DELAY_SCOPE" "G"
					( Parent
						( matchGroupRef "@baseboard_fab2_lib.baseboard_fab2(sch_1):\MG_DDR_CMD_NEAR_DIMM_NG_DDR_F_DLL_6\" )
					)
					( Status sCSetFlattened )
					( Origin gBackEnd )
				)
				( attribute "RELATIVE_PROPAGATION_DELAY" "0.00 MIL,25.00 MIL"
					( Parent
						( matchGroupRef "@baseboard_fab2_lib.baseboard_fab2(sch_1):\MG_DDR_CMD_NEAR_DIMM_NG_DDR_F_DLL_6\" )
					)
					( Units "uMatchProp" "ns" 1.000000)
					( Status sCSetFlattened )
					( Origin gBackEnd )
				)
			)
			( pinPair "@baseboard_fab2_lib.baseboard_fab2(sch_1):\PP3703\"
				( pinRef "@baseboard_fab2_lib.baseboard_fab2(sch_1):page28_i172:DDR5_MA(1)" )
				( pinRef "@baseboard_fab2_lib.baseboard_fab2(sch_1):page53_i111:A1" )
				( attribute "RELATIVE_PROPAGATION_DELAY_SCOPE" "G"
					( Parent
						( matchGroupRef "@crescent_city_bb_fab1_lib.crescent_city_bb_fab1(sch_1):\MG_DDR_FAR_DIMM-CLK0_CLS_DDR_F_CAC-CLKS\" )
					)
					( Status sCSetFlattened )
					( Origin gBackEnd )
				)
				( attribute "RELATIVE_PROPAGATION_DELAY" "0.00 MIL,700.00 MIL"
					( Parent
						( matchGroupRef "@crescent_city_bb_fab1_lib.crescent_city_bb_fab1(sch_1):\MG_DDR_FAR_DIMM-CLK0_CLS_DDR_F_CAC-CLKS\" )
					)
					( Units "uMatchProp" "ns" 1.000000)
					( Status sCSetFlattened )
					( Origin gBackEnd )
				)
				( attribute "RELATIVE_PROPAGATION_DELAY_SCOPE" "G"
					( Parent
						( matchGroupRef "@baseboard_fab2_lib.baseboard_fab2(sch_1):\MG_DDR_FAR_DIMM_CMD_NG_DDR_F_DLL_7\" )
					)
					( Status sCSetFlattened )
					( Origin gBackEnd )
				)
				( attribute "RELATIVE_PROPAGATION_DELAY" "0.00 MIL,25.00 MIL"
					( Parent
						( matchGroupRef "@baseboard_fab2_lib.baseboard_fab2(sch_1):\MG_DDR_FAR_DIMM_CMD_NG_DDR_F_DLL_7\" )
					)
					( Units "uMatchProp" "ns" 1.000000)
					( Status sCSetFlattened )
					( Origin gBackEnd )
				)
			)
			( pinPair "@baseboard_fab2_lib.baseboard_fab2(sch_1):\PP3704\"
				( pinRef "@baseboard_fab2_lib.baseboard_fab2(sch_1):page54_i111:A1" )
				( pinRef "@baseboard_fab2_lib.baseboard_fab2(sch_1):page28_i172:DDR5_MA(1)" )
				( attribute "RELATIVE_PROPAGATION_DELAY_SCOPE" "G"
					( Parent
						( matchGroupRef "@crescent_city_bb_fab1_lib.crescent_city_bb_fab1(sch_1):\MG_DDR_NEAR_DIMM-CLK1_CLS_DDR_F_CAC-CLKS\" )
					)
					( Status sCSetFlattened )
					( Origin gBackEnd )
				)
				( attribute "RELATIVE_PROPAGATION_DELAY" "0.00 MIL,700.00 MIL"
					( Parent
						( matchGroupRef "@crescent_city_bb_fab1_lib.crescent_city_bb_fab1(sch_1):\MG_DDR_NEAR_DIMM-CLK1_CLS_DDR_F_CAC-CLKS\" )
					)
					( Units "uMatchProp" "ns" 1.000000)
					( Status sCSetFlattened )
					( Origin gBackEnd )
				)
				( attribute "RELATIVE_PROPAGATION_DELAY_SCOPE" "G"
					( Parent
						( matchGroupRef "@baseboard_fab2_lib.baseboard_fab2(sch_1):\MG_DDR_CMD_NEAR_DIMM_NG_DDR_F_DLL_7\" )
					)
					( Status sCSetFlattened )
					( Origin gBackEnd )
				)
				( attribute "RELATIVE_PROPAGATION_DELAY" "0.00 MIL,25.00 MIL"
					( Parent
						( matchGroupRef "@baseboard_fab2_lib.baseboard_fab2(sch_1):\MG_DDR_CMD_NEAR_DIMM_NG_DDR_F_DLL_7\" )
					)
					( Units "uMatchProp" "ns" 1.000000)
					( Status sCSetFlattened )
					( Origin gBackEnd )
				)
			)
			( pinPair "@baseboard_fab2_lib.baseboard_fab2(sch_1):\PP3705\"
				( pinRef "@baseboard_fab2_lib.baseboard_fab2(sch_1):page28_i172:DDR5_MA(3)" )
				( pinRef "@baseboard_fab2_lib.baseboard_fab2(sch_1):page53_i111:A3" )
				( attribute "RELATIVE_PROPAGATION_DELAY_SCOPE" "G"
					( Parent
						( matchGroupRef "@crescent_city_bb_fab1_lib.crescent_city_bb_fab1(sch_1):\MG_DDR_FAR_DIMM-CLK0_CLS_DDR_F_CAC-CLKS\" )
					)
					( Status sCSetFlattened )
					( Origin gBackEnd )
				)
				( attribute "RELATIVE_PROPAGATION_DELAY" "0.00 MIL,700.00 MIL"
					( Parent
						( matchGroupRef "@crescent_city_bb_fab1_lib.crescent_city_bb_fab1(sch_1):\MG_DDR_FAR_DIMM-CLK0_CLS_DDR_F_CAC-CLKS\" )
					)
					( Units "uMatchProp" "ns" 1.000000)
					( Status sCSetFlattened )
					( Origin gBackEnd )
				)
				( attribute "RELATIVE_PROPAGATION_DELAY_SCOPE" "G"
					( Parent
						( matchGroupRef "@baseboard_fab2_lib.baseboard_fab2(sch_1):\MG_DDR_FAR_DIMM_CMD_NG_DDR_F_DLL_7\" )
					)
					( Status sCSetFlattened )
					( Origin gBackEnd )
				)
				( attribute "RELATIVE_PROPAGATION_DELAY" "0.00 MIL,25.00 MIL"
					( Parent
						( matchGroupRef "@baseboard_fab2_lib.baseboard_fab2(sch_1):\MG_DDR_FAR_DIMM_CMD_NG_DDR_F_DLL_7\" )
					)
					( Units "uMatchProp" "ns" 1.000000)
					( Status sCSetFlattened )
					( Origin gBackEnd )
				)
			)
			( pinPair "@baseboard_fab2_lib.baseboard_fab2(sch_1):\PP3706\"
				( pinRef "@baseboard_fab2_lib.baseboard_fab2(sch_1):page54_i111:A3" )
				( pinRef "@baseboard_fab2_lib.baseboard_fab2(sch_1):page28_i172:DDR5_MA(3)" )
				( attribute "RELATIVE_PROPAGATION_DELAY_SCOPE" "G"
					( Parent
						( matchGroupRef "@crescent_city_bb_fab1_lib.crescent_city_bb_fab1(sch_1):\MG_DDR_NEAR_DIMM-CLK1_CLS_DDR_F_CAC-CLKS\" )
					)
					( Status sCSetFlattened )
					( Origin gBackEnd )
				)
				( attribute "RELATIVE_PROPAGATION_DELAY" "0.00 MIL,700.00 MIL"
					( Parent
						( matchGroupRef "@crescent_city_bb_fab1_lib.crescent_city_bb_fab1(sch_1):\MG_DDR_NEAR_DIMM-CLK1_CLS_DDR_F_CAC-CLKS\" )
					)
					( Units "uMatchProp" "ns" 1.000000)
					( Status sCSetFlattened )
					( Origin gBackEnd )
				)
				( attribute "RELATIVE_PROPAGATION_DELAY_SCOPE" "G"
					( Parent
						( matchGroupRef "@baseboard_fab2_lib.baseboard_fab2(sch_1):\MG_DDR_CMD_NEAR_DIMM_NG_DDR_F_DLL_7\" )
					)
					( Status sCSetFlattened )
					( Origin gBackEnd )
				)
				( attribute "RELATIVE_PROPAGATION_DELAY" "0.00 MIL,25.00 MIL"
					( Parent
						( matchGroupRef "@baseboard_fab2_lib.baseboard_fab2(sch_1):\MG_DDR_CMD_NEAR_DIMM_NG_DDR_F_DLL_7\" )
					)
					( Units "uMatchProp" "ns" 1.000000)
					( Status sCSetFlattened )
					( Origin gBackEnd )
				)
			)
			( pinPair "@baseboard_fab2_lib.baseboard_fab2(sch_1):\PP3699\"
				( pinRef "@baseboard_fab2_lib.baseboard_fab2(sch_1):page28_i172:DDR5_MA(2)" )
				( pinRef "@baseboard_fab2_lib.baseboard_fab2(sch_1):page53_i111:A2" )
				( attribute "RELATIVE_PROPAGATION_DELAY_SCOPE" "G"
					( Parent
						( matchGroupRef "@crescent_city_bb_fab1_lib.crescent_city_bb_fab1(sch_1):\MG_DDR_FAR_DIMM-CLK0_CLS_DDR_F_CAC-CLKS\" )
					)
					( Status sCSetFlattened )
					( Origin gBackEnd )
				)
				( attribute "RELATIVE_PROPAGATION_DELAY" "0.00 MIL,700.00 MIL"
					( Parent
						( matchGroupRef "@crescent_city_bb_fab1_lib.crescent_city_bb_fab1(sch_1):\MG_DDR_FAR_DIMM-CLK0_CLS_DDR_F_CAC-CLKS\" )
					)
					( Units "uMatchProp" "ns" 1.000000)
					( Status sCSetFlattened )
					( Origin gBackEnd )
				)
				( attribute "RELATIVE_PROPAGATION_DELAY_SCOPE" "G"
					( Parent
						( matchGroupRef "@baseboard_fab2_lib.baseboard_fab2(sch_1):\MG_DDR_FAR_DIMM_CMD_NG_DDR_F_DLL_8\" )
					)
					( Status sCSetFlattened )
					( Origin gBackEnd )
				)
				( attribute "RELATIVE_PROPAGATION_DELAY" "0.00 MIL,25.00 MIL"
					( Parent
						( matchGroupRef "@baseboard_fab2_lib.baseboard_fab2(sch_1):\MG_DDR_FAR_DIMM_CMD_NG_DDR_F_DLL_8\" )
					)
					( Units "uMatchProp" "ns" 1.000000)
					( Status sCSetFlattened )
					( Origin gBackEnd )
				)
			)
			( pinPair "@baseboard_fab2_lib.baseboard_fab2(sch_1):\PP3700\"
				( pinRef "@baseboard_fab2_lib.baseboard_fab2(sch_1):page28_i172:DDR5_MA(2)" )
				( pinRef "@baseboard_fab2_lib.baseboard_fab2(sch_1):page54_i111:A2" )
				( attribute "RELATIVE_PROPAGATION_DELAY_SCOPE" "G"
					( Parent
						( matchGroupRef "@crescent_city_bb_fab1_lib.crescent_city_bb_fab1(sch_1):\MG_DDR_NEAR_DIMM-CLK1_CLS_DDR_F_CAC-CLKS\" )
					)
					( Status sCSetFlattened )
					( Origin gBackEnd )
				)
				( attribute "RELATIVE_PROPAGATION_DELAY" "0.00 MIL,700.00 MIL"
					( Parent
						( matchGroupRef "@crescent_city_bb_fab1_lib.crescent_city_bb_fab1(sch_1):\MG_DDR_NEAR_DIMM-CLK1_CLS_DDR_F_CAC-CLKS\" )
					)
					( Units "uMatchProp" "ns" 1.000000)
					( Status sCSetFlattened )
					( Origin gBackEnd )
				)
				( attribute "RELATIVE_PROPAGATION_DELAY_SCOPE" "G"
					( Parent
						( matchGroupRef "@baseboard_fab2_lib.baseboard_fab2(sch_1):\MG_DDR_CMD_NEAR_DIMM_NG_DDR_F_DLL_8\" )
					)
					( Status sCSetFlattened )
					( Origin gBackEnd )
				)
				( attribute "RELATIVE_PROPAGATION_DELAY" "0.00 MIL,25.00 MIL"
					( Parent
						( matchGroupRef "@baseboard_fab2_lib.baseboard_fab2(sch_1):\MG_DDR_CMD_NEAR_DIMM_NG_DDR_F_DLL_8\" )
					)
					( Units "uMatchProp" "ns" 1.000000)
					( Status sCSetFlattened )
					( Origin gBackEnd )
				)
			)
			( pinPair "@baseboard_fab2_lib.baseboard_fab2(sch_1):\PP3701\"
				( pinRef "@baseboard_fab2_lib.baseboard_fab2(sch_1):page28_i172:DDR5_MA(4)" )
				( pinRef "@baseboard_fab2_lib.baseboard_fab2(sch_1):page53_i111:A4" )
				( attribute "RELATIVE_PROPAGATION_DELAY_SCOPE" "G"
					( Parent
						( matchGroupRef "@crescent_city_bb_fab1_lib.crescent_city_bb_fab1(sch_1):\MG_DDR_FAR_DIMM-CLK0_CLS_DDR_F_CAC-CLKS\" )
					)
					( Status sCSetFlattened )
					( Origin gBackEnd )
				)
				( attribute "RELATIVE_PROPAGATION_DELAY" "0.00 MIL,700.00 MIL"
					( Parent
						( matchGroupRef "@crescent_city_bb_fab1_lib.crescent_city_bb_fab1(sch_1):\MG_DDR_FAR_DIMM-CLK0_CLS_DDR_F_CAC-CLKS\" )
					)
					( Units "uMatchProp" "ns" 1.000000)
					( Status sCSetFlattened )
					( Origin gBackEnd )
				)
				( attribute "RELATIVE_PROPAGATION_DELAY_SCOPE" "G"
					( Parent
						( matchGroupRef "@baseboard_fab2_lib.baseboard_fab2(sch_1):\MG_DDR_FAR_DIMM_CMD_NG_DDR_F_DLL_8\" )
					)
					( Status sCSetFlattened )
					( Origin gBackEnd )
				)
				( attribute "RELATIVE_PROPAGATION_DELAY" "0.00 MIL,25.00 MIL"
					( Parent
						( matchGroupRef "@baseboard_fab2_lib.baseboard_fab2(sch_1):\MG_DDR_FAR_DIMM_CMD_NG_DDR_F_DLL_8\" )
					)
					( Units "uMatchProp" "ns" 1.000000)
					( Status sCSetFlattened )
					( Origin gBackEnd )
				)
			)
			( pinPair "@baseboard_fab2_lib.baseboard_fab2(sch_1):\PP3702\"
				( pinRef "@baseboard_fab2_lib.baseboard_fab2(sch_1):page28_i172:DDR5_MA(4)" )
				( pinRef "@baseboard_fab2_lib.baseboard_fab2(sch_1):page54_i111:A4" )
				( attribute "RELATIVE_PROPAGATION_DELAY_SCOPE" "G"
					( Parent
						( matchGroupRef "@crescent_city_bb_fab1_lib.crescent_city_bb_fab1(sch_1):\MG_DDR_NEAR_DIMM-CLK1_CLS_DDR_F_CAC-CLKS\" )
					)
					( Status sCSetFlattened )
					( Origin gBackEnd )
				)
				( attribute "RELATIVE_PROPAGATION_DELAY" "0.00 MIL,700.00 MIL"
					( Parent
						( matchGroupRef "@crescent_city_bb_fab1_lib.crescent_city_bb_fab1(sch_1):\MG_DDR_NEAR_DIMM-CLK1_CLS_DDR_F_CAC-CLKS\" )
					)
					( Units "uMatchProp" "ns" 1.000000)
					( Status sCSetFlattened )
					( Origin gBackEnd )
				)
				( attribute "RELATIVE_PROPAGATION_DELAY_SCOPE" "G"
					( Parent
						( matchGroupRef "@baseboard_fab2_lib.baseboard_fab2(sch_1):\MG_DDR_CMD_NEAR_DIMM_NG_DDR_F_DLL_8\" )
					)
					( Status sCSetFlattened )
					( Origin gBackEnd )
				)
				( attribute "RELATIVE_PROPAGATION_DELAY" "0.00 MIL,25.00 MIL"
					( Parent
						( matchGroupRef "@baseboard_fab2_lib.baseboard_fab2(sch_1):\MG_DDR_CMD_NEAR_DIMM_NG_DDR_F_DLL_8\" )
					)
					( Units "uMatchProp" "ns" 1.000000)
					( Status sCSetFlattened )
					( Origin gBackEnd )
				)
			)
			( pinPair "@baseboard_fab2_lib.baseboard_fab2(sch_1):\PP3695\"
				( pinRef "@baseboard_fab2_lib.baseboard_fab2(sch_1):page28_i172:DDR5_MA(5)" )
				( pinRef "@baseboard_fab2_lib.baseboard_fab2(sch_1):page53_i111:A5" )
				( attribute "RELATIVE_PROPAGATION_DELAY_SCOPE" "G"
					( Parent
						( matchGroupRef "@crescent_city_bb_fab1_lib.crescent_city_bb_fab1(sch_1):\MG_DDR_FAR_DIMM-CLK0_CLS_DDR_F_CAC-CLKS\" )
					)
					( Status sCSetFlattened )
					( Origin gBackEnd )
				)
				( attribute "RELATIVE_PROPAGATION_DELAY" "0.00 MIL,700.00 MIL"
					( Parent
						( matchGroupRef "@crescent_city_bb_fab1_lib.crescent_city_bb_fab1(sch_1):\MG_DDR_FAR_DIMM-CLK0_CLS_DDR_F_CAC-CLKS\" )
					)
					( Units "uMatchProp" "ns" 1.000000)
					( Status sCSetFlattened )
					( Origin gBackEnd )
				)
				( attribute "RELATIVE_PROPAGATION_DELAY_SCOPE" "G"
					( Parent
						( matchGroupRef "@baseboard_fab2_lib.baseboard_fab2(sch_1):\MG_DDR_FAR_DIMM_CMD_NG_DDR_F_DLL_9\" )
					)
					( Status sCSetFlattened )
					( Origin gBackEnd )
				)
				( attribute "RELATIVE_PROPAGATION_DELAY" "0.00 MIL,25.00 MIL"
					( Parent
						( matchGroupRef "@baseboard_fab2_lib.baseboard_fab2(sch_1):\MG_DDR_FAR_DIMM_CMD_NG_DDR_F_DLL_9\" )
					)
					( Units "uMatchProp" "ns" 1.000000)
					( Status sCSetFlattened )
					( Origin gBackEnd )
				)
			)
			( pinPair "@baseboard_fab2_lib.baseboard_fab2(sch_1):\PP3696\"
				( pinRef "@baseboard_fab2_lib.baseboard_fab2(sch_1):page54_i111:A5" )
				( pinRef "@baseboard_fab2_lib.baseboard_fab2(sch_1):page28_i172:DDR5_MA(5)" )
				( attribute "RELATIVE_PROPAGATION_DELAY_SCOPE" "G"
					( Parent
						( matchGroupRef "@crescent_city_bb_fab1_lib.crescent_city_bb_fab1(sch_1):\MG_DDR_NEAR_DIMM-CLK1_CLS_DDR_F_CAC-CLKS\" )
					)
					( Status sCSetFlattened )
					( Origin gBackEnd )
				)
				( attribute "RELATIVE_PROPAGATION_DELAY" "0.00 MIL,700.00 MIL"
					( Parent
						( matchGroupRef "@crescent_city_bb_fab1_lib.crescent_city_bb_fab1(sch_1):\MG_DDR_NEAR_DIMM-CLK1_CLS_DDR_F_CAC-CLKS\" )
					)
					( Units "uMatchProp" "ns" 1.000000)
					( Status sCSetFlattened )
					( Origin gBackEnd )
				)
				( attribute "RELATIVE_PROPAGATION_DELAY_SCOPE" "G"
					( Parent
						( matchGroupRef "@baseboard_fab2_lib.baseboard_fab2(sch_1):\MG_DDR_CMD_NEAR_DIMM_NG_DDR_F_DLL_9\" )
					)
					( Status sCSetFlattened )
					( Origin gBackEnd )
				)
				( attribute "RELATIVE_PROPAGATION_DELAY" "0.00 MIL,25.00 MIL"
					( Parent
						( matchGroupRef "@baseboard_fab2_lib.baseboard_fab2(sch_1):\MG_DDR_CMD_NEAR_DIMM_NG_DDR_F_DLL_9\" )
					)
					( Units "uMatchProp" "ns" 1.000000)
					( Status sCSetFlattened )
					( Origin gBackEnd )
				)
			)
			( pinPair "@baseboard_fab2_lib.baseboard_fab2(sch_1):\PP3697\"
				( pinRef "@baseboard_fab2_lib.baseboard_fab2(sch_1):page28_i172:DDR5_MA(6)" )
				( pinRef "@baseboard_fab2_lib.baseboard_fab2(sch_1):page53_i111:A6" )
				( attribute "RELATIVE_PROPAGATION_DELAY_SCOPE" "G"
					( Parent
						( matchGroupRef "@crescent_city_bb_fab1_lib.crescent_city_bb_fab1(sch_1):\MG_DDR_FAR_DIMM-CLK0_CLS_DDR_F_CAC-CLKS\" )
					)
					( Status sCSetFlattened )
					( Origin gBackEnd )
				)
				( attribute "RELATIVE_PROPAGATION_DELAY" "0.00 MIL,700.00 MIL"
					( Parent
						( matchGroupRef "@crescent_city_bb_fab1_lib.crescent_city_bb_fab1(sch_1):\MG_DDR_FAR_DIMM-CLK0_CLS_DDR_F_CAC-CLKS\" )
					)
					( Units "uMatchProp" "ns" 1.000000)
					( Status sCSetFlattened )
					( Origin gBackEnd )
				)
				( attribute "RELATIVE_PROPAGATION_DELAY_SCOPE" "G"
					( Parent
						( matchGroupRef "@baseboard_fab2_lib.baseboard_fab2(sch_1):\MG_DDR_FAR_DIMM_CMD_NG_DDR_F_DLL_9\" )
					)
					( Status sCSetFlattened )
					( Origin gBackEnd )
				)
				( attribute "RELATIVE_PROPAGATION_DELAY" "0.00 MIL,25.00 MIL"
					( Parent
						( matchGroupRef "@baseboard_fab2_lib.baseboard_fab2(sch_1):\MG_DDR_FAR_DIMM_CMD_NG_DDR_F_DLL_9\" )
					)
					( Units "uMatchProp" "ns" 1.000000)
					( Status sCSetFlattened )
					( Origin gBackEnd )
				)
			)
			( pinPair "@baseboard_fab2_lib.baseboard_fab2(sch_1):\PP3698\"
				( pinRef "@baseboard_fab2_lib.baseboard_fab2(sch_1):page54_i111:A6" )
				( pinRef "@baseboard_fab2_lib.baseboard_fab2(sch_1):page28_i172:DDR5_MA(6)" )
				( attribute "RELATIVE_PROPAGATION_DELAY_SCOPE" "G"
					( Parent
						( matchGroupRef "@crescent_city_bb_fab1_lib.crescent_city_bb_fab1(sch_1):\MG_DDR_NEAR_DIMM-CLK1_CLS_DDR_F_CAC-CLKS\" )
					)
					( Status sCSetFlattened )
					( Origin gBackEnd )
				)
				( attribute "RELATIVE_PROPAGATION_DELAY" "0.00 MIL,700.00 MIL"
					( Parent
						( matchGroupRef "@crescent_city_bb_fab1_lib.crescent_city_bb_fab1(sch_1):\MG_DDR_NEAR_DIMM-CLK1_CLS_DDR_F_CAC-CLKS\" )
					)
					( Units "uMatchProp" "ns" 1.000000)
					( Status sCSetFlattened )
					( Origin gBackEnd )
				)
				( attribute "RELATIVE_PROPAGATION_DELAY_SCOPE" "G"
					( Parent
						( matchGroupRef "@baseboard_fab2_lib.baseboard_fab2(sch_1):\MG_DDR_CMD_NEAR_DIMM_NG_DDR_F_DLL_9\" )
					)
					( Status sCSetFlattened )
					( Origin gBackEnd )
				)
				( attribute "RELATIVE_PROPAGATION_DELAY" "0.00 MIL,25.00 MIL"
					( Parent
						( matchGroupRef "@baseboard_fab2_lib.baseboard_fab2(sch_1):\MG_DDR_CMD_NEAR_DIMM_NG_DDR_F_DLL_9\" )
					)
					( Units "uMatchProp" "ns" 1.000000)
					( Status sCSetFlattened )
					( Origin gBackEnd )
				)
			)
			( pinPair "@baseboard_fab2_lib.baseboard_fab2(sch_1):\PP3691\"
				( pinRef "@baseboard_fab2_lib.baseboard_fab2(sch_1):page28_i172:DDR5_MA(7)" )
				( pinRef "@baseboard_fab2_lib.baseboard_fab2(sch_1):page53_i111:A7" )
				( attribute "RELATIVE_PROPAGATION_DELAY_SCOPE" "G"
					( Parent
						( matchGroupRef "@crescent_city_bb_fab1_lib.crescent_city_bb_fab1(sch_1):\MG_DDR_FAR_DIMM-CLK0_CLS_DDR_F_CAC-CLKS\" )
					)
					( Status sCSetFlattened )
					( Origin gBackEnd )
				)
				( attribute "RELATIVE_PROPAGATION_DELAY" "0.00 MIL,700.00 MIL"
					( Parent
						( matchGroupRef "@crescent_city_bb_fab1_lib.crescent_city_bb_fab1(sch_1):\MG_DDR_FAR_DIMM-CLK0_CLS_DDR_F_CAC-CLKS\" )
					)
					( Units "uMatchProp" "ns" 1.000000)
					( Status sCSetFlattened )
					( Origin gBackEnd )
				)
				( attribute "RELATIVE_PROPAGATION_DELAY_SCOPE" "G"
					( Parent
						( matchGroupRef "@baseboard_fab2_lib.baseboard_fab2(sch_1):\MG_DDR_FAR_DIMM_CMD_NG_DDR_F_DLL_10\" )
					)
					( Status sCSetFlattened )
					( Origin gBackEnd )
				)
				( attribute "RELATIVE_PROPAGATION_DELAY" "0.00 MIL,25.00 MIL"
					( Parent
						( matchGroupRef "@baseboard_fab2_lib.baseboard_fab2(sch_1):\MG_DDR_FAR_DIMM_CMD_NG_DDR_F_DLL_10\" )
					)
					( Units "uMatchProp" "ns" 1.000000)
					( Status sCSetFlattened )
					( Origin gBackEnd )
				)
			)
			( pinPair "@baseboard_fab2_lib.baseboard_fab2(sch_1):\PP3692\"
				( pinRef "@baseboard_fab2_lib.baseboard_fab2(sch_1):page54_i111:A7" )
				( pinRef "@baseboard_fab2_lib.baseboard_fab2(sch_1):page28_i172:DDR5_MA(7)" )
				( attribute "RELATIVE_PROPAGATION_DELAY_SCOPE" "G"
					( Parent
						( matchGroupRef "@crescent_city_bb_fab1_lib.crescent_city_bb_fab1(sch_1):\MG_DDR_NEAR_DIMM-CLK1_CLS_DDR_F_CAC-CLKS\" )
					)
					( Status sCSetFlattened )
					( Origin gBackEnd )
				)
				( attribute "RELATIVE_PROPAGATION_DELAY" "0.00 MIL,700.00 MIL"
					( Parent
						( matchGroupRef "@crescent_city_bb_fab1_lib.crescent_city_bb_fab1(sch_1):\MG_DDR_NEAR_DIMM-CLK1_CLS_DDR_F_CAC-CLKS\" )
					)
					( Units "uMatchProp" "ns" 1.000000)
					( Status sCSetFlattened )
					( Origin gBackEnd )
				)
				( attribute "RELATIVE_PROPAGATION_DELAY_SCOPE" "G"
					( Parent
						( matchGroupRef "@baseboard_fab2_lib.baseboard_fab2(sch_1):\MG_DDR_CMD_NEAR_DIMM_NG_DDR_F_DLL_10\" )
					)
					( Status sCSetFlattened )
					( Origin gBackEnd )
				)
				( attribute "RELATIVE_PROPAGATION_DELAY" "0.00 MIL,25.00 MIL"
					( Parent
						( matchGroupRef "@baseboard_fab2_lib.baseboard_fab2(sch_1):\MG_DDR_CMD_NEAR_DIMM_NG_DDR_F_DLL_10\" )
					)
					( Units "uMatchProp" "ns" 1.000000)
					( Status sCSetFlattened )
					( Origin gBackEnd )
				)
			)
			( pinPair "@baseboard_fab2_lib.baseboard_fab2(sch_1):\PP3693\"
				( pinRef "@baseboard_fab2_lib.baseboard_fab2(sch_1):page28_i172:DDR5_MA(8)" )
				( pinRef "@baseboard_fab2_lib.baseboard_fab2(sch_1):page53_i111:A8" )
				( attribute "RELATIVE_PROPAGATION_DELAY_SCOPE" "G"
					( Parent
						( matchGroupRef "@crescent_city_bb_fab1_lib.crescent_city_bb_fab1(sch_1):\MG_DDR_FAR_DIMM-CLK0_CLS_DDR_F_CAC-CLKS\" )
					)
					( Status sCSetFlattened )
					( Origin gBackEnd )
				)
				( attribute "RELATIVE_PROPAGATION_DELAY" "0.00 MIL,700.00 MIL"
					( Parent
						( matchGroupRef "@crescent_city_bb_fab1_lib.crescent_city_bb_fab1(sch_1):\MG_DDR_FAR_DIMM-CLK0_CLS_DDR_F_CAC-CLKS\" )
					)
					( Units "uMatchProp" "ns" 1.000000)
					( Status sCSetFlattened )
					( Origin gBackEnd )
				)
				( attribute "RELATIVE_PROPAGATION_DELAY_SCOPE" "G"
					( Parent
						( matchGroupRef "@baseboard_fab2_lib.baseboard_fab2(sch_1):\MG_DDR_FAR_DIMM_CMD_NG_DDR_F_DLL_10\" )
					)
					( Status sCSetFlattened )
					( Origin gBackEnd )
				)
				( attribute "RELATIVE_PROPAGATION_DELAY" "0.00 MIL,25.00 MIL"
					( Parent
						( matchGroupRef "@baseboard_fab2_lib.baseboard_fab2(sch_1):\MG_DDR_FAR_DIMM_CMD_NG_DDR_F_DLL_10\" )
					)
					( Units "uMatchProp" "ns" 1.000000)
					( Status sCSetFlattened )
					( Origin gBackEnd )
				)
			)
			( pinPair "@baseboard_fab2_lib.baseboard_fab2(sch_1):\PP3694\"
				( pinRef "@baseboard_fab2_lib.baseboard_fab2(sch_1):page54_i111:A8" )
				( pinRef "@baseboard_fab2_lib.baseboard_fab2(sch_1):page28_i172:DDR5_MA(8)" )
				( attribute "RELATIVE_PROPAGATION_DELAY_SCOPE" "G"
					( Parent
						( matchGroupRef "@crescent_city_bb_fab1_lib.crescent_city_bb_fab1(sch_1):\MG_DDR_NEAR_DIMM-CLK1_CLS_DDR_F_CAC-CLKS\" )
					)
					( Status sCSetFlattened )
					( Origin gBackEnd )
				)
				( attribute "RELATIVE_PROPAGATION_DELAY" "0.00 MIL,700.00 MIL"
					( Parent
						( matchGroupRef "@crescent_city_bb_fab1_lib.crescent_city_bb_fab1(sch_1):\MG_DDR_NEAR_DIMM-CLK1_CLS_DDR_F_CAC-CLKS\" )
					)
					( Units "uMatchProp" "ns" 1.000000)
					( Status sCSetFlattened )
					( Origin gBackEnd )
				)
				( attribute "RELATIVE_PROPAGATION_DELAY_SCOPE" "G"
					( Parent
						( matchGroupRef "@baseboard_fab2_lib.baseboard_fab2(sch_1):\MG_DDR_CMD_NEAR_DIMM_NG_DDR_F_DLL_10\" )
					)
					( Status sCSetFlattened )
					( Origin gBackEnd )
				)
				( attribute "RELATIVE_PROPAGATION_DELAY" "0.00 MIL,25.00 MIL"
					( Parent
						( matchGroupRef "@baseboard_fab2_lib.baseboard_fab2(sch_1):\MG_DDR_CMD_NEAR_DIMM_NG_DDR_F_DLL_10\" )
					)
					( Units "uMatchProp" "ns" 1.000000)
					( Status sCSetFlattened )
					( Origin gBackEnd )
				)
			)
			( pinPair "@baseboard_fab2_lib.baseboard_fab2(sch_1):\PP3687\"
				( pinRef "@baseboard_fab2_lib.baseboard_fab2(sch_1):page28_i172:DDR5_MA(9)" )
				( pinRef "@baseboard_fab2_lib.baseboard_fab2(sch_1):page53_i111:A9" )
				( attribute "RELATIVE_PROPAGATION_DELAY_SCOPE" "G"
					( Parent
						( matchGroupRef "@crescent_city_bb_fab1_lib.crescent_city_bb_fab1(sch_1):\MG_DDR_FAR_DIMM-CLK0_CLS_DDR_F_CAC-CLKS\" )
					)
					( Status sCSetFlattened )
					( Origin gBackEnd )
				)
				( attribute "RELATIVE_PROPAGATION_DELAY" "0.00 MIL,700.00 MIL"
					( Parent
						( matchGroupRef "@crescent_city_bb_fab1_lib.crescent_city_bb_fab1(sch_1):\MG_DDR_FAR_DIMM-CLK0_CLS_DDR_F_CAC-CLKS\" )
					)
					( Units "uMatchProp" "ns" 1.000000)
					( Status sCSetFlattened )
					( Origin gBackEnd )
				)
				( attribute "RELATIVE_PROPAGATION_DELAY_SCOPE" "G"
					( Parent
						( matchGroupRef "@baseboard_fab2_lib.baseboard_fab2(sch_1):\MG_DDR_FAR_DIMM_CMD_NG_DDR_F_DLL_11\" )
					)
					( Status sCSetFlattened )
					( Origin gBackEnd )
				)
				( attribute "RELATIVE_PROPAGATION_DELAY" "0.00 MIL,25.00 MIL"
					( Parent
						( matchGroupRef "@baseboard_fab2_lib.baseboard_fab2(sch_1):\MG_DDR_FAR_DIMM_CMD_NG_DDR_F_DLL_11\" )
					)
					( Units "uMatchProp" "ns" 1.000000)
					( Status sCSetFlattened )
					( Origin gBackEnd )
				)
			)
			( pinPair "@baseboard_fab2_lib.baseboard_fab2(sch_1):\PP3688\"
				( pinRef "@baseboard_fab2_lib.baseboard_fab2(sch_1):page54_i111:A9" )
				( pinRef "@baseboard_fab2_lib.baseboard_fab2(sch_1):page28_i172:DDR5_MA(9)" )
				( attribute "RELATIVE_PROPAGATION_DELAY_SCOPE" "G"
					( Parent
						( matchGroupRef "@crescent_city_bb_fab1_lib.crescent_city_bb_fab1(sch_1):\MG_DDR_NEAR_DIMM-CLK1_CLS_DDR_F_CAC-CLKS\" )
					)
					( Status sCSetFlattened )
					( Origin gBackEnd )
				)
				( attribute "RELATIVE_PROPAGATION_DELAY" "0.00 MIL,700.00 MIL"
					( Parent
						( matchGroupRef "@crescent_city_bb_fab1_lib.crescent_city_bb_fab1(sch_1):\MG_DDR_NEAR_DIMM-CLK1_CLS_DDR_F_CAC-CLKS\" )
					)
					( Units "uMatchProp" "ns" 1.000000)
					( Status sCSetFlattened )
					( Origin gBackEnd )
				)
				( attribute "RELATIVE_PROPAGATION_DELAY_SCOPE" "G"
					( Parent
						( matchGroupRef "@baseboard_fab2_lib.baseboard_fab2(sch_1):\MG_DDR_CMD_NEAR_DIMM_NG_DDR_F_DLL_11\" )
					)
					( Status sCSetFlattened )
					( Origin gBackEnd )
				)
				( attribute "RELATIVE_PROPAGATION_DELAY" "0.00 MIL,25.00 MIL"
					( Parent
						( matchGroupRef "@baseboard_fab2_lib.baseboard_fab2(sch_1):\MG_DDR_CMD_NEAR_DIMM_NG_DDR_F_DLL_11\" )
					)
					( Units "uMatchProp" "ns" 1.000000)
					( Status sCSetFlattened )
					( Origin gBackEnd )
				)
			)
			( pinPair "@baseboard_fab2_lib.baseboard_fab2(sch_1):\PP3689\"
				( pinRef "@baseboard_fab2_lib.baseboard_fab2(sch_1):page28_i172:DDR5_MA(12)" )
				( pinRef "@baseboard_fab2_lib.baseboard_fab2(sch_1):page53_i111:A12" )
				( attribute "RELATIVE_PROPAGATION_DELAY_SCOPE" "G"
					( Parent
						( matchGroupRef "@crescent_city_bb_fab1_lib.crescent_city_bb_fab1(sch_1):\MG_DDR_FAR_DIMM-CLK0_CLS_DDR_F_CAC-CLKS\" )
					)
					( Status sCSetFlattened )
					( Origin gBackEnd )
				)
				( attribute "RELATIVE_PROPAGATION_DELAY" "0.00 MIL,700.00 MIL"
					( Parent
						( matchGroupRef "@crescent_city_bb_fab1_lib.crescent_city_bb_fab1(sch_1):\MG_DDR_FAR_DIMM-CLK0_CLS_DDR_F_CAC-CLKS\" )
					)
					( Units "uMatchProp" "ns" 1.000000)
					( Status sCSetFlattened )
					( Origin gBackEnd )
				)
				( attribute "RELATIVE_PROPAGATION_DELAY_SCOPE" "G"
					( Parent
						( matchGroupRef "@baseboard_fab2_lib.baseboard_fab2(sch_1):\MG_DDR_FAR_DIMM_CMD_NG_DDR_F_DLL_11\" )
					)
					( Status sCSetFlattened )
					( Origin gBackEnd )
				)
				( attribute "RELATIVE_PROPAGATION_DELAY" "0.00 MIL,25.00 MIL"
					( Parent
						( matchGroupRef "@baseboard_fab2_lib.baseboard_fab2(sch_1):\MG_DDR_FAR_DIMM_CMD_NG_DDR_F_DLL_11\" )
					)
					( Units "uMatchProp" "ns" 1.000000)
					( Status sCSetFlattened )
					( Origin gBackEnd )
				)
			)
			( pinPair "@baseboard_fab2_lib.baseboard_fab2(sch_1):\PP3690\"
				( pinRef "@baseboard_fab2_lib.baseboard_fab2(sch_1):page28_i172:DDR5_MA(12)" )
				( pinRef "@baseboard_fab2_lib.baseboard_fab2(sch_1):page54_i111:A12" )
				( attribute "RELATIVE_PROPAGATION_DELAY_SCOPE" "G"
					( Parent
						( matchGroupRef "@crescent_city_bb_fab1_lib.crescent_city_bb_fab1(sch_1):\MG_DDR_NEAR_DIMM-CLK1_CLS_DDR_F_CAC-CLKS\" )
					)
					( Status sCSetFlattened )
					( Origin gBackEnd )
				)
				( attribute "RELATIVE_PROPAGATION_DELAY" "0.00 MIL,700.00 MIL"
					( Parent
						( matchGroupRef "@crescent_city_bb_fab1_lib.crescent_city_bb_fab1(sch_1):\MG_DDR_NEAR_DIMM-CLK1_CLS_DDR_F_CAC-CLKS\" )
					)
					( Units "uMatchProp" "ns" 1.000000)
					( Status sCSetFlattened )
					( Origin gBackEnd )
				)
				( attribute "RELATIVE_PROPAGATION_DELAY_SCOPE" "G"
					( Parent
						( matchGroupRef "@baseboard_fab2_lib.baseboard_fab2(sch_1):\MG_DDR_CMD_NEAR_DIMM_NG_DDR_F_DLL_11\" )
					)
					( Status sCSetFlattened )
					( Origin gBackEnd )
				)
				( attribute "RELATIVE_PROPAGATION_DELAY" "0.00 MIL,25.00 MIL"
					( Parent
						( matchGroupRef "@baseboard_fab2_lib.baseboard_fab2(sch_1):\MG_DDR_CMD_NEAR_DIMM_NG_DDR_F_DLL_11\" )
					)
					( Units "uMatchProp" "ns" 1.000000)
					( Status sCSetFlattened )
					( Origin gBackEnd )
				)
			)
			( pinPair "@baseboard_fab2_lib.baseboard_fab2(sch_1):\PP3683\"
				( pinRef "@baseboard_fab2_lib.baseboard_fab2(sch_1):page28_i172:DDR5_BG(1)" )
				( pinRef "@baseboard_fab2_lib.baseboard_fab2(sch_1):page53_i111:BG(1)" )
				( attribute "RELATIVE_PROPAGATION_DELAY_SCOPE" "G"
					( Parent
						( matchGroupRef "@crescent_city_bb_fab1_lib.crescent_city_bb_fab1(sch_1):\MG_DDR_FAR_DIMM-CLK0_CLS_DDR_F_CAC-CLKS\" )
					)
					( Status sCSetFlattened )
					( Origin gBackEnd )
				)
				( attribute "RELATIVE_PROPAGATION_DELAY" "0.00 MIL,700.00 MIL"
					( Parent
						( matchGroupRef "@crescent_city_bb_fab1_lib.crescent_city_bb_fab1(sch_1):\MG_DDR_FAR_DIMM-CLK0_CLS_DDR_F_CAC-CLKS\" )
					)
					( Units "uMatchProp" "ns" 1.000000)
					( Status sCSetFlattened )
					( Origin gBackEnd )
				)
				( attribute "RELATIVE_PROPAGATION_DELAY_SCOPE" "G"
					( Parent
						( matchGroupRef "@baseboard_fab2_lib.baseboard_fab2(sch_1):\MG_DDR_FAR_DIMM_CMD_NG_DDR_F_DLL_12\" )
					)
					( Status sCSetFlattened )
					( Origin gBackEnd )
				)
				( attribute "RELATIVE_PROPAGATION_DELAY" "0.00 MIL,25.00 MIL"
					( Parent
						( matchGroupRef "@baseboard_fab2_lib.baseboard_fab2(sch_1):\MG_DDR_FAR_DIMM_CMD_NG_DDR_F_DLL_12\" )
					)
					( Units "uMatchProp" "ns" 1.000000)
					( Status sCSetFlattened )
					( Origin gBackEnd )
				)
			)
			( pinPair "@baseboard_fab2_lib.baseboard_fab2(sch_1):\PP3684\"
				( pinRef "@baseboard_fab2_lib.baseboard_fab2(sch_1):page54_i111:BG(1)" )
				( pinRef "@baseboard_fab2_lib.baseboard_fab2(sch_1):page28_i172:DDR5_BG(1)" )
				( attribute "RELATIVE_PROPAGATION_DELAY_SCOPE" "G"
					( Parent
						( matchGroupRef "@crescent_city_bb_fab1_lib.crescent_city_bb_fab1(sch_1):\MG_DDR_NEAR_DIMM-CLK1_CLS_DDR_F_CAC-CLKS\" )
					)
					( Status sCSetFlattened )
					( Origin gBackEnd )
				)
				( attribute "RELATIVE_PROPAGATION_DELAY" "0.00 MIL,700.00 MIL"
					( Parent
						( matchGroupRef "@crescent_city_bb_fab1_lib.crescent_city_bb_fab1(sch_1):\MG_DDR_NEAR_DIMM-CLK1_CLS_DDR_F_CAC-CLKS\" )
					)
					( Units "uMatchProp" "ns" 1.000000)
					( Status sCSetFlattened )
					( Origin gBackEnd )
				)
				( attribute "RELATIVE_PROPAGATION_DELAY_SCOPE" "G"
					( Parent
						( matchGroupRef "@baseboard_fab2_lib.baseboard_fab2(sch_1):\MG_DDR_CMD_NEAR_DIMM_NG_DDR_F_DLL_12\" )
					)
					( Status sCSetFlattened )
					( Origin gBackEnd )
				)
				( attribute "RELATIVE_PROPAGATION_DELAY" "0.00 MIL,25.00 MIL"
					( Parent
						( matchGroupRef "@baseboard_fab2_lib.baseboard_fab2(sch_1):\MG_DDR_CMD_NEAR_DIMM_NG_DDR_F_DLL_12\" )
					)
					( Units "uMatchProp" "ns" 1.000000)
					( Status sCSetFlattened )
					( Origin gBackEnd )
				)
			)
			( pinPair "@baseboard_fab2_lib.baseboard_fab2(sch_1):\PP3685\"
				( pinRef "@baseboard_fab2_lib.baseboard_fab2(sch_1):page28_i172:DDR5_MA(11)" )
				( pinRef "@baseboard_fab2_lib.baseboard_fab2(sch_1):page53_i111:A11" )
				( attribute "RELATIVE_PROPAGATION_DELAY_SCOPE" "G"
					( Parent
						( matchGroupRef "@crescent_city_bb_fab1_lib.crescent_city_bb_fab1(sch_1):\MG_DDR_FAR_DIMM-CLK0_CLS_DDR_F_CAC-CLKS\" )
					)
					( Status sCSetFlattened )
					( Origin gBackEnd )
				)
				( attribute "RELATIVE_PROPAGATION_DELAY" "0.00 MIL,700.00 MIL"
					( Parent
						( matchGroupRef "@crescent_city_bb_fab1_lib.crescent_city_bb_fab1(sch_1):\MG_DDR_FAR_DIMM-CLK0_CLS_DDR_F_CAC-CLKS\" )
					)
					( Units "uMatchProp" "ns" 1.000000)
					( Status sCSetFlattened )
					( Origin gBackEnd )
				)
				( attribute "RELATIVE_PROPAGATION_DELAY_SCOPE" "G"
					( Parent
						( matchGroupRef "@baseboard_fab2_lib.baseboard_fab2(sch_1):\MG_DDR_FAR_DIMM_CMD_NG_DDR_F_DLL_12\" )
					)
					( Status sCSetFlattened )
					( Origin gBackEnd )
				)
				( attribute "RELATIVE_PROPAGATION_DELAY" "0.00 MIL,25.00 MIL"
					( Parent
						( matchGroupRef "@baseboard_fab2_lib.baseboard_fab2(sch_1):\MG_DDR_FAR_DIMM_CMD_NG_DDR_F_DLL_12\" )
					)
					( Units "uMatchProp" "ns" 1.000000)
					( Status sCSetFlattened )
					( Origin gBackEnd )
				)
			)
			( pinPair "@baseboard_fab2_lib.baseboard_fab2(sch_1):\PP3686\"
				( pinRef "@baseboard_fab2_lib.baseboard_fab2(sch_1):page54_i111:A11" )
				( pinRef "@baseboard_fab2_lib.baseboard_fab2(sch_1):page28_i172:DDR5_MA(11)" )
				( attribute "RELATIVE_PROPAGATION_DELAY_SCOPE" "G"
					( Parent
						( matchGroupRef "@crescent_city_bb_fab1_lib.crescent_city_bb_fab1(sch_1):\MG_DDR_NEAR_DIMM-CLK1_CLS_DDR_F_CAC-CLKS\" )
					)
					( Status sCSetFlattened )
					( Origin gBackEnd )
				)
				( attribute "RELATIVE_PROPAGATION_DELAY" "0.00 MIL,700.00 MIL"
					( Parent
						( matchGroupRef "@crescent_city_bb_fab1_lib.crescent_city_bb_fab1(sch_1):\MG_DDR_NEAR_DIMM-CLK1_CLS_DDR_F_CAC-CLKS\" )
					)
					( Units "uMatchProp" "ns" 1.000000)
					( Status sCSetFlattened )
					( Origin gBackEnd )
				)
				( attribute "RELATIVE_PROPAGATION_DELAY_SCOPE" "G"
					( Parent
						( matchGroupRef "@baseboard_fab2_lib.baseboard_fab2(sch_1):\MG_DDR_CMD_NEAR_DIMM_NG_DDR_F_DLL_12\" )
					)
					( Status sCSetFlattened )
					( Origin gBackEnd )
				)
				( attribute "RELATIVE_PROPAGATION_DELAY" "0.00 MIL,25.00 MIL"
					( Parent
						( matchGroupRef "@baseboard_fab2_lib.baseboard_fab2(sch_1):\MG_DDR_CMD_NEAR_DIMM_NG_DDR_F_DLL_12\" )
					)
					( Units "uMatchProp" "ns" 1.000000)
					( Status sCSetFlattened )
					( Origin gBackEnd )
				)
			)
			( pinPair "@baseboard_fab2_lib.baseboard_fab2(sch_1):\PP3679\"
				( pinRef "@baseboard_fab2_lib.baseboard_fab2(sch_1):page28_i172:DDR5_ACT_N" )
				( pinRef "@baseboard_fab2_lib.baseboard_fab2(sch_1):page53_i111:ACT_N" )
				( attribute "RELATIVE_PROPAGATION_DELAY_SCOPE" "G"
					( Parent
						( matchGroupRef "@crescent_city_bb_fab1_lib.crescent_city_bb_fab1(sch_1):\MG_DDR_FAR_DIMM-CLK0_CLS_DDR_F_CAC-CLKS\" )
					)
					( Status sCSetFlattened )
					( Origin gBackEnd )
				)
				( attribute "RELATIVE_PROPAGATION_DELAY" "0.00 MIL,700.00 MIL"
					( Parent
						( matchGroupRef "@crescent_city_bb_fab1_lib.crescent_city_bb_fab1(sch_1):\MG_DDR_FAR_DIMM-CLK0_CLS_DDR_F_CAC-CLKS\" )
					)
					( Units "uMatchProp" "ns" 1.000000)
					( Status sCSetFlattened )
					( Origin gBackEnd )
				)
				( attribute "RELATIVE_PROPAGATION_DELAY_SCOPE" "G"
					( Parent
						( matchGroupRef "@baseboard_fab2_lib.baseboard_fab2(sch_1):\MG_DDR_FAR_DIMM_CMD_NG_DDR_F_DLL_13\" )
					)
					( Status sCSetFlattened )
					( Origin gBackEnd )
				)
				( attribute "RELATIVE_PROPAGATION_DELAY" "0.00 MIL,25.00 MIL"
					( Parent
						( matchGroupRef "@baseboard_fab2_lib.baseboard_fab2(sch_1):\MG_DDR_FAR_DIMM_CMD_NG_DDR_F_DLL_13\" )
					)
					( Units "uMatchProp" "ns" 1.000000)
					( Status sCSetFlattened )
					( Origin gBackEnd )
				)
			)
			( pinPair "@baseboard_fab2_lib.baseboard_fab2(sch_1):\PP3680\"
				( pinRef "@baseboard_fab2_lib.baseboard_fab2(sch_1):page54_i111:ACT_N" )
				( pinRef "@baseboard_fab2_lib.baseboard_fab2(sch_1):page28_i172:DDR5_ACT_N" )
				( attribute "RELATIVE_PROPAGATION_DELAY_SCOPE" "G"
					( Parent
						( matchGroupRef "@crescent_city_bb_fab1_lib.crescent_city_bb_fab1(sch_1):\MG_DDR_NEAR_DIMM-CLK1_CLS_DDR_F_CAC-CLKS\" )
					)
					( Status sCSetFlattened )
					( Origin gBackEnd )
				)
				( attribute "RELATIVE_PROPAGATION_DELAY" "0.00 MIL,700.00 MIL"
					( Parent
						( matchGroupRef "@crescent_city_bb_fab1_lib.crescent_city_bb_fab1(sch_1):\MG_DDR_NEAR_DIMM-CLK1_CLS_DDR_F_CAC-CLKS\" )
					)
					( Units "uMatchProp" "ns" 1.000000)
					( Status sCSetFlattened )
					( Origin gBackEnd )
				)
				( attribute "RELATIVE_PROPAGATION_DELAY_SCOPE" "G"
					( Parent
						( matchGroupRef "@baseboard_fab2_lib.baseboard_fab2(sch_1):\MG_DDR_CMD_NEAR_DIMM_NG_DDR_F_DLL_13\" )
					)
					( Status sCSetFlattened )
					( Origin gBackEnd )
				)
				( attribute "RELATIVE_PROPAGATION_DELAY" "0.00 MIL,25.00 MIL"
					( Parent
						( matchGroupRef "@baseboard_fab2_lib.baseboard_fab2(sch_1):\MG_DDR_CMD_NEAR_DIMM_NG_DDR_F_DLL_13\" )
					)
					( Units "uMatchProp" "ns" 1.000000)
					( Status sCSetFlattened )
					( Origin gBackEnd )
				)
			)
			( pinPair "@baseboard_fab2_lib.baseboard_fab2(sch_1):\PP3681\"
				( pinRef "@baseboard_fab2_lib.baseboard_fab2(sch_1):page28_i172:DDR5_BG(0)" )
				( pinRef "@baseboard_fab2_lib.baseboard_fab2(sch_1):page53_i111:BG(0)" )
				( attribute "RELATIVE_PROPAGATION_DELAY_SCOPE" "G"
					( Parent
						( matchGroupRef "@crescent_city_bb_fab1_lib.crescent_city_bb_fab1(sch_1):\MG_DDR_FAR_DIMM-CLK0_CLS_DDR_F_CAC-CLKS\" )
					)
					( Status sCSetFlattened )
					( Origin gBackEnd )
				)
				( attribute "RELATIVE_PROPAGATION_DELAY" "0.00 MIL,700.00 MIL"
					( Parent
						( matchGroupRef "@crescent_city_bb_fab1_lib.crescent_city_bb_fab1(sch_1):\MG_DDR_FAR_DIMM-CLK0_CLS_DDR_F_CAC-CLKS\" )
					)
					( Units "uMatchProp" "ns" 1.000000)
					( Status sCSetFlattened )
					( Origin gBackEnd )
				)
				( attribute "RELATIVE_PROPAGATION_DELAY_SCOPE" "G"
					( Parent
						( matchGroupRef "@baseboard_fab2_lib.baseboard_fab2(sch_1):\MG_DDR_FAR_DIMM_CMD_NG_DDR_F_DLL_13\" )
					)
					( Status sCSetFlattened )
					( Origin gBackEnd )
				)
				( attribute "RELATIVE_PROPAGATION_DELAY" "0.00 MIL,25.00 MIL"
					( Parent
						( matchGroupRef "@baseboard_fab2_lib.baseboard_fab2(sch_1):\MG_DDR_FAR_DIMM_CMD_NG_DDR_F_DLL_13\" )
					)
					( Units "uMatchProp" "ns" 1.000000)
					( Status sCSetFlattened )
					( Origin gBackEnd )
				)
			)
			( pinPair "@baseboard_fab2_lib.baseboard_fab2(sch_1):\PP3682\"
				( pinRef "@baseboard_fab2_lib.baseboard_fab2(sch_1):page54_i111:BG(0)" )
				( pinRef "@baseboard_fab2_lib.baseboard_fab2(sch_1):page28_i172:DDR5_BG(0)" )
				( attribute "RELATIVE_PROPAGATION_DELAY_SCOPE" "G"
					( Parent
						( matchGroupRef "@crescent_city_bb_fab1_lib.crescent_city_bb_fab1(sch_1):\MG_DDR_NEAR_DIMM-CLK1_CLS_DDR_F_CAC-CLKS\" )
					)
					( Status sCSetFlattened )
					( Origin gBackEnd )
				)
				( attribute "RELATIVE_PROPAGATION_DELAY" "0.00 MIL,700.00 MIL"
					( Parent
						( matchGroupRef "@crescent_city_bb_fab1_lib.crescent_city_bb_fab1(sch_1):\MG_DDR_NEAR_DIMM-CLK1_CLS_DDR_F_CAC-CLKS\" )
					)
					( Units "uMatchProp" "ns" 1.000000)
					( Status sCSetFlattened )
					( Origin gBackEnd )
				)
				( attribute "RELATIVE_PROPAGATION_DELAY_SCOPE" "G"
					( Parent
						( matchGroupRef "@baseboard_fab2_lib.baseboard_fab2(sch_1):\MG_DDR_CMD_NEAR_DIMM_NG_DDR_F_DLL_13\" )
					)
					( Status sCSetFlattened )
					( Origin gBackEnd )
				)
				( attribute "RELATIVE_PROPAGATION_DELAY" "0.00 MIL,25.00 MIL"
					( Parent
						( matchGroupRef "@baseboard_fab2_lib.baseboard_fab2(sch_1):\MG_DDR_CMD_NEAR_DIMM_NG_DDR_F_DLL_13\" )
					)
					( Units "uMatchProp" "ns" 1.000000)
					( Status sCSetFlattened )
					( Origin gBackEnd )
				)
			)
			( pinPair "@baseboard_fab2_lib.baseboard_fab2(sch_1):\PP3677\"
				( pinRef "@baseboard_fab2_lib.baseboard_fab2(sch_1):page53_i111:S0_N" )
				( pinRef "@baseboard_fab2_lib.baseboard_fab2(sch_1):page28_i172:DDR5_CS_N(0)" )
				( attribute "RELATIVE_PROPAGATION_DELAY_SCOPE" "G"
					( Parent
						( matchGroupRef "@crescent_city_bb_fab1_lib.crescent_city_bb_fab1(sch_1):\MG_DDR_FAR_DIMM-CLK0_CLS_DDR_F_CAC-CLKS\" )
					)
					( Status sCSetFlattened )
					( Origin gBackEnd )
				)
				( attribute "RELATIVE_PROPAGATION_DELAY" "0.00 MIL,300.00 MIL"
					( Parent
						( matchGroupRef "@crescent_city_bb_fab1_lib.crescent_city_bb_fab1(sch_1):\MG_DDR_FAR_DIMM-CLK0_CLS_DDR_F_CAC-CLKS\" )
					)
					( Units "uMatchProp" "ns" 1.000000)
					( Status sCSetFlattened )
					( Origin gBackEnd )
				)
				( attribute "RELATIVE_PROPAGATION_DELAY_SCOPE" "G"
					( Parent
						( matchGroupRef "@baseboard_fab2_lib.baseboard_fab2(sch_1):\MG_DDR_CTRL_NG_DDR_F_DLL_14\" )
					)
					( Status sCSetFlattened )
					( Origin gBackEnd )
				)
				( attribute "RELATIVE_PROPAGATION_DELAY" "0.00 MIL,25.00 MIL"
					( Parent
						( matchGroupRef "@baseboard_fab2_lib.baseboard_fab2(sch_1):\MG_DDR_CTRL_NG_DDR_F_DLL_14\" )
					)
					( Units "uMatchProp" "ns" 1.000000)
					( Status sCSetFlattened )
					( Origin gBackEnd )
				)
			)
			( pinPair "@baseboard_fab2_lib.baseboard_fab2(sch_1):\PP3678\"
				( pinRef "@baseboard_fab2_lib.baseboard_fab2(sch_1):page53_i111:ODT(0)" )
				( pinRef "@baseboard_fab2_lib.baseboard_fab2(sch_1):page28_i172:DDR5_ODT(0)" )
				( attribute "RELATIVE_PROPAGATION_DELAY_SCOPE" "G"
					( Parent
						( matchGroupRef "@crescent_city_bb_fab1_lib.crescent_city_bb_fab1(sch_1):\MG_DDR_FAR_DIMM-CLK0_CLS_DDR_F_CAC-CLKS\" )
					)
					( Status sCSetFlattened )
					( Origin gBackEnd )
				)
				( attribute "RELATIVE_PROPAGATION_DELAY" "0.00 MIL,300.00 MIL"
					( Parent
						( matchGroupRef "@crescent_city_bb_fab1_lib.crescent_city_bb_fab1(sch_1):\MG_DDR_FAR_DIMM-CLK0_CLS_DDR_F_CAC-CLKS\" )
					)
					( Units "uMatchProp" "ns" 1.000000)
					( Status sCSetFlattened )
					( Origin gBackEnd )
				)
				( attribute "RELATIVE_PROPAGATION_DELAY_SCOPE" "G"
					( Parent
						( matchGroupRef "@baseboard_fab2_lib.baseboard_fab2(sch_1):\MG_DDR_CTRL_NG_DDR_F_DLL_14\" )
					)
					( Status sCSetFlattened )
					( Origin gBackEnd )
				)
				( attribute "RELATIVE_PROPAGATION_DELAY" "0.00 MIL,25.00 MIL"
					( Parent
						( matchGroupRef "@baseboard_fab2_lib.baseboard_fab2(sch_1):\MG_DDR_CTRL_NG_DDR_F_DLL_14\" )
					)
					( Units "uMatchProp" "ns" 1.000000)
					( Status sCSetFlattened )
					( Origin gBackEnd )
				)
			)
			( pinPair "@baseboard_fab2_lib.baseboard_fab2(sch_1):\PP3676\"
				( pinRef "@baseboard_fab2_lib.baseboard_fab2(sch_1):page53_i111:CKE(0)" )
				( pinRef "@baseboard_fab2_lib.baseboard_fab2(sch_1):page28_i172:DDR5_CKE(0)" )
				( attribute "RELATIVE_PROPAGATION_DELAY_SCOPE" "G"
					( Parent
						( matchGroupRef "@crescent_city_bb_fab1_lib.crescent_city_bb_fab1(sch_1):\MG_DDR_FAR_DIMM-CLK0_CLS_DDR_F_CAC-CLKS\" )
					)
					( Status sCSetFlattened )
					( Origin gBackEnd )
				)
				( attribute "RELATIVE_PROPAGATION_DELAY" "0.00 MIL,300.00 MIL"
					( Parent
						( matchGroupRef "@crescent_city_bb_fab1_lib.crescent_city_bb_fab1(sch_1):\MG_DDR_FAR_DIMM-CLK0_CLS_DDR_F_CAC-CLKS\" )
					)
					( Units "uMatchProp" "ns" 1.000000)
					( Status sCSetFlattened )
					( Origin gBackEnd )
				)
				( attribute "RELATIVE_PROPAGATION_DELAY_SCOPE" "G"
					( Parent
						( matchGroupRef "@baseboard_fab2_lib.baseboard_fab2(sch_1):\MG_DDR_CTRL_NG_DDR_F_DLL_15\" )
					)
					( Status sCSetFlattened )
					( Origin gBackEnd )
				)
				( attribute "RELATIVE_PROPAGATION_DELAY" "0.00 MIL,25.00 MIL"
					( Parent
						( matchGroupRef "@baseboard_fab2_lib.baseboard_fab2(sch_1):\MG_DDR_CTRL_NG_DDR_F_DLL_15\" )
					)
					( Units "uMatchProp" "ns" 1.000000)
					( Status sCSetFlattened )
					( Origin gBackEnd )
				)
			)
			( pinPair "@baseboard_fab2_lib.baseboard_fab2(sch_1):\PP3675\"
				( pinRef "@baseboard_fab2_lib.baseboard_fab2(sch_1):page53_i111:S2_N_C(0)" )
				( pinRef "@baseboard_fab2_lib.baseboard_fab2(sch_1):page28_i172:DDR5_CS_N(2)" )
				( attribute "RELATIVE_PROPAGATION_DELAY_SCOPE" "G"
					( Parent
						( matchGroupRef "@crescent_city_bb_fab1_lib.crescent_city_bb_fab1(sch_1):\MG_DDR_FAR_DIMM-CLK0_CLS_DDR_F_CAC-CLKS\" )
					)
					( Status sCSetFlattened )
					( Origin gBackEnd )
				)
				( attribute "RELATIVE_PROPAGATION_DELAY" "0.00 MIL,300.00 MIL"
					( Parent
						( matchGroupRef "@crescent_city_bb_fab1_lib.crescent_city_bb_fab1(sch_1):\MG_DDR_FAR_DIMM-CLK0_CLS_DDR_F_CAC-CLKS\" )
					)
					( Units "uMatchProp" "ns" 1.000000)
					( Status sCSetFlattened )
					( Origin gBackEnd )
				)
				( attribute "RELATIVE_PROPAGATION_DELAY_SCOPE" "G"
					( Parent
						( matchGroupRef "@baseboard_fab2_lib.baseboard_fab2(sch_1):\MG_DDR_CTRL_NG_DDR_F_DLL_16\" )
					)
					( Status sCSetFlattened )
					( Origin gBackEnd )
				)
				( attribute "RELATIVE_PROPAGATION_DELAY" "0.00 MIL,25.00 MIL"
					( Parent
						( matchGroupRef "@baseboard_fab2_lib.baseboard_fab2(sch_1):\MG_DDR_CTRL_NG_DDR_F_DLL_16\" )
					)
					( Units "uMatchProp" "ns" 1.000000)
					( Status sCSetFlattened )
					( Origin gBackEnd )
				)
			)
			( pinPair "@baseboard_fab2_lib.baseboard_fab2(sch_1):\PP3674\"
				( pinRef "@baseboard_fab2_lib.baseboard_fab2(sch_1):page53_i111:S3_N_C(1)" )
				( pinRef "@baseboard_fab2_lib.baseboard_fab2(sch_1):page28_i172:DDR5_CS_N(3)" )
				( attribute "RELATIVE_PROPAGATION_DELAY_SCOPE" "G"
					( Parent
						( matchGroupRef "@crescent_city_bb_fab1_lib.crescent_city_bb_fab1(sch_1):\MG_DDR_FAR_DIMM-CLK0_CLS_DDR_F_CAC-CLKS\" )
					)
					( Status sCSetFlattened )
					( Origin gBackEnd )
				)
				( attribute "RELATIVE_PROPAGATION_DELAY" "0.00 MIL,300.00 MIL"
					( Parent
						( matchGroupRef "@crescent_city_bb_fab1_lib.crescent_city_bb_fab1(sch_1):\MG_DDR_FAR_DIMM-CLK0_CLS_DDR_F_CAC-CLKS\" )
					)
					( Units "uMatchProp" "ns" 1.000000)
					( Status sCSetFlattened )
					( Origin gBackEnd )
				)
				( attribute "RELATIVE_PROPAGATION_DELAY_SCOPE" "G"
					( Parent
						( matchGroupRef "@baseboard_fab2_lib.baseboard_fab2(sch_1):\MG_DDR_CTRL_NG_DDR_F_DLL_17\" )
					)
					( Status sCSetFlattened )
					( Origin gBackEnd )
				)
				( attribute "RELATIVE_PROPAGATION_DELAY" "0.00 MIL,25.00 MIL"
					( Parent
						( matchGroupRef "@baseboard_fab2_lib.baseboard_fab2(sch_1):\MG_DDR_CTRL_NG_DDR_F_DLL_17\" )
					)
					( Units "uMatchProp" "ns" 1.000000)
					( Status sCSetFlattened )
					( Origin gBackEnd )
				)
			)
			( pinPair "@baseboard_fab2_lib.baseboard_fab2(sch_1):\PP3672\"
				( pinRef "@baseboard_fab2_lib.baseboard_fab2(sch_1):page53_i111:S1_N" )
				( pinRef "@baseboard_fab2_lib.baseboard_fab2(sch_1):page28_i172:DDR5_CS_N(1)" )
				( attribute "RELATIVE_PROPAGATION_DELAY_SCOPE" "G"
					( Parent
						( matchGroupRef "@crescent_city_bb_fab1_lib.crescent_city_bb_fab1(sch_1):\MG_DDR_FAR_DIMM-CLK0_CLS_DDR_F_CAC-CLKS\" )
					)
					( Status sCSetFlattened )
					( Origin gBackEnd )
				)
				( attribute "RELATIVE_PROPAGATION_DELAY" "0.00 MIL,300.00 MIL"
					( Parent
						( matchGroupRef "@crescent_city_bb_fab1_lib.crescent_city_bb_fab1(sch_1):\MG_DDR_FAR_DIMM-CLK0_CLS_DDR_F_CAC-CLKS\" )
					)
					( Units "uMatchProp" "ns" 1.000000)
					( Status sCSetFlattened )
					( Origin gBackEnd )
				)
				( attribute "RELATIVE_PROPAGATION_DELAY_SCOPE" "G"
					( Parent
						( matchGroupRef "@baseboard_fab2_lib.baseboard_fab2(sch_1):\MG_DDR_CTRL_NG_DDR_F_DLL_18\" )
					)
					( Status sCSetFlattened )
					( Origin gBackEnd )
				)
				( attribute "RELATIVE_PROPAGATION_DELAY" "0.00 MIL,25.00 MIL"
					( Parent
						( matchGroupRef "@baseboard_fab2_lib.baseboard_fab2(sch_1):\MG_DDR_CTRL_NG_DDR_F_DLL_18\" )
					)
					( Units "uMatchProp" "ns" 1.000000)
					( Status sCSetFlattened )
					( Origin gBackEnd )
				)
			)
			( pinPair "@baseboard_fab2_lib.baseboard_fab2(sch_1):\PP3673\"
				( pinRef "@baseboard_fab2_lib.baseboard_fab2(sch_1):page53_i111:ODT(1)" )
				( pinRef "@baseboard_fab2_lib.baseboard_fab2(sch_1):page28_i172:DDR5_ODT(1)" )
				( attribute "RELATIVE_PROPAGATION_DELAY_SCOPE" "G"
					( Parent
						( matchGroupRef "@crescent_city_bb_fab1_lib.crescent_city_bb_fab1(sch_1):\MG_DDR_FAR_DIMM-CLK0_CLS_DDR_F_CAC-CLKS\" )
					)
					( Status sCSetFlattened )
					( Origin gBackEnd )
				)
				( attribute "RELATIVE_PROPAGATION_DELAY" "0.00 MIL,300.00 MIL"
					( Parent
						( matchGroupRef "@crescent_city_bb_fab1_lib.crescent_city_bb_fab1(sch_1):\MG_DDR_FAR_DIMM-CLK0_CLS_DDR_F_CAC-CLKS\" )
					)
					( Units "uMatchProp" "ns" 1.000000)
					( Status sCSetFlattened )
					( Origin gBackEnd )
				)
				( attribute "RELATIVE_PROPAGATION_DELAY_SCOPE" "G"
					( Parent
						( matchGroupRef "@baseboard_fab2_lib.baseboard_fab2(sch_1):\MG_DDR_CTRL_NG_DDR_F_DLL_18\" )
					)
					( Status sCSetFlattened )
					( Origin gBackEnd )
				)
				( attribute "RELATIVE_PROPAGATION_DELAY" "0.00 MIL,25.00 MIL"
					( Parent
						( matchGroupRef "@baseboard_fab2_lib.baseboard_fab2(sch_1):\MG_DDR_CTRL_NG_DDR_F_DLL_18\" )
					)
					( Units "uMatchProp" "ns" 1.000000)
					( Status sCSetFlattened )
					( Origin gBackEnd )
				)
			)
			( pinPair "@baseboard_fab2_lib.baseboard_fab2(sch_1):\PP3671\"
				( pinRef "@baseboard_fab2_lib.baseboard_fab2(sch_1):page53_i111:CKE(1)" )
				( pinRef "@baseboard_fab2_lib.baseboard_fab2(sch_1):page28_i172:DDR5_CKE(1)" )
				( attribute "RELATIVE_PROPAGATION_DELAY_SCOPE" "G"
					( Parent
						( matchGroupRef "@crescent_city_bb_fab1_lib.crescent_city_bb_fab1(sch_1):\MG_DDR_FAR_DIMM-CLK0_CLS_DDR_F_CAC-CLKS\" )
					)
					( Status sCSetFlattened )
					( Origin gBackEnd )
				)
				( attribute "RELATIVE_PROPAGATION_DELAY" "0.00 MIL,300.00 MIL"
					( Parent
						( matchGroupRef "@crescent_city_bb_fab1_lib.crescent_city_bb_fab1(sch_1):\MG_DDR_FAR_DIMM-CLK0_CLS_DDR_F_CAC-CLKS\" )
					)
					( Units "uMatchProp" "ns" 1.000000)
					( Status sCSetFlattened )
					( Origin gBackEnd )
				)
				( attribute "RELATIVE_PROPAGATION_DELAY_SCOPE" "G"
					( Parent
						( matchGroupRef "@baseboard_fab2_lib.baseboard_fab2(sch_1):\MG_DDR_CTRL_NG_DDR_F_DLL_19\" )
					)
					( Status sCSetFlattened )
					( Origin gBackEnd )
				)
				( attribute "RELATIVE_PROPAGATION_DELAY" "0.00 MIL,25.00 MIL"
					( Parent
						( matchGroupRef "@baseboard_fab2_lib.baseboard_fab2(sch_1):\MG_DDR_CTRL_NG_DDR_F_DLL_19\" )
					)
					( Units "uMatchProp" "ns" 1.000000)
					( Status sCSetFlattened )
					( Origin gBackEnd )
				)
			)
			( pinPair "@baseboard_fab2_lib.baseboard_fab2(sch_1):\PP3669\"
				( pinRef "@baseboard_fab2_lib.baseboard_fab2(sch_1):page54_i111:S0_N" )
				( pinRef "@baseboard_fab2_lib.baseboard_fab2(sch_1):page28_i172:DDR5_CS_N(4)" )
				( attribute "RELATIVE_PROPAGATION_DELAY_SCOPE" "G"
					( Parent
						( matchGroupRef "@crescent_city_bb_fab1_lib.crescent_city_bb_fab1(sch_1):\MG_DDR_NEAR_DIMM-CLK1_CLS_DDR_F_CAC-CLKS\" )
					)
					( Status sCSetFlattened )
					( Origin gBackEnd )
				)
				( attribute "RELATIVE_PROPAGATION_DELAY" "0.00 MIL,300.00 MIL"
					( Parent
						( matchGroupRef "@crescent_city_bb_fab1_lib.crescent_city_bb_fab1(sch_1):\MG_DDR_NEAR_DIMM-CLK1_CLS_DDR_F_CAC-CLKS\" )
					)
					( Units "uMatchProp" "ns" 1.000000)
					( Status sCSetFlattened )
					( Origin gBackEnd )
				)
				( attribute "RELATIVE_PROPAGATION_DELAY_SCOPE" "G"
					( Parent
						( matchGroupRef "@baseboard_fab2_lib.baseboard_fab2(sch_1):\MG_DDR_CTRL_NG_DDR_F_DLL_20\" )
					)
					( Status sCSetFlattened )
					( Origin gBackEnd )
				)
				( attribute "RELATIVE_PROPAGATION_DELAY" "0.00 MIL,25.00 MIL"
					( Parent
						( matchGroupRef "@baseboard_fab2_lib.baseboard_fab2(sch_1):\MG_DDR_CTRL_NG_DDR_F_DLL_20\" )
					)
					( Units "uMatchProp" "ns" 1.000000)
					( Status sCSetFlattened )
					( Origin gBackEnd )
				)
			)
			( pinPair "@baseboard_fab2_lib.baseboard_fab2(sch_1):\PP3670\"
				( pinRef "@baseboard_fab2_lib.baseboard_fab2(sch_1):page54_i111:ODT(0)" )
				( pinRef "@baseboard_fab2_lib.baseboard_fab2(sch_1):page28_i172:DDR5_ODT(2)" )
				( attribute "RELATIVE_PROPAGATION_DELAY_SCOPE" "G"
					( Parent
						( matchGroupRef "@crescent_city_bb_fab1_lib.crescent_city_bb_fab1(sch_1):\MG_DDR_NEAR_DIMM-CLK1_CLS_DDR_F_CAC-CLKS\" )
					)
					( Status sCSetFlattened )
					( Origin gBackEnd )
				)
				( attribute "RELATIVE_PROPAGATION_DELAY" "0.00 MIL,300.00 MIL"
					( Parent
						( matchGroupRef "@crescent_city_bb_fab1_lib.crescent_city_bb_fab1(sch_1):\MG_DDR_NEAR_DIMM-CLK1_CLS_DDR_F_CAC-CLKS\" )
					)
					( Units "uMatchProp" "ns" 1.000000)
					( Status sCSetFlattened )
					( Origin gBackEnd )
				)
				( attribute "RELATIVE_PROPAGATION_DELAY_SCOPE" "G"
					( Parent
						( matchGroupRef "@baseboard_fab2_lib.baseboard_fab2(sch_1):\MG_DDR_CTRL_NG_DDR_F_DLL_20\" )
					)
					( Status sCSetFlattened )
					( Origin gBackEnd )
				)
				( attribute "RELATIVE_PROPAGATION_DELAY" "0.00 MIL,25.00 MIL"
					( Parent
						( matchGroupRef "@baseboard_fab2_lib.baseboard_fab2(sch_1):\MG_DDR_CTRL_NG_DDR_F_DLL_20\" )
					)
					( Units "uMatchProp" "ns" 1.000000)
					( Status sCSetFlattened )
					( Origin gBackEnd )
				)
			)
			( pinPair "@baseboard_fab2_lib.baseboard_fab2(sch_1):\PP3668\"
				( pinRef "@baseboard_fab2_lib.baseboard_fab2(sch_1):page28_i172:DDR5_CKE(2)" )
				( pinRef "@baseboard_fab2_lib.baseboard_fab2(sch_1):page54_i111:CKE(0)" )
				( attribute "RELATIVE_PROPAGATION_DELAY_SCOPE" "G"
					( Parent
						( matchGroupRef "@crescent_city_bb_fab1_lib.crescent_city_bb_fab1(sch_1):\MG_DDR_NEAR_DIMM-CLK1_CLS_DDR_F_CAC-CLKS\" )
					)
					( Status sCSetFlattened )
					( Origin gBackEnd )
				)
				( attribute "RELATIVE_PROPAGATION_DELAY" "0.00 MIL,300.00 MIL"
					( Parent
						( matchGroupRef "@crescent_city_bb_fab1_lib.crescent_city_bb_fab1(sch_1):\MG_DDR_NEAR_DIMM-CLK1_CLS_DDR_F_CAC-CLKS\" )
					)
					( Units "uMatchProp" "ns" 1.000000)
					( Status sCSetFlattened )
					( Origin gBackEnd )
				)
				( attribute "RELATIVE_PROPAGATION_DELAY_SCOPE" "G"
					( Parent
						( matchGroupRef "@baseboard_fab2_lib.baseboard_fab2(sch_1):\MG_DDR_CTRL_NG_DDR_F_DLL_21\" )
					)
					( Status sCSetFlattened )
					( Origin gBackEnd )
				)
				( attribute "RELATIVE_PROPAGATION_DELAY" "0.00 MIL,25.00 MIL"
					( Parent
						( matchGroupRef "@baseboard_fab2_lib.baseboard_fab2(sch_1):\MG_DDR_CTRL_NG_DDR_F_DLL_21\" )
					)
					( Units "uMatchProp" "ns" 1.000000)
					( Status sCSetFlattened )
					( Origin gBackEnd )
				)
			)
			( pinPair "@baseboard_fab2_lib.baseboard_fab2(sch_1):\PP3666\"
				( pinRef "@baseboard_fab2_lib.baseboard_fab2(sch_1):page54_i111:S2_N_C(0)" )
				( pinRef "@baseboard_fab2_lib.baseboard_fab2(sch_1):page28_i172:DDR5_CS_N(6)" )
				( attribute "RELATIVE_PROPAGATION_DELAY_SCOPE" "G"
					( Parent
						( matchGroupRef "@crescent_city_bb_fab1_lib.crescent_city_bb_fab1(sch_1):\MG_DDR_NEAR_DIMM-CLK1_CLS_DDR_F_CAC-CLKS\" )
					)
					( Status sCSetFlattened )
					( Origin gBackEnd )
				)
				( attribute "RELATIVE_PROPAGATION_DELAY" "0.00 MIL,300.00 MIL"
					( Parent
						( matchGroupRef "@crescent_city_bb_fab1_lib.crescent_city_bb_fab1(sch_1):\MG_DDR_NEAR_DIMM-CLK1_CLS_DDR_F_CAC-CLKS\" )
					)
					( Units "uMatchProp" "ns" 1.000000)
					( Status sCSetFlattened )
					( Origin gBackEnd )
				)
				( attribute "RELATIVE_PROPAGATION_DELAY_SCOPE" "G"
					( Parent
						( matchGroupRef "@baseboard_fab2_lib.baseboard_fab2(sch_1):\MG_DDR_CTRL_NG_DDR_F_DLL_22\" )
					)
					( Status sCSetFlattened )
					( Origin gBackEnd )
				)
				( attribute "RELATIVE_PROPAGATION_DELAY" "0.00 MIL,25.00 MIL"
					( Parent
						( matchGroupRef "@baseboard_fab2_lib.baseboard_fab2(sch_1):\MG_DDR_CTRL_NG_DDR_F_DLL_22\" )
					)
					( Units "uMatchProp" "ns" 1.000000)
					( Status sCSetFlattened )
					( Origin gBackEnd )
				)
			)
			( pinPair "@baseboard_fab2_lib.baseboard_fab2(sch_1):\PP3667\"
				( pinRef "@baseboard_fab2_lib.baseboard_fab2(sch_1):page54_i111:S3_N_C(1)" )
				( pinRef "@baseboard_fab2_lib.baseboard_fab2(sch_1):page28_i172:DDR5_CS_N(7)" )
				( attribute "RELATIVE_PROPAGATION_DELAY_SCOPE" "G"
					( Parent
						( matchGroupRef "@crescent_city_bb_fab1_lib.crescent_city_bb_fab1(sch_1):\MG_DDR_NEAR_DIMM-CLK1_CLS_DDR_F_CAC-CLKS\" )
					)
					( Status sCSetFlattened )
					( Origin gBackEnd )
				)
				( attribute "RELATIVE_PROPAGATION_DELAY" "0.00 MIL,300.00 MIL"
					( Parent
						( matchGroupRef "@crescent_city_bb_fab1_lib.crescent_city_bb_fab1(sch_1):\MG_DDR_NEAR_DIMM-CLK1_CLS_DDR_F_CAC-CLKS\" )
					)
					( Units "uMatchProp" "ns" 1.000000)
					( Status sCSetFlattened )
					( Origin gBackEnd )
				)
				( attribute "RELATIVE_PROPAGATION_DELAY_SCOPE" "G"
					( Parent
						( matchGroupRef "@baseboard_fab2_lib.baseboard_fab2(sch_1):\MG_DDR_CTRL_NG_DDR_F_DLL_22\" )
					)
					( Status sCSetFlattened )
					( Origin gBackEnd )
				)
				( attribute "RELATIVE_PROPAGATION_DELAY" "0.00 MIL,25.00 MIL"
					( Parent
						( matchGroupRef "@baseboard_fab2_lib.baseboard_fab2(sch_1):\MG_DDR_CTRL_NG_DDR_F_DLL_22\" )
					)
					( Units "uMatchProp" "ns" 1.000000)
					( Status sCSetFlattened )
					( Origin gBackEnd )
				)
			)
			( pinPair "@baseboard_fab2_lib.baseboard_fab2(sch_1):\PP3664\"
				( pinRef "@baseboard_fab2_lib.baseboard_fab2(sch_1):page54_i111:S1_N" )
				( pinRef "@baseboard_fab2_lib.baseboard_fab2(sch_1):page28_i172:DDR5_CS_N(5)" )
				( attribute "RELATIVE_PROPAGATION_DELAY_SCOPE" "G"
					( Parent
						( matchGroupRef "@crescent_city_bb_fab1_lib.crescent_city_bb_fab1(sch_1):\MG_DDR_NEAR_DIMM-CLK1_CLS_DDR_F_CAC-CLKS\" )
					)
					( Status sCSetFlattened )
					( Origin gBackEnd )
				)
				( attribute "RELATIVE_PROPAGATION_DELAY" "0.00 MIL,300.00 MIL"
					( Parent
						( matchGroupRef "@crescent_city_bb_fab1_lib.crescent_city_bb_fab1(sch_1):\MG_DDR_NEAR_DIMM-CLK1_CLS_DDR_F_CAC-CLKS\" )
					)
					( Units "uMatchProp" "ns" 1.000000)
					( Status sCSetFlattened )
					( Origin gBackEnd )
				)
				( attribute "RELATIVE_PROPAGATION_DELAY_SCOPE" "G"
					( Parent
						( matchGroupRef "@baseboard_fab2_lib.baseboard_fab2(sch_1):\MG_DDR_CTRL_NG_DDR_F_DLL_23\" )
					)
					( Status sCSetFlattened )
					( Origin gBackEnd )
				)
				( attribute "RELATIVE_PROPAGATION_DELAY" "0.00 MIL,25.00 MIL"
					( Parent
						( matchGroupRef "@baseboard_fab2_lib.baseboard_fab2(sch_1):\MG_DDR_CTRL_NG_DDR_F_DLL_23\" )
					)
					( Units "uMatchProp" "ns" 1.000000)
					( Status sCSetFlattened )
					( Origin gBackEnd )
				)
			)
			( pinPair "@baseboard_fab2_lib.baseboard_fab2(sch_1):\PP3665\"
				( pinRef "@baseboard_fab2_lib.baseboard_fab2(sch_1):page54_i111:ODT(1)" )
				( pinRef "@baseboard_fab2_lib.baseboard_fab2(sch_1):page28_i172:DDR5_ODT(3)" )
				( attribute "RELATIVE_PROPAGATION_DELAY_SCOPE" "G"
					( Parent
						( matchGroupRef "@crescent_city_bb_fab1_lib.crescent_city_bb_fab1(sch_1):\MG_DDR_NEAR_DIMM-CLK1_CLS_DDR_F_CAC-CLKS\" )
					)
					( Status sCSetFlattened )
					( Origin gBackEnd )
				)
				( attribute "RELATIVE_PROPAGATION_DELAY" "0.00 MIL,300.00 MIL"
					( Parent
						( matchGroupRef "@crescent_city_bb_fab1_lib.crescent_city_bb_fab1(sch_1):\MG_DDR_NEAR_DIMM-CLK1_CLS_DDR_F_CAC-CLKS\" )
					)
					( Units "uMatchProp" "ns" 1.000000)
					( Status sCSetFlattened )
					( Origin gBackEnd )
				)
				( attribute "RELATIVE_PROPAGATION_DELAY_SCOPE" "G"
					( Parent
						( matchGroupRef "@baseboard_fab2_lib.baseboard_fab2(sch_1):\MG_DDR_CTRL_NG_DDR_F_DLL_23\" )
					)
					( Status sCSetFlattened )
					( Origin gBackEnd )
				)
				( attribute "RELATIVE_PROPAGATION_DELAY" "0.00 MIL,25.00 MIL"
					( Parent
						( matchGroupRef "@baseboard_fab2_lib.baseboard_fab2(sch_1):\MG_DDR_CTRL_NG_DDR_F_DLL_23\" )
					)
					( Units "uMatchProp" "ns" 1.000000)
					( Status sCSetFlattened )
					( Origin gBackEnd )
				)
			)
			( pinPair "@baseboard_fab2_lib.baseboard_fab2(sch_1):\PP3663\"
				( pinRef "@baseboard_fab2_lib.baseboard_fab2(sch_1):page54_i111:CKE(1)" )
				( pinRef "@baseboard_fab2_lib.baseboard_fab2(sch_1):page28_i172:DDR5_CKE(3)" )
				( attribute "RELATIVE_PROPAGATION_DELAY_SCOPE" "G"
					( Parent
						( matchGroupRef "@crescent_city_bb_fab1_lib.crescent_city_bb_fab1(sch_1):\MG_DDR_NEAR_DIMM-CLK1_CLS_DDR_F_CAC-CLKS\" )
					)
					( Status sCSetFlattened )
					( Origin gBackEnd )
				)
				( attribute "RELATIVE_PROPAGATION_DELAY" "0.00 MIL,300.00 MIL"
					( Parent
						( matchGroupRef "@crescent_city_bb_fab1_lib.crescent_city_bb_fab1(sch_1):\MG_DDR_NEAR_DIMM-CLK1_CLS_DDR_F_CAC-CLKS\" )
					)
					( Units "uMatchProp" "ns" 1.000000)
					( Status sCSetFlattened )
					( Origin gBackEnd )
				)
				( attribute "RELATIVE_PROPAGATION_DELAY_SCOPE" "G"
					( Parent
						( matchGroupRef "@baseboard_fab2_lib.baseboard_fab2(sch_1):\MG_DDR_CTRL_NG_DDR_F_DLL_24\" )
					)
					( Status sCSetFlattened )
					( Origin gBackEnd )
				)
				( attribute "RELATIVE_PROPAGATION_DELAY" "0.00 MIL,25.00 MIL"
					( Parent
						( matchGroupRef "@baseboard_fab2_lib.baseboard_fab2(sch_1):\MG_DDR_CTRL_NG_DDR_F_DLL_24\" )
					)
					( Units "uMatchProp" "ns" 1.000000)
					( Status sCSetFlattened )
					( Origin gBackEnd )
				)
			)
			( pinPair "@baseboard_fab2_lib.baseboard_fab2(sch_1):\PP3791\"
				( pinRef "@baseboard_fab2_lib.baseboard_fab2(sch_1):page27_i172:DDR4_CID(2)" )
				( pinRef "@baseboard_fab2_lib.baseboard_fab2(sch_1):page51_i111:C(2)" )
				( attribute "RELATIVE_PROPAGATION_DELAY_SCOPE" "G"
					( Parent
						( matchGroupRef "@crescent_city_bb_fab1_lib.crescent_city_bb_fab1(sch_1):\MG_DDR_FAR_DIMM-CLK0_CLS_DDR_E_CAC-CLKS\" )
					)
					( Status sCSetFlattened )
					( Origin gBackEnd )
				)
				( attribute "RELATIVE_PROPAGATION_DELAY" "0.00 MIL,700.00 MIL"
					( Parent
						( matchGroupRef "@crescent_city_bb_fab1_lib.crescent_city_bb_fab1(sch_1):\MG_DDR_FAR_DIMM-CLK0_CLS_DDR_E_CAC-CLKS\" )
					)
					( Units "uMatchProp" "ns" 1.000000)
					( Status sCSetFlattened )
					( Origin gBackEnd )
				)
				( attribute "RELATIVE_PROPAGATION_DELAY_SCOPE" "G"
					( Parent
						( matchGroupRef "@baseboard_fab2_lib.baseboard_fab2(sch_1):\MG_DDR_FAR_DIMM_CMD_NG_DDR_E_DLL_1\" )
					)
					( Status sCSetFlattened )
					( Origin gBackEnd )
				)
				( attribute "RELATIVE_PROPAGATION_DELAY" "0.00 MIL,25.00 MIL"
					( Parent
						( matchGroupRef "@baseboard_fab2_lib.baseboard_fab2(sch_1):\MG_DDR_FAR_DIMM_CMD_NG_DDR_E_DLL_1\" )
					)
					( Units "uMatchProp" "ns" 1.000000)
					( Status sCSetFlattened )
					( Origin gBackEnd )
				)
			)
			( pinPair "@baseboard_fab2_lib.baseboard_fab2(sch_1):\PP3792\"
				( pinRef "@baseboard_fab2_lib.baseboard_fab2(sch_1):page27_i172:DDR4_CID(2)" )
				( pinRef "@baseboard_fab2_lib.baseboard_fab2(sch_1):page52_i12:C(2)" )
				( attribute "RELATIVE_PROPAGATION_DELAY_SCOPE" "G"
					( Parent
						( matchGroupRef "@baseboard_fab2_lib.baseboard_fab2(sch_1):\MG_DDR_CMD_NEAR_DIMM_NG_DDR_E_DLL_1\" )
					)
					( Status sCSetFlattened )
					( Origin gBackEnd )
				)
				( attribute "RELATIVE_PROPAGATION_DELAY" "0.00 MIL,25.00 MIL"
					( Parent
						( matchGroupRef "@baseboard_fab2_lib.baseboard_fab2(sch_1):\MG_DDR_CMD_NEAR_DIMM_NG_DDR_E_DLL_1\" )
					)
					( Units "uMatchProp" "ns" 1.000000)
					( Status sCSetFlattened )
					( Origin gBackEnd )
				)
				( attribute "RELATIVE_PROPAGATION_DELAY_SCOPE" "G"
					( Parent
						( matchGroupRef "@crescent_city_bb_fab1_lib.crescent_city_bb_fab1(sch_1):\MG_DDR_NEAR_DIMM-CLK1_CLS_DDR_E_CAC-CLKS\" )
					)
					( Status sCSetFlattened )
					( Origin gBackEnd )
				)
				( attribute "RELATIVE_PROPAGATION_DELAY" "0.00 MIL,700.00 MIL"
					( Parent
						( matchGroupRef "@crescent_city_bb_fab1_lib.crescent_city_bb_fab1(sch_1):\MG_DDR_NEAR_DIMM-CLK1_CLS_DDR_E_CAC-CLKS\" )
					)
					( Units "uMatchProp" "ns" 1.000000)
					( Status sCSetFlattened )
					( Origin gBackEnd )
				)
			)
			( pinPair "@baseboard_fab2_lib.baseboard_fab2(sch_1):\PP3793\"
				( pinRef "@baseboard_fab2_lib.baseboard_fab2(sch_1):page27_i172:DDR4_MA(17)" )
				( pinRef "@baseboard_fab2_lib.baseboard_fab2(sch_1):page51_i111:A17" )
				( attribute "RELATIVE_PROPAGATION_DELAY_SCOPE" "G"
					( Parent
						( matchGroupRef "@crescent_city_bb_fab1_lib.crescent_city_bb_fab1(sch_1):\MG_DDR_FAR_DIMM-CLK0_CLS_DDR_E_CAC-CLKS\" )
					)
					( Status sCSetFlattened )
					( Origin gBackEnd )
				)
				( attribute "RELATIVE_PROPAGATION_DELAY" "0.00 MIL,700.00 MIL"
					( Parent
						( matchGroupRef "@crescent_city_bb_fab1_lib.crescent_city_bb_fab1(sch_1):\MG_DDR_FAR_DIMM-CLK0_CLS_DDR_E_CAC-CLKS\" )
					)
					( Units "uMatchProp" "ns" 1.000000)
					( Status sCSetFlattened )
					( Origin gBackEnd )
				)
				( attribute "RELATIVE_PROPAGATION_DELAY_SCOPE" "G"
					( Parent
						( matchGroupRef "@baseboard_fab2_lib.baseboard_fab2(sch_1):\MG_DDR_FAR_DIMM_CMD_NG_DDR_E_DLL_1\" )
					)
					( Status sCSetFlattened )
					( Origin gBackEnd )
				)
				( attribute "RELATIVE_PROPAGATION_DELAY" "0.00 MIL,25.00 MIL"
					( Parent
						( matchGroupRef "@baseboard_fab2_lib.baseboard_fab2(sch_1):\MG_DDR_FAR_DIMM_CMD_NG_DDR_E_DLL_1\" )
					)
					( Units "uMatchProp" "ns" 1.000000)
					( Status sCSetFlattened )
					( Origin gBackEnd )
				)
			)
			( pinPair "@baseboard_fab2_lib.baseboard_fab2(sch_1):\PP3794\"
				( pinRef "@baseboard_fab2_lib.baseboard_fab2(sch_1):page52_i12:A17" )
				( pinRef "@baseboard_fab2_lib.baseboard_fab2(sch_1):page27_i172:DDR4_MA(17)" )
				( attribute "RELATIVE_PROPAGATION_DELAY_SCOPE" "G"
					( Parent
						( matchGroupRef "@baseboard_fab2_lib.baseboard_fab2(sch_1):\MG_DDR_CMD_NEAR_DIMM_NG_DDR_E_DLL_1\" )
					)
					( Status sCSetFlattened )
					( Origin gBackEnd )
				)
				( attribute "RELATIVE_PROPAGATION_DELAY" "0.00 MIL,25.00 MIL"
					( Parent
						( matchGroupRef "@baseboard_fab2_lib.baseboard_fab2(sch_1):\MG_DDR_CMD_NEAR_DIMM_NG_DDR_E_DLL_1\" )
					)
					( Units "uMatchProp" "ns" 1.000000)
					( Status sCSetFlattened )
					( Origin gBackEnd )
				)
				( attribute "RELATIVE_PROPAGATION_DELAY_SCOPE" "G"
					( Parent
						( matchGroupRef "@crescent_city_bb_fab1_lib.crescent_city_bb_fab1(sch_1):\MG_DDR_NEAR_DIMM-CLK1_CLS_DDR_E_CAC-CLKS\" )
					)
					( Status sCSetFlattened )
					( Origin gBackEnd )
				)
				( attribute "RELATIVE_PROPAGATION_DELAY" "0.00 MIL,700.00 MIL"
					( Parent
						( matchGroupRef "@crescent_city_bb_fab1_lib.crescent_city_bb_fab1(sch_1):\MG_DDR_NEAR_DIMM-CLK1_CLS_DDR_E_CAC-CLKS\" )
					)
					( Units "uMatchProp" "ns" 1.000000)
					( Status sCSetFlattened )
					( Origin gBackEnd )
				)
			)
			( pinPair "@baseboard_fab2_lib.baseboard_fab2(sch_1):\PP3787\"
				( pinRef "@baseboard_fab2_lib.baseboard_fab2(sch_1):page27_i172:DDR4_MA(13)" )
				( pinRef "@baseboard_fab2_lib.baseboard_fab2(sch_1):page51_i111:A13" )
				( attribute "RELATIVE_PROPAGATION_DELAY_SCOPE" "G"
					( Parent
						( matchGroupRef "@crescent_city_bb_fab1_lib.crescent_city_bb_fab1(sch_1):\MG_DDR_FAR_DIMM-CLK0_CLS_DDR_E_CAC-CLKS\" )
					)
					( Status sCSetFlattened )
					( Origin gBackEnd )
				)
				( attribute "RELATIVE_PROPAGATION_DELAY" "0.00 MIL,700.00 MIL"
					( Parent
						( matchGroupRef "@crescent_city_bb_fab1_lib.crescent_city_bb_fab1(sch_1):\MG_DDR_FAR_DIMM-CLK0_CLS_DDR_E_CAC-CLKS\" )
					)
					( Units "uMatchProp" "ns" 1.000000)
					( Status sCSetFlattened )
					( Origin gBackEnd )
				)
				( attribute "RELATIVE_PROPAGATION_DELAY_SCOPE" "G"
					( Parent
						( matchGroupRef "@baseboard_fab2_lib.baseboard_fab2(sch_1):\MG_DDR_FAR_DIMM_CMD_NG_DDR_E_DLL_2\" )
					)
					( Status sCSetFlattened )
					( Origin gBackEnd )
				)
				( attribute "RELATIVE_PROPAGATION_DELAY" "0.00 MIL,25.00 MIL"
					( Parent
						( matchGroupRef "@baseboard_fab2_lib.baseboard_fab2(sch_1):\MG_DDR_FAR_DIMM_CMD_NG_DDR_E_DLL_2\" )
					)
					( Units "uMatchProp" "ns" 1.000000)
					( Status sCSetFlattened )
					( Origin gBackEnd )
				)
			)
			( pinPair "@baseboard_fab2_lib.baseboard_fab2(sch_1):\PP3788\"
				( pinRef "@baseboard_fab2_lib.baseboard_fab2(sch_1):page27_i172:DDR4_MA(13)" )
				( pinRef "@baseboard_fab2_lib.baseboard_fab2(sch_1):page52_i12:A13" )
				( attribute "RELATIVE_PROPAGATION_DELAY_SCOPE" "G"
					( Parent
						( matchGroupRef "@crescent_city_bb_fab1_lib.crescent_city_bb_fab1(sch_1):\MG_DDR_NEAR_DIMM-CLK1_CLS_DDR_E_CAC-CLKS\" )
					)
					( Status sCSetFlattened )
					( Origin gBackEnd )
				)
				( attribute "RELATIVE_PROPAGATION_DELAY" "0.00 MIL,700.00 MIL"
					( Parent
						( matchGroupRef "@crescent_city_bb_fab1_lib.crescent_city_bb_fab1(sch_1):\MG_DDR_NEAR_DIMM-CLK1_CLS_DDR_E_CAC-CLKS\" )
					)
					( Units "uMatchProp" "ns" 1.000000)
					( Status sCSetFlattened )
					( Origin gBackEnd )
				)
				( attribute "RELATIVE_PROPAGATION_DELAY_SCOPE" "G"
					( Parent
						( matchGroupRef "@baseboard_fab2_lib.baseboard_fab2(sch_1):\MG_DDR_CMD_NEAR_DIMM_NG_DDR_E_DLL_2\" )
					)
					( Status sCSetFlattened )
					( Origin gBackEnd )
				)
				( attribute "RELATIVE_PROPAGATION_DELAY" "0.00 MIL,25.00 MIL"
					( Parent
						( matchGroupRef "@baseboard_fab2_lib.baseboard_fab2(sch_1):\MG_DDR_CMD_NEAR_DIMM_NG_DDR_E_DLL_2\" )
					)
					( Units "uMatchProp" "ns" 1.000000)
					( Status sCSetFlattened )
					( Origin gBackEnd )
				)
			)
			( pinPair "@baseboard_fab2_lib.baseboard_fab2(sch_1):\PP3789\"
				( pinRef "@baseboard_fab2_lib.baseboard_fab2(sch_1):page27_i172:DDR4_MA(15)" )
				( pinRef "@baseboard_fab2_lib.baseboard_fab2(sch_1):page51_i111:A15_CAS_N" )
				( attribute "RELATIVE_PROPAGATION_DELAY_SCOPE" "G"
					( Parent
						( matchGroupRef "@crescent_city_bb_fab1_lib.crescent_city_bb_fab1(sch_1):\MG_DDR_FAR_DIMM-CLK0_CLS_DDR_E_CAC-CLKS\" )
					)
					( Status sCSetFlattened )
					( Origin gBackEnd )
				)
				( attribute "RELATIVE_PROPAGATION_DELAY" "0.00 MIL,700.00 MIL"
					( Parent
						( matchGroupRef "@crescent_city_bb_fab1_lib.crescent_city_bb_fab1(sch_1):\MG_DDR_FAR_DIMM-CLK0_CLS_DDR_E_CAC-CLKS\" )
					)
					( Units "uMatchProp" "ns" 1.000000)
					( Status sCSetFlattened )
					( Origin gBackEnd )
				)
				( attribute "RELATIVE_PROPAGATION_DELAY_SCOPE" "G"
					( Parent
						( matchGroupRef "@baseboard_fab2_lib.baseboard_fab2(sch_1):\MG_DDR_FAR_DIMM_CMD_NG_DDR_E_DLL_2\" )
					)
					( Status sCSetFlattened )
					( Origin gBackEnd )
				)
				( attribute "RELATIVE_PROPAGATION_DELAY" "0.00 MIL,25.00 MIL"
					( Parent
						( matchGroupRef "@baseboard_fab2_lib.baseboard_fab2(sch_1):\MG_DDR_FAR_DIMM_CMD_NG_DDR_E_DLL_2\" )
					)
					( Units "uMatchProp" "ns" 1.000000)
					( Status sCSetFlattened )
					( Origin gBackEnd )
				)
			)
			( pinPair "@baseboard_fab2_lib.baseboard_fab2(sch_1):\PP3790\"
				( pinRef "@baseboard_fab2_lib.baseboard_fab2(sch_1):page52_i12:A15_CAS_N" )
				( pinRef "@baseboard_fab2_lib.baseboard_fab2(sch_1):page27_i172:DDR4_MA(15)" )
				( attribute "RELATIVE_PROPAGATION_DELAY_SCOPE" "G"
					( Parent
						( matchGroupRef "@crescent_city_bb_fab1_lib.crescent_city_bb_fab1(sch_1):\MG_DDR_NEAR_DIMM-CLK1_CLS_DDR_E_CAC-CLKS\" )
					)
					( Status sCSetFlattened )
					( Origin gBackEnd )
				)
				( attribute "RELATIVE_PROPAGATION_DELAY" "0.00 MIL,700.00 MIL"
					( Parent
						( matchGroupRef "@crescent_city_bb_fab1_lib.crescent_city_bb_fab1(sch_1):\MG_DDR_NEAR_DIMM-CLK1_CLS_DDR_E_CAC-CLKS\" )
					)
					( Units "uMatchProp" "ns" 1.000000)
					( Status sCSetFlattened )
					( Origin gBackEnd )
				)
				( attribute "RELATIVE_PROPAGATION_DELAY_SCOPE" "G"
					( Parent
						( matchGroupRef "@baseboard_fab2_lib.baseboard_fab2(sch_1):\MG_DDR_CMD_NEAR_DIMM_NG_DDR_E_DLL_2\" )
					)
					( Status sCSetFlattened )
					( Origin gBackEnd )
				)
				( attribute "RELATIVE_PROPAGATION_DELAY" "0.00 MIL,25.00 MIL"
					( Parent
						( matchGroupRef "@baseboard_fab2_lib.baseboard_fab2(sch_1):\MG_DDR_CMD_NEAR_DIMM_NG_DDR_E_DLL_2\" )
					)
					( Units "uMatchProp" "ns" 1.000000)
					( Status sCSetFlattened )
					( Origin gBackEnd )
				)
			)
			( pinPair "@baseboard_fab2_lib.baseboard_fab2(sch_1):\PP3783\"
				( pinRef "@baseboard_fab2_lib.baseboard_fab2(sch_1):page27_i172:DDR4_MA(14)" )
				( pinRef "@baseboard_fab2_lib.baseboard_fab2(sch_1):page51_i111:A14_WE_N" )
				( attribute "RELATIVE_PROPAGATION_DELAY_SCOPE" "G"
					( Parent
						( matchGroupRef "@crescent_city_bb_fab1_lib.crescent_city_bb_fab1(sch_1):\MG_DDR_FAR_DIMM-CLK0_CLS_DDR_E_CAC-CLKS\" )
					)
					( Status sCSetFlattened )
					( Origin gBackEnd )
				)
				( attribute "RELATIVE_PROPAGATION_DELAY" "0.00 MIL,700.00 MIL"
					( Parent
						( matchGroupRef "@crescent_city_bb_fab1_lib.crescent_city_bb_fab1(sch_1):\MG_DDR_FAR_DIMM-CLK0_CLS_DDR_E_CAC-CLKS\" )
					)
					( Units "uMatchProp" "ns" 1.000000)
					( Status sCSetFlattened )
					( Origin gBackEnd )
				)
				( attribute "RELATIVE_PROPAGATION_DELAY_SCOPE" "G"
					( Parent
						( matchGroupRef "@baseboard_fab2_lib.baseboard_fab2(sch_1):\MG_DDR_FAR_DIMM_CMD_NG_DDR_E_DLL_3\" )
					)
					( Status sCSetFlattened )
					( Origin gBackEnd )
				)
				( attribute "RELATIVE_PROPAGATION_DELAY" "0.00 MIL,25.00 MIL"
					( Parent
						( matchGroupRef "@baseboard_fab2_lib.baseboard_fab2(sch_1):\MG_DDR_FAR_DIMM_CMD_NG_DDR_E_DLL_3\" )
					)
					( Units "uMatchProp" "ns" 1.000000)
					( Status sCSetFlattened )
					( Origin gBackEnd )
				)
			)
			( pinPair "@baseboard_fab2_lib.baseboard_fab2(sch_1):\PP3784\"
				( pinRef "@baseboard_fab2_lib.baseboard_fab2(sch_1):page27_i172:DDR4_MA(14)" )
				( pinRef "@baseboard_fab2_lib.baseboard_fab2(sch_1):page52_i12:A14_WE_N" )
				( attribute "RELATIVE_PROPAGATION_DELAY_SCOPE" "G"
					( Parent
						( matchGroupRef "@crescent_city_bb_fab1_lib.crescent_city_bb_fab1(sch_1):\MG_DDR_NEAR_DIMM-CLK1_CLS_DDR_E_CAC-CLKS\" )
					)
					( Status sCSetFlattened )
					( Origin gBackEnd )
				)
				( attribute "RELATIVE_PROPAGATION_DELAY" "0.00 MIL,700.00 MIL"
					( Parent
						( matchGroupRef "@crescent_city_bb_fab1_lib.crescent_city_bb_fab1(sch_1):\MG_DDR_NEAR_DIMM-CLK1_CLS_DDR_E_CAC-CLKS\" )
					)
					( Units "uMatchProp" "ns" 1.000000)
					( Status sCSetFlattened )
					( Origin gBackEnd )
				)
				( attribute "RELATIVE_PROPAGATION_DELAY_SCOPE" "G"
					( Parent
						( matchGroupRef "@baseboard_fab2_lib.baseboard_fab2(sch_1):\MG_DDR_CMD_NEAR_DIMM_NG_DDR_E_DLL_3\" )
					)
					( Status sCSetFlattened )
					( Origin gBackEnd )
				)
				( attribute "RELATIVE_PROPAGATION_DELAY" "0.00 MIL,25.00 MIL"
					( Parent
						( matchGroupRef "@baseboard_fab2_lib.baseboard_fab2(sch_1):\MG_DDR_CMD_NEAR_DIMM_NG_DDR_E_DLL_3\" )
					)
					( Units "uMatchProp" "ns" 1.000000)
					( Status sCSetFlattened )
					( Origin gBackEnd )
				)
			)
			( pinPair "@baseboard_fab2_lib.baseboard_fab2(sch_1):\PP3785\"
				( pinRef "@baseboard_fab2_lib.baseboard_fab2(sch_1):page27_i172:DDR4_MA(16)" )
				( pinRef "@baseboard_fab2_lib.baseboard_fab2(sch_1):page51_i111:A16_RAS_N" )
				( attribute "RELATIVE_PROPAGATION_DELAY_SCOPE" "G"
					( Parent
						( matchGroupRef "@crescent_city_bb_fab1_lib.crescent_city_bb_fab1(sch_1):\MG_DDR_FAR_DIMM-CLK0_CLS_DDR_E_CAC-CLKS\" )
					)
					( Status sCSetFlattened )
					( Origin gBackEnd )
				)
				( attribute "RELATIVE_PROPAGATION_DELAY" "0.00 MIL,700.00 MIL"
					( Parent
						( matchGroupRef "@crescent_city_bb_fab1_lib.crescent_city_bb_fab1(sch_1):\MG_DDR_FAR_DIMM-CLK0_CLS_DDR_E_CAC-CLKS\" )
					)
					( Units "uMatchProp" "ns" 1.000000)
					( Status sCSetFlattened )
					( Origin gBackEnd )
				)
				( attribute "RELATIVE_PROPAGATION_DELAY_SCOPE" "G"
					( Parent
						( matchGroupRef "@baseboard_fab2_lib.baseboard_fab2(sch_1):\MG_DDR_FAR_DIMM_CMD_NG_DDR_E_DLL_3\" )
					)
					( Status sCSetFlattened )
					( Origin gBackEnd )
				)
				( attribute "RELATIVE_PROPAGATION_DELAY" "0.00 MIL,25.00 MIL"
					( Parent
						( matchGroupRef "@baseboard_fab2_lib.baseboard_fab2(sch_1):\MG_DDR_FAR_DIMM_CMD_NG_DDR_E_DLL_3\" )
					)
					( Units "uMatchProp" "ns" 1.000000)
					( Status sCSetFlattened )
					( Origin gBackEnd )
				)
			)
			( pinPair "@baseboard_fab2_lib.baseboard_fab2(sch_1):\PP3786\"
				( pinRef "@baseboard_fab2_lib.baseboard_fab2(sch_1):page52_i12:A16_RAS_N" )
				( pinRef "@baseboard_fab2_lib.baseboard_fab2(sch_1):page27_i172:DDR4_MA(16)" )
				( attribute "RELATIVE_PROPAGATION_DELAY_SCOPE" "G"
					( Parent
						( matchGroupRef "@crescent_city_bb_fab1_lib.crescent_city_bb_fab1(sch_1):\MG_DDR_NEAR_DIMM-CLK1_CLS_DDR_E_CAC-CLKS\" )
					)
					( Status sCSetFlattened )
					( Origin gBackEnd )
				)
				( attribute "RELATIVE_PROPAGATION_DELAY" "0.00 MIL,700.00 MIL"
					( Parent
						( matchGroupRef "@crescent_city_bb_fab1_lib.crescent_city_bb_fab1(sch_1):\MG_DDR_NEAR_DIMM-CLK1_CLS_DDR_E_CAC-CLKS\" )
					)
					( Units "uMatchProp" "ns" 1.000000)
					( Status sCSetFlattened )
					( Origin gBackEnd )
				)
				( attribute "RELATIVE_PROPAGATION_DELAY_SCOPE" "G"
					( Parent
						( matchGroupRef "@baseboard_fab2_lib.baseboard_fab2(sch_1):\MG_DDR_CMD_NEAR_DIMM_NG_DDR_E_DLL_3\" )
					)
					( Status sCSetFlattened )
					( Origin gBackEnd )
				)
				( attribute "RELATIVE_PROPAGATION_DELAY" "0.00 MIL,25.00 MIL"
					( Parent
						( matchGroupRef "@baseboard_fab2_lib.baseboard_fab2(sch_1):\MG_DDR_CMD_NEAR_DIMM_NG_DDR_E_DLL_3\" )
					)
					( Units "uMatchProp" "ns" 1.000000)
					( Status sCSetFlattened )
					( Origin gBackEnd )
				)
			)
			( pinPair "@baseboard_fab2_lib.baseboard_fab2(sch_1):\PP3779\"
				( pinRef "@baseboard_fab2_lib.baseboard_fab2(sch_1):page27_i172:DDR4_BA(1)" )
				( pinRef "@baseboard_fab2_lib.baseboard_fab2(sch_1):page51_i111:BA(1)" )
				( attribute "RELATIVE_PROPAGATION_DELAY_SCOPE" "G"
					( Parent
						( matchGroupRef "@crescent_city_bb_fab1_lib.crescent_city_bb_fab1(sch_1):\MG_DDR_FAR_DIMM-CLK0_CLS_DDR_E_CAC-CLKS\" )
					)
					( Status sCSetFlattened )
					( Origin gBackEnd )
				)
				( attribute "RELATIVE_PROPAGATION_DELAY" "0.00 MIL,700.00 MIL"
					( Parent
						( matchGroupRef "@crescent_city_bb_fab1_lib.crescent_city_bb_fab1(sch_1):\MG_DDR_FAR_DIMM-CLK0_CLS_DDR_E_CAC-CLKS\" )
					)
					( Units "uMatchProp" "ns" 1.000000)
					( Status sCSetFlattened )
					( Origin gBackEnd )
				)
				( attribute "RELATIVE_PROPAGATION_DELAY_SCOPE" "G"
					( Parent
						( matchGroupRef "@baseboard_fab2_lib.baseboard_fab2(sch_1):\MG_DDR_FAR_DIMM_CMD_NG_DDR_E_DLL_4\" )
					)
					( Status sCSetFlattened )
					( Origin gBackEnd )
				)
				( attribute "RELATIVE_PROPAGATION_DELAY" "0.00 MIL,25.00 MIL"
					( Parent
						( matchGroupRef "@baseboard_fab2_lib.baseboard_fab2(sch_1):\MG_DDR_FAR_DIMM_CMD_NG_DDR_E_DLL_4\" )
					)
					( Units "uMatchProp" "ns" 1.000000)
					( Status sCSetFlattened )
					( Origin gBackEnd )
				)
			)
			( pinPair "@baseboard_fab2_lib.baseboard_fab2(sch_1):\PP3780\"
				( pinRef "@baseboard_fab2_lib.baseboard_fab2(sch_1):page52_i12:BA(1)" )
				( pinRef "@baseboard_fab2_lib.baseboard_fab2(sch_1):page27_i172:DDR4_BA(1)" )
				( attribute "RELATIVE_PROPAGATION_DELAY_SCOPE" "G"
					( Parent
						( matchGroupRef "@crescent_city_bb_fab1_lib.crescent_city_bb_fab1(sch_1):\MG_DDR_NEAR_DIMM-CLK1_CLS_DDR_E_CAC-CLKS\" )
					)
					( Status sCSetFlattened )
					( Origin gBackEnd )
				)
				( attribute "RELATIVE_PROPAGATION_DELAY" "0.00 MIL,700.00 MIL"
					( Parent
						( matchGroupRef "@crescent_city_bb_fab1_lib.crescent_city_bb_fab1(sch_1):\MG_DDR_NEAR_DIMM-CLK1_CLS_DDR_E_CAC-CLKS\" )
					)
					( Units "uMatchProp" "ns" 1.000000)
					( Status sCSetFlattened )
					( Origin gBackEnd )
				)
				( attribute "RELATIVE_PROPAGATION_DELAY_SCOPE" "G"
					( Parent
						( matchGroupRef "@baseboard_fab2_lib.baseboard_fab2(sch_1):\MG_DDR_CMD_NEAR_DIMM_NG_DDR_E_DLL_4\" )
					)
					( Status sCSetFlattened )
					( Origin gBackEnd )
				)
				( attribute "RELATIVE_PROPAGATION_DELAY" "0.00 MIL,25.00 MIL"
					( Parent
						( matchGroupRef "@baseboard_fab2_lib.baseboard_fab2(sch_1):\MG_DDR_CMD_NEAR_DIMM_NG_DDR_E_DLL_4\" )
					)
					( Units "uMatchProp" "ns" 1.000000)
					( Status sCSetFlattened )
					( Origin gBackEnd )
				)
			)
			( pinPair "@baseboard_fab2_lib.baseboard_fab2(sch_1):\PP3781\"
				( pinRef "@baseboard_fab2_lib.baseboard_fab2(sch_1):page27_i172:DDR4_MA(10)" )
				( pinRef "@baseboard_fab2_lib.baseboard_fab2(sch_1):page51_i111:A10" )
				( attribute "RELATIVE_PROPAGATION_DELAY_SCOPE" "G"
					( Parent
						( matchGroupRef "@crescent_city_bb_fab1_lib.crescent_city_bb_fab1(sch_1):\MG_DDR_FAR_DIMM-CLK0_CLS_DDR_E_CAC-CLKS\" )
					)
					( Status sCSetFlattened )
					( Origin gBackEnd )
				)
				( attribute "RELATIVE_PROPAGATION_DELAY" "0.00 MIL,700.00 MIL"
					( Parent
						( matchGroupRef "@crescent_city_bb_fab1_lib.crescent_city_bb_fab1(sch_1):\MG_DDR_FAR_DIMM-CLK0_CLS_DDR_E_CAC-CLKS\" )
					)
					( Units "uMatchProp" "ns" 1.000000)
					( Status sCSetFlattened )
					( Origin gBackEnd )
				)
				( attribute "RELATIVE_PROPAGATION_DELAY_SCOPE" "G"
					( Parent
						( matchGroupRef "@baseboard_fab2_lib.baseboard_fab2(sch_1):\MG_DDR_FAR_DIMM_CMD_NG_DDR_E_DLL_4\" )
					)
					( Status sCSetFlattened )
					( Origin gBackEnd )
				)
				( attribute "RELATIVE_PROPAGATION_DELAY" "0.00 MIL,25.00 MIL"
					( Parent
						( matchGroupRef "@baseboard_fab2_lib.baseboard_fab2(sch_1):\MG_DDR_FAR_DIMM_CMD_NG_DDR_E_DLL_4\" )
					)
					( Units "uMatchProp" "ns" 1.000000)
					( Status sCSetFlattened )
					( Origin gBackEnd )
				)
			)
			( pinPair "@baseboard_fab2_lib.baseboard_fab2(sch_1):\PP3782\"
				( pinRef "@baseboard_fab2_lib.baseboard_fab2(sch_1):page52_i12:A10" )
				( pinRef "@baseboard_fab2_lib.baseboard_fab2(sch_1):page27_i172:DDR4_MA(10)" )
				( attribute "RELATIVE_PROPAGATION_DELAY_SCOPE" "G"
					( Parent
						( matchGroupRef "@crescent_city_bb_fab1_lib.crescent_city_bb_fab1(sch_1):\MG_DDR_NEAR_DIMM-CLK1_CLS_DDR_E_CAC-CLKS\" )
					)
					( Status sCSetFlattened )
					( Origin gBackEnd )
				)
				( attribute "RELATIVE_PROPAGATION_DELAY" "0.00 MIL,700.00 MIL"
					( Parent
						( matchGroupRef "@crescent_city_bb_fab1_lib.crescent_city_bb_fab1(sch_1):\MG_DDR_NEAR_DIMM-CLK1_CLS_DDR_E_CAC-CLKS\" )
					)
					( Units "uMatchProp" "ns" 1.000000)
					( Status sCSetFlattened )
					( Origin gBackEnd )
				)
				( attribute "RELATIVE_PROPAGATION_DELAY_SCOPE" "G"
					( Parent
						( matchGroupRef "@baseboard_fab2_lib.baseboard_fab2(sch_1):\MG_DDR_CMD_NEAR_DIMM_NG_DDR_E_DLL_4\" )
					)
					( Status sCSetFlattened )
					( Origin gBackEnd )
				)
				( attribute "RELATIVE_PROPAGATION_DELAY" "0.00 MIL,25.00 MIL"
					( Parent
						( matchGroupRef "@baseboard_fab2_lib.baseboard_fab2(sch_1):\MG_DDR_CMD_NEAR_DIMM_NG_DDR_E_DLL_4\" )
					)
					( Units "uMatchProp" "ns" 1.000000)
					( Status sCSetFlattened )
					( Origin gBackEnd )
				)
			)
			( pinPair "@baseboard_fab2_lib.baseboard_fab2(sch_1):\PP3775\"
				( pinRef "@baseboard_fab2_lib.baseboard_fab2(sch_1):page27_i172:DDR4_BA(0)" )
				( pinRef "@baseboard_fab2_lib.baseboard_fab2(sch_1):page51_i111:BA(0)" )
				( attribute "RELATIVE_PROPAGATION_DELAY_SCOPE" "G"
					( Parent
						( matchGroupRef "@crescent_city_bb_fab1_lib.crescent_city_bb_fab1(sch_1):\MG_DDR_FAR_DIMM-CLK0_CLS_DDR_E_CAC-CLKS\" )
					)
					( Status sCSetFlattened )
					( Origin gBackEnd )
				)
				( attribute "RELATIVE_PROPAGATION_DELAY" "0.00 MIL,700.00 MIL"
					( Parent
						( matchGroupRef "@crescent_city_bb_fab1_lib.crescent_city_bb_fab1(sch_1):\MG_DDR_FAR_DIMM-CLK0_CLS_DDR_E_CAC-CLKS\" )
					)
					( Units "uMatchProp" "ns" 1.000000)
					( Status sCSetFlattened )
					( Origin gBackEnd )
				)
				( attribute "RELATIVE_PROPAGATION_DELAY_SCOPE" "G"
					( Parent
						( matchGroupRef "@baseboard_fab2_lib.baseboard_fab2(sch_1):\MG_DDR_FAR_DIMM_CMD_NG_DDR_E_DLL_5\" )
					)
					( Status sCSetFlattened )
					( Origin gBackEnd )
				)
				( attribute "RELATIVE_PROPAGATION_DELAY" "0.00 MIL,25.00 MIL"
					( Parent
						( matchGroupRef "@baseboard_fab2_lib.baseboard_fab2(sch_1):\MG_DDR_FAR_DIMM_CMD_NG_DDR_E_DLL_5\" )
					)
					( Units "uMatchProp" "ns" 1.000000)
					( Status sCSetFlattened )
					( Origin gBackEnd )
				)
			)
			( pinPair "@baseboard_fab2_lib.baseboard_fab2(sch_1):\PP3776\"
				( pinRef "@baseboard_fab2_lib.baseboard_fab2(sch_1):page52_i12:BA(0)" )
				( pinRef "@baseboard_fab2_lib.baseboard_fab2(sch_1):page27_i172:DDR4_BA(0)" )
				( attribute "RELATIVE_PROPAGATION_DELAY_SCOPE" "G"
					( Parent
						( matchGroupRef "@crescent_city_bb_fab1_lib.crescent_city_bb_fab1(sch_1):\MG_DDR_NEAR_DIMM-CLK1_CLS_DDR_E_CAC-CLKS\" )
					)
					( Status sCSetFlattened )
					( Origin gBackEnd )
				)
				( attribute "RELATIVE_PROPAGATION_DELAY" "0.00 MIL,700.00 MIL"
					( Parent
						( matchGroupRef "@crescent_city_bb_fab1_lib.crescent_city_bb_fab1(sch_1):\MG_DDR_NEAR_DIMM-CLK1_CLS_DDR_E_CAC-CLKS\" )
					)
					( Units "uMatchProp" "ns" 1.000000)
					( Status sCSetFlattened )
					( Origin gBackEnd )
				)
				( attribute "RELATIVE_PROPAGATION_DELAY_SCOPE" "G"
					( Parent
						( matchGroupRef "@baseboard_fab2_lib.baseboard_fab2(sch_1):\MG_DDR_CMD_NEAR_DIMM_NG_DDR_E_DLL_5\" )
					)
					( Status sCSetFlattened )
					( Origin gBackEnd )
				)
				( attribute "RELATIVE_PROPAGATION_DELAY" "0.00 MIL,25.00 MIL"
					( Parent
						( matchGroupRef "@baseboard_fab2_lib.baseboard_fab2(sch_1):\MG_DDR_CMD_NEAR_DIMM_NG_DDR_E_DLL_5\" )
					)
					( Units "uMatchProp" "ns" 1.000000)
					( Status sCSetFlattened )
					( Origin gBackEnd )
				)
			)
			( pinPair "@baseboard_fab2_lib.baseboard_fab2(sch_1):\PP3777\"
				( pinRef "@baseboard_fab2_lib.baseboard_fab2(sch_1):page27_i172:DDR4_MA(0)" )
				( pinRef "@baseboard_fab2_lib.baseboard_fab2(sch_1):page51_i111:A0" )
				( attribute "RELATIVE_PROPAGATION_DELAY_SCOPE" "G"
					( Parent
						( matchGroupRef "@crescent_city_bb_fab1_lib.crescent_city_bb_fab1(sch_1):\MG_DDR_FAR_DIMM-CLK0_CLS_DDR_E_CAC-CLKS\" )
					)
					( Status sCSetFlattened )
					( Origin gBackEnd )
				)
				( attribute "RELATIVE_PROPAGATION_DELAY" "0.00 MIL,700.00 MIL"
					( Parent
						( matchGroupRef "@crescent_city_bb_fab1_lib.crescent_city_bb_fab1(sch_1):\MG_DDR_FAR_DIMM-CLK0_CLS_DDR_E_CAC-CLKS\" )
					)
					( Units "uMatchProp" "ns" 1.000000)
					( Status sCSetFlattened )
					( Origin gBackEnd )
				)
				( attribute "RELATIVE_PROPAGATION_DELAY_SCOPE" "G"
					( Parent
						( matchGroupRef "@baseboard_fab2_lib.baseboard_fab2(sch_1):\MG_DDR_FAR_DIMM_CMD_NG_DDR_E_DLL_5\" )
					)
					( Status sCSetFlattened )
					( Origin gBackEnd )
				)
				( attribute "RELATIVE_PROPAGATION_DELAY" "0.00 MIL,25.00 MIL"
					( Parent
						( matchGroupRef "@baseboard_fab2_lib.baseboard_fab2(sch_1):\MG_DDR_FAR_DIMM_CMD_NG_DDR_E_DLL_5\" )
					)
					( Units "uMatchProp" "ns" 1.000000)
					( Status sCSetFlattened )
					( Origin gBackEnd )
				)
			)
			( pinPair "@baseboard_fab2_lib.baseboard_fab2(sch_1):\PP3778\"
				( pinRef "@baseboard_fab2_lib.baseboard_fab2(sch_1):page52_i12:A0" )
				( pinRef "@baseboard_fab2_lib.baseboard_fab2(sch_1):page27_i172:DDR4_MA(0)" )
				( attribute "RELATIVE_PROPAGATION_DELAY_SCOPE" "G"
					( Parent
						( matchGroupRef "@crescent_city_bb_fab1_lib.crescent_city_bb_fab1(sch_1):\MG_DDR_NEAR_DIMM-CLK1_CLS_DDR_E_CAC-CLKS\" )
					)
					( Status sCSetFlattened )
					( Origin gBackEnd )
				)
				( attribute "RELATIVE_PROPAGATION_DELAY" "0.00 MIL,700.00 MIL"
					( Parent
						( matchGroupRef "@crescent_city_bb_fab1_lib.crescent_city_bb_fab1(sch_1):\MG_DDR_NEAR_DIMM-CLK1_CLS_DDR_E_CAC-CLKS\" )
					)
					( Units "uMatchProp" "ns" 1.000000)
					( Status sCSetFlattened )
					( Origin gBackEnd )
				)
				( attribute "RELATIVE_PROPAGATION_DELAY_SCOPE" "G"
					( Parent
						( matchGroupRef "@baseboard_fab2_lib.baseboard_fab2(sch_1):\MG_DDR_CMD_NEAR_DIMM_NG_DDR_E_DLL_5\" )
					)
					( Status sCSetFlattened )
					( Origin gBackEnd )
				)
				( attribute "RELATIVE_PROPAGATION_DELAY" "0.00 MIL,25.00 MIL"
					( Parent
						( matchGroupRef "@baseboard_fab2_lib.baseboard_fab2(sch_1):\MG_DDR_CMD_NEAR_DIMM_NG_DDR_E_DLL_5\" )
					)
					( Units "uMatchProp" "ns" 1.000000)
					( Status sCSetFlattened )
					( Origin gBackEnd )
				)
			)
			( pinPair "@baseboard_fab2_lib.baseboard_fab2(sch_1):\PP3773\"
				( pinRef "@baseboard_fab2_lib.baseboard_fab2(sch_1):page27_i172:DDR4_PAR" )
				( pinRef "@baseboard_fab2_lib.baseboard_fab2(sch_1):page51_i111:PAR" )
				( attribute "RELATIVE_PROPAGATION_DELAY_SCOPE" "G"
					( Parent
						( matchGroupRef "@crescent_city_bb_fab1_lib.crescent_city_bb_fab1(sch_1):\MG_DDR_FAR_DIMM-CLK0_CLS_DDR_E_CAC-CLKS\" )
					)
					( Status sCSetFlattened )
					( Origin gBackEnd )
				)
				( attribute "RELATIVE_PROPAGATION_DELAY" "0.00 MIL,700.00 MIL"
					( Parent
						( matchGroupRef "@crescent_city_bb_fab1_lib.crescent_city_bb_fab1(sch_1):\MG_DDR_FAR_DIMM-CLK0_CLS_DDR_E_CAC-CLKS\" )
					)
					( Units "uMatchProp" "ns" 1.000000)
					( Status sCSetFlattened )
					( Origin gBackEnd )
				)
				( attribute "RELATIVE_PROPAGATION_DELAY_SCOPE" "G"
					( Parent
						( matchGroupRef "@baseboard_fab2_lib.baseboard_fab2(sch_1):\MG_DDR_FAR_DIMM_CMD_NG_DDR_E_DLL_6\" )
					)
					( Status sCSetFlattened )
					( Origin gBackEnd )
				)
				( attribute "RELATIVE_PROPAGATION_DELAY" "0.00 MIL,25.00 MIL"
					( Parent
						( matchGroupRef "@baseboard_fab2_lib.baseboard_fab2(sch_1):\MG_DDR_FAR_DIMM_CMD_NG_DDR_E_DLL_6\" )
					)
					( Units "uMatchProp" "ns" 1.000000)
					( Status sCSetFlattened )
					( Origin gBackEnd )
				)
			)
			( pinPair "@baseboard_fab2_lib.baseboard_fab2(sch_1):\PP3774\"
				( pinRef "@baseboard_fab2_lib.baseboard_fab2(sch_1):page52_i12:PAR" )
				( pinRef "@baseboard_fab2_lib.baseboard_fab2(sch_1):page27_i172:DDR4_PAR" )
				( attribute "RELATIVE_PROPAGATION_DELAY_SCOPE" "G"
					( Parent
						( matchGroupRef "@crescent_city_bb_fab1_lib.crescent_city_bb_fab1(sch_1):\MG_DDR_NEAR_DIMM-CLK1_CLS_DDR_E_CAC-CLKS\" )
					)
					( Status sCSetFlattened )
					( Origin gBackEnd )
				)
				( attribute "RELATIVE_PROPAGATION_DELAY" "0.00 MIL,700.00 MIL"
					( Parent
						( matchGroupRef "@crescent_city_bb_fab1_lib.crescent_city_bb_fab1(sch_1):\MG_DDR_NEAR_DIMM-CLK1_CLS_DDR_E_CAC-CLKS\" )
					)
					( Units "uMatchProp" "ns" 1.000000)
					( Status sCSetFlattened )
					( Origin gBackEnd )
				)
				( attribute "RELATIVE_PROPAGATION_DELAY_SCOPE" "G"
					( Parent
						( matchGroupRef "@baseboard_fab2_lib.baseboard_fab2(sch_1):\MG_DDR_CMD_NEAR_DIMM_NG_DDR_E_DLL_6\" )
					)
					( Status sCSetFlattened )
					( Origin gBackEnd )
				)
				( attribute "RELATIVE_PROPAGATION_DELAY" "0.00 MIL,25.00 MIL"
					( Parent
						( matchGroupRef "@baseboard_fab2_lib.baseboard_fab2(sch_1):\MG_DDR_CMD_NEAR_DIMM_NG_DDR_E_DLL_6\" )
					)
					( Units "uMatchProp" "ns" 1.000000)
					( Status sCSetFlattened )
					( Origin gBackEnd )
				)
			)
			( pinPair "@baseboard_fab2_lib.baseboard_fab2(sch_1):\PP3769\"
				( pinRef "@baseboard_fab2_lib.baseboard_fab2(sch_1):page27_i172:DDR4_MA(1)" )
				( pinRef "@baseboard_fab2_lib.baseboard_fab2(sch_1):page51_i111:A1" )
				( attribute "RELATIVE_PROPAGATION_DELAY_SCOPE" "G"
					( Parent
						( matchGroupRef "@crescent_city_bb_fab1_lib.crescent_city_bb_fab1(sch_1):\MG_DDR_FAR_DIMM-CLK0_CLS_DDR_E_CAC-CLKS\" )
					)
					( Status sCSetFlattened )
					( Origin gBackEnd )
				)
				( attribute "RELATIVE_PROPAGATION_DELAY" "0.00 MIL,700.00 MIL"
					( Parent
						( matchGroupRef "@crescent_city_bb_fab1_lib.crescent_city_bb_fab1(sch_1):\MG_DDR_FAR_DIMM-CLK0_CLS_DDR_E_CAC-CLKS\" )
					)
					( Units "uMatchProp" "ns" 1.000000)
					( Status sCSetFlattened )
					( Origin gBackEnd )
				)
				( attribute "RELATIVE_PROPAGATION_DELAY_SCOPE" "G"
					( Parent
						( matchGroupRef "@baseboard_fab2_lib.baseboard_fab2(sch_1):\MG_DDR_FAR_DIMM_CMD_NG_DDR_E_DLL_7\" )
					)
					( Status sCSetFlattened )
					( Origin gBackEnd )
				)
				( attribute "RELATIVE_PROPAGATION_DELAY" "0.00 MIL,25.00 MIL"
					( Parent
						( matchGroupRef "@baseboard_fab2_lib.baseboard_fab2(sch_1):\MG_DDR_FAR_DIMM_CMD_NG_DDR_E_DLL_7\" )
					)
					( Units "uMatchProp" "ns" 1.000000)
					( Status sCSetFlattened )
					( Origin gBackEnd )
				)
			)
			( pinPair "@baseboard_fab2_lib.baseboard_fab2(sch_1):\PP3770\"
				( pinRef "@baseboard_fab2_lib.baseboard_fab2(sch_1):page52_i12:A1" )
				( pinRef "@baseboard_fab2_lib.baseboard_fab2(sch_1):page27_i172:DDR4_MA(1)" )
				( attribute "RELATIVE_PROPAGATION_DELAY_SCOPE" "G"
					( Parent
						( matchGroupRef "@crescent_city_bb_fab1_lib.crescent_city_bb_fab1(sch_1):\MG_DDR_NEAR_DIMM-CLK1_CLS_DDR_E_CAC-CLKS\" )
					)
					( Status sCSetFlattened )
					( Origin gBackEnd )
				)
				( attribute "RELATIVE_PROPAGATION_DELAY" "0.00 MIL,700.00 MIL"
					( Parent
						( matchGroupRef "@crescent_city_bb_fab1_lib.crescent_city_bb_fab1(sch_1):\MG_DDR_NEAR_DIMM-CLK1_CLS_DDR_E_CAC-CLKS\" )
					)
					( Units "uMatchProp" "ns" 1.000000)
					( Status sCSetFlattened )
					( Origin gBackEnd )
				)
				( attribute "RELATIVE_PROPAGATION_DELAY_SCOPE" "G"
					( Parent
						( matchGroupRef "@baseboard_fab2_lib.baseboard_fab2(sch_1):\MG_DDR_CMD_NEAR_DIMM_NG_DDR_E_DLL_7\" )
					)
					( Status sCSetFlattened )
					( Origin gBackEnd )
				)
				( attribute "RELATIVE_PROPAGATION_DELAY" "0.00 MIL,25.00 MIL"
					( Parent
						( matchGroupRef "@baseboard_fab2_lib.baseboard_fab2(sch_1):\MG_DDR_CMD_NEAR_DIMM_NG_DDR_E_DLL_7\" )
					)
					( Units "uMatchProp" "ns" 1.000000)
					( Status sCSetFlattened )
					( Origin gBackEnd )
				)
			)
			( pinPair "@baseboard_fab2_lib.baseboard_fab2(sch_1):\PP3771\"
				( pinRef "@baseboard_fab2_lib.baseboard_fab2(sch_1):page27_i172:DDR4_MA(3)" )
				( pinRef "@baseboard_fab2_lib.baseboard_fab2(sch_1):page51_i111:A3" )
				( attribute "RELATIVE_PROPAGATION_DELAY_SCOPE" "G"
					( Parent
						( matchGroupRef "@crescent_city_bb_fab1_lib.crescent_city_bb_fab1(sch_1):\MG_DDR_FAR_DIMM-CLK0_CLS_DDR_E_CAC-CLKS\" )
					)
					( Status sCSetFlattened )
					( Origin gBackEnd )
				)
				( attribute "RELATIVE_PROPAGATION_DELAY" "0.00 MIL,700.00 MIL"
					( Parent
						( matchGroupRef "@crescent_city_bb_fab1_lib.crescent_city_bb_fab1(sch_1):\MG_DDR_FAR_DIMM-CLK0_CLS_DDR_E_CAC-CLKS\" )
					)
					( Units "uMatchProp" "ns" 1.000000)
					( Status sCSetFlattened )
					( Origin gBackEnd )
				)
				( attribute "RELATIVE_PROPAGATION_DELAY_SCOPE" "G"
					( Parent
						( matchGroupRef "@baseboard_fab2_lib.baseboard_fab2(sch_1):\MG_DDR_FAR_DIMM_CMD_NG_DDR_E_DLL_7\" )
					)
					( Status sCSetFlattened )
					( Origin gBackEnd )
				)
				( attribute "RELATIVE_PROPAGATION_DELAY" "0.00 MIL,25.00 MIL"
					( Parent
						( matchGroupRef "@baseboard_fab2_lib.baseboard_fab2(sch_1):\MG_DDR_FAR_DIMM_CMD_NG_DDR_E_DLL_7\" )
					)
					( Units "uMatchProp" "ns" 1.000000)
					( Status sCSetFlattened )
					( Origin gBackEnd )
				)
			)
			( pinPair "@baseboard_fab2_lib.baseboard_fab2(sch_1):\PP3772\"
				( pinRef "@baseboard_fab2_lib.baseboard_fab2(sch_1):page52_i12:A3" )
				( pinRef "@baseboard_fab2_lib.baseboard_fab2(sch_1):page27_i172:DDR4_MA(3)" )
				( attribute "RELATIVE_PROPAGATION_DELAY_SCOPE" "G"
					( Parent
						( matchGroupRef "@crescent_city_bb_fab1_lib.crescent_city_bb_fab1(sch_1):\MG_DDR_NEAR_DIMM-CLK1_CLS_DDR_E_CAC-CLKS\" )
					)
					( Status sCSetFlattened )
					( Origin gBackEnd )
				)
				( attribute "RELATIVE_PROPAGATION_DELAY" "0.00 MIL,700.00 MIL"
					( Parent
						( matchGroupRef "@crescent_city_bb_fab1_lib.crescent_city_bb_fab1(sch_1):\MG_DDR_NEAR_DIMM-CLK1_CLS_DDR_E_CAC-CLKS\" )
					)
					( Units "uMatchProp" "ns" 1.000000)
					( Status sCSetFlattened )
					( Origin gBackEnd )
				)
				( attribute "RELATIVE_PROPAGATION_DELAY_SCOPE" "G"
					( Parent
						( matchGroupRef "@baseboard_fab2_lib.baseboard_fab2(sch_1):\MG_DDR_CMD_NEAR_DIMM_NG_DDR_E_DLL_7\" )
					)
					( Status sCSetFlattened )
					( Origin gBackEnd )
				)
				( attribute "RELATIVE_PROPAGATION_DELAY" "0.00 MIL,25.00 MIL"
					( Parent
						( matchGroupRef "@baseboard_fab2_lib.baseboard_fab2(sch_1):\MG_DDR_CMD_NEAR_DIMM_NG_DDR_E_DLL_7\" )
					)
					( Units "uMatchProp" "ns" 1.000000)
					( Status sCSetFlattened )
					( Origin gBackEnd )
				)
			)
			( pinPair "@baseboard_fab2_lib.baseboard_fab2(sch_1):\PP3765\"
				( pinRef "@baseboard_fab2_lib.baseboard_fab2(sch_1):page27_i172:DDR4_MA(2)" )
				( pinRef "@baseboard_fab2_lib.baseboard_fab2(sch_1):page51_i111:A2" )
				( attribute "RELATIVE_PROPAGATION_DELAY_SCOPE" "G"
					( Parent
						( matchGroupRef "@crescent_city_bb_fab1_lib.crescent_city_bb_fab1(sch_1):\MG_DDR_FAR_DIMM-CLK0_CLS_DDR_E_CAC-CLKS\" )
					)
					( Status sCSetFlattened )
					( Origin gBackEnd )
				)
				( attribute "RELATIVE_PROPAGATION_DELAY" "0.00 MIL,700.00 MIL"
					( Parent
						( matchGroupRef "@crescent_city_bb_fab1_lib.crescent_city_bb_fab1(sch_1):\MG_DDR_FAR_DIMM-CLK0_CLS_DDR_E_CAC-CLKS\" )
					)
					( Units "uMatchProp" "ns" 1.000000)
					( Status sCSetFlattened )
					( Origin gBackEnd )
				)
				( attribute "RELATIVE_PROPAGATION_DELAY_SCOPE" "G"
					( Parent
						( matchGroupRef "@baseboard_fab2_lib.baseboard_fab2(sch_1):\MG_DDR_FAR_DIMM_CMD_NG_DDR_E_DLL_8\" )
					)
					( Status sCSetFlattened )
					( Origin gBackEnd )
				)
				( attribute "RELATIVE_PROPAGATION_DELAY" "0.00 MIL,25.00 MIL"
					( Parent
						( matchGroupRef "@baseboard_fab2_lib.baseboard_fab2(sch_1):\MG_DDR_FAR_DIMM_CMD_NG_DDR_E_DLL_8\" )
					)
					( Units "uMatchProp" "ns" 1.000000)
					( Status sCSetFlattened )
					( Origin gBackEnd )
				)
			)
			( pinPair "@baseboard_fab2_lib.baseboard_fab2(sch_1):\PP3766\"
				( pinRef "@baseboard_fab2_lib.baseboard_fab2(sch_1):page52_i12:A2" )
				( pinRef "@baseboard_fab2_lib.baseboard_fab2(sch_1):page27_i172:DDR4_MA(2)" )
				( attribute "RELATIVE_PROPAGATION_DELAY_SCOPE" "G"
					( Parent
						( matchGroupRef "@crescent_city_bb_fab1_lib.crescent_city_bb_fab1(sch_1):\MG_DDR_NEAR_DIMM-CLK1_CLS_DDR_E_CAC-CLKS\" )
					)
					( Status sCSetFlattened )
					( Origin gBackEnd )
				)
				( attribute "RELATIVE_PROPAGATION_DELAY" "0.00 MIL,700.00 MIL"
					( Parent
						( matchGroupRef "@crescent_city_bb_fab1_lib.crescent_city_bb_fab1(sch_1):\MG_DDR_NEAR_DIMM-CLK1_CLS_DDR_E_CAC-CLKS\" )
					)
					( Units "uMatchProp" "ns" 1.000000)
					( Status sCSetFlattened )
					( Origin gBackEnd )
				)
				( attribute "RELATIVE_PROPAGATION_DELAY_SCOPE" "G"
					( Parent
						( matchGroupRef "@baseboard_fab2_lib.baseboard_fab2(sch_1):\MG_DDR_CMD_NEAR_DIMM_NG_DDR_E_DLL_8\" )
					)
					( Status sCSetFlattened )
					( Origin gBackEnd )
				)
				( attribute "RELATIVE_PROPAGATION_DELAY" "0.00 MIL,25.00 MIL"
					( Parent
						( matchGroupRef "@baseboard_fab2_lib.baseboard_fab2(sch_1):\MG_DDR_CMD_NEAR_DIMM_NG_DDR_E_DLL_8\" )
					)
					( Units "uMatchProp" "ns" 1.000000)
					( Status sCSetFlattened )
					( Origin gBackEnd )
				)
			)
			( pinPair "@baseboard_fab2_lib.baseboard_fab2(sch_1):\PP3767\"
				( pinRef "@baseboard_fab2_lib.baseboard_fab2(sch_1):page27_i172:DDR4_MA(4)" )
				( pinRef "@baseboard_fab2_lib.baseboard_fab2(sch_1):page51_i111:A4" )
				( attribute "RELATIVE_PROPAGATION_DELAY_SCOPE" "G"
					( Parent
						( matchGroupRef "@crescent_city_bb_fab1_lib.crescent_city_bb_fab1(sch_1):\MG_DDR_FAR_DIMM-CLK0_CLS_DDR_E_CAC-CLKS\" )
					)
					( Status sCSetFlattened )
					( Origin gBackEnd )
				)
				( attribute "RELATIVE_PROPAGATION_DELAY" "0.00 MIL,700.00 MIL"
					( Parent
						( matchGroupRef "@crescent_city_bb_fab1_lib.crescent_city_bb_fab1(sch_1):\MG_DDR_FAR_DIMM-CLK0_CLS_DDR_E_CAC-CLKS\" )
					)
					( Units "uMatchProp" "ns" 1.000000)
					( Status sCSetFlattened )
					( Origin gBackEnd )
				)
				( attribute "RELATIVE_PROPAGATION_DELAY_SCOPE" "G"
					( Parent
						( matchGroupRef "@baseboard_fab2_lib.baseboard_fab2(sch_1):\MG_DDR_FAR_DIMM_CMD_NG_DDR_E_DLL_8\" )
					)
					( Status sCSetFlattened )
					( Origin gBackEnd )
				)
				( attribute "RELATIVE_PROPAGATION_DELAY" "0.00 MIL,25.00 MIL"
					( Parent
						( matchGroupRef "@baseboard_fab2_lib.baseboard_fab2(sch_1):\MG_DDR_FAR_DIMM_CMD_NG_DDR_E_DLL_8\" )
					)
					( Units "uMatchProp" "ns" 1.000000)
					( Status sCSetFlattened )
					( Origin gBackEnd )
				)
			)
			( pinPair "@baseboard_fab2_lib.baseboard_fab2(sch_1):\PP3768\"
				( pinRef "@baseboard_fab2_lib.baseboard_fab2(sch_1):page52_i12:A4" )
				( pinRef "@baseboard_fab2_lib.baseboard_fab2(sch_1):page27_i172:DDR4_MA(4)" )
				( attribute "RELATIVE_PROPAGATION_DELAY_SCOPE" "G"
					( Parent
						( matchGroupRef "@crescent_city_bb_fab1_lib.crescent_city_bb_fab1(sch_1):\MG_DDR_NEAR_DIMM-CLK1_CLS_DDR_E_CAC-CLKS\" )
					)
					( Status sCSetFlattened )
					( Origin gBackEnd )
				)
				( attribute "RELATIVE_PROPAGATION_DELAY" "0.00 MIL,700.00 MIL"
					( Parent
						( matchGroupRef "@crescent_city_bb_fab1_lib.crescent_city_bb_fab1(sch_1):\MG_DDR_NEAR_DIMM-CLK1_CLS_DDR_E_CAC-CLKS\" )
					)
					( Units "uMatchProp" "ns" 1.000000)
					( Status sCSetFlattened )
					( Origin gBackEnd )
				)
				( attribute "RELATIVE_PROPAGATION_DELAY_SCOPE" "G"
					( Parent
						( matchGroupRef "@baseboard_fab2_lib.baseboard_fab2(sch_1):\MG_DDR_CMD_NEAR_DIMM_NG_DDR_E_DLL_8\" )
					)
					( Status sCSetFlattened )
					( Origin gBackEnd )
				)
				( attribute "RELATIVE_PROPAGATION_DELAY" "0.00 MIL,25.00 MIL"
					( Parent
						( matchGroupRef "@baseboard_fab2_lib.baseboard_fab2(sch_1):\MG_DDR_CMD_NEAR_DIMM_NG_DDR_E_DLL_8\" )
					)
					( Units "uMatchProp" "ns" 1.000000)
					( Status sCSetFlattened )
					( Origin gBackEnd )
				)
			)
			( pinPair "@baseboard_fab2_lib.baseboard_fab2(sch_1):\PP3761\"
				( pinRef "@baseboard_fab2_lib.baseboard_fab2(sch_1):page27_i172:DDR4_MA(5)" )
				( pinRef "@baseboard_fab2_lib.baseboard_fab2(sch_1):page51_i111:A5" )
				( attribute "RELATIVE_PROPAGATION_DELAY_SCOPE" "G"
					( Parent
						( matchGroupRef "@crescent_city_bb_fab1_lib.crescent_city_bb_fab1(sch_1):\MG_DDR_FAR_DIMM-CLK0_CLS_DDR_E_CAC-CLKS\" )
					)
					( Status sCSetFlattened )
					( Origin gBackEnd )
				)
				( attribute "RELATIVE_PROPAGATION_DELAY" "0.00 MIL,700.00 MIL"
					( Parent
						( matchGroupRef "@crescent_city_bb_fab1_lib.crescent_city_bb_fab1(sch_1):\MG_DDR_FAR_DIMM-CLK0_CLS_DDR_E_CAC-CLKS\" )
					)
					( Units "uMatchProp" "ns" 1.000000)
					( Status sCSetFlattened )
					( Origin gBackEnd )
				)
				( attribute "RELATIVE_PROPAGATION_DELAY_SCOPE" "G"
					( Parent
						( matchGroupRef "@baseboard_fab2_lib.baseboard_fab2(sch_1):\MG_DDR_FAR_DIMM_CMD_NG_DDR_E_DLL_9\" )
					)
					( Status sCSetFlattened )
					( Origin gBackEnd )
				)
				( attribute "RELATIVE_PROPAGATION_DELAY" "0.00 MIL,25.00 MIL"
					( Parent
						( matchGroupRef "@baseboard_fab2_lib.baseboard_fab2(sch_1):\MG_DDR_FAR_DIMM_CMD_NG_DDR_E_DLL_9\" )
					)
					( Units "uMatchProp" "ns" 1.000000)
					( Status sCSetFlattened )
					( Origin gBackEnd )
				)
			)
			( pinPair "@baseboard_fab2_lib.baseboard_fab2(sch_1):\PP3762\"
				( pinRef "@baseboard_fab2_lib.baseboard_fab2(sch_1):page52_i12:A5" )
				( pinRef "@baseboard_fab2_lib.baseboard_fab2(sch_1):page27_i172:DDR4_MA(5)" )
				( attribute "RELATIVE_PROPAGATION_DELAY_SCOPE" "G"
					( Parent
						( matchGroupRef "@crescent_city_bb_fab1_lib.crescent_city_bb_fab1(sch_1):\MG_DDR_NEAR_DIMM-CLK1_CLS_DDR_E_CAC-CLKS\" )
					)
					( Status sCSetFlattened )
					( Origin gBackEnd )
				)
				( attribute "RELATIVE_PROPAGATION_DELAY" "0.00 MIL,700.00 MIL"
					( Parent
						( matchGroupRef "@crescent_city_bb_fab1_lib.crescent_city_bb_fab1(sch_1):\MG_DDR_NEAR_DIMM-CLK1_CLS_DDR_E_CAC-CLKS\" )
					)
					( Units "uMatchProp" "ns" 1.000000)
					( Status sCSetFlattened )
					( Origin gBackEnd )
				)
				( attribute "RELATIVE_PROPAGATION_DELAY_SCOPE" "G"
					( Parent
						( matchGroupRef "@baseboard_fab2_lib.baseboard_fab2(sch_1):\MG_DDR_CMD_NEAR_DIMM_NG_DDR_E_DLL_9\" )
					)
					( Status sCSetFlattened )
					( Origin gBackEnd )
				)
				( attribute "RELATIVE_PROPAGATION_DELAY" "0.00 MIL,25.00 MIL"
					( Parent
						( matchGroupRef "@baseboard_fab2_lib.baseboard_fab2(sch_1):\MG_DDR_CMD_NEAR_DIMM_NG_DDR_E_DLL_9\" )
					)
					( Units "uMatchProp" "ns" 1.000000)
					( Status sCSetFlattened )
					( Origin gBackEnd )
				)
			)
			( pinPair "@baseboard_fab2_lib.baseboard_fab2(sch_1):\PP3763\"
				( pinRef "@baseboard_fab2_lib.baseboard_fab2(sch_1):page27_i172:DDR4_MA(6)" )
				( pinRef "@baseboard_fab2_lib.baseboard_fab2(sch_1):page51_i111:A6" )
				( attribute "RELATIVE_PROPAGATION_DELAY_SCOPE" "G"
					( Parent
						( matchGroupRef "@crescent_city_bb_fab1_lib.crescent_city_bb_fab1(sch_1):\MG_DDR_FAR_DIMM-CLK0_CLS_DDR_E_CAC-CLKS\" )
					)
					( Status sCSetFlattened )
					( Origin gBackEnd )
				)
				( attribute "RELATIVE_PROPAGATION_DELAY" "0.00 MIL,700.00 MIL"
					( Parent
						( matchGroupRef "@crescent_city_bb_fab1_lib.crescent_city_bb_fab1(sch_1):\MG_DDR_FAR_DIMM-CLK0_CLS_DDR_E_CAC-CLKS\" )
					)
					( Units "uMatchProp" "ns" 1.000000)
					( Status sCSetFlattened )
					( Origin gBackEnd )
				)
				( attribute "RELATIVE_PROPAGATION_DELAY_SCOPE" "G"
					( Parent
						( matchGroupRef "@baseboard_fab2_lib.baseboard_fab2(sch_1):\MG_DDR_FAR_DIMM_CMD_NG_DDR_E_DLL_9\" )
					)
					( Status sCSetFlattened )
					( Origin gBackEnd )
				)
				( attribute "RELATIVE_PROPAGATION_DELAY" "0.00 MIL,25.00 MIL"
					( Parent
						( matchGroupRef "@baseboard_fab2_lib.baseboard_fab2(sch_1):\MG_DDR_FAR_DIMM_CMD_NG_DDR_E_DLL_9\" )
					)
					( Units "uMatchProp" "ns" 1.000000)
					( Status sCSetFlattened )
					( Origin gBackEnd )
				)
			)
			( pinPair "@baseboard_fab2_lib.baseboard_fab2(sch_1):\PP3764\"
				( pinRef "@baseboard_fab2_lib.baseboard_fab2(sch_1):page52_i12:A6" )
				( pinRef "@baseboard_fab2_lib.baseboard_fab2(sch_1):page27_i172:DDR4_MA(6)" )
				( attribute "RELATIVE_PROPAGATION_DELAY_SCOPE" "G"
					( Parent
						( matchGroupRef "@crescent_city_bb_fab1_lib.crescent_city_bb_fab1(sch_1):\MG_DDR_NEAR_DIMM-CLK1_CLS_DDR_E_CAC-CLKS\" )
					)
					( Status sCSetFlattened )
					( Origin gBackEnd )
				)
				( attribute "RELATIVE_PROPAGATION_DELAY" "0.00 MIL,700.00 MIL"
					( Parent
						( matchGroupRef "@crescent_city_bb_fab1_lib.crescent_city_bb_fab1(sch_1):\MG_DDR_NEAR_DIMM-CLK1_CLS_DDR_E_CAC-CLKS\" )
					)
					( Units "uMatchProp" "ns" 1.000000)
					( Status sCSetFlattened )
					( Origin gBackEnd )
				)
				( attribute "RELATIVE_PROPAGATION_DELAY_SCOPE" "G"
					( Parent
						( matchGroupRef "@baseboard_fab2_lib.baseboard_fab2(sch_1):\MG_DDR_CMD_NEAR_DIMM_NG_DDR_E_DLL_9\" )
					)
					( Status sCSetFlattened )
					( Origin gBackEnd )
				)
				( attribute "RELATIVE_PROPAGATION_DELAY" "0.00 MIL,25.00 MIL"
					( Parent
						( matchGroupRef "@baseboard_fab2_lib.baseboard_fab2(sch_1):\MG_DDR_CMD_NEAR_DIMM_NG_DDR_E_DLL_9\" )
					)
					( Units "uMatchProp" "ns" 1.000000)
					( Status sCSetFlattened )
					( Origin gBackEnd )
				)
			)
			( pinPair "@baseboard_fab2_lib.baseboard_fab2(sch_1):\PP3757\"
				( pinRef "@baseboard_fab2_lib.baseboard_fab2(sch_1):page27_i172:DDR4_MA(7)" )
				( pinRef "@baseboard_fab2_lib.baseboard_fab2(sch_1):page51_i111:A7" )
				( attribute "RELATIVE_PROPAGATION_DELAY_SCOPE" "G"
					( Parent
						( matchGroupRef "@crescent_city_bb_fab1_lib.crescent_city_bb_fab1(sch_1):\MG_DDR_FAR_DIMM-CLK0_CLS_DDR_E_CAC-CLKS\" )
					)
					( Status sCSetFlattened )
					( Origin gBackEnd )
				)
				( attribute "RELATIVE_PROPAGATION_DELAY" "0.00 MIL,700.00 MIL"
					( Parent
						( matchGroupRef "@crescent_city_bb_fab1_lib.crescent_city_bb_fab1(sch_1):\MG_DDR_FAR_DIMM-CLK0_CLS_DDR_E_CAC-CLKS\" )
					)
					( Units "uMatchProp" "ns" 1.000000)
					( Status sCSetFlattened )
					( Origin gBackEnd )
				)
				( attribute "RELATIVE_PROPAGATION_DELAY_SCOPE" "G"
					( Parent
						( matchGroupRef "@baseboard_fab2_lib.baseboard_fab2(sch_1):\MG_DDR_FAR_DIMM_CMD_NG_DDR_E_DLL_10\" )
					)
					( Status sCSetFlattened )
					( Origin gBackEnd )
				)
				( attribute "RELATIVE_PROPAGATION_DELAY" "0.00 MIL,25.00 MIL"
					( Parent
						( matchGroupRef "@baseboard_fab2_lib.baseboard_fab2(sch_1):\MG_DDR_FAR_DIMM_CMD_NG_DDR_E_DLL_10\" )
					)
					( Units "uMatchProp" "ns" 1.000000)
					( Status sCSetFlattened )
					( Origin gBackEnd )
				)
			)
			( pinPair "@baseboard_fab2_lib.baseboard_fab2(sch_1):\PP3758\"
				( pinRef "@baseboard_fab2_lib.baseboard_fab2(sch_1):page52_i12:A7" )
				( pinRef "@baseboard_fab2_lib.baseboard_fab2(sch_1):page27_i172:DDR4_MA(7)" )
				( attribute "RELATIVE_PROPAGATION_DELAY_SCOPE" "G"
					( Parent
						( matchGroupRef "@crescent_city_bb_fab1_lib.crescent_city_bb_fab1(sch_1):\MG_DDR_NEAR_DIMM-CLK1_CLS_DDR_E_CAC-CLKS\" )
					)
					( Status sCSetFlattened )
					( Origin gBackEnd )
				)
				( attribute "RELATIVE_PROPAGATION_DELAY" "0.00 MIL,700.00 MIL"
					( Parent
						( matchGroupRef "@crescent_city_bb_fab1_lib.crescent_city_bb_fab1(sch_1):\MG_DDR_NEAR_DIMM-CLK1_CLS_DDR_E_CAC-CLKS\" )
					)
					( Units "uMatchProp" "ns" 1.000000)
					( Status sCSetFlattened )
					( Origin gBackEnd )
				)
				( attribute "RELATIVE_PROPAGATION_DELAY_SCOPE" "G"
					( Parent
						( matchGroupRef "@baseboard_fab2_lib.baseboard_fab2(sch_1):\MG_DDR_CMD_NEAR_DIMM_NG_DDR_E_DLL_10\" )
					)
					( Status sCSetFlattened )
					( Origin gBackEnd )
				)
				( attribute "RELATIVE_PROPAGATION_DELAY" "0.00 MIL,25.00 MIL"
					( Parent
						( matchGroupRef "@baseboard_fab2_lib.baseboard_fab2(sch_1):\MG_DDR_CMD_NEAR_DIMM_NG_DDR_E_DLL_10\" )
					)
					( Units "uMatchProp" "ns" 1.000000)
					( Status sCSetFlattened )
					( Origin gBackEnd )
				)
			)
			( pinPair "@baseboard_fab2_lib.baseboard_fab2(sch_1):\PP3759\"
				( pinRef "@baseboard_fab2_lib.baseboard_fab2(sch_1):page27_i172:DDR4_MA(8)" )
				( pinRef "@baseboard_fab2_lib.baseboard_fab2(sch_1):page51_i111:A8" )
				( attribute "RELATIVE_PROPAGATION_DELAY_SCOPE" "G"
					( Parent
						( matchGroupRef "@crescent_city_bb_fab1_lib.crescent_city_bb_fab1(sch_1):\MG_DDR_FAR_DIMM-CLK0_CLS_DDR_E_CAC-CLKS\" )
					)
					( Status sCSetFlattened )
					( Origin gBackEnd )
				)
				( attribute "RELATIVE_PROPAGATION_DELAY" "0.00 MIL,700.00 MIL"
					( Parent
						( matchGroupRef "@crescent_city_bb_fab1_lib.crescent_city_bb_fab1(sch_1):\MG_DDR_FAR_DIMM-CLK0_CLS_DDR_E_CAC-CLKS\" )
					)
					( Units "uMatchProp" "ns" 1.000000)
					( Status sCSetFlattened )
					( Origin gBackEnd )
				)
				( attribute "RELATIVE_PROPAGATION_DELAY_SCOPE" "G"
					( Parent
						( matchGroupRef "@baseboard_fab2_lib.baseboard_fab2(sch_1):\MG_DDR_FAR_DIMM_CMD_NG_DDR_E_DLL_10\" )
					)
					( Status sCSetFlattened )
					( Origin gBackEnd )
				)
				( attribute "RELATIVE_PROPAGATION_DELAY" "0.00 MIL,25.00 MIL"
					( Parent
						( matchGroupRef "@baseboard_fab2_lib.baseboard_fab2(sch_1):\MG_DDR_FAR_DIMM_CMD_NG_DDR_E_DLL_10\" )
					)
					( Units "uMatchProp" "ns" 1.000000)
					( Status sCSetFlattened )
					( Origin gBackEnd )
				)
			)
			( pinPair "@baseboard_fab2_lib.baseboard_fab2(sch_1):\PP3760\"
				( pinRef "@baseboard_fab2_lib.baseboard_fab2(sch_1):page52_i12:A8" )
				( pinRef "@baseboard_fab2_lib.baseboard_fab2(sch_1):page27_i172:DDR4_MA(8)" )
				( attribute "RELATIVE_PROPAGATION_DELAY_SCOPE" "G"
					( Parent
						( matchGroupRef "@crescent_city_bb_fab1_lib.crescent_city_bb_fab1(sch_1):\MG_DDR_NEAR_DIMM-CLK1_CLS_DDR_E_CAC-CLKS\" )
					)
					( Status sCSetFlattened )
					( Origin gBackEnd )
				)
				( attribute "RELATIVE_PROPAGATION_DELAY" "0.00 MIL,700.00 MIL"
					( Parent
						( matchGroupRef "@crescent_city_bb_fab1_lib.crescent_city_bb_fab1(sch_1):\MG_DDR_NEAR_DIMM-CLK1_CLS_DDR_E_CAC-CLKS\" )
					)
					( Units "uMatchProp" "ns" 1.000000)
					( Status sCSetFlattened )
					( Origin gBackEnd )
				)
				( attribute "RELATIVE_PROPAGATION_DELAY_SCOPE" "G"
					( Parent
						( matchGroupRef "@baseboard_fab2_lib.baseboard_fab2(sch_1):\MG_DDR_CMD_NEAR_DIMM_NG_DDR_E_DLL_10\" )
					)
					( Status sCSetFlattened )
					( Origin gBackEnd )
				)
				( attribute "RELATIVE_PROPAGATION_DELAY" "0.00 MIL,25.00 MIL"
					( Parent
						( matchGroupRef "@baseboard_fab2_lib.baseboard_fab2(sch_1):\MG_DDR_CMD_NEAR_DIMM_NG_DDR_E_DLL_10\" )
					)
					( Units "uMatchProp" "ns" 1.000000)
					( Status sCSetFlattened )
					( Origin gBackEnd )
				)
			)
			( pinPair "@baseboard_fab2_lib.baseboard_fab2(sch_1):\PP3753\"
				( pinRef "@baseboard_fab2_lib.baseboard_fab2(sch_1):page27_i172:DDR4_MA(9)" )
				( pinRef "@baseboard_fab2_lib.baseboard_fab2(sch_1):page51_i111:A9" )
				( attribute "RELATIVE_PROPAGATION_DELAY_SCOPE" "G"
					( Parent
						( matchGroupRef "@crescent_city_bb_fab1_lib.crescent_city_bb_fab1(sch_1):\MG_DDR_FAR_DIMM-CLK0_CLS_DDR_E_CAC-CLKS\" )
					)
					( Status sCSetFlattened )
					( Origin gBackEnd )
				)
				( attribute "RELATIVE_PROPAGATION_DELAY" "0.00 MIL,700.00 MIL"
					( Parent
						( matchGroupRef "@crescent_city_bb_fab1_lib.crescent_city_bb_fab1(sch_1):\MG_DDR_FAR_DIMM-CLK0_CLS_DDR_E_CAC-CLKS\" )
					)
					( Units "uMatchProp" "ns" 1.000000)
					( Status sCSetFlattened )
					( Origin gBackEnd )
				)
				( attribute "RELATIVE_PROPAGATION_DELAY_SCOPE" "G"
					( Parent
						( matchGroupRef "@baseboard_fab2_lib.baseboard_fab2(sch_1):\MG_DDR_FAR_DIMM_CMD_NG_DDR_E_DLL_11\" )
					)
					( Status sCSetFlattened )
					( Origin gBackEnd )
				)
				( attribute "RELATIVE_PROPAGATION_DELAY" "0.00 MIL,25.00 MIL"
					( Parent
						( matchGroupRef "@baseboard_fab2_lib.baseboard_fab2(sch_1):\MG_DDR_FAR_DIMM_CMD_NG_DDR_E_DLL_11\" )
					)
					( Units "uMatchProp" "ns" 1.000000)
					( Status sCSetFlattened )
					( Origin gBackEnd )
				)
			)
			( pinPair "@baseboard_fab2_lib.baseboard_fab2(sch_1):\PP3754\"
				( pinRef "@baseboard_fab2_lib.baseboard_fab2(sch_1):page27_i172:DDR4_MA(9)" )
				( pinRef "@baseboard_fab2_lib.baseboard_fab2(sch_1):page52_i12:A9" )
				( attribute "RELATIVE_PROPAGATION_DELAY_SCOPE" "G"
					( Parent
						( matchGroupRef "@crescent_city_bb_fab1_lib.crescent_city_bb_fab1(sch_1):\MG_DDR_NEAR_DIMM-CLK1_CLS_DDR_E_CAC-CLKS\" )
					)
					( Status sCSetFlattened )
					( Origin gBackEnd )
				)
				( attribute "RELATIVE_PROPAGATION_DELAY" "0.00 MIL,700.00 MIL"
					( Parent
						( matchGroupRef "@crescent_city_bb_fab1_lib.crescent_city_bb_fab1(sch_1):\MG_DDR_NEAR_DIMM-CLK1_CLS_DDR_E_CAC-CLKS\" )
					)
					( Units "uMatchProp" "ns" 1.000000)
					( Status sCSetFlattened )
					( Origin gBackEnd )
				)
				( attribute "RELATIVE_PROPAGATION_DELAY_SCOPE" "G"
					( Parent
						( matchGroupRef "@baseboard_fab2_lib.baseboard_fab2(sch_1):\MG_DDR_CMD_NEAR_DIMM_NG_DDR_E_DLL_11\" )
					)
					( Status sCSetFlattened )
					( Origin gBackEnd )
				)
				( attribute "RELATIVE_PROPAGATION_DELAY" "0.00 MIL,25.00 MIL"
					( Parent
						( matchGroupRef "@baseboard_fab2_lib.baseboard_fab2(sch_1):\MG_DDR_CMD_NEAR_DIMM_NG_DDR_E_DLL_11\" )
					)
					( Units "uMatchProp" "ns" 1.000000)
					( Status sCSetFlattened )
					( Origin gBackEnd )
				)
			)
			( pinPair "@baseboard_fab2_lib.baseboard_fab2(sch_1):\PP3755\"
				( pinRef "@baseboard_fab2_lib.baseboard_fab2(sch_1):page27_i172:DDR4_MA(12)" )
				( pinRef "@baseboard_fab2_lib.baseboard_fab2(sch_1):page51_i111:A12" )
				( attribute "RELATIVE_PROPAGATION_DELAY_SCOPE" "G"
					( Parent
						( matchGroupRef "@crescent_city_bb_fab1_lib.crescent_city_bb_fab1(sch_1):\MG_DDR_FAR_DIMM-CLK0_CLS_DDR_E_CAC-CLKS\" )
					)
					( Status sCSetFlattened )
					( Origin gBackEnd )
				)
				( attribute "RELATIVE_PROPAGATION_DELAY" "0.00 MIL,700.00 MIL"
					( Parent
						( matchGroupRef "@crescent_city_bb_fab1_lib.crescent_city_bb_fab1(sch_1):\MG_DDR_FAR_DIMM-CLK0_CLS_DDR_E_CAC-CLKS\" )
					)
					( Units "uMatchProp" "ns" 1.000000)
					( Status sCSetFlattened )
					( Origin gBackEnd )
				)
				( attribute "RELATIVE_PROPAGATION_DELAY_SCOPE" "G"
					( Parent
						( matchGroupRef "@baseboard_fab2_lib.baseboard_fab2(sch_1):\MG_DDR_FAR_DIMM_CMD_NG_DDR_E_DLL_11\" )
					)
					( Status sCSetFlattened )
					( Origin gBackEnd )
				)
				( attribute "RELATIVE_PROPAGATION_DELAY" "0.00 MIL,25.00 MIL"
					( Parent
						( matchGroupRef "@baseboard_fab2_lib.baseboard_fab2(sch_1):\MG_DDR_FAR_DIMM_CMD_NG_DDR_E_DLL_11\" )
					)
					( Units "uMatchProp" "ns" 1.000000)
					( Status sCSetFlattened )
					( Origin gBackEnd )
				)
			)
			( pinPair "@baseboard_fab2_lib.baseboard_fab2(sch_1):\PP3756\"
				( pinRef "@baseboard_fab2_lib.baseboard_fab2(sch_1):page52_i12:A12" )
				( pinRef "@baseboard_fab2_lib.baseboard_fab2(sch_1):page27_i172:DDR4_MA(12)" )
				( attribute "RELATIVE_PROPAGATION_DELAY_SCOPE" "G"
					( Parent
						( matchGroupRef "@crescent_city_bb_fab1_lib.crescent_city_bb_fab1(sch_1):\MG_DDR_NEAR_DIMM-CLK1_CLS_DDR_E_CAC-CLKS\" )
					)
					( Status sCSetFlattened )
					( Origin gBackEnd )
				)
				( attribute "RELATIVE_PROPAGATION_DELAY" "0.00 MIL,700.00 MIL"
					( Parent
						( matchGroupRef "@crescent_city_bb_fab1_lib.crescent_city_bb_fab1(sch_1):\MG_DDR_NEAR_DIMM-CLK1_CLS_DDR_E_CAC-CLKS\" )
					)
					( Units "uMatchProp" "ns" 1.000000)
					( Status sCSetFlattened )
					( Origin gBackEnd )
				)
				( attribute "RELATIVE_PROPAGATION_DELAY_SCOPE" "G"
					( Parent
						( matchGroupRef "@baseboard_fab2_lib.baseboard_fab2(sch_1):\MG_DDR_CMD_NEAR_DIMM_NG_DDR_E_DLL_11\" )
					)
					( Status sCSetFlattened )
					( Origin gBackEnd )
				)
				( attribute "RELATIVE_PROPAGATION_DELAY" "0.00 MIL,25.00 MIL"
					( Parent
						( matchGroupRef "@baseboard_fab2_lib.baseboard_fab2(sch_1):\MG_DDR_CMD_NEAR_DIMM_NG_DDR_E_DLL_11\" )
					)
					( Units "uMatchProp" "ns" 1.000000)
					( Status sCSetFlattened )
					( Origin gBackEnd )
				)
			)
			( pinPair "@baseboard_fab2_lib.baseboard_fab2(sch_1):\PP3749\"
				( pinRef "@baseboard_fab2_lib.baseboard_fab2(sch_1):page27_i172:DDR4_BG(1)" )
				( pinRef "@baseboard_fab2_lib.baseboard_fab2(sch_1):page51_i111:BG(1)" )
				( attribute "RELATIVE_PROPAGATION_DELAY_SCOPE" "G"
					( Parent
						( matchGroupRef "@crescent_city_bb_fab1_lib.crescent_city_bb_fab1(sch_1):\MG_DDR_FAR_DIMM-CLK0_CLS_DDR_E_CAC-CLKS\" )
					)
					( Status sCSetFlattened )
					( Origin gBackEnd )
				)
				( attribute "RELATIVE_PROPAGATION_DELAY" "0.00 MIL,700.00 MIL"
					( Parent
						( matchGroupRef "@crescent_city_bb_fab1_lib.crescent_city_bb_fab1(sch_1):\MG_DDR_FAR_DIMM-CLK0_CLS_DDR_E_CAC-CLKS\" )
					)
					( Units "uMatchProp" "ns" 1.000000)
					( Status sCSetFlattened )
					( Origin gBackEnd )
				)
				( attribute "RELATIVE_PROPAGATION_DELAY_SCOPE" "G"
					( Parent
						( matchGroupRef "@baseboard_fab2_lib.baseboard_fab2(sch_1):\MG_DDR_FAR_DIMM_CMD_NG_DDR_E_DLL_12\" )
					)
					( Status sCSetFlattened )
					( Origin gBackEnd )
				)
				( attribute "RELATIVE_PROPAGATION_DELAY" "0.00 MIL,25.00 MIL"
					( Parent
						( matchGroupRef "@baseboard_fab2_lib.baseboard_fab2(sch_1):\MG_DDR_FAR_DIMM_CMD_NG_DDR_E_DLL_12\" )
					)
					( Units "uMatchProp" "ns" 1.000000)
					( Status sCSetFlattened )
					( Origin gBackEnd )
				)
			)
			( pinPair "@baseboard_fab2_lib.baseboard_fab2(sch_1):\PP3750\"
				( pinRef "@baseboard_fab2_lib.baseboard_fab2(sch_1):page52_i12:BG(1)" )
				( pinRef "@baseboard_fab2_lib.baseboard_fab2(sch_1):page27_i172:DDR4_BG(1)" )
				( attribute "RELATIVE_PROPAGATION_DELAY_SCOPE" "G"
					( Parent
						( matchGroupRef "@crescent_city_bb_fab1_lib.crescent_city_bb_fab1(sch_1):\MG_DDR_NEAR_DIMM-CLK1_CLS_DDR_E_CAC-CLKS\" )
					)
					( Status sCSetFlattened )
					( Origin gBackEnd )
				)
				( attribute "RELATIVE_PROPAGATION_DELAY" "0.00 MIL,700.00 MIL"
					( Parent
						( matchGroupRef "@crescent_city_bb_fab1_lib.crescent_city_bb_fab1(sch_1):\MG_DDR_NEAR_DIMM-CLK1_CLS_DDR_E_CAC-CLKS\" )
					)
					( Units "uMatchProp" "ns" 1.000000)
					( Status sCSetFlattened )
					( Origin gBackEnd )
				)
				( attribute "RELATIVE_PROPAGATION_DELAY_SCOPE" "G"
					( Parent
						( matchGroupRef "@baseboard_fab2_lib.baseboard_fab2(sch_1):\MG_DDR_CMD_NEAR_DIMM_NG_DDR_E_DLL_12\" )
					)
					( Status sCSetFlattened )
					( Origin gBackEnd )
				)
				( attribute "RELATIVE_PROPAGATION_DELAY" "0.00 MIL,25.00 MIL"
					( Parent
						( matchGroupRef "@baseboard_fab2_lib.baseboard_fab2(sch_1):\MG_DDR_CMD_NEAR_DIMM_NG_DDR_E_DLL_12\" )
					)
					( Units "uMatchProp" "ns" 1.000000)
					( Status sCSetFlattened )
					( Origin gBackEnd )
				)
			)
			( pinPair "@baseboard_fab2_lib.baseboard_fab2(sch_1):\PP3751\"
				( pinRef "@baseboard_fab2_lib.baseboard_fab2(sch_1):page27_i172:DDR4_MA(11)" )
				( pinRef "@baseboard_fab2_lib.baseboard_fab2(sch_1):page51_i111:A11" )
				( attribute "RELATIVE_PROPAGATION_DELAY_SCOPE" "G"
					( Parent
						( matchGroupRef "@crescent_city_bb_fab1_lib.crescent_city_bb_fab1(sch_1):\MG_DDR_FAR_DIMM-CLK0_CLS_DDR_E_CAC-CLKS\" )
					)
					( Status sCSetFlattened )
					( Origin gBackEnd )
				)
				( attribute "RELATIVE_PROPAGATION_DELAY" "0.00 MIL,700.00 MIL"
					( Parent
						( matchGroupRef "@crescent_city_bb_fab1_lib.crescent_city_bb_fab1(sch_1):\MG_DDR_FAR_DIMM-CLK0_CLS_DDR_E_CAC-CLKS\" )
					)
					( Units "uMatchProp" "ns" 1.000000)
					( Status sCSetFlattened )
					( Origin gBackEnd )
				)
				( attribute "RELATIVE_PROPAGATION_DELAY_SCOPE" "G"
					( Parent
						( matchGroupRef "@baseboard_fab2_lib.baseboard_fab2(sch_1):\MG_DDR_FAR_DIMM_CMD_NG_DDR_E_DLL_12\" )
					)
					( Status sCSetFlattened )
					( Origin gBackEnd )
				)
				( attribute "RELATIVE_PROPAGATION_DELAY" "0.00 MIL,25.00 MIL"
					( Parent
						( matchGroupRef "@baseboard_fab2_lib.baseboard_fab2(sch_1):\MG_DDR_FAR_DIMM_CMD_NG_DDR_E_DLL_12\" )
					)
					( Units "uMatchProp" "ns" 1.000000)
					( Status sCSetFlattened )
					( Origin gBackEnd )
				)
			)
			( pinPair "@baseboard_fab2_lib.baseboard_fab2(sch_1):\PP3752\"
				( pinRef "@baseboard_fab2_lib.baseboard_fab2(sch_1):page52_i12:A11" )
				( pinRef "@baseboard_fab2_lib.baseboard_fab2(sch_1):page27_i172:DDR4_MA(11)" )
				( attribute "RELATIVE_PROPAGATION_DELAY_SCOPE" "G"
					( Parent
						( matchGroupRef "@crescent_city_bb_fab1_lib.crescent_city_bb_fab1(sch_1):\MG_DDR_NEAR_DIMM-CLK1_CLS_DDR_E_CAC-CLKS\" )
					)
					( Status sCSetFlattened )
					( Origin gBackEnd )
				)
				( attribute "RELATIVE_PROPAGATION_DELAY" "0.00 MIL,700.00 MIL"
					( Parent
						( matchGroupRef "@crescent_city_bb_fab1_lib.crescent_city_bb_fab1(sch_1):\MG_DDR_NEAR_DIMM-CLK1_CLS_DDR_E_CAC-CLKS\" )
					)
					( Units "uMatchProp" "ns" 1.000000)
					( Status sCSetFlattened )
					( Origin gBackEnd )
				)
				( attribute "RELATIVE_PROPAGATION_DELAY_SCOPE" "G"
					( Parent
						( matchGroupRef "@baseboard_fab2_lib.baseboard_fab2(sch_1):\MG_DDR_CMD_NEAR_DIMM_NG_DDR_E_DLL_12\" )
					)
					( Status sCSetFlattened )
					( Origin gBackEnd )
				)
				( attribute "RELATIVE_PROPAGATION_DELAY" "0.00 MIL,25.00 MIL"
					( Parent
						( matchGroupRef "@baseboard_fab2_lib.baseboard_fab2(sch_1):\MG_DDR_CMD_NEAR_DIMM_NG_DDR_E_DLL_12\" )
					)
					( Units "uMatchProp" "ns" 1.000000)
					( Status sCSetFlattened )
					( Origin gBackEnd )
				)
			)
			( pinPair "@baseboard_fab2_lib.baseboard_fab2(sch_1):\PP3745\"
				( pinRef "@baseboard_fab2_lib.baseboard_fab2(sch_1):page27_i172:DDR4_ACT_N" )
				( pinRef "@baseboard_fab2_lib.baseboard_fab2(sch_1):page51_i111:ACT_N" )
				( attribute "RELATIVE_PROPAGATION_DELAY_SCOPE" "G"
					( Parent
						( matchGroupRef "@crescent_city_bb_fab1_lib.crescent_city_bb_fab1(sch_1):\MG_DDR_FAR_DIMM-CLK0_CLS_DDR_E_CAC-CLKS\" )
					)
					( Status sCSetFlattened )
					( Origin gBackEnd )
				)
				( attribute "RELATIVE_PROPAGATION_DELAY" "0.00 MIL,700.00 MIL"
					( Parent
						( matchGroupRef "@crescent_city_bb_fab1_lib.crescent_city_bb_fab1(sch_1):\MG_DDR_FAR_DIMM-CLK0_CLS_DDR_E_CAC-CLKS\" )
					)
					( Units "uMatchProp" "ns" 1.000000)
					( Status sCSetFlattened )
					( Origin gBackEnd )
				)
				( attribute "RELATIVE_PROPAGATION_DELAY_SCOPE" "G"
					( Parent
						( matchGroupRef "@baseboard_fab2_lib.baseboard_fab2(sch_1):\MG_DDR_FAR_DIMM_CMD_NG_DDR_E_DLL_13\" )
					)
					( Status sCSetFlattened )
					( Origin gBackEnd )
				)
				( attribute "RELATIVE_PROPAGATION_DELAY" "0.00 MIL,25.00 MIL"
					( Parent
						( matchGroupRef "@baseboard_fab2_lib.baseboard_fab2(sch_1):\MG_DDR_FAR_DIMM_CMD_NG_DDR_E_DLL_13\" )
					)
					( Units "uMatchProp" "ns" 1.000000)
					( Status sCSetFlattened )
					( Origin gBackEnd )
				)
			)
			( pinPair "@baseboard_fab2_lib.baseboard_fab2(sch_1):\PP3746\"
				( pinRef "@baseboard_fab2_lib.baseboard_fab2(sch_1):page52_i12:ACT_N" )
				( pinRef "@baseboard_fab2_lib.baseboard_fab2(sch_1):page27_i172:DDR4_ACT_N" )
				( attribute "RELATIVE_PROPAGATION_DELAY_SCOPE" "G"
					( Parent
						( matchGroupRef "@crescent_city_bb_fab1_lib.crescent_city_bb_fab1(sch_1):\MG_DDR_NEAR_DIMM-CLK1_CLS_DDR_E_CAC-CLKS\" )
					)
					( Status sCSetFlattened )
					( Origin gBackEnd )
				)
				( attribute "RELATIVE_PROPAGATION_DELAY" "0.00 MIL,700.00 MIL"
					( Parent
						( matchGroupRef "@crescent_city_bb_fab1_lib.crescent_city_bb_fab1(sch_1):\MG_DDR_NEAR_DIMM-CLK1_CLS_DDR_E_CAC-CLKS\" )
					)
					( Units "uMatchProp" "ns" 1.000000)
					( Status sCSetFlattened )
					( Origin gBackEnd )
				)
				( attribute "RELATIVE_PROPAGATION_DELAY_SCOPE" "G"
					( Parent
						( matchGroupRef "@baseboard_fab2_lib.baseboard_fab2(sch_1):\MG_DDR_CMD_NEAR_DIMM_NG_DDR_E_DLL_13\" )
					)
					( Status sCSetFlattened )
					( Origin gBackEnd )
				)
				( attribute "RELATIVE_PROPAGATION_DELAY" "0.00 MIL,25.00 MIL"
					( Parent
						( matchGroupRef "@baseboard_fab2_lib.baseboard_fab2(sch_1):\MG_DDR_CMD_NEAR_DIMM_NG_DDR_E_DLL_13\" )
					)
					( Units "uMatchProp" "ns" 1.000000)
					( Status sCSetFlattened )
					( Origin gBackEnd )
				)
			)
			( pinPair "@baseboard_fab2_lib.baseboard_fab2(sch_1):\PP3747\"
				( pinRef "@baseboard_fab2_lib.baseboard_fab2(sch_1):page27_i172:DDR4_BG(0)" )
				( pinRef "@baseboard_fab2_lib.baseboard_fab2(sch_1):page51_i111:BG(0)" )
				( attribute "RELATIVE_PROPAGATION_DELAY_SCOPE" "G"
					( Parent
						( matchGroupRef "@crescent_city_bb_fab1_lib.crescent_city_bb_fab1(sch_1):\MG_DDR_FAR_DIMM-CLK0_CLS_DDR_E_CAC-CLKS\" )
					)
					( Status sCSetFlattened )
					( Origin gBackEnd )
				)
				( attribute "RELATIVE_PROPAGATION_DELAY" "0.00 MIL,700.00 MIL"
					( Parent
						( matchGroupRef "@crescent_city_bb_fab1_lib.crescent_city_bb_fab1(sch_1):\MG_DDR_FAR_DIMM-CLK0_CLS_DDR_E_CAC-CLKS\" )
					)
					( Units "uMatchProp" "ns" 1.000000)
					( Status sCSetFlattened )
					( Origin gBackEnd )
				)
				( attribute "RELATIVE_PROPAGATION_DELAY_SCOPE" "G"
					( Parent
						( matchGroupRef "@baseboard_fab2_lib.baseboard_fab2(sch_1):\MG_DDR_FAR_DIMM_CMD_NG_DDR_E_DLL_13\" )
					)
					( Status sCSetFlattened )
					( Origin gBackEnd )
				)
				( attribute "RELATIVE_PROPAGATION_DELAY" "0.00 MIL,25.00 MIL"
					( Parent
						( matchGroupRef "@baseboard_fab2_lib.baseboard_fab2(sch_1):\MG_DDR_FAR_DIMM_CMD_NG_DDR_E_DLL_13\" )
					)
					( Units "uMatchProp" "ns" 1.000000)
					( Status sCSetFlattened )
					( Origin gBackEnd )
				)
			)
			( pinPair "@baseboard_fab2_lib.baseboard_fab2(sch_1):\PP3748\"
				( pinRef "@baseboard_fab2_lib.baseboard_fab2(sch_1):page52_i12:BG(0)" )
				( pinRef "@baseboard_fab2_lib.baseboard_fab2(sch_1):page27_i172:DDR4_BG(0)" )
				( attribute "RELATIVE_PROPAGATION_DELAY_SCOPE" "G"
					( Parent
						( matchGroupRef "@crescent_city_bb_fab1_lib.crescent_city_bb_fab1(sch_1):\MG_DDR_NEAR_DIMM-CLK1_CLS_DDR_E_CAC-CLKS\" )
					)
					( Status sCSetFlattened )
					( Origin gBackEnd )
				)
				( attribute "RELATIVE_PROPAGATION_DELAY" "0.00 MIL,700.00 MIL"
					( Parent
						( matchGroupRef "@crescent_city_bb_fab1_lib.crescent_city_bb_fab1(sch_1):\MG_DDR_NEAR_DIMM-CLK1_CLS_DDR_E_CAC-CLKS\" )
					)
					( Units "uMatchProp" "ns" 1.000000)
					( Status sCSetFlattened )
					( Origin gBackEnd )
				)
				( attribute "RELATIVE_PROPAGATION_DELAY_SCOPE" "G"
					( Parent
						( matchGroupRef "@baseboard_fab2_lib.baseboard_fab2(sch_1):\MG_DDR_CMD_NEAR_DIMM_NG_DDR_E_DLL_13\" )
					)
					( Status sCSetFlattened )
					( Origin gBackEnd )
				)
				( attribute "RELATIVE_PROPAGATION_DELAY" "0.00 MIL,25.00 MIL"
					( Parent
						( matchGroupRef "@baseboard_fab2_lib.baseboard_fab2(sch_1):\MG_DDR_CMD_NEAR_DIMM_NG_DDR_E_DLL_13\" )
					)
					( Units "uMatchProp" "ns" 1.000000)
					( Status sCSetFlattened )
					( Origin gBackEnd )
				)
			)
			( pinPair "@baseboard_fab2_lib.baseboard_fab2(sch_1):\PP3743\"
				( pinRef "@baseboard_fab2_lib.baseboard_fab2(sch_1):page51_i111:S0_N" )
				( pinRef "@baseboard_fab2_lib.baseboard_fab2(sch_1):page27_i172:DDR4_CS_N(0)" )
				( attribute "RELATIVE_PROPAGATION_DELAY_SCOPE" "G"
					( Parent
						( matchGroupRef "@crescent_city_bb_fab1_lib.crescent_city_bb_fab1(sch_1):\MG_DDR_FAR_DIMM-CLK0_CLS_DDR_E_CAC-CLKS\" )
					)
					( Status sCSetFlattened )
					( Origin gBackEnd )
				)
				( attribute "RELATIVE_PROPAGATION_DELAY" "0.00 MIL,300.00 MIL"
					( Parent
						( matchGroupRef "@crescent_city_bb_fab1_lib.crescent_city_bb_fab1(sch_1):\MG_DDR_FAR_DIMM-CLK0_CLS_DDR_E_CAC-CLKS\" )
					)
					( Units "uMatchProp" "ns" 1.000000)
					( Status sCSetFlattened )
					( Origin gBackEnd )
				)
				( attribute "RELATIVE_PROPAGATION_DELAY_SCOPE" "G"
					( Parent
						( matchGroupRef "@baseboard_fab2_lib.baseboard_fab2(sch_1):\MG_DDR_CTRL_NG_DDR_E_DLL_14\" )
					)
					( Status sCSetFlattened )
					( Origin gBackEnd )
				)
				( attribute "RELATIVE_PROPAGATION_DELAY" "0.00 MIL,25.00 MIL"
					( Parent
						( matchGroupRef "@baseboard_fab2_lib.baseboard_fab2(sch_1):\MG_DDR_CTRL_NG_DDR_E_DLL_14\" )
					)
					( Units "uMatchProp" "ns" 1.000000)
					( Status sCSetFlattened )
					( Origin gBackEnd )
				)
			)
			( pinPair "@baseboard_fab2_lib.baseboard_fab2(sch_1):\PP3744\"
				( pinRef "@baseboard_fab2_lib.baseboard_fab2(sch_1):page51_i111:ODT(0)" )
				( pinRef "@baseboard_fab2_lib.baseboard_fab2(sch_1):page27_i172:DDR4_ODT(0)" )
				( attribute "RELATIVE_PROPAGATION_DELAY_SCOPE" "G"
					( Parent
						( matchGroupRef "@crescent_city_bb_fab1_lib.crescent_city_bb_fab1(sch_1):\MG_DDR_FAR_DIMM-CLK0_CLS_DDR_E_CAC-CLKS\" )
					)
					( Status sCSetFlattened )
					( Origin gBackEnd )
				)
				( attribute "RELATIVE_PROPAGATION_DELAY" "0.00 MIL,300.00 MIL"
					( Parent
						( matchGroupRef "@crescent_city_bb_fab1_lib.crescent_city_bb_fab1(sch_1):\MG_DDR_FAR_DIMM-CLK0_CLS_DDR_E_CAC-CLKS\" )
					)
					( Units "uMatchProp" "ns" 1.000000)
					( Status sCSetFlattened )
					( Origin gBackEnd )
				)
				( attribute "RELATIVE_PROPAGATION_DELAY_SCOPE" "G"
					( Parent
						( matchGroupRef "@baseboard_fab2_lib.baseboard_fab2(sch_1):\MG_DDR_CTRL_NG_DDR_E_DLL_14\" )
					)
					( Status sCSetFlattened )
					( Origin gBackEnd )
				)
				( attribute "RELATIVE_PROPAGATION_DELAY" "0.00 MIL,25.00 MIL"
					( Parent
						( matchGroupRef "@baseboard_fab2_lib.baseboard_fab2(sch_1):\MG_DDR_CTRL_NG_DDR_E_DLL_14\" )
					)
					( Units "uMatchProp" "ns" 1.000000)
					( Status sCSetFlattened )
					( Origin gBackEnd )
				)
			)
			( pinPair "@baseboard_fab2_lib.baseboard_fab2(sch_1):\PP3742\"
				( pinRef "@baseboard_fab2_lib.baseboard_fab2(sch_1):page51_i111:CKE(0)" )
				( pinRef "@baseboard_fab2_lib.baseboard_fab2(sch_1):page27_i172:DDR4_CKE(0)" )
				( attribute "RELATIVE_PROPAGATION_DELAY_SCOPE" "G"
					( Parent
						( matchGroupRef "@crescent_city_bb_fab1_lib.crescent_city_bb_fab1(sch_1):\MG_DDR_FAR_DIMM-CLK0_CLS_DDR_E_CAC-CLKS\" )
					)
					( Status sCSetFlattened )
					( Origin gBackEnd )
				)
				( attribute "RELATIVE_PROPAGATION_DELAY" "0.00 MIL,300.00 MIL"
					( Parent
						( matchGroupRef "@crescent_city_bb_fab1_lib.crescent_city_bb_fab1(sch_1):\MG_DDR_FAR_DIMM-CLK0_CLS_DDR_E_CAC-CLKS\" )
					)
					( Units "uMatchProp" "ns" 1.000000)
					( Status sCSetFlattened )
					( Origin gBackEnd )
				)
				( attribute "RELATIVE_PROPAGATION_DELAY_SCOPE" "G"
					( Parent
						( matchGroupRef "@baseboard_fab2_lib.baseboard_fab2(sch_1):\MG_DDR_CTRL_NG_DDR_E_DLL_15\" )
					)
					( Status sCSetFlattened )
					( Origin gBackEnd )
				)
				( attribute "RELATIVE_PROPAGATION_DELAY" "0.00 MIL,25.00 MIL"
					( Parent
						( matchGroupRef "@baseboard_fab2_lib.baseboard_fab2(sch_1):\MG_DDR_CTRL_NG_DDR_E_DLL_15\" )
					)
					( Units "uMatchProp" "ns" 1.000000)
					( Status sCSetFlattened )
					( Origin gBackEnd )
				)
			)
			( pinPair "@baseboard_fab2_lib.baseboard_fab2(sch_1):\PP3741\"
				( pinRef "@baseboard_fab2_lib.baseboard_fab2(sch_1):page51_i111:S2_N_C(0)" )
				( pinRef "@baseboard_fab2_lib.baseboard_fab2(sch_1):page27_i172:DDR4_CS_N(2)" )
				( attribute "RELATIVE_PROPAGATION_DELAY_SCOPE" "G"
					( Parent
						( matchGroupRef "@crescent_city_bb_fab1_lib.crescent_city_bb_fab1(sch_1):\MG_DDR_FAR_DIMM-CLK0_CLS_DDR_E_CAC-CLKS\" )
					)
					( Status sCSetFlattened )
					( Origin gBackEnd )
				)
				( attribute "RELATIVE_PROPAGATION_DELAY" "0.00 MIL,300.00 MIL"
					( Parent
						( matchGroupRef "@crescent_city_bb_fab1_lib.crescent_city_bb_fab1(sch_1):\MG_DDR_FAR_DIMM-CLK0_CLS_DDR_E_CAC-CLKS\" )
					)
					( Units "uMatchProp" "ns" 1.000000)
					( Status sCSetFlattened )
					( Origin gBackEnd )
				)
				( attribute "RELATIVE_PROPAGATION_DELAY_SCOPE" "G"
					( Parent
						( matchGroupRef "@baseboard_fab2_lib.baseboard_fab2(sch_1):\MG_DDR_CTRL_NG_DDR_E_DLL_16\" )
					)
					( Status sCSetFlattened )
					( Origin gBackEnd )
				)
				( attribute "RELATIVE_PROPAGATION_DELAY" "0.00 MIL,25.00 MIL"
					( Parent
						( matchGroupRef "@baseboard_fab2_lib.baseboard_fab2(sch_1):\MG_DDR_CTRL_NG_DDR_E_DLL_16\" )
					)
					( Units "uMatchProp" "ns" 1.000000)
					( Status sCSetFlattened )
					( Origin gBackEnd )
				)
			)
			( pinPair "@baseboard_fab2_lib.baseboard_fab2(sch_1):\PP3740\"
				( pinRef "@baseboard_fab2_lib.baseboard_fab2(sch_1):page51_i111:S3_N_C(1)" )
				( pinRef "@baseboard_fab2_lib.baseboard_fab2(sch_1):page27_i172:DDR4_CS_N(3)" )
				( attribute "RELATIVE_PROPAGATION_DELAY_SCOPE" "G"
					( Parent
						( matchGroupRef "@crescent_city_bb_fab1_lib.crescent_city_bb_fab1(sch_1):\MG_DDR_FAR_DIMM-CLK0_CLS_DDR_E_CAC-CLKS\" )
					)
					( Status sCSetFlattened )
					( Origin gBackEnd )
				)
				( attribute "RELATIVE_PROPAGATION_DELAY" "0.00 MIL,300.00 MIL"
					( Parent
						( matchGroupRef "@crescent_city_bb_fab1_lib.crescent_city_bb_fab1(sch_1):\MG_DDR_FAR_DIMM-CLK0_CLS_DDR_E_CAC-CLKS\" )
					)
					( Units "uMatchProp" "ns" 1.000000)
					( Status sCSetFlattened )
					( Origin gBackEnd )
				)
				( attribute "RELATIVE_PROPAGATION_DELAY_SCOPE" "G"
					( Parent
						( matchGroupRef "@baseboard_fab2_lib.baseboard_fab2(sch_1):\MG_DDR_CTRL_NG_DDR_E_DLL_17\" )
					)
					( Status sCSetFlattened )
					( Origin gBackEnd )
				)
				( attribute "RELATIVE_PROPAGATION_DELAY" "0.00 MIL,25.00 MIL"
					( Parent
						( matchGroupRef "@baseboard_fab2_lib.baseboard_fab2(sch_1):\MG_DDR_CTRL_NG_DDR_E_DLL_17\" )
					)
					( Units "uMatchProp" "ns" 1.000000)
					( Status sCSetFlattened )
					( Origin gBackEnd )
				)
			)
			( pinPair "@baseboard_fab2_lib.baseboard_fab2(sch_1):\PP3738\"
				( pinRef "@baseboard_fab2_lib.baseboard_fab2(sch_1):page51_i111:S1_N" )
				( pinRef "@baseboard_fab2_lib.baseboard_fab2(sch_1):page27_i172:DDR4_CS_N(1)" )
				( attribute "RELATIVE_PROPAGATION_DELAY_SCOPE" "G"
					( Parent
						( matchGroupRef "@crescent_city_bb_fab1_lib.crescent_city_bb_fab1(sch_1):\MG_DDR_FAR_DIMM-CLK0_CLS_DDR_E_CAC-CLKS\" )
					)
					( Status sCSetFlattened )
					( Origin gBackEnd )
				)
				( attribute "RELATIVE_PROPAGATION_DELAY" "0.00 MIL,300.00 MIL"
					( Parent
						( matchGroupRef "@crescent_city_bb_fab1_lib.crescent_city_bb_fab1(sch_1):\MG_DDR_FAR_DIMM-CLK0_CLS_DDR_E_CAC-CLKS\" )
					)
					( Units "uMatchProp" "ns" 1.000000)
					( Status sCSetFlattened )
					( Origin gBackEnd )
				)
				( attribute "RELATIVE_PROPAGATION_DELAY_SCOPE" "G"
					( Parent
						( matchGroupRef "@baseboard_fab2_lib.baseboard_fab2(sch_1):\MG_DDR_CTRL_NG_DDR_E_DLL_18\" )
					)
					( Status sCSetFlattened )
					( Origin gBackEnd )
				)
				( attribute "RELATIVE_PROPAGATION_DELAY" "0.00 MIL,25.00 MIL"
					( Parent
						( matchGroupRef "@baseboard_fab2_lib.baseboard_fab2(sch_1):\MG_DDR_CTRL_NG_DDR_E_DLL_18\" )
					)
					( Units "uMatchProp" "ns" 1.000000)
					( Status sCSetFlattened )
					( Origin gBackEnd )
				)
			)
			( pinPair "@baseboard_fab2_lib.baseboard_fab2(sch_1):\PP3739\"
				( pinRef "@baseboard_fab2_lib.baseboard_fab2(sch_1):page51_i111:ODT(1)" )
				( pinRef "@baseboard_fab2_lib.baseboard_fab2(sch_1):page27_i172:DDR4_ODT(1)" )
				( attribute "RELATIVE_PROPAGATION_DELAY_SCOPE" "G"
					( Parent
						( matchGroupRef "@crescent_city_bb_fab1_lib.crescent_city_bb_fab1(sch_1):\MG_DDR_FAR_DIMM-CLK0_CLS_DDR_E_CAC-CLKS\" )
					)
					( Status sCSetFlattened )
					( Origin gBackEnd )
				)
				( attribute "RELATIVE_PROPAGATION_DELAY" "0.00 MIL,300.00 MIL"
					( Parent
						( matchGroupRef "@crescent_city_bb_fab1_lib.crescent_city_bb_fab1(sch_1):\MG_DDR_FAR_DIMM-CLK0_CLS_DDR_E_CAC-CLKS\" )
					)
					( Units "uMatchProp" "ns" 1.000000)
					( Status sCSetFlattened )
					( Origin gBackEnd )
				)
				( attribute "RELATIVE_PROPAGATION_DELAY_SCOPE" "G"
					( Parent
						( matchGroupRef "@baseboard_fab2_lib.baseboard_fab2(sch_1):\MG_DDR_CTRL_NG_DDR_E_DLL_18\" )
					)
					( Status sCSetFlattened )
					( Origin gBackEnd )
				)
				( attribute "RELATIVE_PROPAGATION_DELAY" "0.00 MIL,25.00 MIL"
					( Parent
						( matchGroupRef "@baseboard_fab2_lib.baseboard_fab2(sch_1):\MG_DDR_CTRL_NG_DDR_E_DLL_18\" )
					)
					( Units "uMatchProp" "ns" 1.000000)
					( Status sCSetFlattened )
					( Origin gBackEnd )
				)
			)
			( pinPair "@baseboard_fab2_lib.baseboard_fab2(sch_1):\PP3737\"
				( pinRef "@baseboard_fab2_lib.baseboard_fab2(sch_1):page51_i111:CKE(1)" )
				( pinRef "@baseboard_fab2_lib.baseboard_fab2(sch_1):page27_i172:DDR4_CKE(1)" )
				( attribute "RELATIVE_PROPAGATION_DELAY_SCOPE" "G"
					( Parent
						( matchGroupRef "@crescent_city_bb_fab1_lib.crescent_city_bb_fab1(sch_1):\MG_DDR_FAR_DIMM-CLK0_CLS_DDR_E_CAC-CLKS\" )
					)
					( Status sCSetFlattened )
					( Origin gBackEnd )
				)
				( attribute "RELATIVE_PROPAGATION_DELAY" "0.00 MIL,300.00 MIL"
					( Parent
						( matchGroupRef "@crescent_city_bb_fab1_lib.crescent_city_bb_fab1(sch_1):\MG_DDR_FAR_DIMM-CLK0_CLS_DDR_E_CAC-CLKS\" )
					)
					( Units "uMatchProp" "ns" 1.000000)
					( Status sCSetFlattened )
					( Origin gBackEnd )
				)
				( attribute "RELATIVE_PROPAGATION_DELAY_SCOPE" "G"
					( Parent
						( matchGroupRef "@baseboard_fab2_lib.baseboard_fab2(sch_1):\MG_DDR_CTRL_NG_DDR_E_DLL_19\" )
					)
					( Status sCSetFlattened )
					( Origin gBackEnd )
				)
				( attribute "RELATIVE_PROPAGATION_DELAY" "0.00 MIL,25.00 MIL"
					( Parent
						( matchGroupRef "@baseboard_fab2_lib.baseboard_fab2(sch_1):\MG_DDR_CTRL_NG_DDR_E_DLL_19\" )
					)
					( Units "uMatchProp" "ns" 1.000000)
					( Status sCSetFlattened )
					( Origin gBackEnd )
				)
			)
			( pinPair "@baseboard_fab2_lib.baseboard_fab2(sch_1):\PP3735\"
				( pinRef "@baseboard_fab2_lib.baseboard_fab2(sch_1):page52_i12:S0_N" )
				( pinRef "@baseboard_fab2_lib.baseboard_fab2(sch_1):page27_i172:DDR4_CS_N(4)" )
				( attribute "RELATIVE_PROPAGATION_DELAY_SCOPE" "G"
					( Parent
						( matchGroupRef "@crescent_city_bb_fab1_lib.crescent_city_bb_fab1(sch_1):\MG_DDR_NEAR_DIMM-CLK1_CLS_DDR_E_CAC-CLKS\" )
					)
					( Status sCSetFlattened )
					( Origin gBackEnd )
				)
				( attribute "RELATIVE_PROPAGATION_DELAY" "0.00 MIL,300.00 MIL"
					( Parent
						( matchGroupRef "@crescent_city_bb_fab1_lib.crescent_city_bb_fab1(sch_1):\MG_DDR_NEAR_DIMM-CLK1_CLS_DDR_E_CAC-CLKS\" )
					)
					( Units "uMatchProp" "ns" 1.000000)
					( Status sCSetFlattened )
					( Origin gBackEnd )
				)
				( attribute "RELATIVE_PROPAGATION_DELAY_SCOPE" "G"
					( Parent
						( matchGroupRef "@baseboard_fab2_lib.baseboard_fab2(sch_1):\MG_DDR_CTRL_NG_DDR_E_DLL_20\" )
					)
					( Status sCSetFlattened )
					( Origin gBackEnd )
				)
				( attribute "RELATIVE_PROPAGATION_DELAY" "0.00 MIL,25.00 MIL"
					( Parent
						( matchGroupRef "@baseboard_fab2_lib.baseboard_fab2(sch_1):\MG_DDR_CTRL_NG_DDR_E_DLL_20\" )
					)
					( Units "uMatchProp" "ns" 1.000000)
					( Status sCSetFlattened )
					( Origin gBackEnd )
				)
			)
			( pinPair "@baseboard_fab2_lib.baseboard_fab2(sch_1):\PP3736\"
				( pinRef "@baseboard_fab2_lib.baseboard_fab2(sch_1):page52_i12:ODT(0)" )
				( pinRef "@baseboard_fab2_lib.baseboard_fab2(sch_1):page27_i172:DDR4_ODT(2)" )
				( attribute "RELATIVE_PROPAGATION_DELAY_SCOPE" "G"
					( Parent
						( matchGroupRef "@crescent_city_bb_fab1_lib.crescent_city_bb_fab1(sch_1):\MG_DDR_NEAR_DIMM-CLK1_CLS_DDR_E_CAC-CLKS\" )
					)
					( Status sCSetFlattened )
					( Origin gBackEnd )
				)
				( attribute "RELATIVE_PROPAGATION_DELAY" "0.00 MIL,300.00 MIL"
					( Parent
						( matchGroupRef "@crescent_city_bb_fab1_lib.crescent_city_bb_fab1(sch_1):\MG_DDR_NEAR_DIMM-CLK1_CLS_DDR_E_CAC-CLKS\" )
					)
					( Units "uMatchProp" "ns" 1.000000)
					( Status sCSetFlattened )
					( Origin gBackEnd )
				)
				( attribute "RELATIVE_PROPAGATION_DELAY_SCOPE" "G"
					( Parent
						( matchGroupRef "@baseboard_fab2_lib.baseboard_fab2(sch_1):\MG_DDR_CTRL_NG_DDR_E_DLL_20\" )
					)
					( Status sCSetFlattened )
					( Origin gBackEnd )
				)
				( attribute "RELATIVE_PROPAGATION_DELAY" "0.00 MIL,25.00 MIL"
					( Parent
						( matchGroupRef "@baseboard_fab2_lib.baseboard_fab2(sch_1):\MG_DDR_CTRL_NG_DDR_E_DLL_20\" )
					)
					( Units "uMatchProp" "ns" 1.000000)
					( Status sCSetFlattened )
					( Origin gBackEnd )
				)
			)
			( pinPair "@baseboard_fab2_lib.baseboard_fab2(sch_1):\PP3734\"
				( pinRef "@baseboard_fab2_lib.baseboard_fab2(sch_1):page52_i12:CKE(0)" )
				( pinRef "@baseboard_fab2_lib.baseboard_fab2(sch_1):page27_i172:DDR4_CKE(2)" )
				( attribute "RELATIVE_PROPAGATION_DELAY_SCOPE" "G"
					( Parent
						( matchGroupRef "@crescent_city_bb_fab1_lib.crescent_city_bb_fab1(sch_1):\MG_DDR_NEAR_DIMM-CLK1_CLS_DDR_E_CAC-CLKS\" )
					)
					( Status sCSetFlattened )
					( Origin gBackEnd )
				)
				( attribute "RELATIVE_PROPAGATION_DELAY" "0.00 MIL,300.00 MIL"
					( Parent
						( matchGroupRef "@crescent_city_bb_fab1_lib.crescent_city_bb_fab1(sch_1):\MG_DDR_NEAR_DIMM-CLK1_CLS_DDR_E_CAC-CLKS\" )
					)
					( Units "uMatchProp" "ns" 1.000000)
					( Status sCSetFlattened )
					( Origin gBackEnd )
				)
				( attribute "RELATIVE_PROPAGATION_DELAY_SCOPE" "G"
					( Parent
						( matchGroupRef "@baseboard_fab2_lib.baseboard_fab2(sch_1):\MG_DDR_CTRL_NG_DDR_E_DLL_21\" )
					)
					( Status sCSetFlattened )
					( Origin gBackEnd )
				)
				( attribute "RELATIVE_PROPAGATION_DELAY" "0.00 MIL,25.00 MIL"
					( Parent
						( matchGroupRef "@baseboard_fab2_lib.baseboard_fab2(sch_1):\MG_DDR_CTRL_NG_DDR_E_DLL_21\" )
					)
					( Units "uMatchProp" "ns" 1.000000)
					( Status sCSetFlattened )
					( Origin gBackEnd )
				)
			)
			( pinPair "@baseboard_fab2_lib.baseboard_fab2(sch_1):\PP3732\"
				( pinRef "@baseboard_fab2_lib.baseboard_fab2(sch_1):page52_i12:S2_N_C(0)" )
				( pinRef "@baseboard_fab2_lib.baseboard_fab2(sch_1):page27_i172:DDR4_CS_N(6)" )
				( attribute "RELATIVE_PROPAGATION_DELAY_SCOPE" "G"
					( Parent
						( matchGroupRef "@crescent_city_bb_fab1_lib.crescent_city_bb_fab1(sch_1):\MG_DDR_NEAR_DIMM-CLK1_CLS_DDR_E_CAC-CLKS\" )
					)
					( Status sCSetFlattened )
					( Origin gBackEnd )
				)
				( attribute "RELATIVE_PROPAGATION_DELAY" "0.00 MIL,300.00 MIL"
					( Parent
						( matchGroupRef "@crescent_city_bb_fab1_lib.crescent_city_bb_fab1(sch_1):\MG_DDR_NEAR_DIMM-CLK1_CLS_DDR_E_CAC-CLKS\" )
					)
					( Units "uMatchProp" "ns" 1.000000)
					( Status sCSetFlattened )
					( Origin gBackEnd )
				)
				( attribute "RELATIVE_PROPAGATION_DELAY_SCOPE" "G"
					( Parent
						( matchGroupRef "@baseboard_fab2_lib.baseboard_fab2(sch_1):\MG_DDR_CTRL_NG_DDR_E_DLL_22\" )
					)
					( Status sCSetFlattened )
					( Origin gBackEnd )
				)
				( attribute "RELATIVE_PROPAGATION_DELAY" "0.00 MIL,25.00 MIL"
					( Parent
						( matchGroupRef "@baseboard_fab2_lib.baseboard_fab2(sch_1):\MG_DDR_CTRL_NG_DDR_E_DLL_22\" )
					)
					( Units "uMatchProp" "ns" 1.000000)
					( Status sCSetFlattened )
					( Origin gBackEnd )
				)
			)
			( pinPair "@baseboard_fab2_lib.baseboard_fab2(sch_1):\PP3733\"
				( pinRef "@baseboard_fab2_lib.baseboard_fab2(sch_1):page52_i12:S3_N_C(1)" )
				( pinRef "@baseboard_fab2_lib.baseboard_fab2(sch_1):page27_i172:DDR4_CS_N(7)" )
				( attribute "RELATIVE_PROPAGATION_DELAY_SCOPE" "G"
					( Parent
						( matchGroupRef "@crescent_city_bb_fab1_lib.crescent_city_bb_fab1(sch_1):\MG_DDR_NEAR_DIMM-CLK1_CLS_DDR_E_CAC-CLKS\" )
					)
					( Status sCSetFlattened )
					( Origin gBackEnd )
				)
				( attribute "RELATIVE_PROPAGATION_DELAY" "0.00 MIL,300.00 MIL"
					( Parent
						( matchGroupRef "@crescent_city_bb_fab1_lib.crescent_city_bb_fab1(sch_1):\MG_DDR_NEAR_DIMM-CLK1_CLS_DDR_E_CAC-CLKS\" )
					)
					( Units "uMatchProp" "ns" 1.000000)
					( Status sCSetFlattened )
					( Origin gBackEnd )
				)
				( attribute "RELATIVE_PROPAGATION_DELAY_SCOPE" "G"
					( Parent
						( matchGroupRef "@baseboard_fab2_lib.baseboard_fab2(sch_1):\MG_DDR_CTRL_NG_DDR_E_DLL_22\" )
					)
					( Status sCSetFlattened )
					( Origin gBackEnd )
				)
				( attribute "RELATIVE_PROPAGATION_DELAY" "0.00 MIL,25.00 MIL"
					( Parent
						( matchGroupRef "@baseboard_fab2_lib.baseboard_fab2(sch_1):\MG_DDR_CTRL_NG_DDR_E_DLL_22\" )
					)
					( Units "uMatchProp" "ns" 1.000000)
					( Status sCSetFlattened )
					( Origin gBackEnd )
				)
			)
			( pinPair "@baseboard_fab2_lib.baseboard_fab2(sch_1):\PP3730\"
				( pinRef "@baseboard_fab2_lib.baseboard_fab2(sch_1):page52_i12:S1_N" )
				( pinRef "@baseboard_fab2_lib.baseboard_fab2(sch_1):page27_i172:DDR4_CS_N(5)" )
				( attribute "RELATIVE_PROPAGATION_DELAY_SCOPE" "G"
					( Parent
						( matchGroupRef "@crescent_city_bb_fab1_lib.crescent_city_bb_fab1(sch_1):\MG_DDR_NEAR_DIMM-CLK1_CLS_DDR_E_CAC-CLKS\" )
					)
					( Status sCSetFlattened )
					( Origin gBackEnd )
				)
				( attribute "RELATIVE_PROPAGATION_DELAY" "0.00 MIL,300.00 MIL"
					( Parent
						( matchGroupRef "@crescent_city_bb_fab1_lib.crescent_city_bb_fab1(sch_1):\MG_DDR_NEAR_DIMM-CLK1_CLS_DDR_E_CAC-CLKS\" )
					)
					( Units "uMatchProp" "ns" 1.000000)
					( Status sCSetFlattened )
					( Origin gBackEnd )
				)
				( attribute "RELATIVE_PROPAGATION_DELAY_SCOPE" "G"
					( Parent
						( matchGroupRef "@baseboard_fab2_lib.baseboard_fab2(sch_1):\MG_DDR_CTRL_NG_DDR_E_DLL_23\" )
					)
					( Status sCSetFlattened )
					( Origin gBackEnd )
				)
				( attribute "RELATIVE_PROPAGATION_DELAY" "0.00 MIL,25.00 MIL"
					( Parent
						( matchGroupRef "@baseboard_fab2_lib.baseboard_fab2(sch_1):\MG_DDR_CTRL_NG_DDR_E_DLL_23\" )
					)
					( Units "uMatchProp" "ns" 1.000000)
					( Status sCSetFlattened )
					( Origin gBackEnd )
				)
			)
			( pinPair "@baseboard_fab2_lib.baseboard_fab2(sch_1):\PP3731\"
				( pinRef "@baseboard_fab2_lib.baseboard_fab2(sch_1):page52_i12:ODT(1)" )
				( pinRef "@baseboard_fab2_lib.baseboard_fab2(sch_1):page27_i172:DDR4_ODT(3)" )
				( attribute "RELATIVE_PROPAGATION_DELAY_SCOPE" "G"
					( Parent
						( matchGroupRef "@crescent_city_bb_fab1_lib.crescent_city_bb_fab1(sch_1):\MG_DDR_NEAR_DIMM-CLK1_CLS_DDR_E_CAC-CLKS\" )
					)
					( Status sCSetFlattened )
					( Origin gBackEnd )
				)
				( attribute "RELATIVE_PROPAGATION_DELAY" "0.00 MIL,300.00 MIL"
					( Parent
						( matchGroupRef "@crescent_city_bb_fab1_lib.crescent_city_bb_fab1(sch_1):\MG_DDR_NEAR_DIMM-CLK1_CLS_DDR_E_CAC-CLKS\" )
					)
					( Units "uMatchProp" "ns" 1.000000)
					( Status sCSetFlattened )
					( Origin gBackEnd )
				)
				( attribute "RELATIVE_PROPAGATION_DELAY_SCOPE" "G"
					( Parent
						( matchGroupRef "@baseboard_fab2_lib.baseboard_fab2(sch_1):\MG_DDR_CTRL_NG_DDR_E_DLL_23\" )
					)
					( Status sCSetFlattened )
					( Origin gBackEnd )
				)
				( attribute "RELATIVE_PROPAGATION_DELAY" "0.00 MIL,25.00 MIL"
					( Parent
						( matchGroupRef "@baseboard_fab2_lib.baseboard_fab2(sch_1):\MG_DDR_CTRL_NG_DDR_E_DLL_23\" )
					)
					( Units "uMatchProp" "ns" 1.000000)
					( Status sCSetFlattened )
					( Origin gBackEnd )
				)
			)
			( pinPair "@baseboard_fab2_lib.baseboard_fab2(sch_1):\PP3729\"
				( pinRef "@baseboard_fab2_lib.baseboard_fab2(sch_1):page27_i172:DDR4_CKE(3)" )
				( pinRef "@baseboard_fab2_lib.baseboard_fab2(sch_1):page52_i12:CKE(1)" )
				( attribute "RELATIVE_PROPAGATION_DELAY_SCOPE" "G"
					( Parent
						( matchGroupRef "@crescent_city_bb_fab1_lib.crescent_city_bb_fab1(sch_1):\MG_DDR_NEAR_DIMM-CLK1_CLS_DDR_E_CAC-CLKS\" )
					)
					( Status sCSetFlattened )
					( Origin gBackEnd )
				)
				( attribute "RELATIVE_PROPAGATION_DELAY" "0.00 MIL,300.00 MIL"
					( Parent
						( matchGroupRef "@crescent_city_bb_fab1_lib.crescent_city_bb_fab1(sch_1):\MG_DDR_NEAR_DIMM-CLK1_CLS_DDR_E_CAC-CLKS\" )
					)
					( Units "uMatchProp" "ns" 1.000000)
					( Status sCSetFlattened )
					( Origin gBackEnd )
				)
				( attribute "RELATIVE_PROPAGATION_DELAY_SCOPE" "G"
					( Parent
						( matchGroupRef "@baseboard_fab2_lib.baseboard_fab2(sch_1):\MG_DDR_CTRL_NG_DDR_E_DLL_24\" )
					)
					( Status sCSetFlattened )
					( Origin gBackEnd )
				)
				( attribute "RELATIVE_PROPAGATION_DELAY" "0.00 MIL,25.00 MIL"
					( Parent
						( matchGroupRef "@baseboard_fab2_lib.baseboard_fab2(sch_1):\MG_DDR_CTRL_NG_DDR_E_DLL_24\" )
					)
					( Units "uMatchProp" "ns" 1.000000)
					( Status sCSetFlattened )
					( Origin gBackEnd )
				)
			)
			( pinPair "@baseboard_fab2_lib.baseboard_fab2(sch_1):\PP3857\"
				( pinRef "@baseboard_fab2_lib.baseboard_fab2(sch_1):page26_i172:DDR3_MA(17)" )
				( pinRef "@baseboard_fab2_lib.baseboard_fab2(sch_1):page49_i111:A17" )
				( attribute "RELATIVE_PROPAGATION_DELAY_SCOPE" "G"
					( Parent
						( matchGroupRef "@crescent_city_bb_fab1_lib.crescent_city_bb_fab1(sch_1):\MG_DDR_FAR_DIMM-CLK0_CLS_DDR_D_CAC-CLKS\" )
					)
					( Status sCSetFlattened )
					( Origin gBackEnd )
				)
				( attribute "RELATIVE_PROPAGATION_DELAY" "0.00 MIL,700.00 MIL"
					( Parent
						( matchGroupRef "@crescent_city_bb_fab1_lib.crescent_city_bb_fab1(sch_1):\MG_DDR_FAR_DIMM-CLK0_CLS_DDR_D_CAC-CLKS\" )
					)
					( Units "uMatchProp" "ns" 1.000000)
					( Status sCSetFlattened )
					( Origin gBackEnd )
				)
				( attribute "RELATIVE_PROPAGATION_DELAY_SCOPE" "G"
					( Parent
						( matchGroupRef "@baseboard_fab2_lib.baseboard_fab2(sch_1):\MG_DDR_FAR_DIMM_CMD_NG_DDR_D_DLL_1\" )
					)
					( Status sCSetFlattened )
					( Origin gBackEnd )
				)
				( attribute "RELATIVE_PROPAGATION_DELAY" "0.00 MIL,25.00 MIL"
					( Parent
						( matchGroupRef "@baseboard_fab2_lib.baseboard_fab2(sch_1):\MG_DDR_FAR_DIMM_CMD_NG_DDR_D_DLL_1\" )
					)
					( Units "uMatchProp" "ns" 1.000000)
					( Status sCSetFlattened )
					( Origin gBackEnd )
				)
			)
			( pinPair "@baseboard_fab2_lib.baseboard_fab2(sch_1):\PP3858\"
				( pinRef "@baseboard_fab2_lib.baseboard_fab2(sch_1):page50_i158:A17" )
				( pinRef "@baseboard_fab2_lib.baseboard_fab2(sch_1):page26_i172:DDR3_MA(17)" )
				( attribute "RELATIVE_PROPAGATION_DELAY_SCOPE" "G"
					( Parent
						( matchGroupRef "@baseboard_fab2_lib.baseboard_fab2(sch_1):\MG_DDR_CMD_NEAR_DIMM_NG_DDR_D_DLL_1\" )
					)
					( Status sCSetFlattened )
					( Origin gBackEnd )
				)
				( attribute "RELATIVE_PROPAGATION_DELAY" "0.00 MIL,25.00 MIL"
					( Parent
						( matchGroupRef "@baseboard_fab2_lib.baseboard_fab2(sch_1):\MG_DDR_CMD_NEAR_DIMM_NG_DDR_D_DLL_1\" )
					)
					( Units "uMatchProp" "ns" 1.000000)
					( Status sCSetFlattened )
					( Origin gBackEnd )
				)
				( attribute "RELATIVE_PROPAGATION_DELAY_SCOPE" "G"
					( Parent
						( matchGroupRef "@crescent_city_bb_fab1_lib.crescent_city_bb_fab1(sch_1):\MG_DDR_NEAR_DIMM-CLK1_CLS_DDR_D_CAC-CLKS\" )
					)
					( Status sCSetFlattened )
					( Origin gBackEnd )
				)
				( attribute "RELATIVE_PROPAGATION_DELAY" "0.00 MIL,700.00 MIL"
					( Parent
						( matchGroupRef "@crescent_city_bb_fab1_lib.crescent_city_bb_fab1(sch_1):\MG_DDR_NEAR_DIMM-CLK1_CLS_DDR_D_CAC-CLKS\" )
					)
					( Units "uMatchProp" "ns" 1.000000)
					( Status sCSetFlattened )
					( Origin gBackEnd )
				)
			)
			( pinPair "@baseboard_fab2_lib.baseboard_fab2(sch_1):\PP3859\"
				( pinRef "@baseboard_fab2_lib.baseboard_fab2(sch_1):page26_i172:DDR3_CID(2)" )
				( pinRef "@baseboard_fab2_lib.baseboard_fab2(sch_1):page49_i111:C(2)" )
				( attribute "RELATIVE_PROPAGATION_DELAY_SCOPE" "G"
					( Parent
						( matchGroupRef "@crescent_city_bb_fab1_lib.crescent_city_bb_fab1(sch_1):\MG_DDR_FAR_DIMM-CLK0_CLS_DDR_D_CAC-CLKS\" )
					)
					( Status sCSetFlattened )
					( Origin gBackEnd )
				)
				( attribute "RELATIVE_PROPAGATION_DELAY" "0.00 MIL,700.00 MIL"
					( Parent
						( matchGroupRef "@crescent_city_bb_fab1_lib.crescent_city_bb_fab1(sch_1):\MG_DDR_FAR_DIMM-CLK0_CLS_DDR_D_CAC-CLKS\" )
					)
					( Units "uMatchProp" "ns" 1.000000)
					( Status sCSetFlattened )
					( Origin gBackEnd )
				)
				( attribute "RELATIVE_PROPAGATION_DELAY_SCOPE" "G"
					( Parent
						( matchGroupRef "@baseboard_fab2_lib.baseboard_fab2(sch_1):\MG_DDR_FAR_DIMM_CMD_NG_DDR_D_DLL_1\" )
					)
					( Status sCSetFlattened )
					( Origin gBackEnd )
				)
				( attribute "RELATIVE_PROPAGATION_DELAY" "0.00 MIL,25.00 MIL"
					( Parent
						( matchGroupRef "@baseboard_fab2_lib.baseboard_fab2(sch_1):\MG_DDR_FAR_DIMM_CMD_NG_DDR_D_DLL_1\" )
					)
					( Units "uMatchProp" "ns" 1.000000)
					( Status sCSetFlattened )
					( Origin gBackEnd )
				)
			)
			( pinPair "@baseboard_fab2_lib.baseboard_fab2(sch_1):\PP3860\"
				( pinRef "@baseboard_fab2_lib.baseboard_fab2(sch_1):page50_i158:C(2)" )
				( pinRef "@baseboard_fab2_lib.baseboard_fab2(sch_1):page26_i172:DDR3_CID(2)" )
				( attribute "RELATIVE_PROPAGATION_DELAY_SCOPE" "G"
					( Parent
						( matchGroupRef "@baseboard_fab2_lib.baseboard_fab2(sch_1):\MG_DDR_CMD_NEAR_DIMM_NG_DDR_D_DLL_1\" )
					)
					( Status sCSetFlattened )
					( Origin gBackEnd )
				)
				( attribute "RELATIVE_PROPAGATION_DELAY" "0.00 MIL,25.00 MIL"
					( Parent
						( matchGroupRef "@baseboard_fab2_lib.baseboard_fab2(sch_1):\MG_DDR_CMD_NEAR_DIMM_NG_DDR_D_DLL_1\" )
					)
					( Units "uMatchProp" "ns" 1.000000)
					( Status sCSetFlattened )
					( Origin gBackEnd )
				)
				( attribute "RELATIVE_PROPAGATION_DELAY_SCOPE" "G"
					( Parent
						( matchGroupRef "@crescent_city_bb_fab1_lib.crescent_city_bb_fab1(sch_1):\MG_DDR_NEAR_DIMM-CLK1_CLS_DDR_D_CAC-CLKS\" )
					)
					( Status sCSetFlattened )
					( Origin gBackEnd )
				)
				( attribute "RELATIVE_PROPAGATION_DELAY" "0.00 MIL,700.00 MIL"
					( Parent
						( matchGroupRef "@crescent_city_bb_fab1_lib.crescent_city_bb_fab1(sch_1):\MG_DDR_NEAR_DIMM-CLK1_CLS_DDR_D_CAC-CLKS\" )
					)
					( Units "uMatchProp" "ns" 1.000000)
					( Status sCSetFlattened )
					( Origin gBackEnd )
				)
			)
			( pinPair "@baseboard_fab2_lib.baseboard_fab2(sch_1):\PP3853\"
				( pinRef "@baseboard_fab2_lib.baseboard_fab2(sch_1):page26_i172:DDR3_MA(13)" )
				( pinRef "@baseboard_fab2_lib.baseboard_fab2(sch_1):page49_i111:A13" )
				( attribute "RELATIVE_PROPAGATION_DELAY_SCOPE" "G"
					( Parent
						( matchGroupRef "@crescent_city_bb_fab1_lib.crescent_city_bb_fab1(sch_1):\MG_DDR_FAR_DIMM-CLK0_CLS_DDR_D_CAC-CLKS\" )
					)
					( Status sCSetFlattened )
					( Origin gBackEnd )
				)
				( attribute "RELATIVE_PROPAGATION_DELAY" "0.00 MIL,700.00 MIL"
					( Parent
						( matchGroupRef "@crescent_city_bb_fab1_lib.crescent_city_bb_fab1(sch_1):\MG_DDR_FAR_DIMM-CLK0_CLS_DDR_D_CAC-CLKS\" )
					)
					( Units "uMatchProp" "ns" 1.000000)
					( Status sCSetFlattened )
					( Origin gBackEnd )
				)
				( attribute "RELATIVE_PROPAGATION_DELAY_SCOPE" "G"
					( Parent
						( matchGroupRef "@baseboard_fab2_lib.baseboard_fab2(sch_1):\MG_DDR_FAR_DIMM_CMD_NG_DDR_D_DLL_2\" )
					)
					( Status sCSetFlattened )
					( Origin gBackEnd )
				)
				( attribute "RELATIVE_PROPAGATION_DELAY" "0.00 MIL,25.00 MIL"
					( Parent
						( matchGroupRef "@baseboard_fab2_lib.baseboard_fab2(sch_1):\MG_DDR_FAR_DIMM_CMD_NG_DDR_D_DLL_2\" )
					)
					( Units "uMatchProp" "ns" 1.000000)
					( Status sCSetFlattened )
					( Origin gBackEnd )
				)
			)
			( pinPair "@baseboard_fab2_lib.baseboard_fab2(sch_1):\PP3854\"
				( pinRef "@baseboard_fab2_lib.baseboard_fab2(sch_1):page50_i158:A13" )
				( pinRef "@baseboard_fab2_lib.baseboard_fab2(sch_1):page26_i172:DDR3_MA(13)" )
				( attribute "RELATIVE_PROPAGATION_DELAY_SCOPE" "G"
					( Parent
						( matchGroupRef "@crescent_city_bb_fab1_lib.crescent_city_bb_fab1(sch_1):\MG_DDR_NEAR_DIMM-CLK1_CLS_DDR_D_CAC-CLKS\" )
					)
					( Status sCSetFlattened )
					( Origin gBackEnd )
				)
				( attribute "RELATIVE_PROPAGATION_DELAY" "0.00 MIL,700.00 MIL"
					( Parent
						( matchGroupRef "@crescent_city_bb_fab1_lib.crescent_city_bb_fab1(sch_1):\MG_DDR_NEAR_DIMM-CLK1_CLS_DDR_D_CAC-CLKS\" )
					)
					( Units "uMatchProp" "ns" 1.000000)
					( Status sCSetFlattened )
					( Origin gBackEnd )
				)
				( attribute "RELATIVE_PROPAGATION_DELAY_SCOPE" "G"
					( Parent
						( matchGroupRef "@baseboard_fab2_lib.baseboard_fab2(sch_1):\MG_DDR_CMD_NEAR_DIMM_NG_DDR_D_DLL_2\" )
					)
					( Status sCSetFlattened )
					( Origin gBackEnd )
				)
				( attribute "RELATIVE_PROPAGATION_DELAY" "0.00 MIL,25.00 MIL"
					( Parent
						( matchGroupRef "@baseboard_fab2_lib.baseboard_fab2(sch_1):\MG_DDR_CMD_NEAR_DIMM_NG_DDR_D_DLL_2\" )
					)
					( Units "uMatchProp" "ns" 1.000000)
					( Status sCSetFlattened )
					( Origin gBackEnd )
				)
			)
			( pinPair "@baseboard_fab2_lib.baseboard_fab2(sch_1):\PP3855\"
				( pinRef "@baseboard_fab2_lib.baseboard_fab2(sch_1):page26_i172:DDR3_MA(15)" )
				( pinRef "@baseboard_fab2_lib.baseboard_fab2(sch_1):page49_i111:A15_CAS_N" )
				( attribute "RELATIVE_PROPAGATION_DELAY_SCOPE" "G"
					( Parent
						( matchGroupRef "@crescent_city_bb_fab1_lib.crescent_city_bb_fab1(sch_1):\MG_DDR_FAR_DIMM-CLK0_CLS_DDR_D_CAC-CLKS\" )
					)
					( Status sCSetFlattened )
					( Origin gBackEnd )
				)
				( attribute "RELATIVE_PROPAGATION_DELAY" "0.00 MIL,700.00 MIL"
					( Parent
						( matchGroupRef "@crescent_city_bb_fab1_lib.crescent_city_bb_fab1(sch_1):\MG_DDR_FAR_DIMM-CLK0_CLS_DDR_D_CAC-CLKS\" )
					)
					( Units "uMatchProp" "ns" 1.000000)
					( Status sCSetFlattened )
					( Origin gBackEnd )
				)
				( attribute "RELATIVE_PROPAGATION_DELAY_SCOPE" "G"
					( Parent
						( matchGroupRef "@baseboard_fab2_lib.baseboard_fab2(sch_1):\MG_DDR_FAR_DIMM_CMD_NG_DDR_D_DLL_2\" )
					)
					( Status sCSetFlattened )
					( Origin gBackEnd )
				)
				( attribute "RELATIVE_PROPAGATION_DELAY" "0.00 MIL,25.00 MIL"
					( Parent
						( matchGroupRef "@baseboard_fab2_lib.baseboard_fab2(sch_1):\MG_DDR_FAR_DIMM_CMD_NG_DDR_D_DLL_2\" )
					)
					( Units "uMatchProp" "ns" 1.000000)
					( Status sCSetFlattened )
					( Origin gBackEnd )
				)
			)
			( pinPair "@baseboard_fab2_lib.baseboard_fab2(sch_1):\PP3856\"
				( pinRef "@baseboard_fab2_lib.baseboard_fab2(sch_1):page26_i172:DDR3_MA(15)" )
				( pinRef "@baseboard_fab2_lib.baseboard_fab2(sch_1):page50_i158:A15_CAS_N" )
				( attribute "RELATIVE_PROPAGATION_DELAY_SCOPE" "G"
					( Parent
						( matchGroupRef "@crescent_city_bb_fab1_lib.crescent_city_bb_fab1(sch_1):\MG_DDR_NEAR_DIMM-CLK1_CLS_DDR_D_CAC-CLKS\" )
					)
					( Status sCSetFlattened )
					( Origin gBackEnd )
				)
				( attribute "RELATIVE_PROPAGATION_DELAY" "0.00 MIL,700.00 MIL"
					( Parent
						( matchGroupRef "@crescent_city_bb_fab1_lib.crescent_city_bb_fab1(sch_1):\MG_DDR_NEAR_DIMM-CLK1_CLS_DDR_D_CAC-CLKS\" )
					)
					( Units "uMatchProp" "ns" 1.000000)
					( Status sCSetFlattened )
					( Origin gBackEnd )
				)
				( attribute "RELATIVE_PROPAGATION_DELAY_SCOPE" "G"
					( Parent
						( matchGroupRef "@baseboard_fab2_lib.baseboard_fab2(sch_1):\MG_DDR_CMD_NEAR_DIMM_NG_DDR_D_DLL_2\" )
					)
					( Status sCSetFlattened )
					( Origin gBackEnd )
				)
				( attribute "RELATIVE_PROPAGATION_DELAY" "0.00 MIL,25.00 MIL"
					( Parent
						( matchGroupRef "@baseboard_fab2_lib.baseboard_fab2(sch_1):\MG_DDR_CMD_NEAR_DIMM_NG_DDR_D_DLL_2\" )
					)
					( Units "uMatchProp" "ns" 1.000000)
					( Status sCSetFlattened )
					( Origin gBackEnd )
				)
			)
			( pinPair "@baseboard_fab2_lib.baseboard_fab2(sch_1):\PP3849\"
				( pinRef "@baseboard_fab2_lib.baseboard_fab2(sch_1):page26_i172:DDR3_MA(14)" )
				( pinRef "@baseboard_fab2_lib.baseboard_fab2(sch_1):page49_i111:A14_WE_N" )
				( attribute "RELATIVE_PROPAGATION_DELAY_SCOPE" "G"
					( Parent
						( matchGroupRef "@crescent_city_bb_fab1_lib.crescent_city_bb_fab1(sch_1):\MG_DDR_FAR_DIMM-CLK0_CLS_DDR_D_CAC-CLKS\" )
					)
					( Status sCSetFlattened )
					( Origin gBackEnd )
				)
				( attribute "RELATIVE_PROPAGATION_DELAY" "0.00 MIL,700.00 MIL"
					( Parent
						( matchGroupRef "@crescent_city_bb_fab1_lib.crescent_city_bb_fab1(sch_1):\MG_DDR_FAR_DIMM-CLK0_CLS_DDR_D_CAC-CLKS\" )
					)
					( Units "uMatchProp" "ns" 1.000000)
					( Status sCSetFlattened )
					( Origin gBackEnd )
				)
				( attribute "RELATIVE_PROPAGATION_DELAY_SCOPE" "G"
					( Parent
						( matchGroupRef "@baseboard_fab2_lib.baseboard_fab2(sch_1):\MG_DDR_FAR_DIMM_CMD_NG_DDR_D_DLL_3\" )
					)
					( Status sCSetFlattened )
					( Origin gBackEnd )
				)
				( attribute "RELATIVE_PROPAGATION_DELAY" "0.00 MIL,25.00 MIL"
					( Parent
						( matchGroupRef "@baseboard_fab2_lib.baseboard_fab2(sch_1):\MG_DDR_FAR_DIMM_CMD_NG_DDR_D_DLL_3\" )
					)
					( Units "uMatchProp" "ns" 1.000000)
					( Status sCSetFlattened )
					( Origin gBackEnd )
				)
			)
			( pinPair "@baseboard_fab2_lib.baseboard_fab2(sch_1):\PP3850\"
				( pinRef "@baseboard_fab2_lib.baseboard_fab2(sch_1):page50_i158:A14_WE_N" )
				( pinRef "@baseboard_fab2_lib.baseboard_fab2(sch_1):page26_i172:DDR3_MA(14)" )
				( attribute "RELATIVE_PROPAGATION_DELAY_SCOPE" "G"
					( Parent
						( matchGroupRef "@crescent_city_bb_fab1_lib.crescent_city_bb_fab1(sch_1):\MG_DDR_NEAR_DIMM-CLK1_CLS_DDR_D_CAC-CLKS\" )
					)
					( Status sCSetFlattened )
					( Origin gBackEnd )
				)
				( attribute "RELATIVE_PROPAGATION_DELAY" "0.00 MIL,700.00 MIL"
					( Parent
						( matchGroupRef "@crescent_city_bb_fab1_lib.crescent_city_bb_fab1(sch_1):\MG_DDR_NEAR_DIMM-CLK1_CLS_DDR_D_CAC-CLKS\" )
					)
					( Units "uMatchProp" "ns" 1.000000)
					( Status sCSetFlattened )
					( Origin gBackEnd )
				)
				( attribute "RELATIVE_PROPAGATION_DELAY_SCOPE" "G"
					( Parent
						( matchGroupRef "@baseboard_fab2_lib.baseboard_fab2(sch_1):\MG_DDR_CMD_NEAR_DIMM_NG_DDR_D_DLL_3\" )
					)
					( Status sCSetFlattened )
					( Origin gBackEnd )
				)
				( attribute "RELATIVE_PROPAGATION_DELAY" "0.00 MIL,25.00 MIL"
					( Parent
						( matchGroupRef "@baseboard_fab2_lib.baseboard_fab2(sch_1):\MG_DDR_CMD_NEAR_DIMM_NG_DDR_D_DLL_3\" )
					)
					( Units "uMatchProp" "ns" 1.000000)
					( Status sCSetFlattened )
					( Origin gBackEnd )
				)
			)
			( pinPair "@baseboard_fab2_lib.baseboard_fab2(sch_1):\PP3851\"
				( pinRef "@baseboard_fab2_lib.baseboard_fab2(sch_1):page26_i172:DDR3_MA(16)" )
				( pinRef "@baseboard_fab2_lib.baseboard_fab2(sch_1):page49_i111:A16_RAS_N" )
				( attribute "RELATIVE_PROPAGATION_DELAY_SCOPE" "G"
					( Parent
						( matchGroupRef "@crescent_city_bb_fab1_lib.crescent_city_bb_fab1(sch_1):\MG_DDR_FAR_DIMM-CLK0_CLS_DDR_D_CAC-CLKS\" )
					)
					( Status sCSetFlattened )
					( Origin gBackEnd )
				)
				( attribute "RELATIVE_PROPAGATION_DELAY" "0.00 MIL,700.00 MIL"
					( Parent
						( matchGroupRef "@crescent_city_bb_fab1_lib.crescent_city_bb_fab1(sch_1):\MG_DDR_FAR_DIMM-CLK0_CLS_DDR_D_CAC-CLKS\" )
					)
					( Units "uMatchProp" "ns" 1.000000)
					( Status sCSetFlattened )
					( Origin gBackEnd )
				)
				( attribute "RELATIVE_PROPAGATION_DELAY_SCOPE" "G"
					( Parent
						( matchGroupRef "@baseboard_fab2_lib.baseboard_fab2(sch_1):\MG_DDR_FAR_DIMM_CMD_NG_DDR_D_DLL_3\" )
					)
					( Status sCSetFlattened )
					( Origin gBackEnd )
				)
				( attribute "RELATIVE_PROPAGATION_DELAY" "0.00 MIL,25.00 MIL"
					( Parent
						( matchGroupRef "@baseboard_fab2_lib.baseboard_fab2(sch_1):\MG_DDR_FAR_DIMM_CMD_NG_DDR_D_DLL_3\" )
					)
					( Units "uMatchProp" "ns" 1.000000)
					( Status sCSetFlattened )
					( Origin gBackEnd )
				)
			)
			( pinPair "@baseboard_fab2_lib.baseboard_fab2(sch_1):\PP3852\"
				( pinRef "@baseboard_fab2_lib.baseboard_fab2(sch_1):page50_i158:A16_RAS_N" )
				( pinRef "@baseboard_fab2_lib.baseboard_fab2(sch_1):page26_i172:DDR3_MA(16)" )
				( attribute "RELATIVE_PROPAGATION_DELAY_SCOPE" "G"
					( Parent
						( matchGroupRef "@crescent_city_bb_fab1_lib.crescent_city_bb_fab1(sch_1):\MG_DDR_NEAR_DIMM-CLK1_CLS_DDR_D_CAC-CLKS\" )
					)
					( Status sCSetFlattened )
					( Origin gBackEnd )
				)
				( attribute "RELATIVE_PROPAGATION_DELAY" "0.00 MIL,700.00 MIL"
					( Parent
						( matchGroupRef "@crescent_city_bb_fab1_lib.crescent_city_bb_fab1(sch_1):\MG_DDR_NEAR_DIMM-CLK1_CLS_DDR_D_CAC-CLKS\" )
					)
					( Units "uMatchProp" "ns" 1.000000)
					( Status sCSetFlattened )
					( Origin gBackEnd )
				)
				( attribute "RELATIVE_PROPAGATION_DELAY_SCOPE" "G"
					( Parent
						( matchGroupRef "@baseboard_fab2_lib.baseboard_fab2(sch_1):\MG_DDR_CMD_NEAR_DIMM_NG_DDR_D_DLL_3\" )
					)
					( Status sCSetFlattened )
					( Origin gBackEnd )
				)
				( attribute "RELATIVE_PROPAGATION_DELAY" "0.00 MIL,25.00 MIL"
					( Parent
						( matchGroupRef "@baseboard_fab2_lib.baseboard_fab2(sch_1):\MG_DDR_CMD_NEAR_DIMM_NG_DDR_D_DLL_3\" )
					)
					( Units "uMatchProp" "ns" 1.000000)
					( Status sCSetFlattened )
					( Origin gBackEnd )
				)
			)
			( pinPair "@baseboard_fab2_lib.baseboard_fab2(sch_1):\PP3845\"
				( pinRef "@baseboard_fab2_lib.baseboard_fab2(sch_1):page26_i172:DDR3_BA(1)" )
				( pinRef "@baseboard_fab2_lib.baseboard_fab2(sch_1):page49_i111:BA(1)" )
				( attribute "RELATIVE_PROPAGATION_DELAY_SCOPE" "G"
					( Parent
						( matchGroupRef "@crescent_city_bb_fab1_lib.crescent_city_bb_fab1(sch_1):\MG_DDR_FAR_DIMM-CLK0_CLS_DDR_D_CAC-CLKS\" )
					)
					( Status sCSetFlattened )
					( Origin gBackEnd )
				)
				( attribute "RELATIVE_PROPAGATION_DELAY" "0.00 MIL,700.00 MIL"
					( Parent
						( matchGroupRef "@crescent_city_bb_fab1_lib.crescent_city_bb_fab1(sch_1):\MG_DDR_FAR_DIMM-CLK0_CLS_DDR_D_CAC-CLKS\" )
					)
					( Units "uMatchProp" "ns" 1.000000)
					( Status sCSetFlattened )
					( Origin gBackEnd )
				)
				( attribute "RELATIVE_PROPAGATION_DELAY_SCOPE" "G"
					( Parent
						( matchGroupRef "@baseboard_fab2_lib.baseboard_fab2(sch_1):\MG_DDR_FAR_DIMM_CMD_NG_DDR_D_DLL_4\" )
					)
					( Status sCSetFlattened )
					( Origin gBackEnd )
				)
				( attribute "RELATIVE_PROPAGATION_DELAY" "0.00 MIL,25.00 MIL"
					( Parent
						( matchGroupRef "@baseboard_fab2_lib.baseboard_fab2(sch_1):\MG_DDR_FAR_DIMM_CMD_NG_DDR_D_DLL_4\" )
					)
					( Units "uMatchProp" "ns" 1.000000)
					( Status sCSetFlattened )
					( Origin gBackEnd )
				)
			)
			( pinPair "@baseboard_fab2_lib.baseboard_fab2(sch_1):\PP3846\"
				( pinRef "@baseboard_fab2_lib.baseboard_fab2(sch_1):page50_i158:BA(1)" )
				( pinRef "@baseboard_fab2_lib.baseboard_fab2(sch_1):page26_i172:DDR3_BA(1)" )
				( attribute "RELATIVE_PROPAGATION_DELAY_SCOPE" "G"
					( Parent
						( matchGroupRef "@crescent_city_bb_fab1_lib.crescent_city_bb_fab1(sch_1):\MG_DDR_NEAR_DIMM-CLK1_CLS_DDR_D_CAC-CLKS\" )
					)
					( Status sCSetFlattened )
					( Origin gBackEnd )
				)
				( attribute "RELATIVE_PROPAGATION_DELAY" "0.00 MIL,700.00 MIL"
					( Parent
						( matchGroupRef "@crescent_city_bb_fab1_lib.crescent_city_bb_fab1(sch_1):\MG_DDR_NEAR_DIMM-CLK1_CLS_DDR_D_CAC-CLKS\" )
					)
					( Units "uMatchProp" "ns" 1.000000)
					( Status sCSetFlattened )
					( Origin gBackEnd )
				)
				( attribute "RELATIVE_PROPAGATION_DELAY_SCOPE" "G"
					( Parent
						( matchGroupRef "@baseboard_fab2_lib.baseboard_fab2(sch_1):\MG_DDR_CMD_NEAR_DIMM_NG_DDR_D_DLL_4\" )
					)
					( Status sCSetFlattened )
					( Origin gBackEnd )
				)
				( attribute "RELATIVE_PROPAGATION_DELAY" "0.00 MIL,25.00 MIL"
					( Parent
						( matchGroupRef "@baseboard_fab2_lib.baseboard_fab2(sch_1):\MG_DDR_CMD_NEAR_DIMM_NG_DDR_D_DLL_4\" )
					)
					( Units "uMatchProp" "ns" 1.000000)
					( Status sCSetFlattened )
					( Origin gBackEnd )
				)
			)
			( pinPair "@baseboard_fab2_lib.baseboard_fab2(sch_1):\PP3847\"
				( pinRef "@baseboard_fab2_lib.baseboard_fab2(sch_1):page26_i172:DDR3_MA(10)" )
				( pinRef "@baseboard_fab2_lib.baseboard_fab2(sch_1):page49_i111:A10" )
				( attribute "RELATIVE_PROPAGATION_DELAY_SCOPE" "G"
					( Parent
						( matchGroupRef "@crescent_city_bb_fab1_lib.crescent_city_bb_fab1(sch_1):\MG_DDR_FAR_DIMM-CLK0_CLS_DDR_D_CAC-CLKS\" )
					)
					( Status sCSetFlattened )
					( Origin gBackEnd )
				)
				( attribute "RELATIVE_PROPAGATION_DELAY" "0.00 MIL,700.00 MIL"
					( Parent
						( matchGroupRef "@crescent_city_bb_fab1_lib.crescent_city_bb_fab1(sch_1):\MG_DDR_FAR_DIMM-CLK0_CLS_DDR_D_CAC-CLKS\" )
					)
					( Units "uMatchProp" "ns" 1.000000)
					( Status sCSetFlattened )
					( Origin gBackEnd )
				)
				( attribute "RELATIVE_PROPAGATION_DELAY_SCOPE" "G"
					( Parent
						( matchGroupRef "@baseboard_fab2_lib.baseboard_fab2(sch_1):\MG_DDR_FAR_DIMM_CMD_NG_DDR_D_DLL_4\" )
					)
					( Status sCSetFlattened )
					( Origin gBackEnd )
				)
				( attribute "RELATIVE_PROPAGATION_DELAY" "0.00 MIL,25.00 MIL"
					( Parent
						( matchGroupRef "@baseboard_fab2_lib.baseboard_fab2(sch_1):\MG_DDR_FAR_DIMM_CMD_NG_DDR_D_DLL_4\" )
					)
					( Units "uMatchProp" "ns" 1.000000)
					( Status sCSetFlattened )
					( Origin gBackEnd )
				)
			)
			( pinPair "@baseboard_fab2_lib.baseboard_fab2(sch_1):\PP3848\"
				( pinRef "@baseboard_fab2_lib.baseboard_fab2(sch_1):page50_i158:A10" )
				( pinRef "@baseboard_fab2_lib.baseboard_fab2(sch_1):page26_i172:DDR3_MA(10)" )
				( attribute "RELATIVE_PROPAGATION_DELAY_SCOPE" "G"
					( Parent
						( matchGroupRef "@crescent_city_bb_fab1_lib.crescent_city_bb_fab1(sch_1):\MG_DDR_NEAR_DIMM-CLK1_CLS_DDR_D_CAC-CLKS\" )
					)
					( Status sCSetFlattened )
					( Origin gBackEnd )
				)
				( attribute "RELATIVE_PROPAGATION_DELAY" "0.00 MIL,700.00 MIL"
					( Parent
						( matchGroupRef "@crescent_city_bb_fab1_lib.crescent_city_bb_fab1(sch_1):\MG_DDR_NEAR_DIMM-CLK1_CLS_DDR_D_CAC-CLKS\" )
					)
					( Units "uMatchProp" "ns" 1.000000)
					( Status sCSetFlattened )
					( Origin gBackEnd )
				)
				( attribute "RELATIVE_PROPAGATION_DELAY_SCOPE" "G"
					( Parent
						( matchGroupRef "@baseboard_fab2_lib.baseboard_fab2(sch_1):\MG_DDR_CMD_NEAR_DIMM_NG_DDR_D_DLL_4\" )
					)
					( Status sCSetFlattened )
					( Origin gBackEnd )
				)
				( attribute "RELATIVE_PROPAGATION_DELAY" "0.00 MIL,25.00 MIL"
					( Parent
						( matchGroupRef "@baseboard_fab2_lib.baseboard_fab2(sch_1):\MG_DDR_CMD_NEAR_DIMM_NG_DDR_D_DLL_4\" )
					)
					( Units "uMatchProp" "ns" 1.000000)
					( Status sCSetFlattened )
					( Origin gBackEnd )
				)
			)
			( pinPair "@baseboard_fab2_lib.baseboard_fab2(sch_1):\PP3841\"
				( pinRef "@baseboard_fab2_lib.baseboard_fab2(sch_1):page26_i172:DDR3_BA(0)" )
				( pinRef "@baseboard_fab2_lib.baseboard_fab2(sch_1):page49_i111:BA(0)" )
				( attribute "RELATIVE_PROPAGATION_DELAY_SCOPE" "G"
					( Parent
						( matchGroupRef "@crescent_city_bb_fab1_lib.crescent_city_bb_fab1(sch_1):\MG_DDR_FAR_DIMM-CLK0_CLS_DDR_D_CAC-CLKS\" )
					)
					( Status sCSetFlattened )
					( Origin gBackEnd )
				)
				( attribute "RELATIVE_PROPAGATION_DELAY" "0.00 MIL,700.00 MIL"
					( Parent
						( matchGroupRef "@crescent_city_bb_fab1_lib.crescent_city_bb_fab1(sch_1):\MG_DDR_FAR_DIMM-CLK0_CLS_DDR_D_CAC-CLKS\" )
					)
					( Units "uMatchProp" "ns" 1.000000)
					( Status sCSetFlattened )
					( Origin gBackEnd )
				)
				( attribute "RELATIVE_PROPAGATION_DELAY_SCOPE" "G"
					( Parent
						( matchGroupRef "@baseboard_fab2_lib.baseboard_fab2(sch_1):\MG_DDR_FAR_DIMM_CMD_NG_DDR_D_DLL_5\" )
					)
					( Status sCSetFlattened )
					( Origin gBackEnd )
				)
				( attribute "RELATIVE_PROPAGATION_DELAY" "0.00 MIL,25.00 MIL"
					( Parent
						( matchGroupRef "@baseboard_fab2_lib.baseboard_fab2(sch_1):\MG_DDR_FAR_DIMM_CMD_NG_DDR_D_DLL_5\" )
					)
					( Units "uMatchProp" "ns" 1.000000)
					( Status sCSetFlattened )
					( Origin gBackEnd )
				)
			)
			( pinPair "@baseboard_fab2_lib.baseboard_fab2(sch_1):\PP3842\"
				( pinRef "@baseboard_fab2_lib.baseboard_fab2(sch_1):page50_i158:BA(0)" )
				( pinRef "@baseboard_fab2_lib.baseboard_fab2(sch_1):page26_i172:DDR3_BA(0)" )
				( attribute "RELATIVE_PROPAGATION_DELAY_SCOPE" "G"
					( Parent
						( matchGroupRef "@crescent_city_bb_fab1_lib.crescent_city_bb_fab1(sch_1):\MG_DDR_NEAR_DIMM-CLK1_CLS_DDR_D_CAC-CLKS\" )
					)
					( Status sCSetFlattened )
					( Origin gBackEnd )
				)
				( attribute "RELATIVE_PROPAGATION_DELAY" "0.00 MIL,700.00 MIL"
					( Parent
						( matchGroupRef "@crescent_city_bb_fab1_lib.crescent_city_bb_fab1(sch_1):\MG_DDR_NEAR_DIMM-CLK1_CLS_DDR_D_CAC-CLKS\" )
					)
					( Units "uMatchProp" "ns" 1.000000)
					( Status sCSetFlattened )
					( Origin gBackEnd )
				)
				( attribute "RELATIVE_PROPAGATION_DELAY_SCOPE" "G"
					( Parent
						( matchGroupRef "@baseboard_fab2_lib.baseboard_fab2(sch_1):\MG_DDR_CMD_NEAR_DIMM_NG_DDR_D_DLL_5\" )
					)
					( Status sCSetFlattened )
					( Origin gBackEnd )
				)
				( attribute "RELATIVE_PROPAGATION_DELAY" "0.00 MIL,25.00 MIL"
					( Parent
						( matchGroupRef "@baseboard_fab2_lib.baseboard_fab2(sch_1):\MG_DDR_CMD_NEAR_DIMM_NG_DDR_D_DLL_5\" )
					)
					( Units "uMatchProp" "ns" 1.000000)
					( Status sCSetFlattened )
					( Origin gBackEnd )
				)
			)
			( pinPair "@baseboard_fab2_lib.baseboard_fab2(sch_1):\PP3843\"
				( pinRef "@baseboard_fab2_lib.baseboard_fab2(sch_1):page26_i172:DDR3_MA(0)" )
				( pinRef "@baseboard_fab2_lib.baseboard_fab2(sch_1):page49_i111:A0" )
				( attribute "RELATIVE_PROPAGATION_DELAY_SCOPE" "G"
					( Parent
						( matchGroupRef "@crescent_city_bb_fab1_lib.crescent_city_bb_fab1(sch_1):\MG_DDR_FAR_DIMM-CLK0_CLS_DDR_D_CAC-CLKS\" )
					)
					( Status sCSetFlattened )
					( Origin gBackEnd )
				)
				( attribute "RELATIVE_PROPAGATION_DELAY" "0.00 MIL,700.00 MIL"
					( Parent
						( matchGroupRef "@crescent_city_bb_fab1_lib.crescent_city_bb_fab1(sch_1):\MG_DDR_FAR_DIMM-CLK0_CLS_DDR_D_CAC-CLKS\" )
					)
					( Units "uMatchProp" "ns" 1.000000)
					( Status sCSetFlattened )
					( Origin gBackEnd )
				)
				( attribute "RELATIVE_PROPAGATION_DELAY_SCOPE" "G"
					( Parent
						( matchGroupRef "@baseboard_fab2_lib.baseboard_fab2(sch_1):\MG_DDR_FAR_DIMM_CMD_NG_DDR_D_DLL_5\" )
					)
					( Status sCSetFlattened )
					( Origin gBackEnd )
				)
				( attribute "RELATIVE_PROPAGATION_DELAY" "0.00 MIL,25.00 MIL"
					( Parent
						( matchGroupRef "@baseboard_fab2_lib.baseboard_fab2(sch_1):\MG_DDR_FAR_DIMM_CMD_NG_DDR_D_DLL_5\" )
					)
					( Units "uMatchProp" "ns" 1.000000)
					( Status sCSetFlattened )
					( Origin gBackEnd )
				)
			)
			( pinPair "@baseboard_fab2_lib.baseboard_fab2(sch_1):\PP3844\"
				( pinRef "@baseboard_fab2_lib.baseboard_fab2(sch_1):page50_i158:A0" )
				( pinRef "@baseboard_fab2_lib.baseboard_fab2(sch_1):page26_i172:DDR3_MA(0)" )
				( attribute "RELATIVE_PROPAGATION_DELAY_SCOPE" "G"
					( Parent
						( matchGroupRef "@crescent_city_bb_fab1_lib.crescent_city_bb_fab1(sch_1):\MG_DDR_NEAR_DIMM-CLK1_CLS_DDR_D_CAC-CLKS\" )
					)
					( Status sCSetFlattened )
					( Origin gBackEnd )
				)
				( attribute "RELATIVE_PROPAGATION_DELAY" "0.00 MIL,700.00 MIL"
					( Parent
						( matchGroupRef "@crescent_city_bb_fab1_lib.crescent_city_bb_fab1(sch_1):\MG_DDR_NEAR_DIMM-CLK1_CLS_DDR_D_CAC-CLKS\" )
					)
					( Units "uMatchProp" "ns" 1.000000)
					( Status sCSetFlattened )
					( Origin gBackEnd )
				)
				( attribute "RELATIVE_PROPAGATION_DELAY_SCOPE" "G"
					( Parent
						( matchGroupRef "@baseboard_fab2_lib.baseboard_fab2(sch_1):\MG_DDR_CMD_NEAR_DIMM_NG_DDR_D_DLL_5\" )
					)
					( Status sCSetFlattened )
					( Origin gBackEnd )
				)
				( attribute "RELATIVE_PROPAGATION_DELAY" "0.00 MIL,25.00 MIL"
					( Parent
						( matchGroupRef "@baseboard_fab2_lib.baseboard_fab2(sch_1):\MG_DDR_CMD_NEAR_DIMM_NG_DDR_D_DLL_5\" )
					)
					( Units "uMatchProp" "ns" 1.000000)
					( Status sCSetFlattened )
					( Origin gBackEnd )
				)
			)
			( pinPair "@baseboard_fab2_lib.baseboard_fab2(sch_1):\PP3839\"
				( pinRef "@baseboard_fab2_lib.baseboard_fab2(sch_1):page26_i172:DDR3_PAR" )
				( pinRef "@baseboard_fab2_lib.baseboard_fab2(sch_1):page49_i111:PAR" )
				( attribute "RELATIVE_PROPAGATION_DELAY_SCOPE" "G"
					( Parent
						( matchGroupRef "@crescent_city_bb_fab1_lib.crescent_city_bb_fab1(sch_1):\MG_DDR_FAR_DIMM-CLK0_CLS_DDR_D_CAC-CLKS\" )
					)
					( Status sCSetFlattened )
					( Origin gBackEnd )
				)
				( attribute "RELATIVE_PROPAGATION_DELAY" "0.00 MIL,700.00 MIL"
					( Parent
						( matchGroupRef "@crescent_city_bb_fab1_lib.crescent_city_bb_fab1(sch_1):\MG_DDR_FAR_DIMM-CLK0_CLS_DDR_D_CAC-CLKS\" )
					)
					( Units "uMatchProp" "ns" 1.000000)
					( Status sCSetFlattened )
					( Origin gBackEnd )
				)
				( attribute "RELATIVE_PROPAGATION_DELAY_SCOPE" "G"
					( Parent
						( matchGroupRef "@baseboard_fab2_lib.baseboard_fab2(sch_1):\MG_DDR_FAR_DIMM_CMD_NG_DDR_D_DLL_6\" )
					)
					( Status sCSetFlattened )
					( Origin gBackEnd )
				)
				( attribute "RELATIVE_PROPAGATION_DELAY" "0.00 MIL,25.00 MIL"
					( Parent
						( matchGroupRef "@baseboard_fab2_lib.baseboard_fab2(sch_1):\MG_DDR_FAR_DIMM_CMD_NG_DDR_D_DLL_6\" )
					)
					( Units "uMatchProp" "ns" 1.000000)
					( Status sCSetFlattened )
					( Origin gBackEnd )
				)
			)
			( pinPair "@baseboard_fab2_lib.baseboard_fab2(sch_1):\PP3840\"
				( pinRef "@baseboard_fab2_lib.baseboard_fab2(sch_1):page50_i158:PAR" )
				( pinRef "@baseboard_fab2_lib.baseboard_fab2(sch_1):page26_i172:DDR3_PAR" )
				( attribute "RELATIVE_PROPAGATION_DELAY_SCOPE" "G"
					( Parent
						( matchGroupRef "@crescent_city_bb_fab1_lib.crescent_city_bb_fab1(sch_1):\MG_DDR_NEAR_DIMM-CLK1_CLS_DDR_D_CAC-CLKS\" )
					)
					( Status sCSetFlattened )
					( Origin gBackEnd )
				)
				( attribute "RELATIVE_PROPAGATION_DELAY" "0.00 MIL,700.00 MIL"
					( Parent
						( matchGroupRef "@crescent_city_bb_fab1_lib.crescent_city_bb_fab1(sch_1):\MG_DDR_NEAR_DIMM-CLK1_CLS_DDR_D_CAC-CLKS\" )
					)
					( Units "uMatchProp" "ns" 1.000000)
					( Status sCSetFlattened )
					( Origin gBackEnd )
				)
				( attribute "RELATIVE_PROPAGATION_DELAY_SCOPE" "G"
					( Parent
						( matchGroupRef "@baseboard_fab2_lib.baseboard_fab2(sch_1):\MG_DDR_CMD_NEAR_DIMM_NG_DDR_D_DLL_6\" )
					)
					( Status sCSetFlattened )
					( Origin gBackEnd )
				)
				( attribute "RELATIVE_PROPAGATION_DELAY" "0.00 MIL,25.00 MIL"
					( Parent
						( matchGroupRef "@baseboard_fab2_lib.baseboard_fab2(sch_1):\MG_DDR_CMD_NEAR_DIMM_NG_DDR_D_DLL_6\" )
					)
					( Units "uMatchProp" "ns" 1.000000)
					( Status sCSetFlattened )
					( Origin gBackEnd )
				)
			)
			( pinPair "@baseboard_fab2_lib.baseboard_fab2(sch_1):\PP3835\"
				( pinRef "@baseboard_fab2_lib.baseboard_fab2(sch_1):page26_i172:DDR3_MA(1)" )
				( pinRef "@baseboard_fab2_lib.baseboard_fab2(sch_1):page49_i111:A1" )
				( attribute "RELATIVE_PROPAGATION_DELAY_SCOPE" "G"
					( Parent
						( matchGroupRef "@crescent_city_bb_fab1_lib.crescent_city_bb_fab1(sch_1):\MG_DDR_FAR_DIMM-CLK0_CLS_DDR_D_CAC-CLKS\" )
					)
					( Status sCSetFlattened )
					( Origin gBackEnd )
				)
				( attribute "RELATIVE_PROPAGATION_DELAY" "0.00 MIL,700.00 MIL"
					( Parent
						( matchGroupRef "@crescent_city_bb_fab1_lib.crescent_city_bb_fab1(sch_1):\MG_DDR_FAR_DIMM-CLK0_CLS_DDR_D_CAC-CLKS\" )
					)
					( Units "uMatchProp" "ns" 1.000000)
					( Status sCSetFlattened )
					( Origin gBackEnd )
				)
				( attribute "RELATIVE_PROPAGATION_DELAY_SCOPE" "G"
					( Parent
						( matchGroupRef "@baseboard_fab2_lib.baseboard_fab2(sch_1):\MG_DDR_FAR_DIMM_CMD_NG_DDR_D_DLL_7\" )
					)
					( Status sCSetFlattened )
					( Origin gBackEnd )
				)
				( attribute "RELATIVE_PROPAGATION_DELAY" "0.00 MIL,25.00 MIL"
					( Parent
						( matchGroupRef "@baseboard_fab2_lib.baseboard_fab2(sch_1):\MG_DDR_FAR_DIMM_CMD_NG_DDR_D_DLL_7\" )
					)
					( Units "uMatchProp" "ns" 1.000000)
					( Status sCSetFlattened )
					( Origin gBackEnd )
				)
			)
			( pinPair "@baseboard_fab2_lib.baseboard_fab2(sch_1):\PP3836\"
				( pinRef "@baseboard_fab2_lib.baseboard_fab2(sch_1):page50_i158:A1" )
				( pinRef "@baseboard_fab2_lib.baseboard_fab2(sch_1):page26_i172:DDR3_MA(1)" )
				( attribute "RELATIVE_PROPAGATION_DELAY_SCOPE" "G"
					( Parent
						( matchGroupRef "@crescent_city_bb_fab1_lib.crescent_city_bb_fab1(sch_1):\MG_DDR_NEAR_DIMM-CLK1_CLS_DDR_D_CAC-CLKS\" )
					)
					( Status sCSetFlattened )
					( Origin gBackEnd )
				)
				( attribute "RELATIVE_PROPAGATION_DELAY" "0.00 MIL,700.00 MIL"
					( Parent
						( matchGroupRef "@crescent_city_bb_fab1_lib.crescent_city_bb_fab1(sch_1):\MG_DDR_NEAR_DIMM-CLK1_CLS_DDR_D_CAC-CLKS\" )
					)
					( Units "uMatchProp" "ns" 1.000000)
					( Status sCSetFlattened )
					( Origin gBackEnd )
				)
				( attribute "RELATIVE_PROPAGATION_DELAY_SCOPE" "G"
					( Parent
						( matchGroupRef "@baseboard_fab2_lib.baseboard_fab2(sch_1):\MG_DDR_CMD_NEAR_DIMM_NG_DDR_D_DLL_7\" )
					)
					( Status sCSetFlattened )
					( Origin gBackEnd )
				)
				( attribute "RELATIVE_PROPAGATION_DELAY" "0.00 MIL,25.00 MIL"
					( Parent
						( matchGroupRef "@baseboard_fab2_lib.baseboard_fab2(sch_1):\MG_DDR_CMD_NEAR_DIMM_NG_DDR_D_DLL_7\" )
					)
					( Units "uMatchProp" "ns" 1.000000)
					( Status sCSetFlattened )
					( Origin gBackEnd )
				)
			)
			( pinPair "@baseboard_fab2_lib.baseboard_fab2(sch_1):\PP3837\"
				( pinRef "@baseboard_fab2_lib.baseboard_fab2(sch_1):page26_i172:DDR3_MA(3)" )
				( pinRef "@baseboard_fab2_lib.baseboard_fab2(sch_1):page49_i111:A3" )
				( attribute "RELATIVE_PROPAGATION_DELAY_SCOPE" "G"
					( Parent
						( matchGroupRef "@crescent_city_bb_fab1_lib.crescent_city_bb_fab1(sch_1):\MG_DDR_FAR_DIMM-CLK0_CLS_DDR_D_CAC-CLKS\" )
					)
					( Status sCSetFlattened )
					( Origin gBackEnd )
				)
				( attribute "RELATIVE_PROPAGATION_DELAY" "0.00 MIL,700.00 MIL"
					( Parent
						( matchGroupRef "@crescent_city_bb_fab1_lib.crescent_city_bb_fab1(sch_1):\MG_DDR_FAR_DIMM-CLK0_CLS_DDR_D_CAC-CLKS\" )
					)
					( Units "uMatchProp" "ns" 1.000000)
					( Status sCSetFlattened )
					( Origin gBackEnd )
				)
				( attribute "RELATIVE_PROPAGATION_DELAY_SCOPE" "G"
					( Parent
						( matchGroupRef "@baseboard_fab2_lib.baseboard_fab2(sch_1):\MG_DDR_FAR_DIMM_CMD_NG_DDR_D_DLL_7\" )
					)
					( Status sCSetFlattened )
					( Origin gBackEnd )
				)
				( attribute "RELATIVE_PROPAGATION_DELAY" "0.00 MIL,25.00 MIL"
					( Parent
						( matchGroupRef "@baseboard_fab2_lib.baseboard_fab2(sch_1):\MG_DDR_FAR_DIMM_CMD_NG_DDR_D_DLL_7\" )
					)
					( Units "uMatchProp" "ns" 1.000000)
					( Status sCSetFlattened )
					( Origin gBackEnd )
				)
			)
			( pinPair "@baseboard_fab2_lib.baseboard_fab2(sch_1):\PP3838\"
				( pinRef "@baseboard_fab2_lib.baseboard_fab2(sch_1):page50_i158:A3" )
				( pinRef "@baseboard_fab2_lib.baseboard_fab2(sch_1):page26_i172:DDR3_MA(3)" )
				( attribute "RELATIVE_PROPAGATION_DELAY_SCOPE" "G"
					( Parent
						( matchGroupRef "@crescent_city_bb_fab1_lib.crescent_city_bb_fab1(sch_1):\MG_DDR_NEAR_DIMM-CLK1_CLS_DDR_D_CAC-CLKS\" )
					)
					( Status sCSetFlattened )
					( Origin gBackEnd )
				)
				( attribute "RELATIVE_PROPAGATION_DELAY" "0.00 MIL,700.00 MIL"
					( Parent
						( matchGroupRef "@crescent_city_bb_fab1_lib.crescent_city_bb_fab1(sch_1):\MG_DDR_NEAR_DIMM-CLK1_CLS_DDR_D_CAC-CLKS\" )
					)
					( Units "uMatchProp" "ns" 1.000000)
					( Status sCSetFlattened )
					( Origin gBackEnd )
				)
				( attribute "RELATIVE_PROPAGATION_DELAY_SCOPE" "G"
					( Parent
						( matchGroupRef "@baseboard_fab2_lib.baseboard_fab2(sch_1):\MG_DDR_CMD_NEAR_DIMM_NG_DDR_D_DLL_7\" )
					)
					( Status sCSetFlattened )
					( Origin gBackEnd )
				)
				( attribute "RELATIVE_PROPAGATION_DELAY" "0.00 MIL,25.00 MIL"
					( Parent
						( matchGroupRef "@baseboard_fab2_lib.baseboard_fab2(sch_1):\MG_DDR_CMD_NEAR_DIMM_NG_DDR_D_DLL_7\" )
					)
					( Units "uMatchProp" "ns" 1.000000)
					( Status sCSetFlattened )
					( Origin gBackEnd )
				)
			)
			( pinPair "@baseboard_fab2_lib.baseboard_fab2(sch_1):\PP3831\"
				( pinRef "@baseboard_fab2_lib.baseboard_fab2(sch_1):page26_i172:DDR3_MA(2)" )
				( pinRef "@baseboard_fab2_lib.baseboard_fab2(sch_1):page49_i111:A2" )
				( attribute "RELATIVE_PROPAGATION_DELAY_SCOPE" "G"
					( Parent
						( matchGroupRef "@crescent_city_bb_fab1_lib.crescent_city_bb_fab1(sch_1):\MG_DDR_FAR_DIMM-CLK0_CLS_DDR_D_CAC-CLKS\" )
					)
					( Status sCSetFlattened )
					( Origin gBackEnd )
				)
				( attribute "RELATIVE_PROPAGATION_DELAY" "0.00 MIL,700.00 MIL"
					( Parent
						( matchGroupRef "@crescent_city_bb_fab1_lib.crescent_city_bb_fab1(sch_1):\MG_DDR_FAR_DIMM-CLK0_CLS_DDR_D_CAC-CLKS\" )
					)
					( Units "uMatchProp" "ns" 1.000000)
					( Status sCSetFlattened )
					( Origin gBackEnd )
				)
				( attribute "RELATIVE_PROPAGATION_DELAY_SCOPE" "G"
					( Parent
						( matchGroupRef "@baseboard_fab2_lib.baseboard_fab2(sch_1):\MG_DDR_FAR_DIMM_CMD_NG_DDR_D_DLL_8\" )
					)
					( Status sCSetFlattened )
					( Origin gBackEnd )
				)
				( attribute "RELATIVE_PROPAGATION_DELAY" "0.00 MIL,25.00 MIL"
					( Parent
						( matchGroupRef "@baseboard_fab2_lib.baseboard_fab2(sch_1):\MG_DDR_FAR_DIMM_CMD_NG_DDR_D_DLL_8\" )
					)
					( Units "uMatchProp" "ns" 1.000000)
					( Status sCSetFlattened )
					( Origin gBackEnd )
				)
			)
			( pinPair "@baseboard_fab2_lib.baseboard_fab2(sch_1):\PP3832\"
				( pinRef "@baseboard_fab2_lib.baseboard_fab2(sch_1):page50_i158:A2" )
				( pinRef "@baseboard_fab2_lib.baseboard_fab2(sch_1):page26_i172:DDR3_MA(2)" )
				( attribute "RELATIVE_PROPAGATION_DELAY_SCOPE" "G"
					( Parent
						( matchGroupRef "@crescent_city_bb_fab1_lib.crescent_city_bb_fab1(sch_1):\MG_DDR_NEAR_DIMM-CLK1_CLS_DDR_D_CAC-CLKS\" )
					)
					( Status sCSetFlattened )
					( Origin gBackEnd )
				)
				( attribute "RELATIVE_PROPAGATION_DELAY" "0.00 MIL,700.00 MIL"
					( Parent
						( matchGroupRef "@crescent_city_bb_fab1_lib.crescent_city_bb_fab1(sch_1):\MG_DDR_NEAR_DIMM-CLK1_CLS_DDR_D_CAC-CLKS\" )
					)
					( Units "uMatchProp" "ns" 1.000000)
					( Status sCSetFlattened )
					( Origin gBackEnd )
				)
				( attribute "RELATIVE_PROPAGATION_DELAY_SCOPE" "G"
					( Parent
						( matchGroupRef "@baseboard_fab2_lib.baseboard_fab2(sch_1):\MG_DDR_CMD_NEAR_DIMM_NG_DDR_D_DLL_8\" )
					)
					( Status sCSetFlattened )
					( Origin gBackEnd )
				)
				( attribute "RELATIVE_PROPAGATION_DELAY" "0.00 MIL,25.00 MIL"
					( Parent
						( matchGroupRef "@baseboard_fab2_lib.baseboard_fab2(sch_1):\MG_DDR_CMD_NEAR_DIMM_NG_DDR_D_DLL_8\" )
					)
					( Units "uMatchProp" "ns" 1.000000)
					( Status sCSetFlattened )
					( Origin gBackEnd )
				)
			)
			( pinPair "@baseboard_fab2_lib.baseboard_fab2(sch_1):\PP3833\"
				( pinRef "@baseboard_fab2_lib.baseboard_fab2(sch_1):page26_i172:DDR3_MA(4)" )
				( pinRef "@baseboard_fab2_lib.baseboard_fab2(sch_1):page49_i111:A4" )
				( attribute "RELATIVE_PROPAGATION_DELAY_SCOPE" "G"
					( Parent
						( matchGroupRef "@crescent_city_bb_fab1_lib.crescent_city_bb_fab1(sch_1):\MG_DDR_FAR_DIMM-CLK0_CLS_DDR_D_CAC-CLKS\" )
					)
					( Status sCSetFlattened )
					( Origin gBackEnd )
				)
				( attribute "RELATIVE_PROPAGATION_DELAY" "0.00 MIL,700.00 MIL"
					( Parent
						( matchGroupRef "@crescent_city_bb_fab1_lib.crescent_city_bb_fab1(sch_1):\MG_DDR_FAR_DIMM-CLK0_CLS_DDR_D_CAC-CLKS\" )
					)
					( Units "uMatchProp" "ns" 1.000000)
					( Status sCSetFlattened )
					( Origin gBackEnd )
				)
				( attribute "RELATIVE_PROPAGATION_DELAY_SCOPE" "G"
					( Parent
						( matchGroupRef "@baseboard_fab2_lib.baseboard_fab2(sch_1):\MG_DDR_FAR_DIMM_CMD_NG_DDR_D_DLL_8\" )
					)
					( Status sCSetFlattened )
					( Origin gBackEnd )
				)
				( attribute "RELATIVE_PROPAGATION_DELAY" "0.00 MIL,25.00 MIL"
					( Parent
						( matchGroupRef "@baseboard_fab2_lib.baseboard_fab2(sch_1):\MG_DDR_FAR_DIMM_CMD_NG_DDR_D_DLL_8\" )
					)
					( Units "uMatchProp" "ns" 1.000000)
					( Status sCSetFlattened )
					( Origin gBackEnd )
				)
			)
			( pinPair "@baseboard_fab2_lib.baseboard_fab2(sch_1):\PP3834\"
				( pinRef "@baseboard_fab2_lib.baseboard_fab2(sch_1):page50_i158:A4" )
				( pinRef "@baseboard_fab2_lib.baseboard_fab2(sch_1):page26_i172:DDR3_MA(4)" )
				( attribute "RELATIVE_PROPAGATION_DELAY_SCOPE" "G"
					( Parent
						( matchGroupRef "@crescent_city_bb_fab1_lib.crescent_city_bb_fab1(sch_1):\MG_DDR_NEAR_DIMM-CLK1_CLS_DDR_D_CAC-CLKS\" )
					)
					( Status sCSetFlattened )
					( Origin gBackEnd )
				)
				( attribute "RELATIVE_PROPAGATION_DELAY" "0.00 MIL,700.00 MIL"
					( Parent
						( matchGroupRef "@crescent_city_bb_fab1_lib.crescent_city_bb_fab1(sch_1):\MG_DDR_NEAR_DIMM-CLK1_CLS_DDR_D_CAC-CLKS\" )
					)
					( Units "uMatchProp" "ns" 1.000000)
					( Status sCSetFlattened )
					( Origin gBackEnd )
				)
				( attribute "RELATIVE_PROPAGATION_DELAY_SCOPE" "G"
					( Parent
						( matchGroupRef "@baseboard_fab2_lib.baseboard_fab2(sch_1):\MG_DDR_CMD_NEAR_DIMM_NG_DDR_D_DLL_8\" )
					)
					( Status sCSetFlattened )
					( Origin gBackEnd )
				)
				( attribute "RELATIVE_PROPAGATION_DELAY" "0.00 MIL,25.00 MIL"
					( Parent
						( matchGroupRef "@baseboard_fab2_lib.baseboard_fab2(sch_1):\MG_DDR_CMD_NEAR_DIMM_NG_DDR_D_DLL_8\" )
					)
					( Units "uMatchProp" "ns" 1.000000)
					( Status sCSetFlattened )
					( Origin gBackEnd )
				)
			)
			( pinPair "@baseboard_fab2_lib.baseboard_fab2(sch_1):\PP3827\"
				( pinRef "@baseboard_fab2_lib.baseboard_fab2(sch_1):page26_i172:DDR3_MA(5)" )
				( pinRef "@baseboard_fab2_lib.baseboard_fab2(sch_1):page49_i111:A5" )
				( attribute "RELATIVE_PROPAGATION_DELAY_SCOPE" "G"
					( Parent
						( matchGroupRef "@crescent_city_bb_fab1_lib.crescent_city_bb_fab1(sch_1):\MG_DDR_FAR_DIMM-CLK0_CLS_DDR_D_CAC-CLKS\" )
					)
					( Status sCSetFlattened )
					( Origin gBackEnd )
				)
				( attribute "RELATIVE_PROPAGATION_DELAY" "0.00 MIL,700.00 MIL"
					( Parent
						( matchGroupRef "@crescent_city_bb_fab1_lib.crescent_city_bb_fab1(sch_1):\MG_DDR_FAR_DIMM-CLK0_CLS_DDR_D_CAC-CLKS\" )
					)
					( Units "uMatchProp" "ns" 1.000000)
					( Status sCSetFlattened )
					( Origin gBackEnd )
				)
				( attribute "RELATIVE_PROPAGATION_DELAY_SCOPE" "G"
					( Parent
						( matchGroupRef "@baseboard_fab2_lib.baseboard_fab2(sch_1):\MG_DDR_FAR_DIMM_CMD_NG_DDR_D_DLL_9\" )
					)
					( Status sCSetFlattened )
					( Origin gBackEnd )
				)
				( attribute "RELATIVE_PROPAGATION_DELAY" "0.00 MIL,25.00 MIL"
					( Parent
						( matchGroupRef "@baseboard_fab2_lib.baseboard_fab2(sch_1):\MG_DDR_FAR_DIMM_CMD_NG_DDR_D_DLL_9\" )
					)
					( Units "uMatchProp" "ns" 1.000000)
					( Status sCSetFlattened )
					( Origin gBackEnd )
				)
			)
			( pinPair "@baseboard_fab2_lib.baseboard_fab2(sch_1):\PP3828\"
				( pinRef "@baseboard_fab2_lib.baseboard_fab2(sch_1):page50_i158:A5" )
				( pinRef "@baseboard_fab2_lib.baseboard_fab2(sch_1):page26_i172:DDR3_MA(5)" )
				( attribute "RELATIVE_PROPAGATION_DELAY_SCOPE" "G"
					( Parent
						( matchGroupRef "@crescent_city_bb_fab1_lib.crescent_city_bb_fab1(sch_1):\MG_DDR_NEAR_DIMM-CLK1_CLS_DDR_D_CAC-CLKS\" )
					)
					( Status sCSetFlattened )
					( Origin gBackEnd )
				)
				( attribute "RELATIVE_PROPAGATION_DELAY" "0.00 MIL,700.00 MIL"
					( Parent
						( matchGroupRef "@crescent_city_bb_fab1_lib.crescent_city_bb_fab1(sch_1):\MG_DDR_NEAR_DIMM-CLK1_CLS_DDR_D_CAC-CLKS\" )
					)
					( Units "uMatchProp" "ns" 1.000000)
					( Status sCSetFlattened )
					( Origin gBackEnd )
				)
				( attribute "RELATIVE_PROPAGATION_DELAY_SCOPE" "G"
					( Parent
						( matchGroupRef "@baseboard_fab2_lib.baseboard_fab2(sch_1):\MG_DDR_CMD_NEAR_DIMM_NG_DDR_D_DLL_9\" )
					)
					( Status sCSetFlattened )
					( Origin gBackEnd )
				)
				( attribute "RELATIVE_PROPAGATION_DELAY" "0.00 MIL,25.00 MIL"
					( Parent
						( matchGroupRef "@baseboard_fab2_lib.baseboard_fab2(sch_1):\MG_DDR_CMD_NEAR_DIMM_NG_DDR_D_DLL_9\" )
					)
					( Units "uMatchProp" "ns" 1.000000)
					( Status sCSetFlattened )
					( Origin gBackEnd )
				)
			)
			( pinPair "@baseboard_fab2_lib.baseboard_fab2(sch_1):\PP3829\"
				( pinRef "@baseboard_fab2_lib.baseboard_fab2(sch_1):page26_i172:DDR3_MA(6)" )
				( pinRef "@baseboard_fab2_lib.baseboard_fab2(sch_1):page49_i111:A6" )
				( attribute "RELATIVE_PROPAGATION_DELAY_SCOPE" "G"
					( Parent
						( matchGroupRef "@crescent_city_bb_fab1_lib.crescent_city_bb_fab1(sch_1):\MG_DDR_FAR_DIMM-CLK0_CLS_DDR_D_CAC-CLKS\" )
					)
					( Status sCSetFlattened )
					( Origin gBackEnd )
				)
				( attribute "RELATIVE_PROPAGATION_DELAY" "0.00 MIL,700.00 MIL"
					( Parent
						( matchGroupRef "@crescent_city_bb_fab1_lib.crescent_city_bb_fab1(sch_1):\MG_DDR_FAR_DIMM-CLK0_CLS_DDR_D_CAC-CLKS\" )
					)
					( Units "uMatchProp" "ns" 1.000000)
					( Status sCSetFlattened )
					( Origin gBackEnd )
				)
				( attribute "RELATIVE_PROPAGATION_DELAY_SCOPE" "G"
					( Parent
						( matchGroupRef "@baseboard_fab2_lib.baseboard_fab2(sch_1):\MG_DDR_FAR_DIMM_CMD_NG_DDR_D_DLL_9\" )
					)
					( Status sCSetFlattened )
					( Origin gBackEnd )
				)
				( attribute "RELATIVE_PROPAGATION_DELAY" "0.00 MIL,25.00 MIL"
					( Parent
						( matchGroupRef "@baseboard_fab2_lib.baseboard_fab2(sch_1):\MG_DDR_FAR_DIMM_CMD_NG_DDR_D_DLL_9\" )
					)
					( Units "uMatchProp" "ns" 1.000000)
					( Status sCSetFlattened )
					( Origin gBackEnd )
				)
			)
			( pinPair "@baseboard_fab2_lib.baseboard_fab2(sch_1):\PP3830\"
				( pinRef "@baseboard_fab2_lib.baseboard_fab2(sch_1):page50_i158:A6" )
				( pinRef "@baseboard_fab2_lib.baseboard_fab2(sch_1):page26_i172:DDR3_MA(6)" )
				( attribute "RELATIVE_PROPAGATION_DELAY_SCOPE" "G"
					( Parent
						( matchGroupRef "@crescent_city_bb_fab1_lib.crescent_city_bb_fab1(sch_1):\MG_DDR_NEAR_DIMM-CLK1_CLS_DDR_D_CAC-CLKS\" )
					)
					( Status sCSetFlattened )
					( Origin gBackEnd )
				)
				( attribute "RELATIVE_PROPAGATION_DELAY" "0.00 MIL,700.00 MIL"
					( Parent
						( matchGroupRef "@crescent_city_bb_fab1_lib.crescent_city_bb_fab1(sch_1):\MG_DDR_NEAR_DIMM-CLK1_CLS_DDR_D_CAC-CLKS\" )
					)
					( Units "uMatchProp" "ns" 1.000000)
					( Status sCSetFlattened )
					( Origin gBackEnd )
				)
				( attribute "RELATIVE_PROPAGATION_DELAY_SCOPE" "G"
					( Parent
						( matchGroupRef "@baseboard_fab2_lib.baseboard_fab2(sch_1):\MG_DDR_CMD_NEAR_DIMM_NG_DDR_D_DLL_9\" )
					)
					( Status sCSetFlattened )
					( Origin gBackEnd )
				)
				( attribute "RELATIVE_PROPAGATION_DELAY" "0.00 MIL,25.00 MIL"
					( Parent
						( matchGroupRef "@baseboard_fab2_lib.baseboard_fab2(sch_1):\MG_DDR_CMD_NEAR_DIMM_NG_DDR_D_DLL_9\" )
					)
					( Units "uMatchProp" "ns" 1.000000)
					( Status sCSetFlattened )
					( Origin gBackEnd )
				)
			)
			( pinPair "@baseboard_fab2_lib.baseboard_fab2(sch_1):\PP3823\"
				( pinRef "@baseboard_fab2_lib.baseboard_fab2(sch_1):page26_i172:DDR3_MA(7)" )
				( pinRef "@baseboard_fab2_lib.baseboard_fab2(sch_1):page49_i111:A7" )
				( attribute "RELATIVE_PROPAGATION_DELAY_SCOPE" "G"
					( Parent
						( matchGroupRef "@crescent_city_bb_fab1_lib.crescent_city_bb_fab1(sch_1):\MG_DDR_FAR_DIMM-CLK0_CLS_DDR_D_CAC-CLKS\" )
					)
					( Status sCSetFlattened )
					( Origin gBackEnd )
				)
				( attribute "RELATIVE_PROPAGATION_DELAY" "0.00 MIL,700.00 MIL"
					( Parent
						( matchGroupRef "@crescent_city_bb_fab1_lib.crescent_city_bb_fab1(sch_1):\MG_DDR_FAR_DIMM-CLK0_CLS_DDR_D_CAC-CLKS\" )
					)
					( Units "uMatchProp" "ns" 1.000000)
					( Status sCSetFlattened )
					( Origin gBackEnd )
				)
				( attribute "RELATIVE_PROPAGATION_DELAY_SCOPE" "G"
					( Parent
						( matchGroupRef "@baseboard_fab2_lib.baseboard_fab2(sch_1):\MG_DDR_FAR_DIMM_CMD_NG_DDR_D_DLL_10\" )
					)
					( Status sCSetFlattened )
					( Origin gBackEnd )
				)
				( attribute "RELATIVE_PROPAGATION_DELAY" "0.00 MIL,25.00 MIL"
					( Parent
						( matchGroupRef "@baseboard_fab2_lib.baseboard_fab2(sch_1):\MG_DDR_FAR_DIMM_CMD_NG_DDR_D_DLL_10\" )
					)
					( Units "uMatchProp" "ns" 1.000000)
					( Status sCSetFlattened )
					( Origin gBackEnd )
				)
			)
			( pinPair "@baseboard_fab2_lib.baseboard_fab2(sch_1):\PP3824\"
				( pinRef "@baseboard_fab2_lib.baseboard_fab2(sch_1):page50_i158:A7" )
				( pinRef "@baseboard_fab2_lib.baseboard_fab2(sch_1):page26_i172:DDR3_MA(7)" )
				( attribute "RELATIVE_PROPAGATION_DELAY_SCOPE" "G"
					( Parent
						( matchGroupRef "@crescent_city_bb_fab1_lib.crescent_city_bb_fab1(sch_1):\MG_DDR_NEAR_DIMM-CLK1_CLS_DDR_D_CAC-CLKS\" )
					)
					( Status sCSetFlattened )
					( Origin gBackEnd )
				)
				( attribute "RELATIVE_PROPAGATION_DELAY" "0.00 MIL,700.00 MIL"
					( Parent
						( matchGroupRef "@crescent_city_bb_fab1_lib.crescent_city_bb_fab1(sch_1):\MG_DDR_NEAR_DIMM-CLK1_CLS_DDR_D_CAC-CLKS\" )
					)
					( Units "uMatchProp" "ns" 1.000000)
					( Status sCSetFlattened )
					( Origin gBackEnd )
				)
				( attribute "RELATIVE_PROPAGATION_DELAY_SCOPE" "G"
					( Parent
						( matchGroupRef "@baseboard_fab2_lib.baseboard_fab2(sch_1):\MG_DDR_CMD_NEAR_DIMM_NG_DDR_D_DLL_10\" )
					)
					( Status sCSetFlattened )
					( Origin gBackEnd )
				)
				( attribute "RELATIVE_PROPAGATION_DELAY" "0.00 MIL,25.00 MIL"
					( Parent
						( matchGroupRef "@baseboard_fab2_lib.baseboard_fab2(sch_1):\MG_DDR_CMD_NEAR_DIMM_NG_DDR_D_DLL_10\" )
					)
					( Units "uMatchProp" "ns" 1.000000)
					( Status sCSetFlattened )
					( Origin gBackEnd )
				)
			)
			( pinPair "@baseboard_fab2_lib.baseboard_fab2(sch_1):\PP3825\"
				( pinRef "@baseboard_fab2_lib.baseboard_fab2(sch_1):page26_i172:DDR3_MA(8)" )
				( pinRef "@baseboard_fab2_lib.baseboard_fab2(sch_1):page49_i111:A8" )
				( attribute "RELATIVE_PROPAGATION_DELAY_SCOPE" "G"
					( Parent
						( matchGroupRef "@crescent_city_bb_fab1_lib.crescent_city_bb_fab1(sch_1):\MG_DDR_FAR_DIMM-CLK0_CLS_DDR_D_CAC-CLKS\" )
					)
					( Status sCSetFlattened )
					( Origin gBackEnd )
				)
				( attribute "RELATIVE_PROPAGATION_DELAY" "0.00 MIL,700.00 MIL"
					( Parent
						( matchGroupRef "@crescent_city_bb_fab1_lib.crescent_city_bb_fab1(sch_1):\MG_DDR_FAR_DIMM-CLK0_CLS_DDR_D_CAC-CLKS\" )
					)
					( Units "uMatchProp" "ns" 1.000000)
					( Status sCSetFlattened )
					( Origin gBackEnd )
				)
				( attribute "RELATIVE_PROPAGATION_DELAY_SCOPE" "G"
					( Parent
						( matchGroupRef "@baseboard_fab2_lib.baseboard_fab2(sch_1):\MG_DDR_FAR_DIMM_CMD_NG_DDR_D_DLL_10\" )
					)
					( Status sCSetFlattened )
					( Origin gBackEnd )
				)
				( attribute "RELATIVE_PROPAGATION_DELAY" "0.00 MIL,25.00 MIL"
					( Parent
						( matchGroupRef "@baseboard_fab2_lib.baseboard_fab2(sch_1):\MG_DDR_FAR_DIMM_CMD_NG_DDR_D_DLL_10\" )
					)
					( Units "uMatchProp" "ns" 1.000000)
					( Status sCSetFlattened )
					( Origin gBackEnd )
				)
			)
			( pinPair "@baseboard_fab2_lib.baseboard_fab2(sch_1):\PP3826\"
				( pinRef "@baseboard_fab2_lib.baseboard_fab2(sch_1):page50_i158:A8" )
				( pinRef "@baseboard_fab2_lib.baseboard_fab2(sch_1):page26_i172:DDR3_MA(8)" )
				( attribute "RELATIVE_PROPAGATION_DELAY_SCOPE" "G"
					( Parent
						( matchGroupRef "@crescent_city_bb_fab1_lib.crescent_city_bb_fab1(sch_1):\MG_DDR_NEAR_DIMM-CLK1_CLS_DDR_D_CAC-CLKS\" )
					)
					( Status sCSetFlattened )
					( Origin gBackEnd )
				)
				( attribute "RELATIVE_PROPAGATION_DELAY" "0.00 MIL,700.00 MIL"
					( Parent
						( matchGroupRef "@crescent_city_bb_fab1_lib.crescent_city_bb_fab1(sch_1):\MG_DDR_NEAR_DIMM-CLK1_CLS_DDR_D_CAC-CLKS\" )
					)
					( Units "uMatchProp" "ns" 1.000000)
					( Status sCSetFlattened )
					( Origin gBackEnd )
				)
				( attribute "RELATIVE_PROPAGATION_DELAY_SCOPE" "G"
					( Parent
						( matchGroupRef "@baseboard_fab2_lib.baseboard_fab2(sch_1):\MG_DDR_CMD_NEAR_DIMM_NG_DDR_D_DLL_10\" )
					)
					( Status sCSetFlattened )
					( Origin gBackEnd )
				)
				( attribute "RELATIVE_PROPAGATION_DELAY" "0.00 MIL,25.00 MIL"
					( Parent
						( matchGroupRef "@baseboard_fab2_lib.baseboard_fab2(sch_1):\MG_DDR_CMD_NEAR_DIMM_NG_DDR_D_DLL_10\" )
					)
					( Units "uMatchProp" "ns" 1.000000)
					( Status sCSetFlattened )
					( Origin gBackEnd )
				)
			)
			( pinPair "@baseboard_fab2_lib.baseboard_fab2(sch_1):\PP3819\"
				( pinRef "@baseboard_fab2_lib.baseboard_fab2(sch_1):page26_i172:DDR3_MA(9)" )
				( pinRef "@baseboard_fab2_lib.baseboard_fab2(sch_1):page49_i111:A9" )
				( attribute "RELATIVE_PROPAGATION_DELAY_SCOPE" "G"
					( Parent
						( matchGroupRef "@crescent_city_bb_fab1_lib.crescent_city_bb_fab1(sch_1):\MG_DDR_FAR_DIMM-CLK0_CLS_DDR_D_CAC-CLKS\" )
					)
					( Status sCSetFlattened )
					( Origin gBackEnd )
				)
				( attribute "RELATIVE_PROPAGATION_DELAY" "0.00 MIL,700.00 MIL"
					( Parent
						( matchGroupRef "@crescent_city_bb_fab1_lib.crescent_city_bb_fab1(sch_1):\MG_DDR_FAR_DIMM-CLK0_CLS_DDR_D_CAC-CLKS\" )
					)
					( Units "uMatchProp" "ns" 1.000000)
					( Status sCSetFlattened )
					( Origin gBackEnd )
				)
				( attribute "RELATIVE_PROPAGATION_DELAY_SCOPE" "G"
					( Parent
						( matchGroupRef "@baseboard_fab2_lib.baseboard_fab2(sch_1):\MG_DDR_FAR_DIMM_CMD_NG_DDR_D_DLL_11\" )
					)
					( Status sCSetFlattened )
					( Origin gBackEnd )
				)
				( attribute "RELATIVE_PROPAGATION_DELAY" "0.00 MIL,25.00 MIL"
					( Parent
						( matchGroupRef "@baseboard_fab2_lib.baseboard_fab2(sch_1):\MG_DDR_FAR_DIMM_CMD_NG_DDR_D_DLL_11\" )
					)
					( Units "uMatchProp" "ns" 1.000000)
					( Status sCSetFlattened )
					( Origin gBackEnd )
				)
			)
			( pinPair "@baseboard_fab2_lib.baseboard_fab2(sch_1):\PP3820\"
				( pinRef "@baseboard_fab2_lib.baseboard_fab2(sch_1):page50_i158:A9" )
				( pinRef "@baseboard_fab2_lib.baseboard_fab2(sch_1):page26_i172:DDR3_MA(9)" )
				( attribute "RELATIVE_PROPAGATION_DELAY_SCOPE" "G"
					( Parent
						( matchGroupRef "@crescent_city_bb_fab1_lib.crescent_city_bb_fab1(sch_1):\MG_DDR_NEAR_DIMM-CLK1_CLS_DDR_D_CAC-CLKS\" )
					)
					( Status sCSetFlattened )
					( Origin gBackEnd )
				)
				( attribute "RELATIVE_PROPAGATION_DELAY" "0.00 MIL,700.00 MIL"
					( Parent
						( matchGroupRef "@crescent_city_bb_fab1_lib.crescent_city_bb_fab1(sch_1):\MG_DDR_NEAR_DIMM-CLK1_CLS_DDR_D_CAC-CLKS\" )
					)
					( Units "uMatchProp" "ns" 1.000000)
					( Status sCSetFlattened )
					( Origin gBackEnd )
				)
				( attribute "RELATIVE_PROPAGATION_DELAY_SCOPE" "G"
					( Parent
						( matchGroupRef "@baseboard_fab2_lib.baseboard_fab2(sch_1):\MG_DDR_CMD_NEAR_DIMM_NG_DDR_D_DLL_11\" )
					)
					( Status sCSetFlattened )
					( Origin gBackEnd )
				)
				( attribute "RELATIVE_PROPAGATION_DELAY" "0.00 MIL,25.00 MIL"
					( Parent
						( matchGroupRef "@baseboard_fab2_lib.baseboard_fab2(sch_1):\MG_DDR_CMD_NEAR_DIMM_NG_DDR_D_DLL_11\" )
					)
					( Units "uMatchProp" "ns" 1.000000)
					( Status sCSetFlattened )
					( Origin gBackEnd )
				)
			)
			( pinPair "@baseboard_fab2_lib.baseboard_fab2(sch_1):\PP3821\"
				( pinRef "@baseboard_fab2_lib.baseboard_fab2(sch_1):page26_i172:DDR3_MA(12)" )
				( pinRef "@baseboard_fab2_lib.baseboard_fab2(sch_1):page49_i111:A12" )
				( attribute "RELATIVE_PROPAGATION_DELAY_SCOPE" "G"
					( Parent
						( matchGroupRef "@crescent_city_bb_fab1_lib.crescent_city_bb_fab1(sch_1):\MG_DDR_FAR_DIMM-CLK0_CLS_DDR_D_CAC-CLKS\" )
					)
					( Status sCSetFlattened )
					( Origin gBackEnd )
				)
				( attribute "RELATIVE_PROPAGATION_DELAY" "0.00 MIL,700.00 MIL"
					( Parent
						( matchGroupRef "@crescent_city_bb_fab1_lib.crescent_city_bb_fab1(sch_1):\MG_DDR_FAR_DIMM-CLK0_CLS_DDR_D_CAC-CLKS\" )
					)
					( Units "uMatchProp" "ns" 1.000000)
					( Status sCSetFlattened )
					( Origin gBackEnd )
				)
				( attribute "RELATIVE_PROPAGATION_DELAY_SCOPE" "G"
					( Parent
						( matchGroupRef "@baseboard_fab2_lib.baseboard_fab2(sch_1):\MG_DDR_FAR_DIMM_CMD_NG_DDR_D_DLL_11\" )
					)
					( Status sCSetFlattened )
					( Origin gBackEnd )
				)
				( attribute "RELATIVE_PROPAGATION_DELAY" "0.00 MIL,25.00 MIL"
					( Parent
						( matchGroupRef "@baseboard_fab2_lib.baseboard_fab2(sch_1):\MG_DDR_FAR_DIMM_CMD_NG_DDR_D_DLL_11\" )
					)
					( Units "uMatchProp" "ns" 1.000000)
					( Status sCSetFlattened )
					( Origin gBackEnd )
				)
			)
			( pinPair "@baseboard_fab2_lib.baseboard_fab2(sch_1):\PP3822\"
				( pinRef "@baseboard_fab2_lib.baseboard_fab2(sch_1):page26_i172:DDR3_MA(12)" )
				( pinRef "@baseboard_fab2_lib.baseboard_fab2(sch_1):page50_i158:A12" )
				( attribute "RELATIVE_PROPAGATION_DELAY_SCOPE" "G"
					( Parent
						( matchGroupRef "@crescent_city_bb_fab1_lib.crescent_city_bb_fab1(sch_1):\MG_DDR_NEAR_DIMM-CLK1_CLS_DDR_D_CAC-CLKS\" )
					)
					( Status sCSetFlattened )
					( Origin gBackEnd )
				)
				( attribute "RELATIVE_PROPAGATION_DELAY" "0.00 MIL,700.00 MIL"
					( Parent
						( matchGroupRef "@crescent_city_bb_fab1_lib.crescent_city_bb_fab1(sch_1):\MG_DDR_NEAR_DIMM-CLK1_CLS_DDR_D_CAC-CLKS\" )
					)
					( Units "uMatchProp" "ns" 1.000000)
					( Status sCSetFlattened )
					( Origin gBackEnd )
				)
				( attribute "RELATIVE_PROPAGATION_DELAY_SCOPE" "G"
					( Parent
						( matchGroupRef "@baseboard_fab2_lib.baseboard_fab2(sch_1):\MG_DDR_CMD_NEAR_DIMM_NG_DDR_D_DLL_11\" )
					)
					( Status sCSetFlattened )
					( Origin gBackEnd )
				)
				( attribute "RELATIVE_PROPAGATION_DELAY" "0.00 MIL,25.00 MIL"
					( Parent
						( matchGroupRef "@baseboard_fab2_lib.baseboard_fab2(sch_1):\MG_DDR_CMD_NEAR_DIMM_NG_DDR_D_DLL_11\" )
					)
					( Units "uMatchProp" "ns" 1.000000)
					( Status sCSetFlattened )
					( Origin gBackEnd )
				)
			)
			( pinPair "@baseboard_fab2_lib.baseboard_fab2(sch_1):\PP3815\"
				( pinRef "@baseboard_fab2_lib.baseboard_fab2(sch_1):page26_i172:DDR3_BG(1)" )
				( pinRef "@baseboard_fab2_lib.baseboard_fab2(sch_1):page49_i111:BG(1)" )
				( attribute "RELATIVE_PROPAGATION_DELAY_SCOPE" "G"
					( Parent
						( matchGroupRef "@crescent_city_bb_fab1_lib.crescent_city_bb_fab1(sch_1):\MG_DDR_FAR_DIMM-CLK0_CLS_DDR_D_CAC-CLKS\" )
					)
					( Status sCSetFlattened )
					( Origin gBackEnd )
				)
				( attribute "RELATIVE_PROPAGATION_DELAY" "0.00 MIL,700.00 MIL"
					( Parent
						( matchGroupRef "@crescent_city_bb_fab1_lib.crescent_city_bb_fab1(sch_1):\MG_DDR_FAR_DIMM-CLK0_CLS_DDR_D_CAC-CLKS\" )
					)
					( Units "uMatchProp" "ns" 1.000000)
					( Status sCSetFlattened )
					( Origin gBackEnd )
				)
				( attribute "RELATIVE_PROPAGATION_DELAY_SCOPE" "G"
					( Parent
						( matchGroupRef "@baseboard_fab2_lib.baseboard_fab2(sch_1):\MG_DDR_FAR_DIMM_CMD_NG_DDR_D_DLL_12\" )
					)
					( Status sCSetFlattened )
					( Origin gBackEnd )
				)
				( attribute "RELATIVE_PROPAGATION_DELAY" "0.00 MIL,25.00 MIL"
					( Parent
						( matchGroupRef "@baseboard_fab2_lib.baseboard_fab2(sch_1):\MG_DDR_FAR_DIMM_CMD_NG_DDR_D_DLL_12\" )
					)
					( Units "uMatchProp" "ns" 1.000000)
					( Status sCSetFlattened )
					( Origin gBackEnd )
				)
			)
			( pinPair "@baseboard_fab2_lib.baseboard_fab2(sch_1):\PP3816\"
				( pinRef "@baseboard_fab2_lib.baseboard_fab2(sch_1):page50_i158:BG(1)" )
				( pinRef "@baseboard_fab2_lib.baseboard_fab2(sch_1):page26_i172:DDR3_BG(1)" )
				( attribute "RELATIVE_PROPAGATION_DELAY_SCOPE" "G"
					( Parent
						( matchGroupRef "@crescent_city_bb_fab1_lib.crescent_city_bb_fab1(sch_1):\MG_DDR_NEAR_DIMM-CLK1_CLS_DDR_D_CAC-CLKS\" )
					)
					( Status sCSetFlattened )
					( Origin gBackEnd )
				)
				( attribute "RELATIVE_PROPAGATION_DELAY" "0.00 MIL,700.00 MIL"
					( Parent
						( matchGroupRef "@crescent_city_bb_fab1_lib.crescent_city_bb_fab1(sch_1):\MG_DDR_NEAR_DIMM-CLK1_CLS_DDR_D_CAC-CLKS\" )
					)
					( Units "uMatchProp" "ns" 1.000000)
					( Status sCSetFlattened )
					( Origin gBackEnd )
				)
				( attribute "RELATIVE_PROPAGATION_DELAY_SCOPE" "G"
					( Parent
						( matchGroupRef "@baseboard_fab2_lib.baseboard_fab2(sch_1):\MG_DDR_CMD_NEAR_DIMM_NG_DDR_D_DLL_12\" )
					)
					( Status sCSetFlattened )
					( Origin gBackEnd )
				)
				( attribute "RELATIVE_PROPAGATION_DELAY" "0.00 MIL,25.00 MIL"
					( Parent
						( matchGroupRef "@baseboard_fab2_lib.baseboard_fab2(sch_1):\MG_DDR_CMD_NEAR_DIMM_NG_DDR_D_DLL_12\" )
					)
					( Units "uMatchProp" "ns" 1.000000)
					( Status sCSetFlattened )
					( Origin gBackEnd )
				)
			)
			( pinPair "@baseboard_fab2_lib.baseboard_fab2(sch_1):\PP3817\"
				( pinRef "@baseboard_fab2_lib.baseboard_fab2(sch_1):page26_i172:DDR3_MA(11)" )
				( pinRef "@baseboard_fab2_lib.baseboard_fab2(sch_1):page49_i111:A11" )
				( attribute "RELATIVE_PROPAGATION_DELAY_SCOPE" "G"
					( Parent
						( matchGroupRef "@crescent_city_bb_fab1_lib.crescent_city_bb_fab1(sch_1):\MG_DDR_FAR_DIMM-CLK0_CLS_DDR_D_CAC-CLKS\" )
					)
					( Status sCSetFlattened )
					( Origin gBackEnd )
				)
				( attribute "RELATIVE_PROPAGATION_DELAY" "0.00 MIL,700.00 MIL"
					( Parent
						( matchGroupRef "@crescent_city_bb_fab1_lib.crescent_city_bb_fab1(sch_1):\MG_DDR_FAR_DIMM-CLK0_CLS_DDR_D_CAC-CLKS\" )
					)
					( Units "uMatchProp" "ns" 1.000000)
					( Status sCSetFlattened )
					( Origin gBackEnd )
				)
				( attribute "RELATIVE_PROPAGATION_DELAY_SCOPE" "G"
					( Parent
						( matchGroupRef "@baseboard_fab2_lib.baseboard_fab2(sch_1):\MG_DDR_FAR_DIMM_CMD_NG_DDR_D_DLL_12\" )
					)
					( Status sCSetFlattened )
					( Origin gBackEnd )
				)
				( attribute "RELATIVE_PROPAGATION_DELAY" "0.00 MIL,25.00 MIL"
					( Parent
						( matchGroupRef "@baseboard_fab2_lib.baseboard_fab2(sch_1):\MG_DDR_FAR_DIMM_CMD_NG_DDR_D_DLL_12\" )
					)
					( Units "uMatchProp" "ns" 1.000000)
					( Status sCSetFlattened )
					( Origin gBackEnd )
				)
			)
			( pinPair "@baseboard_fab2_lib.baseboard_fab2(sch_1):\PP3818\"
				( pinRef "@baseboard_fab2_lib.baseboard_fab2(sch_1):page26_i172:DDR3_MA(11)" )
				( pinRef "@baseboard_fab2_lib.baseboard_fab2(sch_1):page50_i158:A11" )
				( attribute "RELATIVE_PROPAGATION_DELAY_SCOPE" "G"
					( Parent
						( matchGroupRef "@crescent_city_bb_fab1_lib.crescent_city_bb_fab1(sch_1):\MG_DDR_NEAR_DIMM-CLK1_CLS_DDR_D_CAC-CLKS\" )
					)
					( Status sCSetFlattened )
					( Origin gBackEnd )
				)
				( attribute "RELATIVE_PROPAGATION_DELAY" "0.00 MIL,700.00 MIL"
					( Parent
						( matchGroupRef "@crescent_city_bb_fab1_lib.crescent_city_bb_fab1(sch_1):\MG_DDR_NEAR_DIMM-CLK1_CLS_DDR_D_CAC-CLKS\" )
					)
					( Units "uMatchProp" "ns" 1.000000)
					( Status sCSetFlattened )
					( Origin gBackEnd )
				)
				( attribute "RELATIVE_PROPAGATION_DELAY_SCOPE" "G"
					( Parent
						( matchGroupRef "@baseboard_fab2_lib.baseboard_fab2(sch_1):\MG_DDR_CMD_NEAR_DIMM_NG_DDR_D_DLL_12\" )
					)
					( Status sCSetFlattened )
					( Origin gBackEnd )
				)
				( attribute "RELATIVE_PROPAGATION_DELAY" "0.00 MIL,25.00 MIL"
					( Parent
						( matchGroupRef "@baseboard_fab2_lib.baseboard_fab2(sch_1):\MG_DDR_CMD_NEAR_DIMM_NG_DDR_D_DLL_12\" )
					)
					( Units "uMatchProp" "ns" 1.000000)
					( Status sCSetFlattened )
					( Origin gBackEnd )
				)
			)
			( pinPair "@baseboard_fab2_lib.baseboard_fab2(sch_1):\PP3811\"
				( pinRef "@baseboard_fab2_lib.baseboard_fab2(sch_1):page26_i172:DDR3_ACT_N" )
				( pinRef "@baseboard_fab2_lib.baseboard_fab2(sch_1):page49_i111:ACT_N" )
				( attribute "RELATIVE_PROPAGATION_DELAY_SCOPE" "G"
					( Parent
						( matchGroupRef "@crescent_city_bb_fab1_lib.crescent_city_bb_fab1(sch_1):\MG_DDR_FAR_DIMM-CLK0_CLS_DDR_D_CAC-CLKS\" )
					)
					( Status sCSetFlattened )
					( Origin gBackEnd )
				)
				( attribute "RELATIVE_PROPAGATION_DELAY" "0.00 MIL,700.00 MIL"
					( Parent
						( matchGroupRef "@crescent_city_bb_fab1_lib.crescent_city_bb_fab1(sch_1):\MG_DDR_FAR_DIMM-CLK0_CLS_DDR_D_CAC-CLKS\" )
					)
					( Units "uMatchProp" "ns" 1.000000)
					( Status sCSetFlattened )
					( Origin gBackEnd )
				)
				( attribute "RELATIVE_PROPAGATION_DELAY_SCOPE" "G"
					( Parent
						( matchGroupRef "@baseboard_fab2_lib.baseboard_fab2(sch_1):\MG_DDR_FAR_DIMM_CMD_NG_DDR_D_DLL_13\" )
					)
					( Status sCSetFlattened )
					( Origin gBackEnd )
				)
				( attribute "RELATIVE_PROPAGATION_DELAY" "0.00 MIL,25.00 MIL"
					( Parent
						( matchGroupRef "@baseboard_fab2_lib.baseboard_fab2(sch_1):\MG_DDR_FAR_DIMM_CMD_NG_DDR_D_DLL_13\" )
					)
					( Units "uMatchProp" "ns" 1.000000)
					( Status sCSetFlattened )
					( Origin gBackEnd )
				)
			)
			( pinPair "@baseboard_fab2_lib.baseboard_fab2(sch_1):\PP3812\"
				( pinRef "@baseboard_fab2_lib.baseboard_fab2(sch_1):page50_i158:ACT_N" )
				( pinRef "@baseboard_fab2_lib.baseboard_fab2(sch_1):page26_i172:DDR3_ACT_N" )
				( attribute "RELATIVE_PROPAGATION_DELAY_SCOPE" "G"
					( Parent
						( matchGroupRef "@crescent_city_bb_fab1_lib.crescent_city_bb_fab1(sch_1):\MG_DDR_NEAR_DIMM-CLK1_CLS_DDR_D_CAC-CLKS\" )
					)
					( Status sCSetFlattened )
					( Origin gBackEnd )
				)
				( attribute "RELATIVE_PROPAGATION_DELAY" "0.00 MIL,700.00 MIL"
					( Parent
						( matchGroupRef "@crescent_city_bb_fab1_lib.crescent_city_bb_fab1(sch_1):\MG_DDR_NEAR_DIMM-CLK1_CLS_DDR_D_CAC-CLKS\" )
					)
					( Units "uMatchProp" "ns" 1.000000)
					( Status sCSetFlattened )
					( Origin gBackEnd )
				)
				( attribute "RELATIVE_PROPAGATION_DELAY_SCOPE" "G"
					( Parent
						( matchGroupRef "@baseboard_fab2_lib.baseboard_fab2(sch_1):\MG_DDR_CMD_NEAR_DIMM_NG_DDR_D_DLL_13\" )
					)
					( Status sCSetFlattened )
					( Origin gBackEnd )
				)
				( attribute "RELATIVE_PROPAGATION_DELAY" "0.00 MIL,25.00 MIL"
					( Parent
						( matchGroupRef "@baseboard_fab2_lib.baseboard_fab2(sch_1):\MG_DDR_CMD_NEAR_DIMM_NG_DDR_D_DLL_13\" )
					)
					( Units "uMatchProp" "ns" 1.000000)
					( Status sCSetFlattened )
					( Origin gBackEnd )
				)
			)
			( pinPair "@baseboard_fab2_lib.baseboard_fab2(sch_1):\PP3813\"
				( pinRef "@baseboard_fab2_lib.baseboard_fab2(sch_1):page26_i172:DDR3_BG(0)" )
				( pinRef "@baseboard_fab2_lib.baseboard_fab2(sch_1):page49_i111:BG(0)" )
				( attribute "RELATIVE_PROPAGATION_DELAY_SCOPE" "G"
					( Parent
						( matchGroupRef "@crescent_city_bb_fab1_lib.crescent_city_bb_fab1(sch_1):\MG_DDR_FAR_DIMM-CLK0_CLS_DDR_D_CAC-CLKS\" )
					)
					( Status sCSetFlattened )
					( Origin gBackEnd )
				)
				( attribute "RELATIVE_PROPAGATION_DELAY" "0.00 MIL,700.00 MIL"
					( Parent
						( matchGroupRef "@crescent_city_bb_fab1_lib.crescent_city_bb_fab1(sch_1):\MG_DDR_FAR_DIMM-CLK0_CLS_DDR_D_CAC-CLKS\" )
					)
					( Units "uMatchProp" "ns" 1.000000)
					( Status sCSetFlattened )
					( Origin gBackEnd )
				)
				( attribute "RELATIVE_PROPAGATION_DELAY_SCOPE" "G"
					( Parent
						( matchGroupRef "@baseboard_fab2_lib.baseboard_fab2(sch_1):\MG_DDR_FAR_DIMM_CMD_NG_DDR_D_DLL_13\" )
					)
					( Status sCSetFlattened )
					( Origin gBackEnd )
				)
				( attribute "RELATIVE_PROPAGATION_DELAY" "0.00 MIL,25.00 MIL"
					( Parent
						( matchGroupRef "@baseboard_fab2_lib.baseboard_fab2(sch_1):\MG_DDR_FAR_DIMM_CMD_NG_DDR_D_DLL_13\" )
					)
					( Units "uMatchProp" "ns" 1.000000)
					( Status sCSetFlattened )
					( Origin gBackEnd )
				)
			)
			( pinPair "@baseboard_fab2_lib.baseboard_fab2(sch_1):\PP3814\"
				( pinRef "@baseboard_fab2_lib.baseboard_fab2(sch_1):page50_i158:BG(0)" )
				( pinRef "@baseboard_fab2_lib.baseboard_fab2(sch_1):page26_i172:DDR3_BG(0)" )
				( attribute "RELATIVE_PROPAGATION_DELAY_SCOPE" "G"
					( Parent
						( matchGroupRef "@crescent_city_bb_fab1_lib.crescent_city_bb_fab1(sch_1):\MG_DDR_NEAR_DIMM-CLK1_CLS_DDR_D_CAC-CLKS\" )
					)
					( Status sCSetFlattened )
					( Origin gBackEnd )
				)
				( attribute "RELATIVE_PROPAGATION_DELAY" "0.00 MIL,700.00 MIL"
					( Parent
						( matchGroupRef "@crescent_city_bb_fab1_lib.crescent_city_bb_fab1(sch_1):\MG_DDR_NEAR_DIMM-CLK1_CLS_DDR_D_CAC-CLKS\" )
					)
					( Units "uMatchProp" "ns" 1.000000)
					( Status sCSetFlattened )
					( Origin gBackEnd )
				)
				( attribute "RELATIVE_PROPAGATION_DELAY_SCOPE" "G"
					( Parent
						( matchGroupRef "@baseboard_fab2_lib.baseboard_fab2(sch_1):\MG_DDR_CMD_NEAR_DIMM_NG_DDR_D_DLL_13\" )
					)
					( Status sCSetFlattened )
					( Origin gBackEnd )
				)
				( attribute "RELATIVE_PROPAGATION_DELAY" "0.00 MIL,25.00 MIL"
					( Parent
						( matchGroupRef "@baseboard_fab2_lib.baseboard_fab2(sch_1):\MG_DDR_CMD_NEAR_DIMM_NG_DDR_D_DLL_13\" )
					)
					( Units "uMatchProp" "ns" 1.000000)
					( Status sCSetFlattened )
					( Origin gBackEnd )
				)
			)
			( pinPair "@baseboard_fab2_lib.baseboard_fab2(sch_1):\PP3809\"
				( pinRef "@baseboard_fab2_lib.baseboard_fab2(sch_1):page49_i111:S0_N" )
				( pinRef "@baseboard_fab2_lib.baseboard_fab2(sch_1):page26_i172:DDR3_CS_N(0)" )
				( attribute "RELATIVE_PROPAGATION_DELAY_SCOPE" "G"
					( Parent
						( matchGroupRef "@crescent_city_bb_fab1_lib.crescent_city_bb_fab1(sch_1):\MG_DDR_FAR_DIMM-CLK0_CLS_DDR_D_CAC-CLKS\" )
					)
					( Status sCSetFlattened )
					( Origin gBackEnd )
				)
				( attribute "RELATIVE_PROPAGATION_DELAY" "0.00 MIL,300.00 MIL"
					( Parent
						( matchGroupRef "@crescent_city_bb_fab1_lib.crescent_city_bb_fab1(sch_1):\MG_DDR_FAR_DIMM-CLK0_CLS_DDR_D_CAC-CLKS\" )
					)
					( Units "uMatchProp" "ns" 1.000000)
					( Status sCSetFlattened )
					( Origin gBackEnd )
				)
				( attribute "RELATIVE_PROPAGATION_DELAY_SCOPE" "G"
					( Parent
						( matchGroupRef "@baseboard_fab2_lib.baseboard_fab2(sch_1):\MG_DDR_CTRL_NG_DDR_D_DLL_14\" )
					)
					( Status sCSetFlattened )
					( Origin gBackEnd )
				)
				( attribute "RELATIVE_PROPAGATION_DELAY" "0.00 MIL,25.00 MIL"
					( Parent
						( matchGroupRef "@baseboard_fab2_lib.baseboard_fab2(sch_1):\MG_DDR_CTRL_NG_DDR_D_DLL_14\" )
					)
					( Units "uMatchProp" "ns" 1.000000)
					( Status sCSetFlattened )
					( Origin gBackEnd )
				)
			)
			( pinPair "@baseboard_fab2_lib.baseboard_fab2(sch_1):\PP3810\"
				( pinRef "@baseboard_fab2_lib.baseboard_fab2(sch_1):page49_i111:ODT(0)" )
				( pinRef "@baseboard_fab2_lib.baseboard_fab2(sch_1):page26_i172:DDR3_ODT(0)" )
				( attribute "RELATIVE_PROPAGATION_DELAY_SCOPE" "G"
					( Parent
						( matchGroupRef "@crescent_city_bb_fab1_lib.crescent_city_bb_fab1(sch_1):\MG_DDR_FAR_DIMM-CLK0_CLS_DDR_D_CAC-CLKS\" )
					)
					( Status sCSetFlattened )
					( Origin gBackEnd )
				)
				( attribute "RELATIVE_PROPAGATION_DELAY" "0.00 MIL,300.00 MIL"
					( Parent
						( matchGroupRef "@crescent_city_bb_fab1_lib.crescent_city_bb_fab1(sch_1):\MG_DDR_FAR_DIMM-CLK0_CLS_DDR_D_CAC-CLKS\" )
					)
					( Units "uMatchProp" "ns" 1.000000)
					( Status sCSetFlattened )
					( Origin gBackEnd )
				)
				( attribute "RELATIVE_PROPAGATION_DELAY_SCOPE" "G"
					( Parent
						( matchGroupRef "@baseboard_fab2_lib.baseboard_fab2(sch_1):\MG_DDR_CTRL_NG_DDR_D_DLL_14\" )
					)
					( Status sCSetFlattened )
					( Origin gBackEnd )
				)
				( attribute "RELATIVE_PROPAGATION_DELAY" "0.00 MIL,25.00 MIL"
					( Parent
						( matchGroupRef "@baseboard_fab2_lib.baseboard_fab2(sch_1):\MG_DDR_CTRL_NG_DDR_D_DLL_14\" )
					)
					( Units "uMatchProp" "ns" 1.000000)
					( Status sCSetFlattened )
					( Origin gBackEnd )
				)
			)
			( pinPair "@baseboard_fab2_lib.baseboard_fab2(sch_1):\PP3808\"
				( pinRef "@baseboard_fab2_lib.baseboard_fab2(sch_1):page49_i111:CKE(0)" )
				( pinRef "@baseboard_fab2_lib.baseboard_fab2(sch_1):page26_i172:DDR3_CKE(0)" )
				( attribute "RELATIVE_PROPAGATION_DELAY_SCOPE" "G"
					( Parent
						( matchGroupRef "@crescent_city_bb_fab1_lib.crescent_city_bb_fab1(sch_1):\MG_DDR_FAR_DIMM-CLK0_CLS_DDR_D_CAC-CLKS\" )
					)
					( Status sCSetFlattened )
					( Origin gBackEnd )
				)
				( attribute "RELATIVE_PROPAGATION_DELAY" "0.00 MIL,300.00 MIL"
					( Parent
						( matchGroupRef "@crescent_city_bb_fab1_lib.crescent_city_bb_fab1(sch_1):\MG_DDR_FAR_DIMM-CLK0_CLS_DDR_D_CAC-CLKS\" )
					)
					( Units "uMatchProp" "ns" 1.000000)
					( Status sCSetFlattened )
					( Origin gBackEnd )
				)
				( attribute "RELATIVE_PROPAGATION_DELAY_SCOPE" "G"
					( Parent
						( matchGroupRef "@baseboard_fab2_lib.baseboard_fab2(sch_1):\MG_DDR_CTRL_NG_DDR_D_DLL_15\" )
					)
					( Status sCSetFlattened )
					( Origin gBackEnd )
				)
				( attribute "RELATIVE_PROPAGATION_DELAY" "0.00 MIL,25.00 MIL"
					( Parent
						( matchGroupRef "@baseboard_fab2_lib.baseboard_fab2(sch_1):\MG_DDR_CTRL_NG_DDR_D_DLL_15\" )
					)
					( Units "uMatchProp" "ns" 1.000000)
					( Status sCSetFlattened )
					( Origin gBackEnd )
				)
			)
			( pinPair "@baseboard_fab2_lib.baseboard_fab2(sch_1):\PP3807\"
				( pinRef "@baseboard_fab2_lib.baseboard_fab2(sch_1):page49_i111:S2_N_C(0)" )
				( pinRef "@baseboard_fab2_lib.baseboard_fab2(sch_1):page26_i172:DDR3_CS_N(2)" )
				( attribute "RELATIVE_PROPAGATION_DELAY_SCOPE" "G"
					( Parent
						( matchGroupRef "@crescent_city_bb_fab1_lib.crescent_city_bb_fab1(sch_1):\MG_DDR_FAR_DIMM-CLK0_CLS_DDR_D_CAC-CLKS\" )
					)
					( Status sCSetFlattened )
					( Origin gBackEnd )
				)
				( attribute "RELATIVE_PROPAGATION_DELAY" "0.00 MIL,300.00 MIL"
					( Parent
						( matchGroupRef "@crescent_city_bb_fab1_lib.crescent_city_bb_fab1(sch_1):\MG_DDR_FAR_DIMM-CLK0_CLS_DDR_D_CAC-CLKS\" )
					)
					( Units "uMatchProp" "ns" 1.000000)
					( Status sCSetFlattened )
					( Origin gBackEnd )
				)
				( attribute "RELATIVE_PROPAGATION_DELAY_SCOPE" "G"
					( Parent
						( matchGroupRef "@baseboard_fab2_lib.baseboard_fab2(sch_1):\MG_DDR_CTRL_NG_DDR_D_DLL_16\" )
					)
					( Status sCSetFlattened )
					( Origin gBackEnd )
				)
				( attribute "RELATIVE_PROPAGATION_DELAY" "0.00 MIL,25.00 MIL"
					( Parent
						( matchGroupRef "@baseboard_fab2_lib.baseboard_fab2(sch_1):\MG_DDR_CTRL_NG_DDR_D_DLL_16\" )
					)
					( Units "uMatchProp" "ns" 1.000000)
					( Status sCSetFlattened )
					( Origin gBackEnd )
				)
			)
			( pinPair "@baseboard_fab2_lib.baseboard_fab2(sch_1):\PP3806\"
				( pinRef "@baseboard_fab2_lib.baseboard_fab2(sch_1):page49_i111:S3_N_C(1)" )
				( pinRef "@baseboard_fab2_lib.baseboard_fab2(sch_1):page26_i172:DDR3_CS_N(3)" )
				( attribute "RELATIVE_PROPAGATION_DELAY_SCOPE" "G"
					( Parent
						( matchGroupRef "@crescent_city_bb_fab1_lib.crescent_city_bb_fab1(sch_1):\MG_DDR_FAR_DIMM-CLK0_CLS_DDR_D_CAC-CLKS\" )
					)
					( Status sCSetFlattened )
					( Origin gBackEnd )
				)
				( attribute "RELATIVE_PROPAGATION_DELAY" "0.00 MIL,300.00 MIL"
					( Parent
						( matchGroupRef "@crescent_city_bb_fab1_lib.crescent_city_bb_fab1(sch_1):\MG_DDR_FAR_DIMM-CLK0_CLS_DDR_D_CAC-CLKS\" )
					)
					( Units "uMatchProp" "ns" 1.000000)
					( Status sCSetFlattened )
					( Origin gBackEnd )
				)
				( attribute "RELATIVE_PROPAGATION_DELAY_SCOPE" "G"
					( Parent
						( matchGroupRef "@baseboard_fab2_lib.baseboard_fab2(sch_1):\MG_DDR_CTRL_NG_DDR_D_DLL_17\" )
					)
					( Status sCSetFlattened )
					( Origin gBackEnd )
				)
				( attribute "RELATIVE_PROPAGATION_DELAY" "0.00 MIL,25.00 MIL"
					( Parent
						( matchGroupRef "@baseboard_fab2_lib.baseboard_fab2(sch_1):\MG_DDR_CTRL_NG_DDR_D_DLL_17\" )
					)
					( Units "uMatchProp" "ns" 1.000000)
					( Status sCSetFlattened )
					( Origin gBackEnd )
				)
			)
			( pinPair "@baseboard_fab2_lib.baseboard_fab2(sch_1):\PP3804\"
				( pinRef "@baseboard_fab2_lib.baseboard_fab2(sch_1):page49_i111:S1_N" )
				( pinRef "@baseboard_fab2_lib.baseboard_fab2(sch_1):page26_i172:DDR3_CS_N(1)" )
				( attribute "RELATIVE_PROPAGATION_DELAY_SCOPE" "G"
					( Parent
						( matchGroupRef "@crescent_city_bb_fab1_lib.crescent_city_bb_fab1(sch_1):\MG_DDR_FAR_DIMM-CLK0_CLS_DDR_D_CAC-CLKS\" )
					)
					( Status sCSetFlattened )
					( Origin gBackEnd )
				)
				( attribute "RELATIVE_PROPAGATION_DELAY" "0.00 MIL,300.00 MIL"
					( Parent
						( matchGroupRef "@crescent_city_bb_fab1_lib.crescent_city_bb_fab1(sch_1):\MG_DDR_FAR_DIMM-CLK0_CLS_DDR_D_CAC-CLKS\" )
					)
					( Units "uMatchProp" "ns" 1.000000)
					( Status sCSetFlattened )
					( Origin gBackEnd )
				)
				( attribute "RELATIVE_PROPAGATION_DELAY_SCOPE" "G"
					( Parent
						( matchGroupRef "@baseboard_fab2_lib.baseboard_fab2(sch_1):\MG_DDR_CTRL_NG_DDR_D_DLL_18\" )
					)
					( Status sCSetFlattened )
					( Origin gBackEnd )
				)
				( attribute "RELATIVE_PROPAGATION_DELAY" "0.00 MIL,25.00 MIL"
					( Parent
						( matchGroupRef "@baseboard_fab2_lib.baseboard_fab2(sch_1):\MG_DDR_CTRL_NG_DDR_D_DLL_18\" )
					)
					( Units "uMatchProp" "ns" 1.000000)
					( Status sCSetFlattened )
					( Origin gBackEnd )
				)
			)
			( pinPair "@baseboard_fab2_lib.baseboard_fab2(sch_1):\PP3805\"
				( pinRef "@baseboard_fab2_lib.baseboard_fab2(sch_1):page49_i111:ODT(1)" )
				( pinRef "@baseboard_fab2_lib.baseboard_fab2(sch_1):page26_i172:DDR3_ODT(1)" )
				( attribute "RELATIVE_PROPAGATION_DELAY_SCOPE" "G"
					( Parent
						( matchGroupRef "@crescent_city_bb_fab1_lib.crescent_city_bb_fab1(sch_1):\MG_DDR_FAR_DIMM-CLK0_CLS_DDR_D_CAC-CLKS\" )
					)
					( Status sCSetFlattened )
					( Origin gBackEnd )
				)
				( attribute "RELATIVE_PROPAGATION_DELAY" "0.00 MIL,300.00 MIL"
					( Parent
						( matchGroupRef "@crescent_city_bb_fab1_lib.crescent_city_bb_fab1(sch_1):\MG_DDR_FAR_DIMM-CLK0_CLS_DDR_D_CAC-CLKS\" )
					)
					( Units "uMatchProp" "ns" 1.000000)
					( Status sCSetFlattened )
					( Origin gBackEnd )
				)
				( attribute "RELATIVE_PROPAGATION_DELAY_SCOPE" "G"
					( Parent
						( matchGroupRef "@baseboard_fab2_lib.baseboard_fab2(sch_1):\MG_DDR_CTRL_NG_DDR_D_DLL_18\" )
					)
					( Status sCSetFlattened )
					( Origin gBackEnd )
				)
				( attribute "RELATIVE_PROPAGATION_DELAY" "0.00 MIL,25.00 MIL"
					( Parent
						( matchGroupRef "@baseboard_fab2_lib.baseboard_fab2(sch_1):\MG_DDR_CTRL_NG_DDR_D_DLL_18\" )
					)
					( Units "uMatchProp" "ns" 1.000000)
					( Status sCSetFlattened )
					( Origin gBackEnd )
				)
			)
			( pinPair "@baseboard_fab2_lib.baseboard_fab2(sch_1):\PP3803\"
				( pinRef "@baseboard_fab2_lib.baseboard_fab2(sch_1):page49_i111:CKE(1)" )
				( pinRef "@baseboard_fab2_lib.baseboard_fab2(sch_1):page26_i172:DDR3_CKE(1)" )
				( attribute "RELATIVE_PROPAGATION_DELAY_SCOPE" "G"
					( Parent
						( matchGroupRef "@crescent_city_bb_fab1_lib.crescent_city_bb_fab1(sch_1):\MG_DDR_FAR_DIMM-CLK0_CLS_DDR_D_CAC-CLKS\" )
					)
					( Status sCSetFlattened )
					( Origin gBackEnd )
				)
				( attribute "RELATIVE_PROPAGATION_DELAY" "0.00 MIL,300.00 MIL"
					( Parent
						( matchGroupRef "@crescent_city_bb_fab1_lib.crescent_city_bb_fab1(sch_1):\MG_DDR_FAR_DIMM-CLK0_CLS_DDR_D_CAC-CLKS\" )
					)
					( Units "uMatchProp" "ns" 1.000000)
					( Status sCSetFlattened )
					( Origin gBackEnd )
				)
				( attribute "RELATIVE_PROPAGATION_DELAY_SCOPE" "G"
					( Parent
						( matchGroupRef "@baseboard_fab2_lib.baseboard_fab2(sch_1):\MG_DDR_CTRL_NG_DDR_D_DLL_19\" )
					)
					( Status sCSetFlattened )
					( Origin gBackEnd )
				)
				( attribute "RELATIVE_PROPAGATION_DELAY" "0.00 MIL,25.00 MIL"
					( Parent
						( matchGroupRef "@baseboard_fab2_lib.baseboard_fab2(sch_1):\MG_DDR_CTRL_NG_DDR_D_DLL_19\" )
					)
					( Units "uMatchProp" "ns" 1.000000)
					( Status sCSetFlattened )
					( Origin gBackEnd )
				)
			)
			( pinPair "@baseboard_fab2_lib.baseboard_fab2(sch_1):\PP3801\"
				( pinRef "@baseboard_fab2_lib.baseboard_fab2(sch_1):page50_i158:S0_N" )
				( pinRef "@baseboard_fab2_lib.baseboard_fab2(sch_1):page26_i172:DDR3_CS_N(4)" )
				( attribute "RELATIVE_PROPAGATION_DELAY_SCOPE" "G"
					( Parent
						( matchGroupRef "@crescent_city_bb_fab1_lib.crescent_city_bb_fab1(sch_1):\MG_DDR_NEAR_DIMM-CLK1_CLS_DDR_D_CAC-CLKS\" )
					)
					( Status sCSetFlattened )
					( Origin gBackEnd )
				)
				( attribute "RELATIVE_PROPAGATION_DELAY" "0.00 MIL,300.00 MIL"
					( Parent
						( matchGroupRef "@crescent_city_bb_fab1_lib.crescent_city_bb_fab1(sch_1):\MG_DDR_NEAR_DIMM-CLK1_CLS_DDR_D_CAC-CLKS\" )
					)
					( Units "uMatchProp" "ns" 1.000000)
					( Status sCSetFlattened )
					( Origin gBackEnd )
				)
				( attribute "RELATIVE_PROPAGATION_DELAY_SCOPE" "G"
					( Parent
						( matchGroupRef "@baseboard_fab2_lib.baseboard_fab2(sch_1):\MG_DDR_CTRL_NG_DDR_D_DLL_20\" )
					)
					( Status sCSetFlattened )
					( Origin gBackEnd )
				)
				( attribute "RELATIVE_PROPAGATION_DELAY" "0.00 MIL,25.00 MIL"
					( Parent
						( matchGroupRef "@baseboard_fab2_lib.baseboard_fab2(sch_1):\MG_DDR_CTRL_NG_DDR_D_DLL_20\" )
					)
					( Units "uMatchProp" "ns" 1.000000)
					( Status sCSetFlattened )
					( Origin gBackEnd )
				)
			)
			( pinPair "@baseboard_fab2_lib.baseboard_fab2(sch_1):\PP3802\"
				( pinRef "@baseboard_fab2_lib.baseboard_fab2(sch_1):page50_i158:ODT(0)" )
				( pinRef "@baseboard_fab2_lib.baseboard_fab2(sch_1):page26_i172:DDR3_ODT(2)" )
				( attribute "RELATIVE_PROPAGATION_DELAY_SCOPE" "G"
					( Parent
						( matchGroupRef "@crescent_city_bb_fab1_lib.crescent_city_bb_fab1(sch_1):\MG_DDR_NEAR_DIMM-CLK1_CLS_DDR_D_CAC-CLKS\" )
					)
					( Status sCSetFlattened )
					( Origin gBackEnd )
				)
				( attribute "RELATIVE_PROPAGATION_DELAY" "0.00 MIL,300.00 MIL"
					( Parent
						( matchGroupRef "@crescent_city_bb_fab1_lib.crescent_city_bb_fab1(sch_1):\MG_DDR_NEAR_DIMM-CLK1_CLS_DDR_D_CAC-CLKS\" )
					)
					( Units "uMatchProp" "ns" 1.000000)
					( Status sCSetFlattened )
					( Origin gBackEnd )
				)
				( attribute "RELATIVE_PROPAGATION_DELAY_SCOPE" "G"
					( Parent
						( matchGroupRef "@baseboard_fab2_lib.baseboard_fab2(sch_1):\MG_DDR_CTRL_NG_DDR_D_DLL_20\" )
					)
					( Status sCSetFlattened )
					( Origin gBackEnd )
				)
				( attribute "RELATIVE_PROPAGATION_DELAY" "0.00 MIL,25.00 MIL"
					( Parent
						( matchGroupRef "@baseboard_fab2_lib.baseboard_fab2(sch_1):\MG_DDR_CTRL_NG_DDR_D_DLL_20\" )
					)
					( Units "uMatchProp" "ns" 1.000000)
					( Status sCSetFlattened )
					( Origin gBackEnd )
				)
			)
			( pinPair "@baseboard_fab2_lib.baseboard_fab2(sch_1):\PP3800\"
				( pinRef "@baseboard_fab2_lib.baseboard_fab2(sch_1):page50_i158:CKE(0)" )
				( pinRef "@baseboard_fab2_lib.baseboard_fab2(sch_1):page26_i172:DDR3_CKE(2)" )
				( attribute "RELATIVE_PROPAGATION_DELAY_SCOPE" "G"
					( Parent
						( matchGroupRef "@crescent_city_bb_fab1_lib.crescent_city_bb_fab1(sch_1):\MG_DDR_NEAR_DIMM-CLK1_CLS_DDR_D_CAC-CLKS\" )
					)
					( Status sCSetFlattened )
					( Origin gBackEnd )
				)
				( attribute "RELATIVE_PROPAGATION_DELAY" "0.00 MIL,300.00 MIL"
					( Parent
						( matchGroupRef "@crescent_city_bb_fab1_lib.crescent_city_bb_fab1(sch_1):\MG_DDR_NEAR_DIMM-CLK1_CLS_DDR_D_CAC-CLKS\" )
					)
					( Units "uMatchProp" "ns" 1.000000)
					( Status sCSetFlattened )
					( Origin gBackEnd )
				)
				( attribute "RELATIVE_PROPAGATION_DELAY_SCOPE" "G"
					( Parent
						( matchGroupRef "@baseboard_fab2_lib.baseboard_fab2(sch_1):\MG_DDR_CTRL_NG_DDR_D_DLL_21\" )
					)
					( Status sCSetFlattened )
					( Origin gBackEnd )
				)
				( attribute "RELATIVE_PROPAGATION_DELAY" "0.00 MIL,25.00 MIL"
					( Parent
						( matchGroupRef "@baseboard_fab2_lib.baseboard_fab2(sch_1):\MG_DDR_CTRL_NG_DDR_D_DLL_21\" )
					)
					( Units "uMatchProp" "ns" 1.000000)
					( Status sCSetFlattened )
					( Origin gBackEnd )
				)
			)
			( pinPair "@baseboard_fab2_lib.baseboard_fab2(sch_1):\PP3798\"
				( pinRef "@baseboard_fab2_lib.baseboard_fab2(sch_1):page50_i158:S2_N_C(0)" )
				( pinRef "@baseboard_fab2_lib.baseboard_fab2(sch_1):page26_i172:DDR3_CS_N(6)" )
				( attribute "RELATIVE_PROPAGATION_DELAY_SCOPE" "G"
					( Parent
						( matchGroupRef "@crescent_city_bb_fab1_lib.crescent_city_bb_fab1(sch_1):\MG_DDR_NEAR_DIMM-CLK1_CLS_DDR_D_CAC-CLKS\" )
					)
					( Status sCSetFlattened )
					( Origin gBackEnd )
				)
				( attribute "RELATIVE_PROPAGATION_DELAY" "0.00 MIL,300.00 MIL"
					( Parent
						( matchGroupRef "@crescent_city_bb_fab1_lib.crescent_city_bb_fab1(sch_1):\MG_DDR_NEAR_DIMM-CLK1_CLS_DDR_D_CAC-CLKS\" )
					)
					( Units "uMatchProp" "ns" 1.000000)
					( Status sCSetFlattened )
					( Origin gBackEnd )
				)
				( attribute "RELATIVE_PROPAGATION_DELAY_SCOPE" "G"
					( Parent
						( matchGroupRef "@baseboard_fab2_lib.baseboard_fab2(sch_1):\MG_DDR_CTRL_NG_DDR_D_DLL_22\" )
					)
					( Status sCSetFlattened )
					( Origin gBackEnd )
				)
				( attribute "RELATIVE_PROPAGATION_DELAY" "0.00 MIL,25.00 MIL"
					( Parent
						( matchGroupRef "@baseboard_fab2_lib.baseboard_fab2(sch_1):\MG_DDR_CTRL_NG_DDR_D_DLL_22\" )
					)
					( Units "uMatchProp" "ns" 1.000000)
					( Status sCSetFlattened )
					( Origin gBackEnd )
				)
			)
			( pinPair "@baseboard_fab2_lib.baseboard_fab2(sch_1):\PP3799\"
				( pinRef "@baseboard_fab2_lib.baseboard_fab2(sch_1):page50_i158:S3_N_C(1)" )
				( pinRef "@baseboard_fab2_lib.baseboard_fab2(sch_1):page26_i172:DDR3_CS_N(7)" )
				( attribute "RELATIVE_PROPAGATION_DELAY_SCOPE" "G"
					( Parent
						( matchGroupRef "@crescent_city_bb_fab1_lib.crescent_city_bb_fab1(sch_1):\MG_DDR_NEAR_DIMM-CLK1_CLS_DDR_D_CAC-CLKS\" )
					)
					( Status sCSetFlattened )
					( Origin gBackEnd )
				)
				( attribute "RELATIVE_PROPAGATION_DELAY" "0.00 MIL,300.00 MIL"
					( Parent
						( matchGroupRef "@crescent_city_bb_fab1_lib.crescent_city_bb_fab1(sch_1):\MG_DDR_NEAR_DIMM-CLK1_CLS_DDR_D_CAC-CLKS\" )
					)
					( Units "uMatchProp" "ns" 1.000000)
					( Status sCSetFlattened )
					( Origin gBackEnd )
				)
				( attribute "RELATIVE_PROPAGATION_DELAY_SCOPE" "G"
					( Parent
						( matchGroupRef "@baseboard_fab2_lib.baseboard_fab2(sch_1):\MG_DDR_CTRL_NG_DDR_D_DLL_22\" )
					)
					( Status sCSetFlattened )
					( Origin gBackEnd )
				)
				( attribute "RELATIVE_PROPAGATION_DELAY" "0.00 MIL,25.00 MIL"
					( Parent
						( matchGroupRef "@baseboard_fab2_lib.baseboard_fab2(sch_1):\MG_DDR_CTRL_NG_DDR_D_DLL_22\" )
					)
					( Units "uMatchProp" "ns" 1.000000)
					( Status sCSetFlattened )
					( Origin gBackEnd )
				)
			)
			( pinPair "@baseboard_fab2_lib.baseboard_fab2(sch_1):\PP3796\"
				( pinRef "@baseboard_fab2_lib.baseboard_fab2(sch_1):page50_i158:S1_N" )
				( pinRef "@baseboard_fab2_lib.baseboard_fab2(sch_1):page26_i172:DDR3_CS_N(5)" )
				( attribute "RELATIVE_PROPAGATION_DELAY_SCOPE" "G"
					( Parent
						( matchGroupRef "@crescent_city_bb_fab1_lib.crescent_city_bb_fab1(sch_1):\MG_DDR_NEAR_DIMM-CLK1_CLS_DDR_D_CAC-CLKS\" )
					)
					( Status sCSetFlattened )
					( Origin gBackEnd )
				)
				( attribute "RELATIVE_PROPAGATION_DELAY" "0.00 MIL,300.00 MIL"
					( Parent
						( matchGroupRef "@crescent_city_bb_fab1_lib.crescent_city_bb_fab1(sch_1):\MG_DDR_NEAR_DIMM-CLK1_CLS_DDR_D_CAC-CLKS\" )
					)
					( Units "uMatchProp" "ns" 1.000000)
					( Status sCSetFlattened )
					( Origin gBackEnd )
				)
				( attribute "RELATIVE_PROPAGATION_DELAY_SCOPE" "G"
					( Parent
						( matchGroupRef "@baseboard_fab2_lib.baseboard_fab2(sch_1):\MG_DDR_CTRL_NG_DDR_D_DLL_23\" )
					)
					( Status sCSetFlattened )
					( Origin gBackEnd )
				)
				( attribute "RELATIVE_PROPAGATION_DELAY" "0.00 MIL,25.00 MIL"
					( Parent
						( matchGroupRef "@baseboard_fab2_lib.baseboard_fab2(sch_1):\MG_DDR_CTRL_NG_DDR_D_DLL_23\" )
					)
					( Units "uMatchProp" "ns" 1.000000)
					( Status sCSetFlattened )
					( Origin gBackEnd )
				)
			)
			( pinPair "@baseboard_fab2_lib.baseboard_fab2(sch_1):\PP3797\"
				( pinRef "@baseboard_fab2_lib.baseboard_fab2(sch_1):page50_i158:ODT(1)" )
				( pinRef "@baseboard_fab2_lib.baseboard_fab2(sch_1):page26_i172:DDR3_ODT(3)" )
				( attribute "RELATIVE_PROPAGATION_DELAY_SCOPE" "G"
					( Parent
						( matchGroupRef "@crescent_city_bb_fab1_lib.crescent_city_bb_fab1(sch_1):\MG_DDR_NEAR_DIMM-CLK1_CLS_DDR_D_CAC-CLKS\" )
					)
					( Status sCSetFlattened )
					( Origin gBackEnd )
				)
				( attribute "RELATIVE_PROPAGATION_DELAY" "0.00 MIL,300.00 MIL"
					( Parent
						( matchGroupRef "@crescent_city_bb_fab1_lib.crescent_city_bb_fab1(sch_1):\MG_DDR_NEAR_DIMM-CLK1_CLS_DDR_D_CAC-CLKS\" )
					)
					( Units "uMatchProp" "ns" 1.000000)
					( Status sCSetFlattened )
					( Origin gBackEnd )
				)
				( attribute "RELATIVE_PROPAGATION_DELAY_SCOPE" "G"
					( Parent
						( matchGroupRef "@baseboard_fab2_lib.baseboard_fab2(sch_1):\MG_DDR_CTRL_NG_DDR_D_DLL_23\" )
					)
					( Status sCSetFlattened )
					( Origin gBackEnd )
				)
				( attribute "RELATIVE_PROPAGATION_DELAY" "0.00 MIL,25.00 MIL"
					( Parent
						( matchGroupRef "@baseboard_fab2_lib.baseboard_fab2(sch_1):\MG_DDR_CTRL_NG_DDR_D_DLL_23\" )
					)
					( Units "uMatchProp" "ns" 1.000000)
					( Status sCSetFlattened )
					( Origin gBackEnd )
				)
			)
			( pinPair "@baseboard_fab2_lib.baseboard_fab2(sch_1):\PP3795\"
				( pinRef "@baseboard_fab2_lib.baseboard_fab2(sch_1):page50_i158:CKE(1)" )
				( pinRef "@baseboard_fab2_lib.baseboard_fab2(sch_1):page26_i172:DDR3_CKE(3)" )
				( attribute "RELATIVE_PROPAGATION_DELAY_SCOPE" "G"
					( Parent
						( matchGroupRef "@crescent_city_bb_fab1_lib.crescent_city_bb_fab1(sch_1):\MG_DDR_NEAR_DIMM-CLK1_CLS_DDR_D_CAC-CLKS\" )
					)
					( Status sCSetFlattened )
					( Origin gBackEnd )
				)
				( attribute "RELATIVE_PROPAGATION_DELAY" "0.00 MIL,300.00 MIL"
					( Parent
						( matchGroupRef "@crescent_city_bb_fab1_lib.crescent_city_bb_fab1(sch_1):\MG_DDR_NEAR_DIMM-CLK1_CLS_DDR_D_CAC-CLKS\" )
					)
					( Units "uMatchProp" "ns" 1.000000)
					( Status sCSetFlattened )
					( Origin gBackEnd )
				)
				( attribute "RELATIVE_PROPAGATION_DELAY_SCOPE" "G"
					( Parent
						( matchGroupRef "@baseboard_fab2_lib.baseboard_fab2(sch_1):\MG_DDR_CTRL_NG_DDR_D_DLL_24\" )
					)
					( Status sCSetFlattened )
					( Origin gBackEnd )
				)
				( attribute "RELATIVE_PROPAGATION_DELAY" "0.00 MIL,25.00 MIL"
					( Parent
						( matchGroupRef "@baseboard_fab2_lib.baseboard_fab2(sch_1):\MG_DDR_CTRL_NG_DDR_D_DLL_24\" )
					)
					( Units "uMatchProp" "ns" 1.000000)
					( Status sCSetFlattened )
					( Origin gBackEnd )
				)
			)
			( pinPair "@baseboard_fab2_lib.baseboard_fab2(sch_1):\PP3923\"
				( pinRef "@baseboard_fab2_lib.baseboard_fab2(sch_1):page25_i172:DDR2_CID(2)" )
				( pinRef "@baseboard_fab2_lib.baseboard_fab2(sch_1):page47_i111:C(2)" )
				( attribute "RELATIVE_PROPAGATION_DELAY_SCOPE" "G"
					( Parent
						( matchGroupRef "@crescent_city_bb_fab1_lib.crescent_city_bb_fab1(sch_1):\MG_DDR_FAR_DIMM-CLK0_CLS_DDR_C_CAC-CLKS\" )
					)
					( Status sCSetFlattened )
					( Origin gBackEnd )
				)
				( attribute "RELATIVE_PROPAGATION_DELAY" "0.00 MIL,700.00 MIL"
					( Parent
						( matchGroupRef "@crescent_city_bb_fab1_lib.crescent_city_bb_fab1(sch_1):\MG_DDR_FAR_DIMM-CLK0_CLS_DDR_C_CAC-CLKS\" )
					)
					( Units "uMatchProp" "ns" 1.000000)
					( Status sCSetFlattened )
					( Origin gBackEnd )
				)
				( attribute "RELATIVE_PROPAGATION_DELAY_SCOPE" "G"
					( Parent
						( matchGroupRef "@baseboard_fab2_lib.baseboard_fab2(sch_1):\MG_DDR_FAR_DIMM_CMD_NG_DDR_C_DLL_1\" )
					)
					( Status sCSetFlattened )
					( Origin gBackEnd )
				)
				( attribute "RELATIVE_PROPAGATION_DELAY" "0.00 MIL,25.00 MIL"
					( Parent
						( matchGroupRef "@baseboard_fab2_lib.baseboard_fab2(sch_1):\MG_DDR_FAR_DIMM_CMD_NG_DDR_C_DLL_1\" )
					)
					( Units "uMatchProp" "ns" 1.000000)
					( Status sCSetFlattened )
					( Origin gBackEnd )
				)
			)
			( pinPair "@baseboard_fab2_lib.baseboard_fab2(sch_1):\PP3924\"
				( pinRef "@baseboard_fab2_lib.baseboard_fab2(sch_1):page25_i172:DDR2_CID(2)" )
				( pinRef "@baseboard_fab2_lib.baseboard_fab2(sch_1):page48_i111:C(2)" )
				( attribute "RELATIVE_PROPAGATION_DELAY_SCOPE" "G"
					( Parent
						( matchGroupRef "@baseboard_fab2_lib.baseboard_fab2(sch_1):\MG_DDR_CMD_NEAR_DIMM_NG_DDR_C_DLL_1\" )
					)
					( Status sCSetFlattened )
					( Origin gBackEnd )
				)
				( attribute "RELATIVE_PROPAGATION_DELAY" "0.00 MIL,25.00 MIL"
					( Parent
						( matchGroupRef "@baseboard_fab2_lib.baseboard_fab2(sch_1):\MG_DDR_CMD_NEAR_DIMM_NG_DDR_C_DLL_1\" )
					)
					( Units "uMatchProp" "ns" 1.000000)
					( Status sCSetFlattened )
					( Origin gBackEnd )
				)
				( attribute "RELATIVE_PROPAGATION_DELAY_SCOPE" "G"
					( Parent
						( matchGroupRef "@crescent_city_bb_fab1_lib.crescent_city_bb_fab1(sch_1):\MG_DDR_NEAR_DIMM-CLK1_CLS_DDR_C_CAC-CLKS\" )
					)
					( Status sCSetFlattened )
					( Origin gBackEnd )
				)
				( attribute "RELATIVE_PROPAGATION_DELAY" "0.00 MIL,700.00 MIL"
					( Parent
						( matchGroupRef "@crescent_city_bb_fab1_lib.crescent_city_bb_fab1(sch_1):\MG_DDR_NEAR_DIMM-CLK1_CLS_DDR_C_CAC-CLKS\" )
					)
					( Units "uMatchProp" "ns" 1.000000)
					( Status sCSetFlattened )
					( Origin gBackEnd )
				)
			)
			( pinPair "@baseboard_fab2_lib.baseboard_fab2(sch_1):\PP3925\"
				( pinRef "@baseboard_fab2_lib.baseboard_fab2(sch_1):page25_i172:DDR2_MA(17)" )
				( pinRef "@baseboard_fab2_lib.baseboard_fab2(sch_1):page47_i111:A17" )
				( attribute "RELATIVE_PROPAGATION_DELAY_SCOPE" "G"
					( Parent
						( matchGroupRef "@crescent_city_bb_fab1_lib.crescent_city_bb_fab1(sch_1):\MG_DDR_FAR_DIMM-CLK0_CLS_DDR_C_CAC-CLKS\" )
					)
					( Status sCSetFlattened )
					( Origin gBackEnd )
				)
				( attribute "RELATIVE_PROPAGATION_DELAY" "0.00 MIL,700.00 MIL"
					( Parent
						( matchGroupRef "@crescent_city_bb_fab1_lib.crescent_city_bb_fab1(sch_1):\MG_DDR_FAR_DIMM-CLK0_CLS_DDR_C_CAC-CLKS\" )
					)
					( Units "uMatchProp" "ns" 1.000000)
					( Status sCSetFlattened )
					( Origin gBackEnd )
				)
				( attribute "RELATIVE_PROPAGATION_DELAY_SCOPE" "G"
					( Parent
						( matchGroupRef "@baseboard_fab2_lib.baseboard_fab2(sch_1):\MG_DDR_FAR_DIMM_CMD_NG_DDR_C_DLL_1\" )
					)
					( Status sCSetFlattened )
					( Origin gBackEnd )
				)
				( attribute "RELATIVE_PROPAGATION_DELAY" "0.00 MIL,25.00 MIL"
					( Parent
						( matchGroupRef "@baseboard_fab2_lib.baseboard_fab2(sch_1):\MG_DDR_FAR_DIMM_CMD_NG_DDR_C_DLL_1\" )
					)
					( Units "uMatchProp" "ns" 1.000000)
					( Status sCSetFlattened )
					( Origin gBackEnd )
				)
			)
			( pinPair "@baseboard_fab2_lib.baseboard_fab2(sch_1):\PP3926\"
				( pinRef "@baseboard_fab2_lib.baseboard_fab2(sch_1):page48_i111:A17" )
				( pinRef "@baseboard_fab2_lib.baseboard_fab2(sch_1):page25_i172:DDR2_MA(17)" )
				( attribute "RELATIVE_PROPAGATION_DELAY_SCOPE" "G"
					( Parent
						( matchGroupRef "@baseboard_fab2_lib.baseboard_fab2(sch_1):\MG_DDR_CMD_NEAR_DIMM_NG_DDR_C_DLL_1\" )
					)
					( Status sCSetFlattened )
					( Origin gBackEnd )
				)
				( attribute "RELATIVE_PROPAGATION_DELAY" "0.00 MIL,25.00 MIL"
					( Parent
						( matchGroupRef "@baseboard_fab2_lib.baseboard_fab2(sch_1):\MG_DDR_CMD_NEAR_DIMM_NG_DDR_C_DLL_1\" )
					)
					( Units "uMatchProp" "ns" 1.000000)
					( Status sCSetFlattened )
					( Origin gBackEnd )
				)
				( attribute "RELATIVE_PROPAGATION_DELAY_SCOPE" "G"
					( Parent
						( matchGroupRef "@crescent_city_bb_fab1_lib.crescent_city_bb_fab1(sch_1):\MG_DDR_NEAR_DIMM-CLK1_CLS_DDR_C_CAC-CLKS\" )
					)
					( Status sCSetFlattened )
					( Origin gBackEnd )
				)
				( attribute "RELATIVE_PROPAGATION_DELAY" "0.00 MIL,700.00 MIL"
					( Parent
						( matchGroupRef "@crescent_city_bb_fab1_lib.crescent_city_bb_fab1(sch_1):\MG_DDR_NEAR_DIMM-CLK1_CLS_DDR_C_CAC-CLKS\" )
					)
					( Units "uMatchProp" "ns" 1.000000)
					( Status sCSetFlattened )
					( Origin gBackEnd )
				)
			)
			( pinPair "@baseboard_fab2_lib.baseboard_fab2(sch_1):\PP3919\"
				( pinRef "@baseboard_fab2_lib.baseboard_fab2(sch_1):page25_i172:DDR2_MA(13)" )
				( pinRef "@baseboard_fab2_lib.baseboard_fab2(sch_1):page47_i111:A13" )
				( attribute "RELATIVE_PROPAGATION_DELAY_SCOPE" "G"
					( Parent
						( matchGroupRef "@crescent_city_bb_fab1_lib.crescent_city_bb_fab1(sch_1):\MG_DDR_FAR_DIMM-CLK0_CLS_DDR_C_CAC-CLKS\" )
					)
					( Status sCSetFlattened )
					( Origin gBackEnd )
				)
				( attribute "RELATIVE_PROPAGATION_DELAY" "0.00 MIL,700.00 MIL"
					( Parent
						( matchGroupRef "@crescent_city_bb_fab1_lib.crescent_city_bb_fab1(sch_1):\MG_DDR_FAR_DIMM-CLK0_CLS_DDR_C_CAC-CLKS\" )
					)
					( Units "uMatchProp" "ns" 1.000000)
					( Status sCSetFlattened )
					( Origin gBackEnd )
				)
				( attribute "RELATIVE_PROPAGATION_DELAY_SCOPE" "G"
					( Parent
						( matchGroupRef "@baseboard_fab2_lib.baseboard_fab2(sch_1):\MG_DDR_FAR_DIMM_CMD_NG_DDR_C_DLL_2\" )
					)
					( Status sCSetFlattened )
					( Origin gBackEnd )
				)
				( attribute "RELATIVE_PROPAGATION_DELAY" "0.00 MIL,25.00 MIL"
					( Parent
						( matchGroupRef "@baseboard_fab2_lib.baseboard_fab2(sch_1):\MG_DDR_FAR_DIMM_CMD_NG_DDR_C_DLL_2\" )
					)
					( Units "uMatchProp" "ns" 1.000000)
					( Status sCSetFlattened )
					( Origin gBackEnd )
				)
			)
			( pinPair "@baseboard_fab2_lib.baseboard_fab2(sch_1):\PP3920\"
				( pinRef "@baseboard_fab2_lib.baseboard_fab2(sch_1):page48_i111:A13" )
				( pinRef "@baseboard_fab2_lib.baseboard_fab2(sch_1):page25_i172:DDR2_MA(13)" )
				( attribute "RELATIVE_PROPAGATION_DELAY_SCOPE" "G"
					( Parent
						( matchGroupRef "@crescent_city_bb_fab1_lib.crescent_city_bb_fab1(sch_1):\MG_DDR_NEAR_DIMM-CLK1_CLS_DDR_C_CAC-CLKS\" )
					)
					( Status sCSetFlattened )
					( Origin gBackEnd )
				)
				( attribute "RELATIVE_PROPAGATION_DELAY" "0.00 MIL,700.00 MIL"
					( Parent
						( matchGroupRef "@crescent_city_bb_fab1_lib.crescent_city_bb_fab1(sch_1):\MG_DDR_NEAR_DIMM-CLK1_CLS_DDR_C_CAC-CLKS\" )
					)
					( Units "uMatchProp" "ns" 1.000000)
					( Status sCSetFlattened )
					( Origin gBackEnd )
				)
				( attribute "RELATIVE_PROPAGATION_DELAY_SCOPE" "G"
					( Parent
						( matchGroupRef "@baseboard_fab2_lib.baseboard_fab2(sch_1):\MG_DDR_CMD_NEAR_DIMM_NG_DDR_C_DLL_2\" )
					)
					( Status sCSetFlattened )
					( Origin gBackEnd )
				)
				( attribute "RELATIVE_PROPAGATION_DELAY" "0.00 MIL,25.00 MIL"
					( Parent
						( matchGroupRef "@baseboard_fab2_lib.baseboard_fab2(sch_1):\MG_DDR_CMD_NEAR_DIMM_NG_DDR_C_DLL_2\" )
					)
					( Units "uMatchProp" "ns" 1.000000)
					( Status sCSetFlattened )
					( Origin gBackEnd )
				)
			)
			( pinPair "@baseboard_fab2_lib.baseboard_fab2(sch_1):\PP3921\"
				( pinRef "@baseboard_fab2_lib.baseboard_fab2(sch_1):page25_i172:DDR2_MA(15)" )
				( pinRef "@baseboard_fab2_lib.baseboard_fab2(sch_1):page47_i111:A15_CAS_N" )
				( attribute "RELATIVE_PROPAGATION_DELAY_SCOPE" "G"
					( Parent
						( matchGroupRef "@crescent_city_bb_fab1_lib.crescent_city_bb_fab1(sch_1):\MG_DDR_FAR_DIMM-CLK0_CLS_DDR_C_CAC-CLKS\" )
					)
					( Status sCSetFlattened )
					( Origin gBackEnd )
				)
				( attribute "RELATIVE_PROPAGATION_DELAY" "0.00 MIL,700.00 MIL"
					( Parent
						( matchGroupRef "@crescent_city_bb_fab1_lib.crescent_city_bb_fab1(sch_1):\MG_DDR_FAR_DIMM-CLK0_CLS_DDR_C_CAC-CLKS\" )
					)
					( Units "uMatchProp" "ns" 1.000000)
					( Status sCSetFlattened )
					( Origin gBackEnd )
				)
				( attribute "RELATIVE_PROPAGATION_DELAY_SCOPE" "G"
					( Parent
						( matchGroupRef "@baseboard_fab2_lib.baseboard_fab2(sch_1):\MG_DDR_FAR_DIMM_CMD_NG_DDR_C_DLL_2\" )
					)
					( Status sCSetFlattened )
					( Origin gBackEnd )
				)
				( attribute "RELATIVE_PROPAGATION_DELAY" "0.00 MIL,25.00 MIL"
					( Parent
						( matchGroupRef "@baseboard_fab2_lib.baseboard_fab2(sch_1):\MG_DDR_FAR_DIMM_CMD_NG_DDR_C_DLL_2\" )
					)
					( Units "uMatchProp" "ns" 1.000000)
					( Status sCSetFlattened )
					( Origin gBackEnd )
				)
			)
			( pinPair "@baseboard_fab2_lib.baseboard_fab2(sch_1):\PP3922\"
				( pinRef "@baseboard_fab2_lib.baseboard_fab2(sch_1):page25_i172:DDR2_MA(15)" )
				( pinRef "@baseboard_fab2_lib.baseboard_fab2(sch_1):page48_i111:A15_CAS_N" )
				( attribute "RELATIVE_PROPAGATION_DELAY_SCOPE" "G"
					( Parent
						( matchGroupRef "@crescent_city_bb_fab1_lib.crescent_city_bb_fab1(sch_1):\MG_DDR_NEAR_DIMM-CLK1_CLS_DDR_C_CAC-CLKS\" )
					)
					( Status sCSetFlattened )
					( Origin gBackEnd )
				)
				( attribute "RELATIVE_PROPAGATION_DELAY" "0.00 MIL,700.00 MIL"
					( Parent
						( matchGroupRef "@crescent_city_bb_fab1_lib.crescent_city_bb_fab1(sch_1):\MG_DDR_NEAR_DIMM-CLK1_CLS_DDR_C_CAC-CLKS\" )
					)
					( Units "uMatchProp" "ns" 1.000000)
					( Status sCSetFlattened )
					( Origin gBackEnd )
				)
				( attribute "RELATIVE_PROPAGATION_DELAY_SCOPE" "G"
					( Parent
						( matchGroupRef "@baseboard_fab2_lib.baseboard_fab2(sch_1):\MG_DDR_CMD_NEAR_DIMM_NG_DDR_C_DLL_2\" )
					)
					( Status sCSetFlattened )
					( Origin gBackEnd )
				)
				( attribute "RELATIVE_PROPAGATION_DELAY" "0.00 MIL,25.00 MIL"
					( Parent
						( matchGroupRef "@baseboard_fab2_lib.baseboard_fab2(sch_1):\MG_DDR_CMD_NEAR_DIMM_NG_DDR_C_DLL_2\" )
					)
					( Units "uMatchProp" "ns" 1.000000)
					( Status sCSetFlattened )
					( Origin gBackEnd )
				)
			)
			( pinPair "@baseboard_fab2_lib.baseboard_fab2(sch_1):\PP3915\"
				( pinRef "@baseboard_fab2_lib.baseboard_fab2(sch_1):page25_i172:DDR2_MA(14)" )
				( pinRef "@baseboard_fab2_lib.baseboard_fab2(sch_1):page47_i111:A14_WE_N" )
				( attribute "RELATIVE_PROPAGATION_DELAY_SCOPE" "G"
					( Parent
						( matchGroupRef "@crescent_city_bb_fab1_lib.crescent_city_bb_fab1(sch_1):\MG_DDR_FAR_DIMM-CLK0_CLS_DDR_C_CAC-CLKS\" )
					)
					( Status sCSetFlattened )
					( Origin gBackEnd )
				)
				( attribute "RELATIVE_PROPAGATION_DELAY" "0.00 MIL,700.00 MIL"
					( Parent
						( matchGroupRef "@crescent_city_bb_fab1_lib.crescent_city_bb_fab1(sch_1):\MG_DDR_FAR_DIMM-CLK0_CLS_DDR_C_CAC-CLKS\" )
					)
					( Units "uMatchProp" "ns" 1.000000)
					( Status sCSetFlattened )
					( Origin gBackEnd )
				)
				( attribute "RELATIVE_PROPAGATION_DELAY_SCOPE" "G"
					( Parent
						( matchGroupRef "@baseboard_fab2_lib.baseboard_fab2(sch_1):\MG_DDR_FAR_DIMM_CMD_NG_DDR_C_DLL_3\" )
					)
					( Status sCSetFlattened )
					( Origin gBackEnd )
				)
				( attribute "RELATIVE_PROPAGATION_DELAY" "0.00 MIL,25.00 MIL"
					( Parent
						( matchGroupRef "@baseboard_fab2_lib.baseboard_fab2(sch_1):\MG_DDR_FAR_DIMM_CMD_NG_DDR_C_DLL_3\" )
					)
					( Units "uMatchProp" "ns" 1.000000)
					( Status sCSetFlattened )
					( Origin gBackEnd )
				)
			)
			( pinPair "@baseboard_fab2_lib.baseboard_fab2(sch_1):\PP3916\"
				( pinRef "@baseboard_fab2_lib.baseboard_fab2(sch_1):page48_i111:A14_WE_N" )
				( pinRef "@baseboard_fab2_lib.baseboard_fab2(sch_1):page25_i172:DDR2_MA(14)" )
				( attribute "RELATIVE_PROPAGATION_DELAY_SCOPE" "G"
					( Parent
						( matchGroupRef "@crescent_city_bb_fab1_lib.crescent_city_bb_fab1(sch_1):\MG_DDR_NEAR_DIMM-CLK1_CLS_DDR_C_CAC-CLKS\" )
					)
					( Status sCSetFlattened )
					( Origin gBackEnd )
				)
				( attribute "RELATIVE_PROPAGATION_DELAY" "0.00 MIL,700.00 MIL"
					( Parent
						( matchGroupRef "@crescent_city_bb_fab1_lib.crescent_city_bb_fab1(sch_1):\MG_DDR_NEAR_DIMM-CLK1_CLS_DDR_C_CAC-CLKS\" )
					)
					( Units "uMatchProp" "ns" 1.000000)
					( Status sCSetFlattened )
					( Origin gBackEnd )
				)
				( attribute "RELATIVE_PROPAGATION_DELAY_SCOPE" "G"
					( Parent
						( matchGroupRef "@baseboard_fab2_lib.baseboard_fab2(sch_1):\MG_DDR_CMD_NEAR_DIMM_NG_DDR_C_DLL_3\" )
					)
					( Status sCSetFlattened )
					( Origin gBackEnd )
				)
				( attribute "RELATIVE_PROPAGATION_DELAY" "0.00 MIL,25.00 MIL"
					( Parent
						( matchGroupRef "@baseboard_fab2_lib.baseboard_fab2(sch_1):\MG_DDR_CMD_NEAR_DIMM_NG_DDR_C_DLL_3\" )
					)
					( Units "uMatchProp" "ns" 1.000000)
					( Status sCSetFlattened )
					( Origin gBackEnd )
				)
			)
			( pinPair "@baseboard_fab2_lib.baseboard_fab2(sch_1):\PP3917\"
				( pinRef "@baseboard_fab2_lib.baseboard_fab2(sch_1):page25_i172:DDR2_MA(16)" )
				( pinRef "@baseboard_fab2_lib.baseboard_fab2(sch_1):page47_i111:A16_RAS_N" )
				( attribute "RELATIVE_PROPAGATION_DELAY_SCOPE" "G"
					( Parent
						( matchGroupRef "@crescent_city_bb_fab1_lib.crescent_city_bb_fab1(sch_1):\MG_DDR_FAR_DIMM-CLK0_CLS_DDR_C_CAC-CLKS\" )
					)
					( Status sCSetFlattened )
					( Origin gBackEnd )
				)
				( attribute "RELATIVE_PROPAGATION_DELAY" "0.00 MIL,700.00 MIL"
					( Parent
						( matchGroupRef "@crescent_city_bb_fab1_lib.crescent_city_bb_fab1(sch_1):\MG_DDR_FAR_DIMM-CLK0_CLS_DDR_C_CAC-CLKS\" )
					)
					( Units "uMatchProp" "ns" 1.000000)
					( Status sCSetFlattened )
					( Origin gBackEnd )
				)
				( attribute "RELATIVE_PROPAGATION_DELAY_SCOPE" "G"
					( Parent
						( matchGroupRef "@baseboard_fab2_lib.baseboard_fab2(sch_1):\MG_DDR_FAR_DIMM_CMD_NG_DDR_C_DLL_3\" )
					)
					( Status sCSetFlattened )
					( Origin gBackEnd )
				)
				( attribute "RELATIVE_PROPAGATION_DELAY" "0.00 MIL,25.00 MIL"
					( Parent
						( matchGroupRef "@baseboard_fab2_lib.baseboard_fab2(sch_1):\MG_DDR_FAR_DIMM_CMD_NG_DDR_C_DLL_3\" )
					)
					( Units "uMatchProp" "ns" 1.000000)
					( Status sCSetFlattened )
					( Origin gBackEnd )
				)
			)
			( pinPair "@baseboard_fab2_lib.baseboard_fab2(sch_1):\PP3918\"
				( pinRef "@baseboard_fab2_lib.baseboard_fab2(sch_1):page48_i111:A16_RAS_N" )
				( pinRef "@baseboard_fab2_lib.baseboard_fab2(sch_1):page25_i172:DDR2_MA(16)" )
				( attribute "RELATIVE_PROPAGATION_DELAY_SCOPE" "G"
					( Parent
						( matchGroupRef "@crescent_city_bb_fab1_lib.crescent_city_bb_fab1(sch_1):\MG_DDR_NEAR_DIMM-CLK1_CLS_DDR_C_CAC-CLKS\" )
					)
					( Status sCSetFlattened )
					( Origin gBackEnd )
				)
				( attribute "RELATIVE_PROPAGATION_DELAY" "0.00 MIL,700.00 MIL"
					( Parent
						( matchGroupRef "@crescent_city_bb_fab1_lib.crescent_city_bb_fab1(sch_1):\MG_DDR_NEAR_DIMM-CLK1_CLS_DDR_C_CAC-CLKS\" )
					)
					( Units "uMatchProp" "ns" 1.000000)
					( Status sCSetFlattened )
					( Origin gBackEnd )
				)
				( attribute "RELATIVE_PROPAGATION_DELAY_SCOPE" "G"
					( Parent
						( matchGroupRef "@baseboard_fab2_lib.baseboard_fab2(sch_1):\MG_DDR_CMD_NEAR_DIMM_NG_DDR_C_DLL_3\" )
					)
					( Status sCSetFlattened )
					( Origin gBackEnd )
				)
				( attribute "RELATIVE_PROPAGATION_DELAY" "0.00 MIL,25.00 MIL"
					( Parent
						( matchGroupRef "@baseboard_fab2_lib.baseboard_fab2(sch_1):\MG_DDR_CMD_NEAR_DIMM_NG_DDR_C_DLL_3\" )
					)
					( Units "uMatchProp" "ns" 1.000000)
					( Status sCSetFlattened )
					( Origin gBackEnd )
				)
			)
			( pinPair "@baseboard_fab2_lib.baseboard_fab2(sch_1):\PP3911\"
				( pinRef "@baseboard_fab2_lib.baseboard_fab2(sch_1):page25_i172:DDR2_BA(1)" )
				( pinRef "@baseboard_fab2_lib.baseboard_fab2(sch_1):page47_i111:BA(1)" )
				( attribute "RELATIVE_PROPAGATION_DELAY_SCOPE" "G"
					( Parent
						( matchGroupRef "@crescent_city_bb_fab1_lib.crescent_city_bb_fab1(sch_1):\MG_DDR_FAR_DIMM-CLK0_CLS_DDR_C_CAC-CLKS\" )
					)
					( Status sCSetFlattened )
					( Origin gBackEnd )
				)
				( attribute "RELATIVE_PROPAGATION_DELAY" "0.00 MIL,700.00 MIL"
					( Parent
						( matchGroupRef "@crescent_city_bb_fab1_lib.crescent_city_bb_fab1(sch_1):\MG_DDR_FAR_DIMM-CLK0_CLS_DDR_C_CAC-CLKS\" )
					)
					( Units "uMatchProp" "ns" 1.000000)
					( Status sCSetFlattened )
					( Origin gBackEnd )
				)
				( attribute "RELATIVE_PROPAGATION_DELAY_SCOPE" "G"
					( Parent
						( matchGroupRef "@baseboard_fab2_lib.baseboard_fab2(sch_1):\MG_DDR_FAR_DIMM_CMD_NG_DDR_C_DLL_4\" )
					)
					( Status sCSetFlattened )
					( Origin gBackEnd )
				)
				( attribute "RELATIVE_PROPAGATION_DELAY" "0.00 MIL,25.00 MIL"
					( Parent
						( matchGroupRef "@baseboard_fab2_lib.baseboard_fab2(sch_1):\MG_DDR_FAR_DIMM_CMD_NG_DDR_C_DLL_4\" )
					)
					( Units "uMatchProp" "ns" 1.000000)
					( Status sCSetFlattened )
					( Origin gBackEnd )
				)
			)
			( pinPair "@baseboard_fab2_lib.baseboard_fab2(sch_1):\PP3912\"
				( pinRef "@baseboard_fab2_lib.baseboard_fab2(sch_1):page48_i111:BA(1)" )
				( pinRef "@baseboard_fab2_lib.baseboard_fab2(sch_1):page25_i172:DDR2_BA(1)" )
				( attribute "RELATIVE_PROPAGATION_DELAY_SCOPE" "G"
					( Parent
						( matchGroupRef "@crescent_city_bb_fab1_lib.crescent_city_bb_fab1(sch_1):\MG_DDR_NEAR_DIMM-CLK1_CLS_DDR_C_CAC-CLKS\" )
					)
					( Status sCSetFlattened )
					( Origin gBackEnd )
				)
				( attribute "RELATIVE_PROPAGATION_DELAY" "0.00 MIL,700.00 MIL"
					( Parent
						( matchGroupRef "@crescent_city_bb_fab1_lib.crescent_city_bb_fab1(sch_1):\MG_DDR_NEAR_DIMM-CLK1_CLS_DDR_C_CAC-CLKS\" )
					)
					( Units "uMatchProp" "ns" 1.000000)
					( Status sCSetFlattened )
					( Origin gBackEnd )
				)
				( attribute "RELATIVE_PROPAGATION_DELAY_SCOPE" "G"
					( Parent
						( matchGroupRef "@baseboard_fab2_lib.baseboard_fab2(sch_1):\MG_DDR_CMD_NEAR_DIMM_NG_DDR_C_DLL_4\" )
					)
					( Status sCSetFlattened )
					( Origin gBackEnd )
				)
				( attribute "RELATIVE_PROPAGATION_DELAY" "0.00 MIL,25.00 MIL"
					( Parent
						( matchGroupRef "@baseboard_fab2_lib.baseboard_fab2(sch_1):\MG_DDR_CMD_NEAR_DIMM_NG_DDR_C_DLL_4\" )
					)
					( Units "uMatchProp" "ns" 1.000000)
					( Status sCSetFlattened )
					( Origin gBackEnd )
				)
			)
			( pinPair "@baseboard_fab2_lib.baseboard_fab2(sch_1):\PP3913\"
				( pinRef "@baseboard_fab2_lib.baseboard_fab2(sch_1):page25_i172:DDR2_MA(10)" )
				( pinRef "@baseboard_fab2_lib.baseboard_fab2(sch_1):page47_i111:A10" )
				( attribute "RELATIVE_PROPAGATION_DELAY_SCOPE" "G"
					( Parent
						( matchGroupRef "@crescent_city_bb_fab1_lib.crescent_city_bb_fab1(sch_1):\MG_DDR_FAR_DIMM-CLK0_CLS_DDR_C_CAC-CLKS\" )
					)
					( Status sCSetFlattened )
					( Origin gBackEnd )
				)
				( attribute "RELATIVE_PROPAGATION_DELAY" "0.00 MIL,700.00 MIL"
					( Parent
						( matchGroupRef "@crescent_city_bb_fab1_lib.crescent_city_bb_fab1(sch_1):\MG_DDR_FAR_DIMM-CLK0_CLS_DDR_C_CAC-CLKS\" )
					)
					( Units "uMatchProp" "ns" 1.000000)
					( Status sCSetFlattened )
					( Origin gBackEnd )
				)
				( attribute "RELATIVE_PROPAGATION_DELAY_SCOPE" "G"
					( Parent
						( matchGroupRef "@baseboard_fab2_lib.baseboard_fab2(sch_1):\MG_DDR_FAR_DIMM_CMD_NG_DDR_C_DLL_4\" )
					)
					( Status sCSetFlattened )
					( Origin gBackEnd )
				)
				( attribute "RELATIVE_PROPAGATION_DELAY" "0.00 MIL,25.00 MIL"
					( Parent
						( matchGroupRef "@baseboard_fab2_lib.baseboard_fab2(sch_1):\MG_DDR_FAR_DIMM_CMD_NG_DDR_C_DLL_4\" )
					)
					( Units "uMatchProp" "ns" 1.000000)
					( Status sCSetFlattened )
					( Origin gBackEnd )
				)
			)
			( pinPair "@baseboard_fab2_lib.baseboard_fab2(sch_1):\PP3914\"
				( pinRef "@baseboard_fab2_lib.baseboard_fab2(sch_1):page48_i111:A10" )
				( pinRef "@baseboard_fab2_lib.baseboard_fab2(sch_1):page25_i172:DDR2_MA(10)" )
				( attribute "RELATIVE_PROPAGATION_DELAY_SCOPE" "G"
					( Parent
						( matchGroupRef "@crescent_city_bb_fab1_lib.crescent_city_bb_fab1(sch_1):\MG_DDR_NEAR_DIMM-CLK1_CLS_DDR_C_CAC-CLKS\" )
					)
					( Status sCSetFlattened )
					( Origin gBackEnd )
				)
				( attribute "RELATIVE_PROPAGATION_DELAY" "0.00 MIL,700.00 MIL"
					( Parent
						( matchGroupRef "@crescent_city_bb_fab1_lib.crescent_city_bb_fab1(sch_1):\MG_DDR_NEAR_DIMM-CLK1_CLS_DDR_C_CAC-CLKS\" )
					)
					( Units "uMatchProp" "ns" 1.000000)
					( Status sCSetFlattened )
					( Origin gBackEnd )
				)
				( attribute "RELATIVE_PROPAGATION_DELAY_SCOPE" "G"
					( Parent
						( matchGroupRef "@baseboard_fab2_lib.baseboard_fab2(sch_1):\MG_DDR_CMD_NEAR_DIMM_NG_DDR_C_DLL_4\" )
					)
					( Status sCSetFlattened )
					( Origin gBackEnd )
				)
				( attribute "RELATIVE_PROPAGATION_DELAY" "0.00 MIL,25.00 MIL"
					( Parent
						( matchGroupRef "@baseboard_fab2_lib.baseboard_fab2(sch_1):\MG_DDR_CMD_NEAR_DIMM_NG_DDR_C_DLL_4\" )
					)
					( Units "uMatchProp" "ns" 1.000000)
					( Status sCSetFlattened )
					( Origin gBackEnd )
				)
			)
			( pinPair "@baseboard_fab2_lib.baseboard_fab2(sch_1):\PP3907\"
				( pinRef "@baseboard_fab2_lib.baseboard_fab2(sch_1):page25_i172:DDR2_BA(0)" )
				( pinRef "@baseboard_fab2_lib.baseboard_fab2(sch_1):page47_i111:BA(0)" )
				( attribute "RELATIVE_PROPAGATION_DELAY_SCOPE" "G"
					( Parent
						( matchGroupRef "@crescent_city_bb_fab1_lib.crescent_city_bb_fab1(sch_1):\MG_DDR_FAR_DIMM-CLK0_CLS_DDR_C_CAC-CLKS\" )
					)
					( Status sCSetFlattened )
					( Origin gBackEnd )
				)
				( attribute "RELATIVE_PROPAGATION_DELAY" "0.00 MIL,700.00 MIL"
					( Parent
						( matchGroupRef "@crescent_city_bb_fab1_lib.crescent_city_bb_fab1(sch_1):\MG_DDR_FAR_DIMM-CLK0_CLS_DDR_C_CAC-CLKS\" )
					)
					( Units "uMatchProp" "ns" 1.000000)
					( Status sCSetFlattened )
					( Origin gBackEnd )
				)
				( attribute "RELATIVE_PROPAGATION_DELAY_SCOPE" "G"
					( Parent
						( matchGroupRef "@baseboard_fab2_lib.baseboard_fab2(sch_1):\MG_DDR_FAR_DIMM_CMD_NG_DDR_C_DLL_5\" )
					)
					( Status sCSetFlattened )
					( Origin gBackEnd )
				)
				( attribute "RELATIVE_PROPAGATION_DELAY" "0.00 MIL,25.00 MIL"
					( Parent
						( matchGroupRef "@baseboard_fab2_lib.baseboard_fab2(sch_1):\MG_DDR_FAR_DIMM_CMD_NG_DDR_C_DLL_5\" )
					)
					( Units "uMatchProp" "ns" 1.000000)
					( Status sCSetFlattened )
					( Origin gBackEnd )
				)
			)
			( pinPair "@baseboard_fab2_lib.baseboard_fab2(sch_1):\PP3908\"
				( pinRef "@baseboard_fab2_lib.baseboard_fab2(sch_1):page48_i111:BA(0)" )
				( pinRef "@baseboard_fab2_lib.baseboard_fab2(sch_1):page25_i172:DDR2_BA(0)" )
				( attribute "RELATIVE_PROPAGATION_DELAY_SCOPE" "G"
					( Parent
						( matchGroupRef "@crescent_city_bb_fab1_lib.crescent_city_bb_fab1(sch_1):\MG_DDR_NEAR_DIMM-CLK1_CLS_DDR_C_CAC-CLKS\" )
					)
					( Status sCSetFlattened )
					( Origin gBackEnd )
				)
				( attribute "RELATIVE_PROPAGATION_DELAY" "0.00 MIL,700.00 MIL"
					( Parent
						( matchGroupRef "@crescent_city_bb_fab1_lib.crescent_city_bb_fab1(sch_1):\MG_DDR_NEAR_DIMM-CLK1_CLS_DDR_C_CAC-CLKS\" )
					)
					( Units "uMatchProp" "ns" 1.000000)
					( Status sCSetFlattened )
					( Origin gBackEnd )
				)
				( attribute "RELATIVE_PROPAGATION_DELAY_SCOPE" "G"
					( Parent
						( matchGroupRef "@baseboard_fab2_lib.baseboard_fab2(sch_1):\MG_DDR_CMD_NEAR_DIMM_NG_DDR_C_DLL_5\" )
					)
					( Status sCSetFlattened )
					( Origin gBackEnd )
				)
				( attribute "RELATIVE_PROPAGATION_DELAY" "0.00 MIL,25.00 MIL"
					( Parent
						( matchGroupRef "@baseboard_fab2_lib.baseboard_fab2(sch_1):\MG_DDR_CMD_NEAR_DIMM_NG_DDR_C_DLL_5\" )
					)
					( Units "uMatchProp" "ns" 1.000000)
					( Status sCSetFlattened )
					( Origin gBackEnd )
				)
			)
			( pinPair "@baseboard_fab2_lib.baseboard_fab2(sch_1):\PP3909\"
				( pinRef "@baseboard_fab2_lib.baseboard_fab2(sch_1):page25_i172:DDR2_MA(0)" )
				( pinRef "@baseboard_fab2_lib.baseboard_fab2(sch_1):page47_i111:A0" )
				( attribute "RELATIVE_PROPAGATION_DELAY_SCOPE" "G"
					( Parent
						( matchGroupRef "@crescent_city_bb_fab1_lib.crescent_city_bb_fab1(sch_1):\MG_DDR_FAR_DIMM-CLK0_CLS_DDR_C_CAC-CLKS\" )
					)
					( Status sCSetFlattened )
					( Origin gBackEnd )
				)
				( attribute "RELATIVE_PROPAGATION_DELAY" "0.00 MIL,700.00 MIL"
					( Parent
						( matchGroupRef "@crescent_city_bb_fab1_lib.crescent_city_bb_fab1(sch_1):\MG_DDR_FAR_DIMM-CLK0_CLS_DDR_C_CAC-CLKS\" )
					)
					( Units "uMatchProp" "ns" 1.000000)
					( Status sCSetFlattened )
					( Origin gBackEnd )
				)
				( attribute "RELATIVE_PROPAGATION_DELAY_SCOPE" "G"
					( Parent
						( matchGroupRef "@baseboard_fab2_lib.baseboard_fab2(sch_1):\MG_DDR_FAR_DIMM_CMD_NG_DDR_C_DLL_5\" )
					)
					( Status sCSetFlattened )
					( Origin gBackEnd )
				)
				( attribute "RELATIVE_PROPAGATION_DELAY" "0.00 MIL,25.00 MIL"
					( Parent
						( matchGroupRef "@baseboard_fab2_lib.baseboard_fab2(sch_1):\MG_DDR_FAR_DIMM_CMD_NG_DDR_C_DLL_5\" )
					)
					( Units "uMatchProp" "ns" 1.000000)
					( Status sCSetFlattened )
					( Origin gBackEnd )
				)
			)
			( pinPair "@baseboard_fab2_lib.baseboard_fab2(sch_1):\PP3910\"
				( pinRef "@baseboard_fab2_lib.baseboard_fab2(sch_1):page48_i111:A0" )
				( pinRef "@baseboard_fab2_lib.baseboard_fab2(sch_1):page25_i172:DDR2_MA(0)" )
				( attribute "RELATIVE_PROPAGATION_DELAY_SCOPE" "G"
					( Parent
						( matchGroupRef "@crescent_city_bb_fab1_lib.crescent_city_bb_fab1(sch_1):\MG_DDR_NEAR_DIMM-CLK1_CLS_DDR_C_CAC-CLKS\" )
					)
					( Status sCSetFlattened )
					( Origin gBackEnd )
				)
				( attribute "RELATIVE_PROPAGATION_DELAY" "0.00 MIL,700.00 MIL"
					( Parent
						( matchGroupRef "@crescent_city_bb_fab1_lib.crescent_city_bb_fab1(sch_1):\MG_DDR_NEAR_DIMM-CLK1_CLS_DDR_C_CAC-CLKS\" )
					)
					( Units "uMatchProp" "ns" 1.000000)
					( Status sCSetFlattened )
					( Origin gBackEnd )
				)
				( attribute "RELATIVE_PROPAGATION_DELAY_SCOPE" "G"
					( Parent
						( matchGroupRef "@baseboard_fab2_lib.baseboard_fab2(sch_1):\MG_DDR_CMD_NEAR_DIMM_NG_DDR_C_DLL_5\" )
					)
					( Status sCSetFlattened )
					( Origin gBackEnd )
				)
				( attribute "RELATIVE_PROPAGATION_DELAY" "0.00 MIL,25.00 MIL"
					( Parent
						( matchGroupRef "@baseboard_fab2_lib.baseboard_fab2(sch_1):\MG_DDR_CMD_NEAR_DIMM_NG_DDR_C_DLL_5\" )
					)
					( Units "uMatchProp" "ns" 1.000000)
					( Status sCSetFlattened )
					( Origin gBackEnd )
				)
			)
			( pinPair "@baseboard_fab2_lib.baseboard_fab2(sch_1):\PP3905\"
				( pinRef "@baseboard_fab2_lib.baseboard_fab2(sch_1):page25_i172:DDR2_PAR" )
				( pinRef "@baseboard_fab2_lib.baseboard_fab2(sch_1):page47_i111:PAR" )
				( attribute "RELATIVE_PROPAGATION_DELAY_SCOPE" "G"
					( Parent
						( matchGroupRef "@crescent_city_bb_fab1_lib.crescent_city_bb_fab1(sch_1):\MG_DDR_FAR_DIMM-CLK0_CLS_DDR_C_CAC-CLKS\" )
					)
					( Status sCSetFlattened )
					( Origin gBackEnd )
				)
				( attribute "RELATIVE_PROPAGATION_DELAY" "0.00 MIL,700.00 MIL"
					( Parent
						( matchGroupRef "@crescent_city_bb_fab1_lib.crescent_city_bb_fab1(sch_1):\MG_DDR_FAR_DIMM-CLK0_CLS_DDR_C_CAC-CLKS\" )
					)
					( Units "uMatchProp" "ns" 1.000000)
					( Status sCSetFlattened )
					( Origin gBackEnd )
				)
				( attribute "RELATIVE_PROPAGATION_DELAY_SCOPE" "G"
					( Parent
						( matchGroupRef "@baseboard_fab2_lib.baseboard_fab2(sch_1):\MG_DDR_FAR_DIMM_CMD_NG_DDR_C_DLL_6\" )
					)
					( Status sCSetFlattened )
					( Origin gBackEnd )
				)
				( attribute "RELATIVE_PROPAGATION_DELAY" "0.00 MIL,25.00 MIL"
					( Parent
						( matchGroupRef "@baseboard_fab2_lib.baseboard_fab2(sch_1):\MG_DDR_FAR_DIMM_CMD_NG_DDR_C_DLL_6\" )
					)
					( Units "uMatchProp" "ns" 1.000000)
					( Status sCSetFlattened )
					( Origin gBackEnd )
				)
			)
			( pinPair "@baseboard_fab2_lib.baseboard_fab2(sch_1):\PP3906\"
				( pinRef "@baseboard_fab2_lib.baseboard_fab2(sch_1):page48_i111:PAR" )
				( pinRef "@baseboard_fab2_lib.baseboard_fab2(sch_1):page25_i172:DDR2_PAR" )
				( attribute "RELATIVE_PROPAGATION_DELAY_SCOPE" "G"
					( Parent
						( matchGroupRef "@crescent_city_bb_fab1_lib.crescent_city_bb_fab1(sch_1):\MG_DDR_NEAR_DIMM-CLK1_CLS_DDR_C_CAC-CLKS\" )
					)
					( Status sCSetFlattened )
					( Origin gBackEnd )
				)
				( attribute "RELATIVE_PROPAGATION_DELAY" "0.00 MIL,700.00 MIL"
					( Parent
						( matchGroupRef "@crescent_city_bb_fab1_lib.crescent_city_bb_fab1(sch_1):\MG_DDR_NEAR_DIMM-CLK1_CLS_DDR_C_CAC-CLKS\" )
					)
					( Units "uMatchProp" "ns" 1.000000)
					( Status sCSetFlattened )
					( Origin gBackEnd )
				)
				( attribute "RELATIVE_PROPAGATION_DELAY_SCOPE" "G"
					( Parent
						( matchGroupRef "@baseboard_fab2_lib.baseboard_fab2(sch_1):\MG_DDR_CMD_NEAR_DIMM_NG_DDR_C_DLL_6\" )
					)
					( Status sCSetFlattened )
					( Origin gBackEnd )
				)
				( attribute "RELATIVE_PROPAGATION_DELAY" "0.00 MIL,25.00 MIL"
					( Parent
						( matchGroupRef "@baseboard_fab2_lib.baseboard_fab2(sch_1):\MG_DDR_CMD_NEAR_DIMM_NG_DDR_C_DLL_6\" )
					)
					( Units "uMatchProp" "ns" 1.000000)
					( Status sCSetFlattened )
					( Origin gBackEnd )
				)
			)
			( pinPair "@baseboard_fab2_lib.baseboard_fab2(sch_1):\PP3901\"
				( pinRef "@baseboard_fab2_lib.baseboard_fab2(sch_1):page25_i172:DDR2_MA(1)" )
				( pinRef "@baseboard_fab2_lib.baseboard_fab2(sch_1):page47_i111:A1" )
				( attribute "RELATIVE_PROPAGATION_DELAY_SCOPE" "G"
					( Parent
						( matchGroupRef "@crescent_city_bb_fab1_lib.crescent_city_bb_fab1(sch_1):\MG_DDR_FAR_DIMM-CLK0_CLS_DDR_C_CAC-CLKS\" )
					)
					( Status sCSetFlattened )
					( Origin gBackEnd )
				)
				( attribute "RELATIVE_PROPAGATION_DELAY" "0.00 MIL,700.00 MIL"
					( Parent
						( matchGroupRef "@crescent_city_bb_fab1_lib.crescent_city_bb_fab1(sch_1):\MG_DDR_FAR_DIMM-CLK0_CLS_DDR_C_CAC-CLKS\" )
					)
					( Units "uMatchProp" "ns" 1.000000)
					( Status sCSetFlattened )
					( Origin gBackEnd )
				)
				( attribute "RELATIVE_PROPAGATION_DELAY_SCOPE" "G"
					( Parent
						( matchGroupRef "@baseboard_fab2_lib.baseboard_fab2(sch_1):\MG_DDR_FAR_DIMM_CMD_NG_DDR_C_DLL_7\" )
					)
					( Status sCSetFlattened )
					( Origin gBackEnd )
				)
				( attribute "RELATIVE_PROPAGATION_DELAY" "0.00 MIL,25.00 MIL"
					( Parent
						( matchGroupRef "@baseboard_fab2_lib.baseboard_fab2(sch_1):\MG_DDR_FAR_DIMM_CMD_NG_DDR_C_DLL_7\" )
					)
					( Units "uMatchProp" "ns" 1.000000)
					( Status sCSetFlattened )
					( Origin gBackEnd )
				)
			)
			( pinPair "@baseboard_fab2_lib.baseboard_fab2(sch_1):\PP3902\"
				( pinRef "@baseboard_fab2_lib.baseboard_fab2(sch_1):page25_i172:DDR2_MA(1)" )
				( pinRef "@baseboard_fab2_lib.baseboard_fab2(sch_1):page48_i111:A1" )
				( attribute "RELATIVE_PROPAGATION_DELAY_SCOPE" "G"
					( Parent
						( matchGroupRef "@crescent_city_bb_fab1_lib.crescent_city_bb_fab1(sch_1):\MG_DDR_NEAR_DIMM-CLK1_CLS_DDR_C_CAC-CLKS\" )
					)
					( Status sCSetFlattened )
					( Origin gBackEnd )
				)
				( attribute "RELATIVE_PROPAGATION_DELAY" "0.00 MIL,700.00 MIL"
					( Parent
						( matchGroupRef "@crescent_city_bb_fab1_lib.crescent_city_bb_fab1(sch_1):\MG_DDR_NEAR_DIMM-CLK1_CLS_DDR_C_CAC-CLKS\" )
					)
					( Units "uMatchProp" "ns" 1.000000)
					( Status sCSetFlattened )
					( Origin gBackEnd )
				)
				( attribute "RELATIVE_PROPAGATION_DELAY_SCOPE" "G"
					( Parent
						( matchGroupRef "@baseboard_fab2_lib.baseboard_fab2(sch_1):\MG_DDR_CMD_NEAR_DIMM_NG_DDR_C_DLL_7\" )
					)
					( Status sCSetFlattened )
					( Origin gBackEnd )
				)
				( attribute "RELATIVE_PROPAGATION_DELAY" "0.00 MIL,25.00 MIL"
					( Parent
						( matchGroupRef "@baseboard_fab2_lib.baseboard_fab2(sch_1):\MG_DDR_CMD_NEAR_DIMM_NG_DDR_C_DLL_7\" )
					)
					( Units "uMatchProp" "ns" 1.000000)
					( Status sCSetFlattened )
					( Origin gBackEnd )
				)
			)
			( pinPair "@baseboard_fab2_lib.baseboard_fab2(sch_1):\PP3903\"
				( pinRef "@baseboard_fab2_lib.baseboard_fab2(sch_1):page25_i172:DDR2_MA(3)" )
				( pinRef "@baseboard_fab2_lib.baseboard_fab2(sch_1):page47_i111:A3" )
				( attribute "RELATIVE_PROPAGATION_DELAY_SCOPE" "G"
					( Parent
						( matchGroupRef "@crescent_city_bb_fab1_lib.crescent_city_bb_fab1(sch_1):\MG_DDR_FAR_DIMM-CLK0_CLS_DDR_C_CAC-CLKS\" )
					)
					( Status sCSetFlattened )
					( Origin gBackEnd )
				)
				( attribute "RELATIVE_PROPAGATION_DELAY" "0.00 MIL,700.00 MIL"
					( Parent
						( matchGroupRef "@crescent_city_bb_fab1_lib.crescent_city_bb_fab1(sch_1):\MG_DDR_FAR_DIMM-CLK0_CLS_DDR_C_CAC-CLKS\" )
					)
					( Units "uMatchProp" "ns" 1.000000)
					( Status sCSetFlattened )
					( Origin gBackEnd )
				)
				( attribute "RELATIVE_PROPAGATION_DELAY_SCOPE" "G"
					( Parent
						( matchGroupRef "@baseboard_fab2_lib.baseboard_fab2(sch_1):\MG_DDR_FAR_DIMM_CMD_NG_DDR_C_DLL_7\" )
					)
					( Status sCSetFlattened )
					( Origin gBackEnd )
				)
				( attribute "RELATIVE_PROPAGATION_DELAY" "0.00 MIL,25.00 MIL"
					( Parent
						( matchGroupRef "@baseboard_fab2_lib.baseboard_fab2(sch_1):\MG_DDR_FAR_DIMM_CMD_NG_DDR_C_DLL_7\" )
					)
					( Units "uMatchProp" "ns" 1.000000)
					( Status sCSetFlattened )
					( Origin gBackEnd )
				)
			)
			( pinPair "@baseboard_fab2_lib.baseboard_fab2(sch_1):\PP3904\"
				( pinRef "@baseboard_fab2_lib.baseboard_fab2(sch_1):page25_i172:DDR2_MA(3)" )
				( pinRef "@baseboard_fab2_lib.baseboard_fab2(sch_1):page48_i111:A3" )
				( attribute "RELATIVE_PROPAGATION_DELAY_SCOPE" "G"
					( Parent
						( matchGroupRef "@crescent_city_bb_fab1_lib.crescent_city_bb_fab1(sch_1):\MG_DDR_NEAR_DIMM-CLK1_CLS_DDR_C_CAC-CLKS\" )
					)
					( Status sCSetFlattened )
					( Origin gBackEnd )
				)
				( attribute "RELATIVE_PROPAGATION_DELAY" "0.00 MIL,700.00 MIL"
					( Parent
						( matchGroupRef "@crescent_city_bb_fab1_lib.crescent_city_bb_fab1(sch_1):\MG_DDR_NEAR_DIMM-CLK1_CLS_DDR_C_CAC-CLKS\" )
					)
					( Units "uMatchProp" "ns" 1.000000)
					( Status sCSetFlattened )
					( Origin gBackEnd )
				)
				( attribute "RELATIVE_PROPAGATION_DELAY_SCOPE" "G"
					( Parent
						( matchGroupRef "@baseboard_fab2_lib.baseboard_fab2(sch_1):\MG_DDR_CMD_NEAR_DIMM_NG_DDR_C_DLL_7\" )
					)
					( Status sCSetFlattened )
					( Origin gBackEnd )
				)
				( attribute "RELATIVE_PROPAGATION_DELAY" "0.00 MIL,25.00 MIL"
					( Parent
						( matchGroupRef "@baseboard_fab2_lib.baseboard_fab2(sch_1):\MG_DDR_CMD_NEAR_DIMM_NG_DDR_C_DLL_7\" )
					)
					( Units "uMatchProp" "ns" 1.000000)
					( Status sCSetFlattened )
					( Origin gBackEnd )
				)
			)
			( pinPair "@baseboard_fab2_lib.baseboard_fab2(sch_1):\PP3897\"
				( pinRef "@baseboard_fab2_lib.baseboard_fab2(sch_1):page25_i172:DDR2_MA(2)" )
				( pinRef "@baseboard_fab2_lib.baseboard_fab2(sch_1):page47_i111:A2" )
				( attribute "RELATIVE_PROPAGATION_DELAY_SCOPE" "G"
					( Parent
						( matchGroupRef "@crescent_city_bb_fab1_lib.crescent_city_bb_fab1(sch_1):\MG_DDR_FAR_DIMM-CLK0_CLS_DDR_C_CAC-CLKS\" )
					)
					( Status sCSetFlattened )
					( Origin gBackEnd )
				)
				( attribute "RELATIVE_PROPAGATION_DELAY" "0.00 MIL,700.00 MIL"
					( Parent
						( matchGroupRef "@crescent_city_bb_fab1_lib.crescent_city_bb_fab1(sch_1):\MG_DDR_FAR_DIMM-CLK0_CLS_DDR_C_CAC-CLKS\" )
					)
					( Units "uMatchProp" "ns" 1.000000)
					( Status sCSetFlattened )
					( Origin gBackEnd )
				)
				( attribute "RELATIVE_PROPAGATION_DELAY_SCOPE" "G"
					( Parent
						( matchGroupRef "@baseboard_fab2_lib.baseboard_fab2(sch_1):\MG_DDR_FAR_DIMM_CMD_NG_DDR_C_DLL_8\" )
					)
					( Status sCSetFlattened )
					( Origin gBackEnd )
				)
				( attribute "RELATIVE_PROPAGATION_DELAY" "0.00 MIL,25.00 MIL"
					( Parent
						( matchGroupRef "@baseboard_fab2_lib.baseboard_fab2(sch_1):\MG_DDR_FAR_DIMM_CMD_NG_DDR_C_DLL_8\" )
					)
					( Units "uMatchProp" "ns" 1.000000)
					( Status sCSetFlattened )
					( Origin gBackEnd )
				)
			)
			( pinPair "@baseboard_fab2_lib.baseboard_fab2(sch_1):\PP3898\"
				( pinRef "@baseboard_fab2_lib.baseboard_fab2(sch_1):page25_i172:DDR2_MA(2)" )
				( pinRef "@baseboard_fab2_lib.baseboard_fab2(sch_1):page48_i111:A2" )
				( attribute "RELATIVE_PROPAGATION_DELAY_SCOPE" "G"
					( Parent
						( matchGroupRef "@crescent_city_bb_fab1_lib.crescent_city_bb_fab1(sch_1):\MG_DDR_NEAR_DIMM-CLK1_CLS_DDR_C_CAC-CLKS\" )
					)
					( Status sCSetFlattened )
					( Origin gBackEnd )
				)
				( attribute "RELATIVE_PROPAGATION_DELAY" "0.00 MIL,700.00 MIL"
					( Parent
						( matchGroupRef "@crescent_city_bb_fab1_lib.crescent_city_bb_fab1(sch_1):\MG_DDR_NEAR_DIMM-CLK1_CLS_DDR_C_CAC-CLKS\" )
					)
					( Units "uMatchProp" "ns" 1.000000)
					( Status sCSetFlattened )
					( Origin gBackEnd )
				)
				( attribute "RELATIVE_PROPAGATION_DELAY_SCOPE" "G"
					( Parent
						( matchGroupRef "@baseboard_fab2_lib.baseboard_fab2(sch_1):\MG_DDR_CMD_NEAR_DIMM_NG_DDR_C_DLL_8\" )
					)
					( Status sCSetFlattened )
					( Origin gBackEnd )
				)
				( attribute "RELATIVE_PROPAGATION_DELAY" "0.00 MIL,25.00 MIL"
					( Parent
						( matchGroupRef "@baseboard_fab2_lib.baseboard_fab2(sch_1):\MG_DDR_CMD_NEAR_DIMM_NG_DDR_C_DLL_8\" )
					)
					( Units "uMatchProp" "ns" 1.000000)
					( Status sCSetFlattened )
					( Origin gBackEnd )
				)
			)
			( pinPair "@baseboard_fab2_lib.baseboard_fab2(sch_1):\PP3899\"
				( pinRef "@baseboard_fab2_lib.baseboard_fab2(sch_1):page25_i172:DDR2_MA(4)" )
				( pinRef "@baseboard_fab2_lib.baseboard_fab2(sch_1):page47_i111:A4" )
				( attribute "RELATIVE_PROPAGATION_DELAY_SCOPE" "G"
					( Parent
						( matchGroupRef "@crescent_city_bb_fab1_lib.crescent_city_bb_fab1(sch_1):\MG_DDR_FAR_DIMM-CLK0_CLS_DDR_C_CAC-CLKS\" )
					)
					( Status sCSetFlattened )
					( Origin gBackEnd )
				)
				( attribute "RELATIVE_PROPAGATION_DELAY" "0.00 MIL,700.00 MIL"
					( Parent
						( matchGroupRef "@crescent_city_bb_fab1_lib.crescent_city_bb_fab1(sch_1):\MG_DDR_FAR_DIMM-CLK0_CLS_DDR_C_CAC-CLKS\" )
					)
					( Units "uMatchProp" "ns" 1.000000)
					( Status sCSetFlattened )
					( Origin gBackEnd )
				)
				( attribute "RELATIVE_PROPAGATION_DELAY_SCOPE" "G"
					( Parent
						( matchGroupRef "@baseboard_fab2_lib.baseboard_fab2(sch_1):\MG_DDR_FAR_DIMM_CMD_NG_DDR_C_DLL_8\" )
					)
					( Status sCSetFlattened )
					( Origin gBackEnd )
				)
				( attribute "RELATIVE_PROPAGATION_DELAY" "0.00 MIL,25.00 MIL"
					( Parent
						( matchGroupRef "@baseboard_fab2_lib.baseboard_fab2(sch_1):\MG_DDR_FAR_DIMM_CMD_NG_DDR_C_DLL_8\" )
					)
					( Units "uMatchProp" "ns" 1.000000)
					( Status sCSetFlattened )
					( Origin gBackEnd )
				)
			)
			( pinPair "@baseboard_fab2_lib.baseboard_fab2(sch_1):\PP3900\"
				( pinRef "@baseboard_fab2_lib.baseboard_fab2(sch_1):page25_i172:DDR2_MA(4)" )
				( pinRef "@baseboard_fab2_lib.baseboard_fab2(sch_1):page48_i111:A4" )
				( attribute "RELATIVE_PROPAGATION_DELAY_SCOPE" "G"
					( Parent
						( matchGroupRef "@crescent_city_bb_fab1_lib.crescent_city_bb_fab1(sch_1):\MG_DDR_NEAR_DIMM-CLK1_CLS_DDR_C_CAC-CLKS\" )
					)
					( Status sCSetFlattened )
					( Origin gBackEnd )
				)
				( attribute "RELATIVE_PROPAGATION_DELAY" "0.00 MIL,700.00 MIL"
					( Parent
						( matchGroupRef "@crescent_city_bb_fab1_lib.crescent_city_bb_fab1(sch_1):\MG_DDR_NEAR_DIMM-CLK1_CLS_DDR_C_CAC-CLKS\" )
					)
					( Units "uMatchProp" "ns" 1.000000)
					( Status sCSetFlattened )
					( Origin gBackEnd )
				)
				( attribute "RELATIVE_PROPAGATION_DELAY_SCOPE" "G"
					( Parent
						( matchGroupRef "@baseboard_fab2_lib.baseboard_fab2(sch_1):\MG_DDR_CMD_NEAR_DIMM_NG_DDR_C_DLL_8\" )
					)
					( Status sCSetFlattened )
					( Origin gBackEnd )
				)
				( attribute "RELATIVE_PROPAGATION_DELAY" "0.00 MIL,25.00 MIL"
					( Parent
						( matchGroupRef "@baseboard_fab2_lib.baseboard_fab2(sch_1):\MG_DDR_CMD_NEAR_DIMM_NG_DDR_C_DLL_8\" )
					)
					( Units "uMatchProp" "ns" 1.000000)
					( Status sCSetFlattened )
					( Origin gBackEnd )
				)
			)
			( pinPair "@baseboard_fab2_lib.baseboard_fab2(sch_1):\PP3893\"
				( pinRef "@baseboard_fab2_lib.baseboard_fab2(sch_1):page25_i172:DDR2_MA(5)" )
				( pinRef "@baseboard_fab2_lib.baseboard_fab2(sch_1):page47_i111:A5" )
				( attribute "RELATIVE_PROPAGATION_DELAY_SCOPE" "G"
					( Parent
						( matchGroupRef "@crescent_city_bb_fab1_lib.crescent_city_bb_fab1(sch_1):\MG_DDR_FAR_DIMM-CLK0_CLS_DDR_C_CAC-CLKS\" )
					)
					( Status sCSetFlattened )
					( Origin gBackEnd )
				)
				( attribute "RELATIVE_PROPAGATION_DELAY" "0.00 MIL,700.00 MIL"
					( Parent
						( matchGroupRef "@crescent_city_bb_fab1_lib.crescent_city_bb_fab1(sch_1):\MG_DDR_FAR_DIMM-CLK0_CLS_DDR_C_CAC-CLKS\" )
					)
					( Units "uMatchProp" "ns" 1.000000)
					( Status sCSetFlattened )
					( Origin gBackEnd )
				)
				( attribute "RELATIVE_PROPAGATION_DELAY_SCOPE" "G"
					( Parent
						( matchGroupRef "@baseboard_fab2_lib.baseboard_fab2(sch_1):\MG_DDR_FAR_DIMM_CMD_NG_DDR_C_DLL_9\" )
					)
					( Status sCSetFlattened )
					( Origin gBackEnd )
				)
				( attribute "RELATIVE_PROPAGATION_DELAY" "0.00 MIL,25.00 MIL"
					( Parent
						( matchGroupRef "@baseboard_fab2_lib.baseboard_fab2(sch_1):\MG_DDR_FAR_DIMM_CMD_NG_DDR_C_DLL_9\" )
					)
					( Units "uMatchProp" "ns" 1.000000)
					( Status sCSetFlattened )
					( Origin gBackEnd )
				)
			)
			( pinPair "@baseboard_fab2_lib.baseboard_fab2(sch_1):\PP3894\"
				( pinRef "@baseboard_fab2_lib.baseboard_fab2(sch_1):page25_i172:DDR2_MA(5)" )
				( pinRef "@baseboard_fab2_lib.baseboard_fab2(sch_1):page48_i111:A5" )
				( attribute "RELATIVE_PROPAGATION_DELAY_SCOPE" "G"
					( Parent
						( matchGroupRef "@crescent_city_bb_fab1_lib.crescent_city_bb_fab1(sch_1):\MG_DDR_NEAR_DIMM-CLK1_CLS_DDR_C_CAC-CLKS\" )
					)
					( Status sCSetFlattened )
					( Origin gBackEnd )
				)
				( attribute "RELATIVE_PROPAGATION_DELAY" "0.00 MIL,700.00 MIL"
					( Parent
						( matchGroupRef "@crescent_city_bb_fab1_lib.crescent_city_bb_fab1(sch_1):\MG_DDR_NEAR_DIMM-CLK1_CLS_DDR_C_CAC-CLKS\" )
					)
					( Units "uMatchProp" "ns" 1.000000)
					( Status sCSetFlattened )
					( Origin gBackEnd )
				)
				( attribute "RELATIVE_PROPAGATION_DELAY_SCOPE" "G"
					( Parent
						( matchGroupRef "@baseboard_fab2_lib.baseboard_fab2(sch_1):\MG_DDR_CMD_NEAR_DIMM_NG_DDR_C_DLL_9\" )
					)
					( Status sCSetFlattened )
					( Origin gBackEnd )
				)
				( attribute "RELATIVE_PROPAGATION_DELAY" "0.00 MIL,25.00 MIL"
					( Parent
						( matchGroupRef "@baseboard_fab2_lib.baseboard_fab2(sch_1):\MG_DDR_CMD_NEAR_DIMM_NG_DDR_C_DLL_9\" )
					)
					( Units "uMatchProp" "ns" 1.000000)
					( Status sCSetFlattened )
					( Origin gBackEnd )
				)
			)
			( pinPair "@baseboard_fab2_lib.baseboard_fab2(sch_1):\PP3895\"
				( pinRef "@baseboard_fab2_lib.baseboard_fab2(sch_1):page25_i172:DDR2_MA(6)" )
				( pinRef "@baseboard_fab2_lib.baseboard_fab2(sch_1):page47_i111:A6" )
				( attribute "RELATIVE_PROPAGATION_DELAY_SCOPE" "G"
					( Parent
						( matchGroupRef "@crescent_city_bb_fab1_lib.crescent_city_bb_fab1(sch_1):\MG_DDR_FAR_DIMM-CLK0_CLS_DDR_C_CAC-CLKS\" )
					)
					( Status sCSetFlattened )
					( Origin gBackEnd )
				)
				( attribute "RELATIVE_PROPAGATION_DELAY" "0.00 MIL,700.00 MIL"
					( Parent
						( matchGroupRef "@crescent_city_bb_fab1_lib.crescent_city_bb_fab1(sch_1):\MG_DDR_FAR_DIMM-CLK0_CLS_DDR_C_CAC-CLKS\" )
					)
					( Units "uMatchProp" "ns" 1.000000)
					( Status sCSetFlattened )
					( Origin gBackEnd )
				)
				( attribute "RELATIVE_PROPAGATION_DELAY_SCOPE" "G"
					( Parent
						( matchGroupRef "@baseboard_fab2_lib.baseboard_fab2(sch_1):\MG_DDR_FAR_DIMM_CMD_NG_DDR_C_DLL_9\" )
					)
					( Status sCSetFlattened )
					( Origin gBackEnd )
				)
				( attribute "RELATIVE_PROPAGATION_DELAY" "0.00 MIL,25.00 MIL"
					( Parent
						( matchGroupRef "@baseboard_fab2_lib.baseboard_fab2(sch_1):\MG_DDR_FAR_DIMM_CMD_NG_DDR_C_DLL_9\" )
					)
					( Units "uMatchProp" "ns" 1.000000)
					( Status sCSetFlattened )
					( Origin gBackEnd )
				)
			)
			( pinPair "@baseboard_fab2_lib.baseboard_fab2(sch_1):\PP3896\"
				( pinRef "@baseboard_fab2_lib.baseboard_fab2(sch_1):page48_i111:A6" )
				( pinRef "@baseboard_fab2_lib.baseboard_fab2(sch_1):page25_i172:DDR2_MA(6)" )
				( attribute "RELATIVE_PROPAGATION_DELAY_SCOPE" "G"
					( Parent
						( matchGroupRef "@crescent_city_bb_fab1_lib.crescent_city_bb_fab1(sch_1):\MG_DDR_NEAR_DIMM-CLK1_CLS_DDR_C_CAC-CLKS\" )
					)
					( Status sCSetFlattened )
					( Origin gBackEnd )
				)
				( attribute "RELATIVE_PROPAGATION_DELAY" "0.00 MIL,700.00 MIL"
					( Parent
						( matchGroupRef "@crescent_city_bb_fab1_lib.crescent_city_bb_fab1(sch_1):\MG_DDR_NEAR_DIMM-CLK1_CLS_DDR_C_CAC-CLKS\" )
					)
					( Units "uMatchProp" "ns" 1.000000)
					( Status sCSetFlattened )
					( Origin gBackEnd )
				)
				( attribute "RELATIVE_PROPAGATION_DELAY_SCOPE" "G"
					( Parent
						( matchGroupRef "@baseboard_fab2_lib.baseboard_fab2(sch_1):\MG_DDR_CMD_NEAR_DIMM_NG_DDR_C_DLL_9\" )
					)
					( Status sCSetFlattened )
					( Origin gBackEnd )
				)
				( attribute "RELATIVE_PROPAGATION_DELAY" "0.00 MIL,25.00 MIL"
					( Parent
						( matchGroupRef "@baseboard_fab2_lib.baseboard_fab2(sch_1):\MG_DDR_CMD_NEAR_DIMM_NG_DDR_C_DLL_9\" )
					)
					( Units "uMatchProp" "ns" 1.000000)
					( Status sCSetFlattened )
					( Origin gBackEnd )
				)
			)
			( pinPair "@baseboard_fab2_lib.baseboard_fab2(sch_1):\PP3889\"
				( pinRef "@baseboard_fab2_lib.baseboard_fab2(sch_1):page25_i172:DDR2_MA(7)" )
				( pinRef "@baseboard_fab2_lib.baseboard_fab2(sch_1):page47_i111:A7" )
				( attribute "RELATIVE_PROPAGATION_DELAY_SCOPE" "G"
					( Parent
						( matchGroupRef "@crescent_city_bb_fab1_lib.crescent_city_bb_fab1(sch_1):\MG_DDR_FAR_DIMM-CLK0_CLS_DDR_C_CAC-CLKS\" )
					)
					( Status sCSetFlattened )
					( Origin gBackEnd )
				)
				( attribute "RELATIVE_PROPAGATION_DELAY" "0.00 MIL,700.00 MIL"
					( Parent
						( matchGroupRef "@crescent_city_bb_fab1_lib.crescent_city_bb_fab1(sch_1):\MG_DDR_FAR_DIMM-CLK0_CLS_DDR_C_CAC-CLKS\" )
					)
					( Units "uMatchProp" "ns" 1.000000)
					( Status sCSetFlattened )
					( Origin gBackEnd )
				)
				( attribute "RELATIVE_PROPAGATION_DELAY_SCOPE" "G"
					( Parent
						( matchGroupRef "@baseboard_fab2_lib.baseboard_fab2(sch_1):\MG_DDR_FAR_DIMM_CMD_NG_DDR_C_DLL_10\" )
					)
					( Status sCSetFlattened )
					( Origin gBackEnd )
				)
				( attribute "RELATIVE_PROPAGATION_DELAY" "0.00 MIL,25.00 MIL"
					( Parent
						( matchGroupRef "@baseboard_fab2_lib.baseboard_fab2(sch_1):\MG_DDR_FAR_DIMM_CMD_NG_DDR_C_DLL_10\" )
					)
					( Units "uMatchProp" "ns" 1.000000)
					( Status sCSetFlattened )
					( Origin gBackEnd )
				)
			)
			( pinPair "@baseboard_fab2_lib.baseboard_fab2(sch_1):\PP3890\"
				( pinRef "@baseboard_fab2_lib.baseboard_fab2(sch_1):page25_i172:DDR2_MA(7)" )
				( pinRef "@baseboard_fab2_lib.baseboard_fab2(sch_1):page48_i111:A7" )
				( attribute "RELATIVE_PROPAGATION_DELAY_SCOPE" "G"
					( Parent
						( matchGroupRef "@crescent_city_bb_fab1_lib.crescent_city_bb_fab1(sch_1):\MG_DDR_NEAR_DIMM-CLK1_CLS_DDR_C_CAC-CLKS\" )
					)
					( Status sCSetFlattened )
					( Origin gBackEnd )
				)
				( attribute "RELATIVE_PROPAGATION_DELAY" "0.00 MIL,700.00 MIL"
					( Parent
						( matchGroupRef "@crescent_city_bb_fab1_lib.crescent_city_bb_fab1(sch_1):\MG_DDR_NEAR_DIMM-CLK1_CLS_DDR_C_CAC-CLKS\" )
					)
					( Units "uMatchProp" "ns" 1.000000)
					( Status sCSetFlattened )
					( Origin gBackEnd )
				)
				( attribute "RELATIVE_PROPAGATION_DELAY_SCOPE" "G"
					( Parent
						( matchGroupRef "@baseboard_fab2_lib.baseboard_fab2(sch_1):\MG_DDR_CMD_NEAR_DIMM_NG_DDR_C_DLL_10\" )
					)
					( Status sCSetFlattened )
					( Origin gBackEnd )
				)
				( attribute "RELATIVE_PROPAGATION_DELAY" "0.00 MIL,25.00 MIL"
					( Parent
						( matchGroupRef "@baseboard_fab2_lib.baseboard_fab2(sch_1):\MG_DDR_CMD_NEAR_DIMM_NG_DDR_C_DLL_10\" )
					)
					( Units "uMatchProp" "ns" 1.000000)
					( Status sCSetFlattened )
					( Origin gBackEnd )
				)
			)
			( pinPair "@baseboard_fab2_lib.baseboard_fab2(sch_1):\PP3891\"
				( pinRef "@baseboard_fab2_lib.baseboard_fab2(sch_1):page25_i172:DDR2_MA(8)" )
				( pinRef "@baseboard_fab2_lib.baseboard_fab2(sch_1):page47_i111:A8" )
				( attribute "RELATIVE_PROPAGATION_DELAY_SCOPE" "G"
					( Parent
						( matchGroupRef "@crescent_city_bb_fab1_lib.crescent_city_bb_fab1(sch_1):\MG_DDR_FAR_DIMM-CLK0_CLS_DDR_C_CAC-CLKS\" )
					)
					( Status sCSetFlattened )
					( Origin gBackEnd )
				)
				( attribute "RELATIVE_PROPAGATION_DELAY" "0.00 MIL,700.00 MIL"
					( Parent
						( matchGroupRef "@crescent_city_bb_fab1_lib.crescent_city_bb_fab1(sch_1):\MG_DDR_FAR_DIMM-CLK0_CLS_DDR_C_CAC-CLKS\" )
					)
					( Units "uMatchProp" "ns" 1.000000)
					( Status sCSetFlattened )
					( Origin gBackEnd )
				)
				( attribute "RELATIVE_PROPAGATION_DELAY_SCOPE" "G"
					( Parent
						( matchGroupRef "@baseboard_fab2_lib.baseboard_fab2(sch_1):\MG_DDR_FAR_DIMM_CMD_NG_DDR_C_DLL_10\" )
					)
					( Status sCSetFlattened )
					( Origin gBackEnd )
				)
				( attribute "RELATIVE_PROPAGATION_DELAY" "0.00 MIL,25.00 MIL"
					( Parent
						( matchGroupRef "@baseboard_fab2_lib.baseboard_fab2(sch_1):\MG_DDR_FAR_DIMM_CMD_NG_DDR_C_DLL_10\" )
					)
					( Units "uMatchProp" "ns" 1.000000)
					( Status sCSetFlattened )
					( Origin gBackEnd )
				)
			)
			( pinPair "@baseboard_fab2_lib.baseboard_fab2(sch_1):\PP3892\"
				( pinRef "@baseboard_fab2_lib.baseboard_fab2(sch_1):page25_i172:DDR2_MA(8)" )
				( pinRef "@baseboard_fab2_lib.baseboard_fab2(sch_1):page48_i111:A8" )
				( attribute "RELATIVE_PROPAGATION_DELAY_SCOPE" "G"
					( Parent
						( matchGroupRef "@crescent_city_bb_fab1_lib.crescent_city_bb_fab1(sch_1):\MG_DDR_NEAR_DIMM-CLK1_CLS_DDR_C_CAC-CLKS\" )
					)
					( Status sCSetFlattened )
					( Origin gBackEnd )
				)
				( attribute "RELATIVE_PROPAGATION_DELAY" "0.00 MIL,700.00 MIL"
					( Parent
						( matchGroupRef "@crescent_city_bb_fab1_lib.crescent_city_bb_fab1(sch_1):\MG_DDR_NEAR_DIMM-CLK1_CLS_DDR_C_CAC-CLKS\" )
					)
					( Units "uMatchProp" "ns" 1.000000)
					( Status sCSetFlattened )
					( Origin gBackEnd )
				)
				( attribute "RELATIVE_PROPAGATION_DELAY_SCOPE" "G"
					( Parent
						( matchGroupRef "@baseboard_fab2_lib.baseboard_fab2(sch_1):\MG_DDR_CMD_NEAR_DIMM_NG_DDR_C_DLL_10\" )
					)
					( Status sCSetFlattened )
					( Origin gBackEnd )
				)
				( attribute "RELATIVE_PROPAGATION_DELAY" "0.00 MIL,25.00 MIL"
					( Parent
						( matchGroupRef "@baseboard_fab2_lib.baseboard_fab2(sch_1):\MG_DDR_CMD_NEAR_DIMM_NG_DDR_C_DLL_10\" )
					)
					( Units "uMatchProp" "ns" 1.000000)
					( Status sCSetFlattened )
					( Origin gBackEnd )
				)
			)
			( pinPair "@baseboard_fab2_lib.baseboard_fab2(sch_1):\PP3885\"
				( pinRef "@baseboard_fab2_lib.baseboard_fab2(sch_1):page25_i172:DDR2_MA(9)" )
				( pinRef "@baseboard_fab2_lib.baseboard_fab2(sch_1):page47_i111:A9" )
				( attribute "RELATIVE_PROPAGATION_DELAY_SCOPE" "G"
					( Parent
						( matchGroupRef "@crescent_city_bb_fab1_lib.crescent_city_bb_fab1(sch_1):\MG_DDR_FAR_DIMM-CLK0_CLS_DDR_C_CAC-CLKS\" )
					)
					( Status sCSetFlattened )
					( Origin gBackEnd )
				)
				( attribute "RELATIVE_PROPAGATION_DELAY" "0.00 MIL,700.00 MIL"
					( Parent
						( matchGroupRef "@crescent_city_bb_fab1_lib.crescent_city_bb_fab1(sch_1):\MG_DDR_FAR_DIMM-CLK0_CLS_DDR_C_CAC-CLKS\" )
					)
					( Units "uMatchProp" "ns" 1.000000)
					( Status sCSetFlattened )
					( Origin gBackEnd )
				)
				( attribute "RELATIVE_PROPAGATION_DELAY_SCOPE" "G"
					( Parent
						( matchGroupRef "@baseboard_fab2_lib.baseboard_fab2(sch_1):\MG_DDR_FAR_DIMM_CMD_NG_DDR_C_DLL_11\" )
					)
					( Status sCSetFlattened )
					( Origin gBackEnd )
				)
				( attribute "RELATIVE_PROPAGATION_DELAY" "0.00 MIL,25.00 MIL"
					( Parent
						( matchGroupRef "@baseboard_fab2_lib.baseboard_fab2(sch_1):\MG_DDR_FAR_DIMM_CMD_NG_DDR_C_DLL_11\" )
					)
					( Units "uMatchProp" "ns" 1.000000)
					( Status sCSetFlattened )
					( Origin gBackEnd )
				)
			)
			( pinPair "@baseboard_fab2_lib.baseboard_fab2(sch_1):\PP3886\"
				( pinRef "@baseboard_fab2_lib.baseboard_fab2(sch_1):page25_i172:DDR2_MA(9)" )
				( pinRef "@baseboard_fab2_lib.baseboard_fab2(sch_1):page48_i111:A9" )
				( attribute "RELATIVE_PROPAGATION_DELAY_SCOPE" "G"
					( Parent
						( matchGroupRef "@crescent_city_bb_fab1_lib.crescent_city_bb_fab1(sch_1):\MG_DDR_NEAR_DIMM-CLK1_CLS_DDR_C_CAC-CLKS\" )
					)
					( Status sCSetFlattened )
					( Origin gBackEnd )
				)
				( attribute "RELATIVE_PROPAGATION_DELAY" "0.00 MIL,700.00 MIL"
					( Parent
						( matchGroupRef "@crescent_city_bb_fab1_lib.crescent_city_bb_fab1(sch_1):\MG_DDR_NEAR_DIMM-CLK1_CLS_DDR_C_CAC-CLKS\" )
					)
					( Units "uMatchProp" "ns" 1.000000)
					( Status sCSetFlattened )
					( Origin gBackEnd )
				)
				( attribute "RELATIVE_PROPAGATION_DELAY_SCOPE" "G"
					( Parent
						( matchGroupRef "@baseboard_fab2_lib.baseboard_fab2(sch_1):\MG_DDR_CMD_NEAR_DIMM_NG_DDR_C_DLL_11\" )
					)
					( Status sCSetFlattened )
					( Origin gBackEnd )
				)
				( attribute "RELATIVE_PROPAGATION_DELAY" "0.00 MIL,25.00 MIL"
					( Parent
						( matchGroupRef "@baseboard_fab2_lib.baseboard_fab2(sch_1):\MG_DDR_CMD_NEAR_DIMM_NG_DDR_C_DLL_11\" )
					)
					( Units "uMatchProp" "ns" 1.000000)
					( Status sCSetFlattened )
					( Origin gBackEnd )
				)
			)
			( pinPair "@baseboard_fab2_lib.baseboard_fab2(sch_1):\PP3887\"
				( pinRef "@baseboard_fab2_lib.baseboard_fab2(sch_1):page25_i172:DDR2_MA(12)" )
				( pinRef "@baseboard_fab2_lib.baseboard_fab2(sch_1):page47_i111:A12" )
				( attribute "RELATIVE_PROPAGATION_DELAY_SCOPE" "G"
					( Parent
						( matchGroupRef "@crescent_city_bb_fab1_lib.crescent_city_bb_fab1(sch_1):\MG_DDR_FAR_DIMM-CLK0_CLS_DDR_C_CAC-CLKS\" )
					)
					( Status sCSetFlattened )
					( Origin gBackEnd )
				)
				( attribute "RELATIVE_PROPAGATION_DELAY" "0.00 MIL,700.00 MIL"
					( Parent
						( matchGroupRef "@crescent_city_bb_fab1_lib.crescent_city_bb_fab1(sch_1):\MG_DDR_FAR_DIMM-CLK0_CLS_DDR_C_CAC-CLKS\" )
					)
					( Units "uMatchProp" "ns" 1.000000)
					( Status sCSetFlattened )
					( Origin gBackEnd )
				)
				( attribute "RELATIVE_PROPAGATION_DELAY_SCOPE" "G"
					( Parent
						( matchGroupRef "@baseboard_fab2_lib.baseboard_fab2(sch_1):\MG_DDR_FAR_DIMM_CMD_NG_DDR_C_DLL_11\" )
					)
					( Status sCSetFlattened )
					( Origin gBackEnd )
				)
				( attribute "RELATIVE_PROPAGATION_DELAY" "0.00 MIL,25.00 MIL"
					( Parent
						( matchGroupRef "@baseboard_fab2_lib.baseboard_fab2(sch_1):\MG_DDR_FAR_DIMM_CMD_NG_DDR_C_DLL_11\" )
					)
					( Units "uMatchProp" "ns" 1.000000)
					( Status sCSetFlattened )
					( Origin gBackEnd )
				)
			)
			( pinPair "@baseboard_fab2_lib.baseboard_fab2(sch_1):\PP3888\"
				( pinRef "@baseboard_fab2_lib.baseboard_fab2(sch_1):page25_i172:DDR2_MA(12)" )
				( pinRef "@baseboard_fab2_lib.baseboard_fab2(sch_1):page48_i111:A12" )
				( attribute "RELATIVE_PROPAGATION_DELAY_SCOPE" "G"
					( Parent
						( matchGroupRef "@crescent_city_bb_fab1_lib.crescent_city_bb_fab1(sch_1):\MG_DDR_NEAR_DIMM-CLK1_CLS_DDR_C_CAC-CLKS\" )
					)
					( Status sCSetFlattened )
					( Origin gBackEnd )
				)
				( attribute "RELATIVE_PROPAGATION_DELAY" "0.00 MIL,700.00 MIL"
					( Parent
						( matchGroupRef "@crescent_city_bb_fab1_lib.crescent_city_bb_fab1(sch_1):\MG_DDR_NEAR_DIMM-CLK1_CLS_DDR_C_CAC-CLKS\" )
					)
					( Units "uMatchProp" "ns" 1.000000)
					( Status sCSetFlattened )
					( Origin gBackEnd )
				)
				( attribute "RELATIVE_PROPAGATION_DELAY_SCOPE" "G"
					( Parent
						( matchGroupRef "@baseboard_fab2_lib.baseboard_fab2(sch_1):\MG_DDR_CMD_NEAR_DIMM_NG_DDR_C_DLL_11\" )
					)
					( Status sCSetFlattened )
					( Origin gBackEnd )
				)
				( attribute "RELATIVE_PROPAGATION_DELAY" "0.00 MIL,25.00 MIL"
					( Parent
						( matchGroupRef "@baseboard_fab2_lib.baseboard_fab2(sch_1):\MG_DDR_CMD_NEAR_DIMM_NG_DDR_C_DLL_11\" )
					)
					( Units "uMatchProp" "ns" 1.000000)
					( Status sCSetFlattened )
					( Origin gBackEnd )
				)
			)
			( pinPair "@baseboard_fab2_lib.baseboard_fab2(sch_1):\PP3881\"
				( pinRef "@baseboard_fab2_lib.baseboard_fab2(sch_1):page25_i172:DDR2_BG(1)" )
				( pinRef "@baseboard_fab2_lib.baseboard_fab2(sch_1):page47_i111:BG(1)" )
				( attribute "RELATIVE_PROPAGATION_DELAY_SCOPE" "G"
					( Parent
						( matchGroupRef "@crescent_city_bb_fab1_lib.crescent_city_bb_fab1(sch_1):\MG_DDR_FAR_DIMM-CLK0_CLS_DDR_C_CAC-CLKS\" )
					)
					( Status sCSetFlattened )
					( Origin gBackEnd )
				)
				( attribute "RELATIVE_PROPAGATION_DELAY" "0.00 MIL,700.00 MIL"
					( Parent
						( matchGroupRef "@crescent_city_bb_fab1_lib.crescent_city_bb_fab1(sch_1):\MG_DDR_FAR_DIMM-CLK0_CLS_DDR_C_CAC-CLKS\" )
					)
					( Units "uMatchProp" "ns" 1.000000)
					( Status sCSetFlattened )
					( Origin gBackEnd )
				)
				( attribute "RELATIVE_PROPAGATION_DELAY_SCOPE" "G"
					( Parent
						( matchGroupRef "@baseboard_fab2_lib.baseboard_fab2(sch_1):\MG_DDR_FAR_DIMM_CMD_NG_DDR_C_DLL_12\" )
					)
					( Status sCSetFlattened )
					( Origin gBackEnd )
				)
				( attribute "RELATIVE_PROPAGATION_DELAY" "0.00 MIL,25.00 MIL"
					( Parent
						( matchGroupRef "@baseboard_fab2_lib.baseboard_fab2(sch_1):\MG_DDR_FAR_DIMM_CMD_NG_DDR_C_DLL_12\" )
					)
					( Units "uMatchProp" "ns" 1.000000)
					( Status sCSetFlattened )
					( Origin gBackEnd )
				)
			)
			( pinPair "@baseboard_fab2_lib.baseboard_fab2(sch_1):\PP3882\"
				( pinRef "@baseboard_fab2_lib.baseboard_fab2(sch_1):page25_i172:DDR2_BG(1)" )
				( pinRef "@baseboard_fab2_lib.baseboard_fab2(sch_1):page48_i111:BG(1)" )
				( attribute "RELATIVE_PROPAGATION_DELAY_SCOPE" "G"
					( Parent
						( matchGroupRef "@crescent_city_bb_fab1_lib.crescent_city_bb_fab1(sch_1):\MG_DDR_NEAR_DIMM-CLK1_CLS_DDR_C_CAC-CLKS\" )
					)
					( Status sCSetFlattened )
					( Origin gBackEnd )
				)
				( attribute "RELATIVE_PROPAGATION_DELAY" "0.00 MIL,700.00 MIL"
					( Parent
						( matchGroupRef "@crescent_city_bb_fab1_lib.crescent_city_bb_fab1(sch_1):\MG_DDR_NEAR_DIMM-CLK1_CLS_DDR_C_CAC-CLKS\" )
					)
					( Units "uMatchProp" "ns" 1.000000)
					( Status sCSetFlattened )
					( Origin gBackEnd )
				)
				( attribute "RELATIVE_PROPAGATION_DELAY_SCOPE" "G"
					( Parent
						( matchGroupRef "@baseboard_fab2_lib.baseboard_fab2(sch_1):\MG_DDR_CMD_NEAR_DIMM_NG_DDR_C_DLL_12\" )
					)
					( Status sCSetFlattened )
					( Origin gBackEnd )
				)
				( attribute "RELATIVE_PROPAGATION_DELAY" "0.00 MIL,25.00 MIL"
					( Parent
						( matchGroupRef "@baseboard_fab2_lib.baseboard_fab2(sch_1):\MG_DDR_CMD_NEAR_DIMM_NG_DDR_C_DLL_12\" )
					)
					( Units "uMatchProp" "ns" 1.000000)
					( Status sCSetFlattened )
					( Origin gBackEnd )
				)
			)
			( pinPair "@baseboard_fab2_lib.baseboard_fab2(sch_1):\PP3883\"
				( pinRef "@baseboard_fab2_lib.baseboard_fab2(sch_1):page25_i172:DDR2_MA(11)" )
				( pinRef "@baseboard_fab2_lib.baseboard_fab2(sch_1):page47_i111:A11" )
				( attribute "RELATIVE_PROPAGATION_DELAY_SCOPE" "G"
					( Parent
						( matchGroupRef "@crescent_city_bb_fab1_lib.crescent_city_bb_fab1(sch_1):\MG_DDR_FAR_DIMM-CLK0_CLS_DDR_C_CAC-CLKS\" )
					)
					( Status sCSetFlattened )
					( Origin gBackEnd )
				)
				( attribute "RELATIVE_PROPAGATION_DELAY" "0.00 MIL,700.00 MIL"
					( Parent
						( matchGroupRef "@crescent_city_bb_fab1_lib.crescent_city_bb_fab1(sch_1):\MG_DDR_FAR_DIMM-CLK0_CLS_DDR_C_CAC-CLKS\" )
					)
					( Units "uMatchProp" "ns" 1.000000)
					( Status sCSetFlattened )
					( Origin gBackEnd )
				)
				( attribute "RELATIVE_PROPAGATION_DELAY_SCOPE" "G"
					( Parent
						( matchGroupRef "@baseboard_fab2_lib.baseboard_fab2(sch_1):\MG_DDR_FAR_DIMM_CMD_NG_DDR_C_DLL_12\" )
					)
					( Status sCSetFlattened )
					( Origin gBackEnd )
				)
				( attribute "RELATIVE_PROPAGATION_DELAY" "0.00 MIL,25.00 MIL"
					( Parent
						( matchGroupRef "@baseboard_fab2_lib.baseboard_fab2(sch_1):\MG_DDR_FAR_DIMM_CMD_NG_DDR_C_DLL_12\" )
					)
					( Units "uMatchProp" "ns" 1.000000)
					( Status sCSetFlattened )
					( Origin gBackEnd )
				)
			)
			( pinPair "@baseboard_fab2_lib.baseboard_fab2(sch_1):\PP3884\"
				( pinRef "@baseboard_fab2_lib.baseboard_fab2(sch_1):page25_i172:DDR2_MA(11)" )
				( pinRef "@baseboard_fab2_lib.baseboard_fab2(sch_1):page48_i111:A11" )
				( attribute "RELATIVE_PROPAGATION_DELAY_SCOPE" "G"
					( Parent
						( matchGroupRef "@crescent_city_bb_fab1_lib.crescent_city_bb_fab1(sch_1):\MG_DDR_NEAR_DIMM-CLK1_CLS_DDR_C_CAC-CLKS\" )
					)
					( Status sCSetFlattened )
					( Origin gBackEnd )
				)
				( attribute "RELATIVE_PROPAGATION_DELAY" "0.00 MIL,700.00 MIL"
					( Parent
						( matchGroupRef "@crescent_city_bb_fab1_lib.crescent_city_bb_fab1(sch_1):\MG_DDR_NEAR_DIMM-CLK1_CLS_DDR_C_CAC-CLKS\" )
					)
					( Units "uMatchProp" "ns" 1.000000)
					( Status sCSetFlattened )
					( Origin gBackEnd )
				)
				( attribute "RELATIVE_PROPAGATION_DELAY_SCOPE" "G"
					( Parent
						( matchGroupRef "@baseboard_fab2_lib.baseboard_fab2(sch_1):\MG_DDR_CMD_NEAR_DIMM_NG_DDR_C_DLL_12\" )
					)
					( Status sCSetFlattened )
					( Origin gBackEnd )
				)
				( attribute "RELATIVE_PROPAGATION_DELAY" "0.00 MIL,25.00 MIL"
					( Parent
						( matchGroupRef "@baseboard_fab2_lib.baseboard_fab2(sch_1):\MG_DDR_CMD_NEAR_DIMM_NG_DDR_C_DLL_12\" )
					)
					( Units "uMatchProp" "ns" 1.000000)
					( Status sCSetFlattened )
					( Origin gBackEnd )
				)
			)
			( pinPair "@baseboard_fab2_lib.baseboard_fab2(sch_1):\PP3877\"
				( pinRef "@baseboard_fab2_lib.baseboard_fab2(sch_1):page25_i172:DDR2_ACT_N" )
				( pinRef "@baseboard_fab2_lib.baseboard_fab2(sch_1):page47_i111:ACT_N" )
				( attribute "RELATIVE_PROPAGATION_DELAY_SCOPE" "G"
					( Parent
						( matchGroupRef "@crescent_city_bb_fab1_lib.crescent_city_bb_fab1(sch_1):\MG_DDR_FAR_DIMM-CLK0_CLS_DDR_C_CAC-CLKS\" )
					)
					( Status sCSetFlattened )
					( Origin gBackEnd )
				)
				( attribute "RELATIVE_PROPAGATION_DELAY" "0.00 MIL,700.00 MIL"
					( Parent
						( matchGroupRef "@crescent_city_bb_fab1_lib.crescent_city_bb_fab1(sch_1):\MG_DDR_FAR_DIMM-CLK0_CLS_DDR_C_CAC-CLKS\" )
					)
					( Units "uMatchProp" "ns" 1.000000)
					( Status sCSetFlattened )
					( Origin gBackEnd )
				)
				( attribute "RELATIVE_PROPAGATION_DELAY_SCOPE" "G"
					( Parent
						( matchGroupRef "@baseboard_fab2_lib.baseboard_fab2(sch_1):\MG_DDR_FAR_DIMM_CMD_NG_DDR_C_DLL_13\" )
					)
					( Status sCSetFlattened )
					( Origin gBackEnd )
				)
				( attribute "RELATIVE_PROPAGATION_DELAY" "0.00 MIL,25.00 MIL"
					( Parent
						( matchGroupRef "@baseboard_fab2_lib.baseboard_fab2(sch_1):\MG_DDR_FAR_DIMM_CMD_NG_DDR_C_DLL_13\" )
					)
					( Units "uMatchProp" "ns" 1.000000)
					( Status sCSetFlattened )
					( Origin gBackEnd )
				)
			)
			( pinPair "@baseboard_fab2_lib.baseboard_fab2(sch_1):\PP3878\"
				( pinRef "@baseboard_fab2_lib.baseboard_fab2(sch_1):page25_i172:DDR2_ACT_N" )
				( pinRef "@baseboard_fab2_lib.baseboard_fab2(sch_1):page48_i111:ACT_N" )
				( attribute "RELATIVE_PROPAGATION_DELAY_SCOPE" "G"
					( Parent
						( matchGroupRef "@crescent_city_bb_fab1_lib.crescent_city_bb_fab1(sch_1):\MG_DDR_NEAR_DIMM-CLK1_CLS_DDR_C_CAC-CLKS\" )
					)
					( Status sCSetFlattened )
					( Origin gBackEnd )
				)
				( attribute "RELATIVE_PROPAGATION_DELAY" "0.00 MIL,700.00 MIL"
					( Parent
						( matchGroupRef "@crescent_city_bb_fab1_lib.crescent_city_bb_fab1(sch_1):\MG_DDR_NEAR_DIMM-CLK1_CLS_DDR_C_CAC-CLKS\" )
					)
					( Units "uMatchProp" "ns" 1.000000)
					( Status sCSetFlattened )
					( Origin gBackEnd )
				)
				( attribute "RELATIVE_PROPAGATION_DELAY_SCOPE" "G"
					( Parent
						( matchGroupRef "@baseboard_fab2_lib.baseboard_fab2(sch_1):\MG_DDR_CMD_NEAR_DIMM_NG_DDR_C_DLL_13\" )
					)
					( Status sCSetFlattened )
					( Origin gBackEnd )
				)
				( attribute "RELATIVE_PROPAGATION_DELAY" "0.00 MIL,25.00 MIL"
					( Parent
						( matchGroupRef "@baseboard_fab2_lib.baseboard_fab2(sch_1):\MG_DDR_CMD_NEAR_DIMM_NG_DDR_C_DLL_13\" )
					)
					( Units "uMatchProp" "ns" 1.000000)
					( Status sCSetFlattened )
					( Origin gBackEnd )
				)
			)
			( pinPair "@baseboard_fab2_lib.baseboard_fab2(sch_1):\PP3879\"
				( pinRef "@baseboard_fab2_lib.baseboard_fab2(sch_1):page25_i172:DDR2_BG(0)" )
				( pinRef "@baseboard_fab2_lib.baseboard_fab2(sch_1):page47_i111:BG(0)" )
				( attribute "RELATIVE_PROPAGATION_DELAY_SCOPE" "G"
					( Parent
						( matchGroupRef "@crescent_city_bb_fab1_lib.crescent_city_bb_fab1(sch_1):\MG_DDR_FAR_DIMM-CLK0_CLS_DDR_C_CAC-CLKS\" )
					)
					( Status sCSetFlattened )
					( Origin gBackEnd )
				)
				( attribute "RELATIVE_PROPAGATION_DELAY" "0.00 MIL,700.00 MIL"
					( Parent
						( matchGroupRef "@crescent_city_bb_fab1_lib.crescent_city_bb_fab1(sch_1):\MG_DDR_FAR_DIMM-CLK0_CLS_DDR_C_CAC-CLKS\" )
					)
					( Units "uMatchProp" "ns" 1.000000)
					( Status sCSetFlattened )
					( Origin gBackEnd )
				)
				( attribute "RELATIVE_PROPAGATION_DELAY_SCOPE" "G"
					( Parent
						( matchGroupRef "@baseboard_fab2_lib.baseboard_fab2(sch_1):\MG_DDR_FAR_DIMM_CMD_NG_DDR_C_DLL_13\" )
					)
					( Status sCSetFlattened )
					( Origin gBackEnd )
				)
				( attribute "RELATIVE_PROPAGATION_DELAY" "0.00 MIL,25.00 MIL"
					( Parent
						( matchGroupRef "@baseboard_fab2_lib.baseboard_fab2(sch_1):\MG_DDR_FAR_DIMM_CMD_NG_DDR_C_DLL_13\" )
					)
					( Units "uMatchProp" "ns" 1.000000)
					( Status sCSetFlattened )
					( Origin gBackEnd )
				)
			)
			( pinPair "@baseboard_fab2_lib.baseboard_fab2(sch_1):\PP3880\"
				( pinRef "@baseboard_fab2_lib.baseboard_fab2(sch_1):page25_i172:DDR2_BG(0)" )
				( pinRef "@baseboard_fab2_lib.baseboard_fab2(sch_1):page48_i111:BG(0)" )
				( attribute "RELATIVE_PROPAGATION_DELAY_SCOPE" "G"
					( Parent
						( matchGroupRef "@crescent_city_bb_fab1_lib.crescent_city_bb_fab1(sch_1):\MG_DDR_NEAR_DIMM-CLK1_CLS_DDR_C_CAC-CLKS\" )
					)
					( Status sCSetFlattened )
					( Origin gBackEnd )
				)
				( attribute "RELATIVE_PROPAGATION_DELAY" "0.00 MIL,700.00 MIL"
					( Parent
						( matchGroupRef "@crescent_city_bb_fab1_lib.crescent_city_bb_fab1(sch_1):\MG_DDR_NEAR_DIMM-CLK1_CLS_DDR_C_CAC-CLKS\" )
					)
					( Units "uMatchProp" "ns" 1.000000)
					( Status sCSetFlattened )
					( Origin gBackEnd )
				)
				( attribute "RELATIVE_PROPAGATION_DELAY_SCOPE" "G"
					( Parent
						( matchGroupRef "@baseboard_fab2_lib.baseboard_fab2(sch_1):\MG_DDR_CMD_NEAR_DIMM_NG_DDR_C_DLL_13\" )
					)
					( Status sCSetFlattened )
					( Origin gBackEnd )
				)
				( attribute "RELATIVE_PROPAGATION_DELAY" "0.00 MIL,25.00 MIL"
					( Parent
						( matchGroupRef "@baseboard_fab2_lib.baseboard_fab2(sch_1):\MG_DDR_CMD_NEAR_DIMM_NG_DDR_C_DLL_13\" )
					)
					( Units "uMatchProp" "ns" 1.000000)
					( Status sCSetFlattened )
					( Origin gBackEnd )
				)
			)
			( pinPair "@baseboard_fab2_lib.baseboard_fab2(sch_1):\PP3875\"
				( pinRef "@baseboard_fab2_lib.baseboard_fab2(sch_1):page47_i111:S0_N" )
				( pinRef "@baseboard_fab2_lib.baseboard_fab2(sch_1):page25_i172:DDR2_CS_N(0)" )
				( attribute "RELATIVE_PROPAGATION_DELAY_SCOPE" "G"
					( Parent
						( matchGroupRef "@crescent_city_bb_fab1_lib.crescent_city_bb_fab1(sch_1):\MG_DDR_FAR_DIMM-CLK0_CLS_DDR_C_CAC-CLKS\" )
					)
					( Status sCSetFlattened )
					( Origin gBackEnd )
				)
				( attribute "RELATIVE_PROPAGATION_DELAY" "0.00 MIL,300.00 MIL"
					( Parent
						( matchGroupRef "@crescent_city_bb_fab1_lib.crescent_city_bb_fab1(sch_1):\MG_DDR_FAR_DIMM-CLK0_CLS_DDR_C_CAC-CLKS\" )
					)
					( Units "uMatchProp" "ns" 1.000000)
					( Status sCSetFlattened )
					( Origin gBackEnd )
				)
				( attribute "RELATIVE_PROPAGATION_DELAY_SCOPE" "G"
					( Parent
						( matchGroupRef "@baseboard_fab2_lib.baseboard_fab2(sch_1):\MG_DDR_CTRL_NG_DDR_C_DLL_14\" )
					)
					( Status sCSetFlattened )
					( Origin gBackEnd )
				)
				( attribute "RELATIVE_PROPAGATION_DELAY" "0.00 MIL,25.00 MIL"
					( Parent
						( matchGroupRef "@baseboard_fab2_lib.baseboard_fab2(sch_1):\MG_DDR_CTRL_NG_DDR_C_DLL_14\" )
					)
					( Units "uMatchProp" "ns" 1.000000)
					( Status sCSetFlattened )
					( Origin gBackEnd )
				)
			)
			( pinPair "@baseboard_fab2_lib.baseboard_fab2(sch_1):\PP3876\"
				( pinRef "@baseboard_fab2_lib.baseboard_fab2(sch_1):page47_i111:ODT(0)" )
				( pinRef "@baseboard_fab2_lib.baseboard_fab2(sch_1):page25_i172:DDR2_ODT(0)" )
				( attribute "RELATIVE_PROPAGATION_DELAY_SCOPE" "G"
					( Parent
						( matchGroupRef "@crescent_city_bb_fab1_lib.crescent_city_bb_fab1(sch_1):\MG_DDR_FAR_DIMM-CLK0_CLS_DDR_C_CAC-CLKS\" )
					)
					( Status sCSetFlattened )
					( Origin gBackEnd )
				)
				( attribute "RELATIVE_PROPAGATION_DELAY" "0.00 MIL,300.00 MIL"
					( Parent
						( matchGroupRef "@crescent_city_bb_fab1_lib.crescent_city_bb_fab1(sch_1):\MG_DDR_FAR_DIMM-CLK0_CLS_DDR_C_CAC-CLKS\" )
					)
					( Units "uMatchProp" "ns" 1.000000)
					( Status sCSetFlattened )
					( Origin gBackEnd )
				)
				( attribute "RELATIVE_PROPAGATION_DELAY_SCOPE" "G"
					( Parent
						( matchGroupRef "@baseboard_fab2_lib.baseboard_fab2(sch_1):\MG_DDR_CTRL_NG_DDR_C_DLL_14\" )
					)
					( Status sCSetFlattened )
					( Origin gBackEnd )
				)
				( attribute "RELATIVE_PROPAGATION_DELAY" "0.00 MIL,25.00 MIL"
					( Parent
						( matchGroupRef "@baseboard_fab2_lib.baseboard_fab2(sch_1):\MG_DDR_CTRL_NG_DDR_C_DLL_14\" )
					)
					( Units "uMatchProp" "ns" 1.000000)
					( Status sCSetFlattened )
					( Origin gBackEnd )
				)
			)
			( pinPair "@baseboard_fab2_lib.baseboard_fab2(sch_1):\PP3874\"
				( pinRef "@baseboard_fab2_lib.baseboard_fab2(sch_1):page47_i111:CKE(0)" )
				( pinRef "@baseboard_fab2_lib.baseboard_fab2(sch_1):page25_i172:DDR2_CKE(0)" )
				( attribute "RELATIVE_PROPAGATION_DELAY_SCOPE" "G"
					( Parent
						( matchGroupRef "@crescent_city_bb_fab1_lib.crescent_city_bb_fab1(sch_1):\MG_DDR_FAR_DIMM-CLK0_CLS_DDR_C_CAC-CLKS\" )
					)
					( Status sCSetFlattened )
					( Origin gBackEnd )
				)
				( attribute "RELATIVE_PROPAGATION_DELAY" "0.00 MIL,300.00 MIL"
					( Parent
						( matchGroupRef "@crescent_city_bb_fab1_lib.crescent_city_bb_fab1(sch_1):\MG_DDR_FAR_DIMM-CLK0_CLS_DDR_C_CAC-CLKS\" )
					)
					( Units "uMatchProp" "ns" 1.000000)
					( Status sCSetFlattened )
					( Origin gBackEnd )
				)
				( attribute "RELATIVE_PROPAGATION_DELAY_SCOPE" "G"
					( Parent
						( matchGroupRef "@baseboard_fab2_lib.baseboard_fab2(sch_1):\MG_DDR_CTRL_NG_DDR_C_DLL_15\" )
					)
					( Status sCSetFlattened )
					( Origin gBackEnd )
				)
				( attribute "RELATIVE_PROPAGATION_DELAY" "0.00 MIL,25.00 MIL"
					( Parent
						( matchGroupRef "@baseboard_fab2_lib.baseboard_fab2(sch_1):\MG_DDR_CTRL_NG_DDR_C_DLL_15\" )
					)
					( Units "uMatchProp" "ns" 1.000000)
					( Status sCSetFlattened )
					( Origin gBackEnd )
				)
			)
			( pinPair "@baseboard_fab2_lib.baseboard_fab2(sch_1):\PP3873\"
				( pinRef "@baseboard_fab2_lib.baseboard_fab2(sch_1):page25_i172:DDR2_CS_N(2)" )
				( pinRef "@baseboard_fab2_lib.baseboard_fab2(sch_1):page47_i111:S2_N_C(0)" )
				( attribute "RELATIVE_PROPAGATION_DELAY_SCOPE" "G"
					( Parent
						( matchGroupRef "@crescent_city_bb_fab1_lib.crescent_city_bb_fab1(sch_1):\MG_DDR_FAR_DIMM-CLK0_CLS_DDR_C_CAC-CLKS\" )
					)
					( Status sCSetFlattened )
					( Origin gBackEnd )
				)
				( attribute "RELATIVE_PROPAGATION_DELAY" "0.00 MIL,300.00 MIL"
					( Parent
						( matchGroupRef "@crescent_city_bb_fab1_lib.crescent_city_bb_fab1(sch_1):\MG_DDR_FAR_DIMM-CLK0_CLS_DDR_C_CAC-CLKS\" )
					)
					( Units "uMatchProp" "ns" 1.000000)
					( Status sCSetFlattened )
					( Origin gBackEnd )
				)
				( attribute "RELATIVE_PROPAGATION_DELAY_SCOPE" "G"
					( Parent
						( matchGroupRef "@baseboard_fab2_lib.baseboard_fab2(sch_1):\MG_DDR_CTRL_NG_DDR_C_DLL_16\" )
					)
					( Status sCSetFlattened )
					( Origin gBackEnd )
				)
				( attribute "RELATIVE_PROPAGATION_DELAY" "0.00 MIL,25.00 MIL"
					( Parent
						( matchGroupRef "@baseboard_fab2_lib.baseboard_fab2(sch_1):\MG_DDR_CTRL_NG_DDR_C_DLL_16\" )
					)
					( Units "uMatchProp" "ns" 1.000000)
					( Status sCSetFlattened )
					( Origin gBackEnd )
				)
			)
			( pinPair "@baseboard_fab2_lib.baseboard_fab2(sch_1):\PP3872\"
				( pinRef "@baseboard_fab2_lib.baseboard_fab2(sch_1):page47_i111:S3_N_C(1)" )
				( pinRef "@baseboard_fab2_lib.baseboard_fab2(sch_1):page25_i172:DDR2_CS_N(3)" )
				( attribute "RELATIVE_PROPAGATION_DELAY_SCOPE" "G"
					( Parent
						( matchGroupRef "@crescent_city_bb_fab1_lib.crescent_city_bb_fab1(sch_1):\MG_DDR_FAR_DIMM-CLK0_CLS_DDR_C_CAC-CLKS\" )
					)
					( Status sCSetFlattened )
					( Origin gBackEnd )
				)
				( attribute "RELATIVE_PROPAGATION_DELAY" "0.00 MIL,300.00 MIL"
					( Parent
						( matchGroupRef "@crescent_city_bb_fab1_lib.crescent_city_bb_fab1(sch_1):\MG_DDR_FAR_DIMM-CLK0_CLS_DDR_C_CAC-CLKS\" )
					)
					( Units "uMatchProp" "ns" 1.000000)
					( Status sCSetFlattened )
					( Origin gBackEnd )
				)
				( attribute "RELATIVE_PROPAGATION_DELAY_SCOPE" "G"
					( Parent
						( matchGroupRef "@baseboard_fab2_lib.baseboard_fab2(sch_1):\MG_DDR_CTRL_NG_DDR_C_DLL_17\" )
					)
					( Status sCSetFlattened )
					( Origin gBackEnd )
				)
				( attribute "RELATIVE_PROPAGATION_DELAY" "0.00 MIL,25.00 MIL"
					( Parent
						( matchGroupRef "@baseboard_fab2_lib.baseboard_fab2(sch_1):\MG_DDR_CTRL_NG_DDR_C_DLL_17\" )
					)
					( Units "uMatchProp" "ns" 1.000000)
					( Status sCSetFlattened )
					( Origin gBackEnd )
				)
			)
			( pinPair "@baseboard_fab2_lib.baseboard_fab2(sch_1):\PP3870\"
				( pinRef "@baseboard_fab2_lib.baseboard_fab2(sch_1):page25_i172:DDR2_CS_N(1)" )
				( pinRef "@baseboard_fab2_lib.baseboard_fab2(sch_1):page47_i111:S1_N" )
				( attribute "RELATIVE_PROPAGATION_DELAY_SCOPE" "G"
					( Parent
						( matchGroupRef "@crescent_city_bb_fab1_lib.crescent_city_bb_fab1(sch_1):\MG_DDR_FAR_DIMM-CLK0_CLS_DDR_C_CAC-CLKS\" )
					)
					( Status sCSetFlattened )
					( Origin gBackEnd )
				)
				( attribute "RELATIVE_PROPAGATION_DELAY" "0.00 MIL,300.00 MIL"
					( Parent
						( matchGroupRef "@crescent_city_bb_fab1_lib.crescent_city_bb_fab1(sch_1):\MG_DDR_FAR_DIMM-CLK0_CLS_DDR_C_CAC-CLKS\" )
					)
					( Units "uMatchProp" "ns" 1.000000)
					( Status sCSetFlattened )
					( Origin gBackEnd )
				)
				( attribute "RELATIVE_PROPAGATION_DELAY_SCOPE" "G"
					( Parent
						( matchGroupRef "@baseboard_fab2_lib.baseboard_fab2(sch_1):\MG_DDR_CTRL_NG_DDR_C_DLL_18\" )
					)
					( Status sCSetFlattened )
					( Origin gBackEnd )
				)
				( attribute "RELATIVE_PROPAGATION_DELAY" "0.00 MIL,25.00 MIL"
					( Parent
						( matchGroupRef "@baseboard_fab2_lib.baseboard_fab2(sch_1):\MG_DDR_CTRL_NG_DDR_C_DLL_18\" )
					)
					( Units "uMatchProp" "ns" 1.000000)
					( Status sCSetFlattened )
					( Origin gBackEnd )
				)
			)
			( pinPair "@baseboard_fab2_lib.baseboard_fab2(sch_1):\PP3871\"
				( pinRef "@baseboard_fab2_lib.baseboard_fab2(sch_1):page25_i172:DDR2_ODT(1)" )
				( pinRef "@baseboard_fab2_lib.baseboard_fab2(sch_1):page47_i111:ODT(1)" )
				( attribute "RELATIVE_PROPAGATION_DELAY_SCOPE" "G"
					( Parent
						( matchGroupRef "@crescent_city_bb_fab1_lib.crescent_city_bb_fab1(sch_1):\MG_DDR_FAR_DIMM-CLK0_CLS_DDR_C_CAC-CLKS\" )
					)
					( Status sCSetFlattened )
					( Origin gBackEnd )
				)
				( attribute "RELATIVE_PROPAGATION_DELAY" "0.00 MIL,300.00 MIL"
					( Parent
						( matchGroupRef "@crescent_city_bb_fab1_lib.crescent_city_bb_fab1(sch_1):\MG_DDR_FAR_DIMM-CLK0_CLS_DDR_C_CAC-CLKS\" )
					)
					( Units "uMatchProp" "ns" 1.000000)
					( Status sCSetFlattened )
					( Origin gBackEnd )
				)
				( attribute "RELATIVE_PROPAGATION_DELAY_SCOPE" "G"
					( Parent
						( matchGroupRef "@baseboard_fab2_lib.baseboard_fab2(sch_1):\MG_DDR_CTRL_NG_DDR_C_DLL_18\" )
					)
					( Status sCSetFlattened )
					( Origin gBackEnd )
				)
				( attribute "RELATIVE_PROPAGATION_DELAY" "0.00 MIL,25.00 MIL"
					( Parent
						( matchGroupRef "@baseboard_fab2_lib.baseboard_fab2(sch_1):\MG_DDR_CTRL_NG_DDR_C_DLL_18\" )
					)
					( Units "uMatchProp" "ns" 1.000000)
					( Status sCSetFlattened )
					( Origin gBackEnd )
				)
			)
			( pinPair "@baseboard_fab2_lib.baseboard_fab2(sch_1):\PP3869\"
				( pinRef "@baseboard_fab2_lib.baseboard_fab2(sch_1):page47_i111:CKE(1)" )
				( pinRef "@baseboard_fab2_lib.baseboard_fab2(sch_1):page25_i172:DDR2_CKE(1)" )
				( attribute "RELATIVE_PROPAGATION_DELAY_SCOPE" "G"
					( Parent
						( matchGroupRef "@crescent_city_bb_fab1_lib.crescent_city_bb_fab1(sch_1):\MG_DDR_FAR_DIMM-CLK0_CLS_DDR_C_CAC-CLKS\" )
					)
					( Status sCSetFlattened )
					( Origin gBackEnd )
				)
				( attribute "RELATIVE_PROPAGATION_DELAY" "0.00 MIL,300.00 MIL"
					( Parent
						( matchGroupRef "@crescent_city_bb_fab1_lib.crescent_city_bb_fab1(sch_1):\MG_DDR_FAR_DIMM-CLK0_CLS_DDR_C_CAC-CLKS\" )
					)
					( Units "uMatchProp" "ns" 1.000000)
					( Status sCSetFlattened )
					( Origin gBackEnd )
				)
				( attribute "RELATIVE_PROPAGATION_DELAY_SCOPE" "G"
					( Parent
						( matchGroupRef "@baseboard_fab2_lib.baseboard_fab2(sch_1):\MG_DDR_CTRL_NG_DDR_C_DLL_19\" )
					)
					( Status sCSetFlattened )
					( Origin gBackEnd )
				)
				( attribute "RELATIVE_PROPAGATION_DELAY" "0.00 MIL,25.00 MIL"
					( Parent
						( matchGroupRef "@baseboard_fab2_lib.baseboard_fab2(sch_1):\MG_DDR_CTRL_NG_DDR_C_DLL_19\" )
					)
					( Units "uMatchProp" "ns" 1.000000)
					( Status sCSetFlattened )
					( Origin gBackEnd )
				)
			)
			( pinPair "@baseboard_fab2_lib.baseboard_fab2(sch_1):\PP3867\"
				( pinRef "@baseboard_fab2_lib.baseboard_fab2(sch_1):page48_i111:S0_N" )
				( pinRef "@baseboard_fab2_lib.baseboard_fab2(sch_1):page25_i172:DDR2_CS_N(4)" )
				( attribute "RELATIVE_PROPAGATION_DELAY_SCOPE" "G"
					( Parent
						( matchGroupRef "@crescent_city_bb_fab1_lib.crescent_city_bb_fab1(sch_1):\MG_DDR_NEAR_DIMM-CLK1_CLS_DDR_C_CAC-CLKS\" )
					)
					( Status sCSetFlattened )
					( Origin gBackEnd )
				)
				( attribute "RELATIVE_PROPAGATION_DELAY" "0.00 MIL,300.00 MIL"
					( Parent
						( matchGroupRef "@crescent_city_bb_fab1_lib.crescent_city_bb_fab1(sch_1):\MG_DDR_NEAR_DIMM-CLK1_CLS_DDR_C_CAC-CLKS\" )
					)
					( Units "uMatchProp" "ns" 1.000000)
					( Status sCSetFlattened )
					( Origin gBackEnd )
				)
				( attribute "RELATIVE_PROPAGATION_DELAY_SCOPE" "G"
					( Parent
						( matchGroupRef "@baseboard_fab2_lib.baseboard_fab2(sch_1):\MG_DDR_CTRL_NG_DDR_C_DLL_20\" )
					)
					( Status sCSetFlattened )
					( Origin gBackEnd )
				)
				( attribute "RELATIVE_PROPAGATION_DELAY" "0.00 MIL,25.00 MIL"
					( Parent
						( matchGroupRef "@baseboard_fab2_lib.baseboard_fab2(sch_1):\MG_DDR_CTRL_NG_DDR_C_DLL_20\" )
					)
					( Units "uMatchProp" "ns" 1.000000)
					( Status sCSetFlattened )
					( Origin gBackEnd )
				)
			)
			( pinPair "@baseboard_fab2_lib.baseboard_fab2(sch_1):\PP3868\"
				( pinRef "@baseboard_fab2_lib.baseboard_fab2(sch_1):page25_i172:DDR2_ODT(2)" )
				( pinRef "@baseboard_fab2_lib.baseboard_fab2(sch_1):page48_i111:ODT(0)" )
				( attribute "RELATIVE_PROPAGATION_DELAY_SCOPE" "G"
					( Parent
						( matchGroupRef "@crescent_city_bb_fab1_lib.crescent_city_bb_fab1(sch_1):\MG_DDR_NEAR_DIMM-CLK1_CLS_DDR_C_CAC-CLKS\" )
					)
					( Status sCSetFlattened )
					( Origin gBackEnd )
				)
				( attribute "RELATIVE_PROPAGATION_DELAY" "0.00 MIL,300.00 MIL"
					( Parent
						( matchGroupRef "@crescent_city_bb_fab1_lib.crescent_city_bb_fab1(sch_1):\MG_DDR_NEAR_DIMM-CLK1_CLS_DDR_C_CAC-CLKS\" )
					)
					( Units "uMatchProp" "ns" 1.000000)
					( Status sCSetFlattened )
					( Origin gBackEnd )
				)
				( attribute "RELATIVE_PROPAGATION_DELAY_SCOPE" "G"
					( Parent
						( matchGroupRef "@baseboard_fab2_lib.baseboard_fab2(sch_1):\MG_DDR_CTRL_NG_DDR_C_DLL_20\" )
					)
					( Status sCSetFlattened )
					( Origin gBackEnd )
				)
				( attribute "RELATIVE_PROPAGATION_DELAY" "0.00 MIL,25.00 MIL"
					( Parent
						( matchGroupRef "@baseboard_fab2_lib.baseboard_fab2(sch_1):\MG_DDR_CTRL_NG_DDR_C_DLL_20\" )
					)
					( Units "uMatchProp" "ns" 1.000000)
					( Status sCSetFlattened )
					( Origin gBackEnd )
				)
			)
			( pinPair "@baseboard_fab2_lib.baseboard_fab2(sch_1):\PP3866\"
				( pinRef "@baseboard_fab2_lib.baseboard_fab2(sch_1):page48_i111:CKE(0)" )
				( pinRef "@baseboard_fab2_lib.baseboard_fab2(sch_1):page25_i172:DDR2_CKE(2)" )
				( attribute "RELATIVE_PROPAGATION_DELAY_SCOPE" "G"
					( Parent
						( matchGroupRef "@crescent_city_bb_fab1_lib.crescent_city_bb_fab1(sch_1):\MG_DDR_NEAR_DIMM-CLK1_CLS_DDR_C_CAC-CLKS\" )
					)
					( Status sCSetFlattened )
					( Origin gBackEnd )
				)
				( attribute "RELATIVE_PROPAGATION_DELAY" "0.00 MIL,300.00 MIL"
					( Parent
						( matchGroupRef "@crescent_city_bb_fab1_lib.crescent_city_bb_fab1(sch_1):\MG_DDR_NEAR_DIMM-CLK1_CLS_DDR_C_CAC-CLKS\" )
					)
					( Units "uMatchProp" "ns" 1.000000)
					( Status sCSetFlattened )
					( Origin gBackEnd )
				)
				( attribute "RELATIVE_PROPAGATION_DELAY_SCOPE" "G"
					( Parent
						( matchGroupRef "@baseboard_fab2_lib.baseboard_fab2(sch_1):\MG_DDR_CTRL_NG_DDR_C_DLL_21\" )
					)
					( Status sCSetFlattened )
					( Origin gBackEnd )
				)
				( attribute "RELATIVE_PROPAGATION_DELAY" "0.00 MIL,25.00 MIL"
					( Parent
						( matchGroupRef "@baseboard_fab2_lib.baseboard_fab2(sch_1):\MG_DDR_CTRL_NG_DDR_C_DLL_21\" )
					)
					( Units "uMatchProp" "ns" 1.000000)
					( Status sCSetFlattened )
					( Origin gBackEnd )
				)
			)
			( pinPair "@baseboard_fab2_lib.baseboard_fab2(sch_1):\PP3864\"
				( pinRef "@baseboard_fab2_lib.baseboard_fab2(sch_1):page25_i172:DDR2_CS_N(6)" )
				( pinRef "@baseboard_fab2_lib.baseboard_fab2(sch_1):page48_i111:S2_N_C(0)" )
				( attribute "RELATIVE_PROPAGATION_DELAY_SCOPE" "G"
					( Parent
						( matchGroupRef "@crescent_city_bb_fab1_lib.crescent_city_bb_fab1(sch_1):\MG_DDR_NEAR_DIMM-CLK1_CLS_DDR_C_CAC-CLKS\" )
					)
					( Status sCSetFlattened )
					( Origin gBackEnd )
				)
				( attribute "RELATIVE_PROPAGATION_DELAY" "0.00 MIL,300.00 MIL"
					( Parent
						( matchGroupRef "@crescent_city_bb_fab1_lib.crescent_city_bb_fab1(sch_1):\MG_DDR_NEAR_DIMM-CLK1_CLS_DDR_C_CAC-CLKS\" )
					)
					( Units "uMatchProp" "ns" 1.000000)
					( Status sCSetFlattened )
					( Origin gBackEnd )
				)
				( attribute "RELATIVE_PROPAGATION_DELAY_SCOPE" "G"
					( Parent
						( matchGroupRef "@baseboard_fab2_lib.baseboard_fab2(sch_1):\MG_DDR_CTRL_NG_DDR_C_DLL_22\" )
					)
					( Status sCSetFlattened )
					( Origin gBackEnd )
				)
				( attribute "RELATIVE_PROPAGATION_DELAY" "0.00 MIL,25.00 MIL"
					( Parent
						( matchGroupRef "@baseboard_fab2_lib.baseboard_fab2(sch_1):\MG_DDR_CTRL_NG_DDR_C_DLL_22\" )
					)
					( Units "uMatchProp" "ns" 1.000000)
					( Status sCSetFlattened )
					( Origin gBackEnd )
				)
			)
			( pinPair "@baseboard_fab2_lib.baseboard_fab2(sch_1):\PP3865\"
				( pinRef "@baseboard_fab2_lib.baseboard_fab2(sch_1):page25_i172:DDR2_CS_N(7)" )
				( pinRef "@baseboard_fab2_lib.baseboard_fab2(sch_1):page48_i111:S3_N_C(1)" )
				( attribute "RELATIVE_PROPAGATION_DELAY_SCOPE" "G"
					( Parent
						( matchGroupRef "@crescent_city_bb_fab1_lib.crescent_city_bb_fab1(sch_1):\MG_DDR_NEAR_DIMM-CLK1_CLS_DDR_C_CAC-CLKS\" )
					)
					( Status sCSetFlattened )
					( Origin gBackEnd )
				)
				( attribute "RELATIVE_PROPAGATION_DELAY" "0.00 MIL,300.00 MIL"
					( Parent
						( matchGroupRef "@crescent_city_bb_fab1_lib.crescent_city_bb_fab1(sch_1):\MG_DDR_NEAR_DIMM-CLK1_CLS_DDR_C_CAC-CLKS\" )
					)
					( Units "uMatchProp" "ns" 1.000000)
					( Status sCSetFlattened )
					( Origin gBackEnd )
				)
				( attribute "RELATIVE_PROPAGATION_DELAY_SCOPE" "G"
					( Parent
						( matchGroupRef "@baseboard_fab2_lib.baseboard_fab2(sch_1):\MG_DDR_CTRL_NG_DDR_C_DLL_22\" )
					)
					( Status sCSetFlattened )
					( Origin gBackEnd )
				)
				( attribute "RELATIVE_PROPAGATION_DELAY" "0.00 MIL,25.00 MIL"
					( Parent
						( matchGroupRef "@baseboard_fab2_lib.baseboard_fab2(sch_1):\MG_DDR_CTRL_NG_DDR_C_DLL_22\" )
					)
					( Units "uMatchProp" "ns" 1.000000)
					( Status sCSetFlattened )
					( Origin gBackEnd )
				)
			)
			( pinPair "@baseboard_fab2_lib.baseboard_fab2(sch_1):\PP3862\"
				( pinRef "@baseboard_fab2_lib.baseboard_fab2(sch_1):page48_i111:S1_N" )
				( pinRef "@baseboard_fab2_lib.baseboard_fab2(sch_1):page25_i172:DDR2_CS_N(5)" )
				( attribute "RELATIVE_PROPAGATION_DELAY_SCOPE" "G"
					( Parent
						( matchGroupRef "@crescent_city_bb_fab1_lib.crescent_city_bb_fab1(sch_1):\MG_DDR_NEAR_DIMM-CLK1_CLS_DDR_C_CAC-CLKS\" )
					)
					( Status sCSetFlattened )
					( Origin gBackEnd )
				)
				( attribute "RELATIVE_PROPAGATION_DELAY" "0.00 MIL,300.00 MIL"
					( Parent
						( matchGroupRef "@crescent_city_bb_fab1_lib.crescent_city_bb_fab1(sch_1):\MG_DDR_NEAR_DIMM-CLK1_CLS_DDR_C_CAC-CLKS\" )
					)
					( Units "uMatchProp" "ns" 1.000000)
					( Status sCSetFlattened )
					( Origin gBackEnd )
				)
				( attribute "RELATIVE_PROPAGATION_DELAY_SCOPE" "G"
					( Parent
						( matchGroupRef "@baseboard_fab2_lib.baseboard_fab2(sch_1):\MG_DDR_CTRL_NG_DDR_C_DLL_23\" )
					)
					( Status sCSetFlattened )
					( Origin gBackEnd )
				)
				( attribute "RELATIVE_PROPAGATION_DELAY" "0.00 MIL,25.00 MIL"
					( Parent
						( matchGroupRef "@baseboard_fab2_lib.baseboard_fab2(sch_1):\MG_DDR_CTRL_NG_DDR_C_DLL_23\" )
					)
					( Units "uMatchProp" "ns" 1.000000)
					( Status sCSetFlattened )
					( Origin gBackEnd )
				)
			)
			( pinPair "@baseboard_fab2_lib.baseboard_fab2(sch_1):\PP3863\"
				( pinRef "@baseboard_fab2_lib.baseboard_fab2(sch_1):page48_i111:ODT(1)" )
				( pinRef "@baseboard_fab2_lib.baseboard_fab2(sch_1):page25_i172:DDR2_ODT(3)" )
				( attribute "RELATIVE_PROPAGATION_DELAY_SCOPE" "G"
					( Parent
						( matchGroupRef "@crescent_city_bb_fab1_lib.crescent_city_bb_fab1(sch_1):\MG_DDR_NEAR_DIMM-CLK1_CLS_DDR_C_CAC-CLKS\" )
					)
					( Status sCSetFlattened )
					( Origin gBackEnd )
				)
				( attribute "RELATIVE_PROPAGATION_DELAY" "0.00 MIL,300.00 MIL"
					( Parent
						( matchGroupRef "@crescent_city_bb_fab1_lib.crescent_city_bb_fab1(sch_1):\MG_DDR_NEAR_DIMM-CLK1_CLS_DDR_C_CAC-CLKS\" )
					)
					( Units "uMatchProp" "ns" 1.000000)
					( Status sCSetFlattened )
					( Origin gBackEnd )
				)
				( attribute "RELATIVE_PROPAGATION_DELAY_SCOPE" "G"
					( Parent
						( matchGroupRef "@baseboard_fab2_lib.baseboard_fab2(sch_1):\MG_DDR_CTRL_NG_DDR_C_DLL_23\" )
					)
					( Status sCSetFlattened )
					( Origin gBackEnd )
				)
				( attribute "RELATIVE_PROPAGATION_DELAY" "0.00 MIL,25.00 MIL"
					( Parent
						( matchGroupRef "@baseboard_fab2_lib.baseboard_fab2(sch_1):\MG_DDR_CTRL_NG_DDR_C_DLL_23\" )
					)
					( Units "uMatchProp" "ns" 1.000000)
					( Status sCSetFlattened )
					( Origin gBackEnd )
				)
			)
			( pinPair "@baseboard_fab2_lib.baseboard_fab2(sch_1):\PP3861\"
				( pinRef "@baseboard_fab2_lib.baseboard_fab2(sch_1):page48_i111:CKE(1)" )
				( pinRef "@baseboard_fab2_lib.baseboard_fab2(sch_1):page25_i172:DDR2_CKE(3)" )
				( attribute "RELATIVE_PROPAGATION_DELAY_SCOPE" "G"
					( Parent
						( matchGroupRef "@crescent_city_bb_fab1_lib.crescent_city_bb_fab1(sch_1):\MG_DDR_NEAR_DIMM-CLK1_CLS_DDR_C_CAC-CLKS\" )
					)
					( Status sCSetFlattened )
					( Origin gBackEnd )
				)
				( attribute "RELATIVE_PROPAGATION_DELAY" "0.00 MIL,300.00 MIL"
					( Parent
						( matchGroupRef "@crescent_city_bb_fab1_lib.crescent_city_bb_fab1(sch_1):\MG_DDR_NEAR_DIMM-CLK1_CLS_DDR_C_CAC-CLKS\" )
					)
					( Units "uMatchProp" "ns" 1.000000)
					( Status sCSetFlattened )
					( Origin gBackEnd )
				)
				( attribute "RELATIVE_PROPAGATION_DELAY_SCOPE" "G"
					( Parent
						( matchGroupRef "@baseboard_fab2_lib.baseboard_fab2(sch_1):\MG_DDR_CTRL_NG_DDR_C_DLL_24\" )
					)
					( Status sCSetFlattened )
					( Origin gBackEnd )
				)
				( attribute "RELATIVE_PROPAGATION_DELAY" "0.00 MIL,25.00 MIL"
					( Parent
						( matchGroupRef "@baseboard_fab2_lib.baseboard_fab2(sch_1):\MG_DDR_CTRL_NG_DDR_C_DLL_24\" )
					)
					( Units "uMatchProp" "ns" 1.000000)
					( Status sCSetFlattened )
					( Origin gBackEnd )
				)
			)
			( pinPair "@baseboard_fab2_lib.baseboard_fab2(sch_1):\PP3989\"
				( pinRef "@baseboard_fab2_lib.baseboard_fab2(sch_1):page24_i172:DDR1_CID(2)" )
				( pinRef "@baseboard_fab2_lib.baseboard_fab2(sch_1):page45_i111:C(2)" )
				( attribute "RELATIVE_PROPAGATION_DELAY_SCOPE" "G"
					( Parent
						( matchGroupRef "@crescent_city_bb_fab1_lib.crescent_city_bb_fab1(sch_1):\MG_DDR_FAR_DIMM-CLK0_CLS_DDR_B_CAC-CLKS\" )
					)
					( Status sCSetFlattened )
					( Origin gBackEnd )
				)
				( attribute "RELATIVE_PROPAGATION_DELAY" "0.00 MIL,700.00 MIL"
					( Parent
						( matchGroupRef "@crescent_city_bb_fab1_lib.crescent_city_bb_fab1(sch_1):\MG_DDR_FAR_DIMM-CLK0_CLS_DDR_B_CAC-CLKS\" )
					)
					( Units "uMatchProp" "ns" 1.000000)
					( Status sCSetFlattened )
					( Origin gBackEnd )
				)
				( attribute "RELATIVE_PROPAGATION_DELAY_SCOPE" "G"
					( Parent
						( matchGroupRef "@baseboard_fab2_lib.baseboard_fab2(sch_1):\MG_DDR_FAR_DIMM_CMD_NG_DDR_B_DLL_1\" )
					)
					( Status sCSetFlattened )
					( Origin gBackEnd )
				)
				( attribute "RELATIVE_PROPAGATION_DELAY" "0.00 MIL,25.00 MIL"
					( Parent
						( matchGroupRef "@baseboard_fab2_lib.baseboard_fab2(sch_1):\MG_DDR_FAR_DIMM_CMD_NG_DDR_B_DLL_1\" )
					)
					( Units "uMatchProp" "ns" 1.000000)
					( Status sCSetFlattened )
					( Origin gBackEnd )
				)
			)
			( pinPair "@baseboard_fab2_lib.baseboard_fab2(sch_1):\PP3990\"
				( pinRef "@baseboard_fab2_lib.baseboard_fab2(sch_1):page46_i14:C(2)" )
				( pinRef "@baseboard_fab2_lib.baseboard_fab2(sch_1):page24_i172:DDR1_CID(2)" )
				( attribute "RELATIVE_PROPAGATION_DELAY_SCOPE" "G"
					( Parent
						( matchGroupRef "@baseboard_fab2_lib.baseboard_fab2(sch_1):\MG_DDR_CMD_NEAR_DIMM_NG_DDR_B_DLL_1\" )
					)
					( Status sCSetFlattened )
					( Origin gBackEnd )
				)
				( attribute "RELATIVE_PROPAGATION_DELAY" "0.00 MIL,25.00 MIL"
					( Parent
						( matchGroupRef "@baseboard_fab2_lib.baseboard_fab2(sch_1):\MG_DDR_CMD_NEAR_DIMM_NG_DDR_B_DLL_1\" )
					)
					( Units "uMatchProp" "ns" 1.000000)
					( Status sCSetFlattened )
					( Origin gBackEnd )
				)
				( attribute "RELATIVE_PROPAGATION_DELAY_SCOPE" "G"
					( Parent
						( matchGroupRef "@crescent_city_bb_fab1_lib.crescent_city_bb_fab1(sch_1):\MG_DDR_NEAR_DIMM-CLK1_CLS_DDR_B_CAC-CLKS\" )
					)
					( Status sCSetFlattened )
					( Origin gBackEnd )
				)
				( attribute "RELATIVE_PROPAGATION_DELAY" "0.00 MIL,700.00 MIL"
					( Parent
						( matchGroupRef "@crescent_city_bb_fab1_lib.crescent_city_bb_fab1(sch_1):\MG_DDR_NEAR_DIMM-CLK1_CLS_DDR_B_CAC-CLKS\" )
					)
					( Units "uMatchProp" "ns" 1.000000)
					( Status sCSetFlattened )
					( Origin gBackEnd )
				)
			)
			( pinPair "@baseboard_fab2_lib.baseboard_fab2(sch_1):\PP3991\"
				( pinRef "@baseboard_fab2_lib.baseboard_fab2(sch_1):page24_i172:DDR1_MA(17)" )
				( pinRef "@baseboard_fab2_lib.baseboard_fab2(sch_1):page45_i111:A17" )
				( attribute "RELATIVE_PROPAGATION_DELAY_SCOPE" "G"
					( Parent
						( matchGroupRef "@crescent_city_bb_fab1_lib.crescent_city_bb_fab1(sch_1):\MG_DDR_FAR_DIMM-CLK0_CLS_DDR_B_CAC-CLKS\" )
					)
					( Status sCSetFlattened )
					( Origin gBackEnd )
				)
				( attribute "RELATIVE_PROPAGATION_DELAY" "0.00 MIL,700.00 MIL"
					( Parent
						( matchGroupRef "@crescent_city_bb_fab1_lib.crescent_city_bb_fab1(sch_1):\MG_DDR_FAR_DIMM-CLK0_CLS_DDR_B_CAC-CLKS\" )
					)
					( Units "uMatchProp" "ns" 1.000000)
					( Status sCSetFlattened )
					( Origin gBackEnd )
				)
				( attribute "RELATIVE_PROPAGATION_DELAY_SCOPE" "G"
					( Parent
						( matchGroupRef "@baseboard_fab2_lib.baseboard_fab2(sch_1):\MG_DDR_FAR_DIMM_CMD_NG_DDR_B_DLL_1\" )
					)
					( Status sCSetFlattened )
					( Origin gBackEnd )
				)
				( attribute "RELATIVE_PROPAGATION_DELAY" "0.00 MIL,25.00 MIL"
					( Parent
						( matchGroupRef "@baseboard_fab2_lib.baseboard_fab2(sch_1):\MG_DDR_FAR_DIMM_CMD_NG_DDR_B_DLL_1\" )
					)
					( Units "uMatchProp" "ns" 1.000000)
					( Status sCSetFlattened )
					( Origin gBackEnd )
				)
			)
			( pinPair "@baseboard_fab2_lib.baseboard_fab2(sch_1):\PP3992\"
				( pinRef "@baseboard_fab2_lib.baseboard_fab2(sch_1):page46_i14:A17" )
				( pinRef "@baseboard_fab2_lib.baseboard_fab2(sch_1):page24_i172:DDR1_MA(17)" )
				( attribute "RELATIVE_PROPAGATION_DELAY_SCOPE" "G"
					( Parent
						( matchGroupRef "@baseboard_fab2_lib.baseboard_fab2(sch_1):\MG_DDR_CMD_NEAR_DIMM_NG_DDR_B_DLL_1\" )
					)
					( Status sCSetFlattened )
					( Origin gBackEnd )
				)
				( attribute "RELATIVE_PROPAGATION_DELAY" "0.00 MIL,25.00 MIL"
					( Parent
						( matchGroupRef "@baseboard_fab2_lib.baseboard_fab2(sch_1):\MG_DDR_CMD_NEAR_DIMM_NG_DDR_B_DLL_1\" )
					)
					( Units "uMatchProp" "ns" 1.000000)
					( Status sCSetFlattened )
					( Origin gBackEnd )
				)
				( attribute "RELATIVE_PROPAGATION_DELAY_SCOPE" "G"
					( Parent
						( matchGroupRef "@crescent_city_bb_fab1_lib.crescent_city_bb_fab1(sch_1):\MG_DDR_NEAR_DIMM-CLK1_CLS_DDR_B_CAC-CLKS\" )
					)
					( Status sCSetFlattened )
					( Origin gBackEnd )
				)
				( attribute "RELATIVE_PROPAGATION_DELAY" "0.00 MIL,700.00 MIL"
					( Parent
						( matchGroupRef "@crescent_city_bb_fab1_lib.crescent_city_bb_fab1(sch_1):\MG_DDR_NEAR_DIMM-CLK1_CLS_DDR_B_CAC-CLKS\" )
					)
					( Units "uMatchProp" "ns" 1.000000)
					( Status sCSetFlattened )
					( Origin gBackEnd )
				)
			)
			( pinPair "@baseboard_fab2_lib.baseboard_fab2(sch_1):\PP3985\"
				( pinRef "@baseboard_fab2_lib.baseboard_fab2(sch_1):page24_i172:DDR1_MA(13)" )
				( pinRef "@baseboard_fab2_lib.baseboard_fab2(sch_1):page45_i111:A13" )
				( attribute "RELATIVE_PROPAGATION_DELAY_SCOPE" "G"
					( Parent
						( matchGroupRef "@crescent_city_bb_fab1_lib.crescent_city_bb_fab1(sch_1):\MG_DDR_FAR_DIMM-CLK0_CLS_DDR_B_CAC-CLKS\" )
					)
					( Status sCSetFlattened )
					( Origin gBackEnd )
				)
				( attribute "RELATIVE_PROPAGATION_DELAY" "0.00 MIL,700.00 MIL"
					( Parent
						( matchGroupRef "@crescent_city_bb_fab1_lib.crescent_city_bb_fab1(sch_1):\MG_DDR_FAR_DIMM-CLK0_CLS_DDR_B_CAC-CLKS\" )
					)
					( Units "uMatchProp" "ns" 1.000000)
					( Status sCSetFlattened )
					( Origin gBackEnd )
				)
				( attribute "RELATIVE_PROPAGATION_DELAY_SCOPE" "G"
					( Parent
						( matchGroupRef "@baseboard_fab2_lib.baseboard_fab2(sch_1):\MG_DDR_FAR_DIMM_CMD_NG_DDR_B_DLL_2\" )
					)
					( Status sCSetFlattened )
					( Origin gBackEnd )
				)
				( attribute "RELATIVE_PROPAGATION_DELAY" "0.00 MIL,25.00 MIL"
					( Parent
						( matchGroupRef "@baseboard_fab2_lib.baseboard_fab2(sch_1):\MG_DDR_FAR_DIMM_CMD_NG_DDR_B_DLL_2\" )
					)
					( Units "uMatchProp" "ns" 1.000000)
					( Status sCSetFlattened )
					( Origin gBackEnd )
				)
			)
			( pinPair "@baseboard_fab2_lib.baseboard_fab2(sch_1):\PP3986\"
				( pinRef "@baseboard_fab2_lib.baseboard_fab2(sch_1):page46_i14:A13" )
				( pinRef "@baseboard_fab2_lib.baseboard_fab2(sch_1):page24_i172:DDR1_MA(13)" )
				( attribute "RELATIVE_PROPAGATION_DELAY_SCOPE" "G"
					( Parent
						( matchGroupRef "@crescent_city_bb_fab1_lib.crescent_city_bb_fab1(sch_1):\MG_DDR_NEAR_DIMM-CLK1_CLS_DDR_B_CAC-CLKS\" )
					)
					( Status sCSetFlattened )
					( Origin gBackEnd )
				)
				( attribute "RELATIVE_PROPAGATION_DELAY" "0.00 MIL,700.00 MIL"
					( Parent
						( matchGroupRef "@crescent_city_bb_fab1_lib.crescent_city_bb_fab1(sch_1):\MG_DDR_NEAR_DIMM-CLK1_CLS_DDR_B_CAC-CLKS\" )
					)
					( Units "uMatchProp" "ns" 1.000000)
					( Status sCSetFlattened )
					( Origin gBackEnd )
				)
				( attribute "RELATIVE_PROPAGATION_DELAY_SCOPE" "G"
					( Parent
						( matchGroupRef "@baseboard_fab2_lib.baseboard_fab2(sch_1):\MG_DDR_CMD_NEAR_DIMM_NG_DDR_B_DLL_2\" )
					)
					( Status sCSetFlattened )
					( Origin gBackEnd )
				)
				( attribute "RELATIVE_PROPAGATION_DELAY" "0.00 MIL,25.00 MIL"
					( Parent
						( matchGroupRef "@baseboard_fab2_lib.baseboard_fab2(sch_1):\MG_DDR_CMD_NEAR_DIMM_NG_DDR_B_DLL_2\" )
					)
					( Units "uMatchProp" "ns" 1.000000)
					( Status sCSetFlattened )
					( Origin gBackEnd )
				)
			)
			( pinPair "@baseboard_fab2_lib.baseboard_fab2(sch_1):\PP3987\"
				( pinRef "@baseboard_fab2_lib.baseboard_fab2(sch_1):page24_i172:DDR1_MA(15)" )
				( pinRef "@baseboard_fab2_lib.baseboard_fab2(sch_1):page45_i111:A15_CAS_N" )
				( attribute "RELATIVE_PROPAGATION_DELAY_SCOPE" "G"
					( Parent
						( matchGroupRef "@crescent_city_bb_fab1_lib.crescent_city_bb_fab1(sch_1):\MG_DDR_FAR_DIMM-CLK0_CLS_DDR_B_CAC-CLKS\" )
					)
					( Status sCSetFlattened )
					( Origin gBackEnd )
				)
				( attribute "RELATIVE_PROPAGATION_DELAY" "0.00 MIL,700.00 MIL"
					( Parent
						( matchGroupRef "@crescent_city_bb_fab1_lib.crescent_city_bb_fab1(sch_1):\MG_DDR_FAR_DIMM-CLK0_CLS_DDR_B_CAC-CLKS\" )
					)
					( Units "uMatchProp" "ns" 1.000000)
					( Status sCSetFlattened )
					( Origin gBackEnd )
				)
				( attribute "RELATIVE_PROPAGATION_DELAY_SCOPE" "G"
					( Parent
						( matchGroupRef "@baseboard_fab2_lib.baseboard_fab2(sch_1):\MG_DDR_FAR_DIMM_CMD_NG_DDR_B_DLL_2\" )
					)
					( Status sCSetFlattened )
					( Origin gBackEnd )
				)
				( attribute "RELATIVE_PROPAGATION_DELAY" "0.00 MIL,25.00 MIL"
					( Parent
						( matchGroupRef "@baseboard_fab2_lib.baseboard_fab2(sch_1):\MG_DDR_FAR_DIMM_CMD_NG_DDR_B_DLL_2\" )
					)
					( Units "uMatchProp" "ns" 1.000000)
					( Status sCSetFlattened )
					( Origin gBackEnd )
				)
			)
			( pinPair "@baseboard_fab2_lib.baseboard_fab2(sch_1):\PP3988\"
				( pinRef "@baseboard_fab2_lib.baseboard_fab2(sch_1):page46_i14:A15_CAS_N" )
				( pinRef "@baseboard_fab2_lib.baseboard_fab2(sch_1):page24_i172:DDR1_MA(15)" )
				( attribute "RELATIVE_PROPAGATION_DELAY_SCOPE" "G"
					( Parent
						( matchGroupRef "@crescent_city_bb_fab1_lib.crescent_city_bb_fab1(sch_1):\MG_DDR_NEAR_DIMM-CLK1_CLS_DDR_B_CAC-CLKS\" )
					)
					( Status sCSetFlattened )
					( Origin gBackEnd )
				)
				( attribute "RELATIVE_PROPAGATION_DELAY" "0.00 MIL,700.00 MIL"
					( Parent
						( matchGroupRef "@crescent_city_bb_fab1_lib.crescent_city_bb_fab1(sch_1):\MG_DDR_NEAR_DIMM-CLK1_CLS_DDR_B_CAC-CLKS\" )
					)
					( Units "uMatchProp" "ns" 1.000000)
					( Status sCSetFlattened )
					( Origin gBackEnd )
				)
				( attribute "RELATIVE_PROPAGATION_DELAY_SCOPE" "G"
					( Parent
						( matchGroupRef "@baseboard_fab2_lib.baseboard_fab2(sch_1):\MG_DDR_CMD_NEAR_DIMM_NG_DDR_B_DLL_2\" )
					)
					( Status sCSetFlattened )
					( Origin gBackEnd )
				)
				( attribute "RELATIVE_PROPAGATION_DELAY" "0.00 MIL,25.00 MIL"
					( Parent
						( matchGroupRef "@baseboard_fab2_lib.baseboard_fab2(sch_1):\MG_DDR_CMD_NEAR_DIMM_NG_DDR_B_DLL_2\" )
					)
					( Units "uMatchProp" "ns" 1.000000)
					( Status sCSetFlattened )
					( Origin gBackEnd )
				)
			)
			( pinPair "@baseboard_fab2_lib.baseboard_fab2(sch_1):\PP3981\"
				( pinRef "@baseboard_fab2_lib.baseboard_fab2(sch_1):page24_i172:DDR1_MA(14)" )
				( pinRef "@baseboard_fab2_lib.baseboard_fab2(sch_1):page45_i111:A14_WE_N" )
				( attribute "RELATIVE_PROPAGATION_DELAY_SCOPE" "G"
					( Parent
						( matchGroupRef "@crescent_city_bb_fab1_lib.crescent_city_bb_fab1(sch_1):\MG_DDR_FAR_DIMM-CLK0_CLS_DDR_B_CAC-CLKS\" )
					)
					( Status sCSetFlattened )
					( Origin gBackEnd )
				)
				( attribute "RELATIVE_PROPAGATION_DELAY" "0.00 MIL,700.00 MIL"
					( Parent
						( matchGroupRef "@crescent_city_bb_fab1_lib.crescent_city_bb_fab1(sch_1):\MG_DDR_FAR_DIMM-CLK0_CLS_DDR_B_CAC-CLKS\" )
					)
					( Units "uMatchProp" "ns" 1.000000)
					( Status sCSetFlattened )
					( Origin gBackEnd )
				)
				( attribute "RELATIVE_PROPAGATION_DELAY_SCOPE" "G"
					( Parent
						( matchGroupRef "@baseboard_fab2_lib.baseboard_fab2(sch_1):\MG_DDR_FAR_DIMM_CMD_NG_DDR_B_DLL_3\" )
					)
					( Status sCSetFlattened )
					( Origin gBackEnd )
				)
				( attribute "RELATIVE_PROPAGATION_DELAY" "0.00 MIL,25.00 MIL"
					( Parent
						( matchGroupRef "@baseboard_fab2_lib.baseboard_fab2(sch_1):\MG_DDR_FAR_DIMM_CMD_NG_DDR_B_DLL_3\" )
					)
					( Units "uMatchProp" "ns" 1.000000)
					( Status sCSetFlattened )
					( Origin gBackEnd )
				)
			)
			( pinPair "@baseboard_fab2_lib.baseboard_fab2(sch_1):\PP3982\"
				( pinRef "@baseboard_fab2_lib.baseboard_fab2(sch_1):page46_i14:A14_WE_N" )
				( pinRef "@baseboard_fab2_lib.baseboard_fab2(sch_1):page24_i172:DDR1_MA(14)" )
				( attribute "RELATIVE_PROPAGATION_DELAY_SCOPE" "G"
					( Parent
						( matchGroupRef "@crescent_city_bb_fab1_lib.crescent_city_bb_fab1(sch_1):\MG_DDR_NEAR_DIMM-CLK1_CLS_DDR_B_CAC-CLKS\" )
					)
					( Status sCSetFlattened )
					( Origin gBackEnd )
				)
				( attribute "RELATIVE_PROPAGATION_DELAY" "0.00 MIL,700.00 MIL"
					( Parent
						( matchGroupRef "@crescent_city_bb_fab1_lib.crescent_city_bb_fab1(sch_1):\MG_DDR_NEAR_DIMM-CLK1_CLS_DDR_B_CAC-CLKS\" )
					)
					( Units "uMatchProp" "ns" 1.000000)
					( Status sCSetFlattened )
					( Origin gBackEnd )
				)
				( attribute "RELATIVE_PROPAGATION_DELAY_SCOPE" "G"
					( Parent
						( matchGroupRef "@baseboard_fab2_lib.baseboard_fab2(sch_1):\MG_DDR_CMD_NEAR_DIMM_NG_DDR_B_DLL_3\" )
					)
					( Status sCSetFlattened )
					( Origin gBackEnd )
				)
				( attribute "RELATIVE_PROPAGATION_DELAY" "0.00 MIL,25.00 MIL"
					( Parent
						( matchGroupRef "@baseboard_fab2_lib.baseboard_fab2(sch_1):\MG_DDR_CMD_NEAR_DIMM_NG_DDR_B_DLL_3\" )
					)
					( Units "uMatchProp" "ns" 1.000000)
					( Status sCSetFlattened )
					( Origin gBackEnd )
				)
			)
			( pinPair "@baseboard_fab2_lib.baseboard_fab2(sch_1):\PP3983\"
				( pinRef "@baseboard_fab2_lib.baseboard_fab2(sch_1):page24_i172:DDR1_MA(16)" )
				( pinRef "@baseboard_fab2_lib.baseboard_fab2(sch_1):page45_i111:A16_RAS_N" )
				( attribute "RELATIVE_PROPAGATION_DELAY_SCOPE" "G"
					( Parent
						( matchGroupRef "@crescent_city_bb_fab1_lib.crescent_city_bb_fab1(sch_1):\MG_DDR_FAR_DIMM-CLK0_CLS_DDR_B_CAC-CLKS\" )
					)
					( Status sCSetFlattened )
					( Origin gBackEnd )
				)
				( attribute "RELATIVE_PROPAGATION_DELAY" "0.00 MIL,700.00 MIL"
					( Parent
						( matchGroupRef "@crescent_city_bb_fab1_lib.crescent_city_bb_fab1(sch_1):\MG_DDR_FAR_DIMM-CLK0_CLS_DDR_B_CAC-CLKS\" )
					)
					( Units "uMatchProp" "ns" 1.000000)
					( Status sCSetFlattened )
					( Origin gBackEnd )
				)
				( attribute "RELATIVE_PROPAGATION_DELAY_SCOPE" "G"
					( Parent
						( matchGroupRef "@baseboard_fab2_lib.baseboard_fab2(sch_1):\MG_DDR_FAR_DIMM_CMD_NG_DDR_B_DLL_3\" )
					)
					( Status sCSetFlattened )
					( Origin gBackEnd )
				)
				( attribute "RELATIVE_PROPAGATION_DELAY" "0.00 MIL,25.00 MIL"
					( Parent
						( matchGroupRef "@baseboard_fab2_lib.baseboard_fab2(sch_1):\MG_DDR_FAR_DIMM_CMD_NG_DDR_B_DLL_3\" )
					)
					( Units "uMatchProp" "ns" 1.000000)
					( Status sCSetFlattened )
					( Origin gBackEnd )
				)
			)
			( pinPair "@baseboard_fab2_lib.baseboard_fab2(sch_1):\PP3984\"
				( pinRef "@baseboard_fab2_lib.baseboard_fab2(sch_1):page46_i14:A16_RAS_N" )
				( pinRef "@baseboard_fab2_lib.baseboard_fab2(sch_1):page24_i172:DDR1_MA(16)" )
				( attribute "RELATIVE_PROPAGATION_DELAY_SCOPE" "G"
					( Parent
						( matchGroupRef "@crescent_city_bb_fab1_lib.crescent_city_bb_fab1(sch_1):\MG_DDR_NEAR_DIMM-CLK1_CLS_DDR_B_CAC-CLKS\" )
					)
					( Status sCSetFlattened )
					( Origin gBackEnd )
				)
				( attribute "RELATIVE_PROPAGATION_DELAY" "0.00 MIL,700.00 MIL"
					( Parent
						( matchGroupRef "@crescent_city_bb_fab1_lib.crescent_city_bb_fab1(sch_1):\MG_DDR_NEAR_DIMM-CLK1_CLS_DDR_B_CAC-CLKS\" )
					)
					( Units "uMatchProp" "ns" 1.000000)
					( Status sCSetFlattened )
					( Origin gBackEnd )
				)
				( attribute "RELATIVE_PROPAGATION_DELAY_SCOPE" "G"
					( Parent
						( matchGroupRef "@baseboard_fab2_lib.baseboard_fab2(sch_1):\MG_DDR_CMD_NEAR_DIMM_NG_DDR_B_DLL_3\" )
					)
					( Status sCSetFlattened )
					( Origin gBackEnd )
				)
				( attribute "RELATIVE_PROPAGATION_DELAY" "0.00 MIL,25.00 MIL"
					( Parent
						( matchGroupRef "@baseboard_fab2_lib.baseboard_fab2(sch_1):\MG_DDR_CMD_NEAR_DIMM_NG_DDR_B_DLL_3\" )
					)
					( Units "uMatchProp" "ns" 1.000000)
					( Status sCSetFlattened )
					( Origin gBackEnd )
				)
			)
			( pinPair "@baseboard_fab2_lib.baseboard_fab2(sch_1):\PP3977\"
				( pinRef "@baseboard_fab2_lib.baseboard_fab2(sch_1):page24_i172:DDR1_BA(1)" )
				( pinRef "@baseboard_fab2_lib.baseboard_fab2(sch_1):page45_i111:BA(1)" )
				( attribute "RELATIVE_PROPAGATION_DELAY_SCOPE" "G"
					( Parent
						( matchGroupRef "@crescent_city_bb_fab1_lib.crescent_city_bb_fab1(sch_1):\MG_DDR_FAR_DIMM-CLK0_CLS_DDR_B_CAC-CLKS\" )
					)
					( Status sCSetFlattened )
					( Origin gBackEnd )
				)
				( attribute "RELATIVE_PROPAGATION_DELAY" "0.00 MIL,700.00 MIL"
					( Parent
						( matchGroupRef "@crescent_city_bb_fab1_lib.crescent_city_bb_fab1(sch_1):\MG_DDR_FAR_DIMM-CLK0_CLS_DDR_B_CAC-CLKS\" )
					)
					( Units "uMatchProp" "ns" 1.000000)
					( Status sCSetFlattened )
					( Origin gBackEnd )
				)
				( attribute "RELATIVE_PROPAGATION_DELAY_SCOPE" "G"
					( Parent
						( matchGroupRef "@baseboard_fab2_lib.baseboard_fab2(sch_1):\MG_DDR_FAR_DIMM_CMD_NG_DDR_B_DLL_4\" )
					)
					( Status sCSetFlattened )
					( Origin gBackEnd )
				)
				( attribute "RELATIVE_PROPAGATION_DELAY" "0.00 MIL,25.00 MIL"
					( Parent
						( matchGroupRef "@baseboard_fab2_lib.baseboard_fab2(sch_1):\MG_DDR_FAR_DIMM_CMD_NG_DDR_B_DLL_4\" )
					)
					( Units "uMatchProp" "ns" 1.000000)
					( Status sCSetFlattened )
					( Origin gBackEnd )
				)
			)
			( pinPair "@baseboard_fab2_lib.baseboard_fab2(sch_1):\PP3978\"
				( pinRef "@baseboard_fab2_lib.baseboard_fab2(sch_1):page24_i172:DDR1_BA(1)" )
				( pinRef "@baseboard_fab2_lib.baseboard_fab2(sch_1):page46_i14:BA(1)" )
				( attribute "RELATIVE_PROPAGATION_DELAY_SCOPE" "G"
					( Parent
						( matchGroupRef "@crescent_city_bb_fab1_lib.crescent_city_bb_fab1(sch_1):\MG_DDR_NEAR_DIMM-CLK1_CLS_DDR_B_CAC-CLKS\" )
					)
					( Status sCSetFlattened )
					( Origin gBackEnd )
				)
				( attribute "RELATIVE_PROPAGATION_DELAY" "0.00 MIL,700.00 MIL"
					( Parent
						( matchGroupRef "@crescent_city_bb_fab1_lib.crescent_city_bb_fab1(sch_1):\MG_DDR_NEAR_DIMM-CLK1_CLS_DDR_B_CAC-CLKS\" )
					)
					( Units "uMatchProp" "ns" 1.000000)
					( Status sCSetFlattened )
					( Origin gBackEnd )
				)
				( attribute "RELATIVE_PROPAGATION_DELAY_SCOPE" "G"
					( Parent
						( matchGroupRef "@baseboard_fab2_lib.baseboard_fab2(sch_1):\MG_DDR_CMD_NEAR_DIMM_NG_DDR_B_DLL_4\" )
					)
					( Status sCSetFlattened )
					( Origin gBackEnd )
				)
				( attribute "RELATIVE_PROPAGATION_DELAY" "0.00 MIL,25.00 MIL"
					( Parent
						( matchGroupRef "@baseboard_fab2_lib.baseboard_fab2(sch_1):\MG_DDR_CMD_NEAR_DIMM_NG_DDR_B_DLL_4\" )
					)
					( Units "uMatchProp" "ns" 1.000000)
					( Status sCSetFlattened )
					( Origin gBackEnd )
				)
			)
			( pinPair "@baseboard_fab2_lib.baseboard_fab2(sch_1):\PP3979\"
				( pinRef "@baseboard_fab2_lib.baseboard_fab2(sch_1):page24_i172:DDR1_MA(10)" )
				( pinRef "@baseboard_fab2_lib.baseboard_fab2(sch_1):page45_i111:A10" )
				( attribute "RELATIVE_PROPAGATION_DELAY_SCOPE" "G"
					( Parent
						( matchGroupRef "@crescent_city_bb_fab1_lib.crescent_city_bb_fab1(sch_1):\MG_DDR_FAR_DIMM-CLK0_CLS_DDR_B_CAC-CLKS\" )
					)
					( Status sCSetFlattened )
					( Origin gBackEnd )
				)
				( attribute "RELATIVE_PROPAGATION_DELAY" "0.00 MIL,700.00 MIL"
					( Parent
						( matchGroupRef "@crescent_city_bb_fab1_lib.crescent_city_bb_fab1(sch_1):\MG_DDR_FAR_DIMM-CLK0_CLS_DDR_B_CAC-CLKS\" )
					)
					( Units "uMatchProp" "ns" 1.000000)
					( Status sCSetFlattened )
					( Origin gBackEnd )
				)
				( attribute "RELATIVE_PROPAGATION_DELAY_SCOPE" "G"
					( Parent
						( matchGroupRef "@baseboard_fab2_lib.baseboard_fab2(sch_1):\MG_DDR_FAR_DIMM_CMD_NG_DDR_B_DLL_4\" )
					)
					( Status sCSetFlattened )
					( Origin gBackEnd )
				)
				( attribute "RELATIVE_PROPAGATION_DELAY" "0.00 MIL,25.00 MIL"
					( Parent
						( matchGroupRef "@baseboard_fab2_lib.baseboard_fab2(sch_1):\MG_DDR_FAR_DIMM_CMD_NG_DDR_B_DLL_4\" )
					)
					( Units "uMatchProp" "ns" 1.000000)
					( Status sCSetFlattened )
					( Origin gBackEnd )
				)
			)
			( pinPair "@baseboard_fab2_lib.baseboard_fab2(sch_1):\PP3980\"
				( pinRef "@baseboard_fab2_lib.baseboard_fab2(sch_1):page24_i172:DDR1_MA(10)" )
				( pinRef "@baseboard_fab2_lib.baseboard_fab2(sch_1):page46_i14:A10" )
				( attribute "RELATIVE_PROPAGATION_DELAY_SCOPE" "G"
					( Parent
						( matchGroupRef "@crescent_city_bb_fab1_lib.crescent_city_bb_fab1(sch_1):\MG_DDR_NEAR_DIMM-CLK1_CLS_DDR_B_CAC-CLKS\" )
					)
					( Status sCSetFlattened )
					( Origin gBackEnd )
				)
				( attribute "RELATIVE_PROPAGATION_DELAY" "0.00 MIL,700.00 MIL"
					( Parent
						( matchGroupRef "@crescent_city_bb_fab1_lib.crescent_city_bb_fab1(sch_1):\MG_DDR_NEAR_DIMM-CLK1_CLS_DDR_B_CAC-CLKS\" )
					)
					( Units "uMatchProp" "ns" 1.000000)
					( Status sCSetFlattened )
					( Origin gBackEnd )
				)
				( attribute "RELATIVE_PROPAGATION_DELAY_SCOPE" "G"
					( Parent
						( matchGroupRef "@baseboard_fab2_lib.baseboard_fab2(sch_1):\MG_DDR_CMD_NEAR_DIMM_NG_DDR_B_DLL_4\" )
					)
					( Status sCSetFlattened )
					( Origin gBackEnd )
				)
				( attribute "RELATIVE_PROPAGATION_DELAY" "0.00 MIL,25.00 MIL"
					( Parent
						( matchGroupRef "@baseboard_fab2_lib.baseboard_fab2(sch_1):\MG_DDR_CMD_NEAR_DIMM_NG_DDR_B_DLL_4\" )
					)
					( Units "uMatchProp" "ns" 1.000000)
					( Status sCSetFlattened )
					( Origin gBackEnd )
				)
			)
			( pinPair "@baseboard_fab2_lib.baseboard_fab2(sch_1):\PP3973\"
				( pinRef "@baseboard_fab2_lib.baseboard_fab2(sch_1):page24_i172:DDR1_BA(0)" )
				( pinRef "@baseboard_fab2_lib.baseboard_fab2(sch_1):page45_i111:BA(0)" )
				( attribute "RELATIVE_PROPAGATION_DELAY_SCOPE" "G"
					( Parent
						( matchGroupRef "@crescent_city_bb_fab1_lib.crescent_city_bb_fab1(sch_1):\MG_DDR_FAR_DIMM-CLK0_CLS_DDR_B_CAC-CLKS\" )
					)
					( Status sCSetFlattened )
					( Origin gBackEnd )
				)
				( attribute "RELATIVE_PROPAGATION_DELAY" "0.00 MIL,700.00 MIL"
					( Parent
						( matchGroupRef "@crescent_city_bb_fab1_lib.crescent_city_bb_fab1(sch_1):\MG_DDR_FAR_DIMM-CLK0_CLS_DDR_B_CAC-CLKS\" )
					)
					( Units "uMatchProp" "ns" 1.000000)
					( Status sCSetFlattened )
					( Origin gBackEnd )
				)
				( attribute "RELATIVE_PROPAGATION_DELAY_SCOPE" "G"
					( Parent
						( matchGroupRef "@baseboard_fab2_lib.baseboard_fab2(sch_1):\MG_DDR_FAR_DIMM_CMD_NG_DDR_B_DLL_5\" )
					)
					( Status sCSetFlattened )
					( Origin gBackEnd )
				)
				( attribute "RELATIVE_PROPAGATION_DELAY" "0.00 MIL,25.00 MIL"
					( Parent
						( matchGroupRef "@baseboard_fab2_lib.baseboard_fab2(sch_1):\MG_DDR_FAR_DIMM_CMD_NG_DDR_B_DLL_5\" )
					)
					( Units "uMatchProp" "ns" 1.000000)
					( Status sCSetFlattened )
					( Origin gBackEnd )
				)
			)
			( pinPair "@baseboard_fab2_lib.baseboard_fab2(sch_1):\PP3974\"
				( pinRef "@baseboard_fab2_lib.baseboard_fab2(sch_1):page46_i14:BA(0)" )
				( pinRef "@baseboard_fab2_lib.baseboard_fab2(sch_1):page24_i172:DDR1_BA(0)" )
				( attribute "RELATIVE_PROPAGATION_DELAY_SCOPE" "G"
					( Parent
						( matchGroupRef "@crescent_city_bb_fab1_lib.crescent_city_bb_fab1(sch_1):\MG_DDR_NEAR_DIMM-CLK1_CLS_DDR_B_CAC-CLKS\" )
					)
					( Status sCSetFlattened )
					( Origin gBackEnd )
				)
				( attribute "RELATIVE_PROPAGATION_DELAY" "0.00 MIL,700.00 MIL"
					( Parent
						( matchGroupRef "@crescent_city_bb_fab1_lib.crescent_city_bb_fab1(sch_1):\MG_DDR_NEAR_DIMM-CLK1_CLS_DDR_B_CAC-CLKS\" )
					)
					( Units "uMatchProp" "ns" 1.000000)
					( Status sCSetFlattened )
					( Origin gBackEnd )
				)
				( attribute "RELATIVE_PROPAGATION_DELAY_SCOPE" "G"
					( Parent
						( matchGroupRef "@baseboard_fab2_lib.baseboard_fab2(sch_1):\MG_DDR_CMD_NEAR_DIMM_NG_DDR_B_DLL_5\" )
					)
					( Status sCSetFlattened )
					( Origin gBackEnd )
				)
				( attribute "RELATIVE_PROPAGATION_DELAY" "0.00 MIL,25.00 MIL"
					( Parent
						( matchGroupRef "@baseboard_fab2_lib.baseboard_fab2(sch_1):\MG_DDR_CMD_NEAR_DIMM_NG_DDR_B_DLL_5\" )
					)
					( Units "uMatchProp" "ns" 1.000000)
					( Status sCSetFlattened )
					( Origin gBackEnd )
				)
			)
			( pinPair "@baseboard_fab2_lib.baseboard_fab2(sch_1):\PP3975\"
				( pinRef "@baseboard_fab2_lib.baseboard_fab2(sch_1):page24_i172:DDR1_MA(0)" )
				( pinRef "@baseboard_fab2_lib.baseboard_fab2(sch_1):page45_i111:A0" )
				( attribute "RELATIVE_PROPAGATION_DELAY_SCOPE" "G"
					( Parent
						( matchGroupRef "@crescent_city_bb_fab1_lib.crescent_city_bb_fab1(sch_1):\MG_DDR_FAR_DIMM-CLK0_CLS_DDR_B_CAC-CLKS\" )
					)
					( Status sCSetFlattened )
					( Origin gBackEnd )
				)
				( attribute "RELATIVE_PROPAGATION_DELAY" "0.00 MIL,700.00 MIL"
					( Parent
						( matchGroupRef "@crescent_city_bb_fab1_lib.crescent_city_bb_fab1(sch_1):\MG_DDR_FAR_DIMM-CLK0_CLS_DDR_B_CAC-CLKS\" )
					)
					( Units "uMatchProp" "ns" 1.000000)
					( Status sCSetFlattened )
					( Origin gBackEnd )
				)
				( attribute "RELATIVE_PROPAGATION_DELAY_SCOPE" "G"
					( Parent
						( matchGroupRef "@baseboard_fab2_lib.baseboard_fab2(sch_1):\MG_DDR_FAR_DIMM_CMD_NG_DDR_B_DLL_5\" )
					)
					( Status sCSetFlattened )
					( Origin gBackEnd )
				)
				( attribute "RELATIVE_PROPAGATION_DELAY" "0.00 MIL,25.00 MIL"
					( Parent
						( matchGroupRef "@baseboard_fab2_lib.baseboard_fab2(sch_1):\MG_DDR_FAR_DIMM_CMD_NG_DDR_B_DLL_5\" )
					)
					( Units "uMatchProp" "ns" 1.000000)
					( Status sCSetFlattened )
					( Origin gBackEnd )
				)
			)
			( pinPair "@baseboard_fab2_lib.baseboard_fab2(sch_1):\PP3976\"
				( pinRef "@baseboard_fab2_lib.baseboard_fab2(sch_1):page46_i14:A0" )
				( pinRef "@baseboard_fab2_lib.baseboard_fab2(sch_1):page24_i172:DDR1_MA(0)" )
				( attribute "RELATIVE_PROPAGATION_DELAY_SCOPE" "G"
					( Parent
						( matchGroupRef "@crescent_city_bb_fab1_lib.crescent_city_bb_fab1(sch_1):\MG_DDR_NEAR_DIMM-CLK1_CLS_DDR_B_CAC-CLKS\" )
					)
					( Status sCSetFlattened )
					( Origin gBackEnd )
				)
				( attribute "RELATIVE_PROPAGATION_DELAY" "0.00 MIL,700.00 MIL"
					( Parent
						( matchGroupRef "@crescent_city_bb_fab1_lib.crescent_city_bb_fab1(sch_1):\MG_DDR_NEAR_DIMM-CLK1_CLS_DDR_B_CAC-CLKS\" )
					)
					( Units "uMatchProp" "ns" 1.000000)
					( Status sCSetFlattened )
					( Origin gBackEnd )
				)
				( attribute "RELATIVE_PROPAGATION_DELAY_SCOPE" "G"
					( Parent
						( matchGroupRef "@baseboard_fab2_lib.baseboard_fab2(sch_1):\MG_DDR_CMD_NEAR_DIMM_NG_DDR_B_DLL_5\" )
					)
					( Status sCSetFlattened )
					( Origin gBackEnd )
				)
				( attribute "RELATIVE_PROPAGATION_DELAY" "0.00 MIL,25.00 MIL"
					( Parent
						( matchGroupRef "@baseboard_fab2_lib.baseboard_fab2(sch_1):\MG_DDR_CMD_NEAR_DIMM_NG_DDR_B_DLL_5\" )
					)
					( Units "uMatchProp" "ns" 1.000000)
					( Status sCSetFlattened )
					( Origin gBackEnd )
				)
			)
			( pinPair "@baseboard_fab2_lib.baseboard_fab2(sch_1):\PP3971\"
				( pinRef "@baseboard_fab2_lib.baseboard_fab2(sch_1):page24_i172:DDR1_PAR" )
				( pinRef "@baseboard_fab2_lib.baseboard_fab2(sch_1):page45_i111:PAR" )
				( attribute "RELATIVE_PROPAGATION_DELAY_SCOPE" "G"
					( Parent
						( matchGroupRef "@crescent_city_bb_fab1_lib.crescent_city_bb_fab1(sch_1):\MG_DDR_FAR_DIMM-CLK0_CLS_DDR_B_CAC-CLKS\" )
					)
					( Status sCSetFlattened )
					( Origin gBackEnd )
				)
				( attribute "RELATIVE_PROPAGATION_DELAY" "0.00 MIL,700.00 MIL"
					( Parent
						( matchGroupRef "@crescent_city_bb_fab1_lib.crescent_city_bb_fab1(sch_1):\MG_DDR_FAR_DIMM-CLK0_CLS_DDR_B_CAC-CLKS\" )
					)
					( Units "uMatchProp" "ns" 1.000000)
					( Status sCSetFlattened )
					( Origin gBackEnd )
				)
				( attribute "RELATIVE_PROPAGATION_DELAY_SCOPE" "G"
					( Parent
						( matchGroupRef "@baseboard_fab2_lib.baseboard_fab2(sch_1):\MG_DDR_FAR_DIMM_CMD_NG_DDR_B_DLL_6\" )
					)
					( Status sCSetFlattened )
					( Origin gBackEnd )
				)
				( attribute "RELATIVE_PROPAGATION_DELAY" "0.00 MIL,25.00 MIL"
					( Parent
						( matchGroupRef "@baseboard_fab2_lib.baseboard_fab2(sch_1):\MG_DDR_FAR_DIMM_CMD_NG_DDR_B_DLL_6\" )
					)
					( Units "uMatchProp" "ns" 1.000000)
					( Status sCSetFlattened )
					( Origin gBackEnd )
				)
			)
			( pinPair "@baseboard_fab2_lib.baseboard_fab2(sch_1):\PP3972\"
				( pinRef "@baseboard_fab2_lib.baseboard_fab2(sch_1):page46_i14:PAR" )
				( pinRef "@baseboard_fab2_lib.baseboard_fab2(sch_1):page24_i172:DDR1_PAR" )
				( attribute "RELATIVE_PROPAGATION_DELAY_SCOPE" "G"
					( Parent
						( matchGroupRef "@crescent_city_bb_fab1_lib.crescent_city_bb_fab1(sch_1):\MG_DDR_NEAR_DIMM-CLK1_CLS_DDR_B_CAC-CLKS\" )
					)
					( Status sCSetFlattened )
					( Origin gBackEnd )
				)
				( attribute "RELATIVE_PROPAGATION_DELAY" "0.00 MIL,700.00 MIL"
					( Parent
						( matchGroupRef "@crescent_city_bb_fab1_lib.crescent_city_bb_fab1(sch_1):\MG_DDR_NEAR_DIMM-CLK1_CLS_DDR_B_CAC-CLKS\" )
					)
					( Units "uMatchProp" "ns" 1.000000)
					( Status sCSetFlattened )
					( Origin gBackEnd )
				)
				( attribute "RELATIVE_PROPAGATION_DELAY_SCOPE" "G"
					( Parent
						( matchGroupRef "@baseboard_fab2_lib.baseboard_fab2(sch_1):\MG_DDR_CMD_NEAR_DIMM_NG_DDR_B_DLL_6\" )
					)
					( Status sCSetFlattened )
					( Origin gBackEnd )
				)
				( attribute "RELATIVE_PROPAGATION_DELAY" "0.00 MIL,25.00 MIL"
					( Parent
						( matchGroupRef "@baseboard_fab2_lib.baseboard_fab2(sch_1):\MG_DDR_CMD_NEAR_DIMM_NG_DDR_B_DLL_6\" )
					)
					( Units "uMatchProp" "ns" 1.000000)
					( Status sCSetFlattened )
					( Origin gBackEnd )
				)
			)
			( pinPair "@baseboard_fab2_lib.baseboard_fab2(sch_1):\PP3967\"
				( pinRef "@baseboard_fab2_lib.baseboard_fab2(sch_1):page24_i172:DDR1_MA(1)" )
				( pinRef "@baseboard_fab2_lib.baseboard_fab2(sch_1):page45_i111:A1" )
				( attribute "RELATIVE_PROPAGATION_DELAY_SCOPE" "G"
					( Parent
						( matchGroupRef "@crescent_city_bb_fab1_lib.crescent_city_bb_fab1(sch_1):\MG_DDR_FAR_DIMM-CLK0_CLS_DDR_B_CAC-CLKS\" )
					)
					( Status sCSetFlattened )
					( Origin gBackEnd )
				)
				( attribute "RELATIVE_PROPAGATION_DELAY" "0.00 MIL,700.00 MIL"
					( Parent
						( matchGroupRef "@crescent_city_bb_fab1_lib.crescent_city_bb_fab1(sch_1):\MG_DDR_FAR_DIMM-CLK0_CLS_DDR_B_CAC-CLKS\" )
					)
					( Units "uMatchProp" "ns" 1.000000)
					( Status sCSetFlattened )
					( Origin gBackEnd )
				)
				( attribute "RELATIVE_PROPAGATION_DELAY_SCOPE" "G"
					( Parent
						( matchGroupRef "@baseboard_fab2_lib.baseboard_fab2(sch_1):\MG_DDR_FAR_DIMM_CMD_NG_DDR_B_DLL_7\" )
					)
					( Status sCSetFlattened )
					( Origin gBackEnd )
				)
				( attribute "RELATIVE_PROPAGATION_DELAY" "0.00 MIL,25.00 MIL"
					( Parent
						( matchGroupRef "@baseboard_fab2_lib.baseboard_fab2(sch_1):\MG_DDR_FAR_DIMM_CMD_NG_DDR_B_DLL_7\" )
					)
					( Units "uMatchProp" "ns" 1.000000)
					( Status sCSetFlattened )
					( Origin gBackEnd )
				)
			)
			( pinPair "@baseboard_fab2_lib.baseboard_fab2(sch_1):\PP3968\"
				( pinRef "@baseboard_fab2_lib.baseboard_fab2(sch_1):page46_i14:A1" )
				( pinRef "@baseboard_fab2_lib.baseboard_fab2(sch_1):page24_i172:DDR1_MA(1)" )
				( attribute "RELATIVE_PROPAGATION_DELAY_SCOPE" "G"
					( Parent
						( matchGroupRef "@crescent_city_bb_fab1_lib.crescent_city_bb_fab1(sch_1):\MG_DDR_NEAR_DIMM-CLK1_CLS_DDR_B_CAC-CLKS\" )
					)
					( Status sCSetFlattened )
					( Origin gBackEnd )
				)
				( attribute "RELATIVE_PROPAGATION_DELAY" "0.00 MIL,700.00 MIL"
					( Parent
						( matchGroupRef "@crescent_city_bb_fab1_lib.crescent_city_bb_fab1(sch_1):\MG_DDR_NEAR_DIMM-CLK1_CLS_DDR_B_CAC-CLKS\" )
					)
					( Units "uMatchProp" "ns" 1.000000)
					( Status sCSetFlattened )
					( Origin gBackEnd )
				)
				( attribute "RELATIVE_PROPAGATION_DELAY_SCOPE" "G"
					( Parent
						( matchGroupRef "@baseboard_fab2_lib.baseboard_fab2(sch_1):\MG_DDR_CMD_NEAR_DIMM_NG_DDR_B_DLL_7\" )
					)
					( Status sCSetFlattened )
					( Origin gBackEnd )
				)
				( attribute "RELATIVE_PROPAGATION_DELAY" "0.00 MIL,25.00 MIL"
					( Parent
						( matchGroupRef "@baseboard_fab2_lib.baseboard_fab2(sch_1):\MG_DDR_CMD_NEAR_DIMM_NG_DDR_B_DLL_7\" )
					)
					( Units "uMatchProp" "ns" 1.000000)
					( Status sCSetFlattened )
					( Origin gBackEnd )
				)
			)
			( pinPair "@baseboard_fab2_lib.baseboard_fab2(sch_1):\PP3969\"
				( pinRef "@baseboard_fab2_lib.baseboard_fab2(sch_1):page24_i172:DDR1_MA(3)" )
				( pinRef "@baseboard_fab2_lib.baseboard_fab2(sch_1):page45_i111:A3" )
				( attribute "RELATIVE_PROPAGATION_DELAY_SCOPE" "G"
					( Parent
						( matchGroupRef "@crescent_city_bb_fab1_lib.crescent_city_bb_fab1(sch_1):\MG_DDR_FAR_DIMM-CLK0_CLS_DDR_B_CAC-CLKS\" )
					)
					( Status sCSetFlattened )
					( Origin gBackEnd )
				)
				( attribute "RELATIVE_PROPAGATION_DELAY" "0.00 MIL,700.00 MIL"
					( Parent
						( matchGroupRef "@crescent_city_bb_fab1_lib.crescent_city_bb_fab1(sch_1):\MG_DDR_FAR_DIMM-CLK0_CLS_DDR_B_CAC-CLKS\" )
					)
					( Units "uMatchProp" "ns" 1.000000)
					( Status sCSetFlattened )
					( Origin gBackEnd )
				)
				( attribute "RELATIVE_PROPAGATION_DELAY_SCOPE" "G"
					( Parent
						( matchGroupRef "@baseboard_fab2_lib.baseboard_fab2(sch_1):\MG_DDR_FAR_DIMM_CMD_NG_DDR_B_DLL_7\" )
					)
					( Status sCSetFlattened )
					( Origin gBackEnd )
				)
				( attribute "RELATIVE_PROPAGATION_DELAY" "0.00 MIL,25.00 MIL"
					( Parent
						( matchGroupRef "@baseboard_fab2_lib.baseboard_fab2(sch_1):\MG_DDR_FAR_DIMM_CMD_NG_DDR_B_DLL_7\" )
					)
					( Units "uMatchProp" "ns" 1.000000)
					( Status sCSetFlattened )
					( Origin gBackEnd )
				)
			)
			( pinPair "@baseboard_fab2_lib.baseboard_fab2(sch_1):\PP3970\"
				( pinRef "@baseboard_fab2_lib.baseboard_fab2(sch_1):page46_i14:A3" )
				( pinRef "@baseboard_fab2_lib.baseboard_fab2(sch_1):page24_i172:DDR1_MA(3)" )
				( attribute "RELATIVE_PROPAGATION_DELAY_SCOPE" "G"
					( Parent
						( matchGroupRef "@crescent_city_bb_fab1_lib.crescent_city_bb_fab1(sch_1):\MG_DDR_NEAR_DIMM-CLK1_CLS_DDR_B_CAC-CLKS\" )
					)
					( Status sCSetFlattened )
					( Origin gBackEnd )
				)
				( attribute "RELATIVE_PROPAGATION_DELAY" "0.00 MIL,700.00 MIL"
					( Parent
						( matchGroupRef "@crescent_city_bb_fab1_lib.crescent_city_bb_fab1(sch_1):\MG_DDR_NEAR_DIMM-CLK1_CLS_DDR_B_CAC-CLKS\" )
					)
					( Units "uMatchProp" "ns" 1.000000)
					( Status sCSetFlattened )
					( Origin gBackEnd )
				)
				( attribute "RELATIVE_PROPAGATION_DELAY_SCOPE" "G"
					( Parent
						( matchGroupRef "@baseboard_fab2_lib.baseboard_fab2(sch_1):\MG_DDR_CMD_NEAR_DIMM_NG_DDR_B_DLL_7\" )
					)
					( Status sCSetFlattened )
					( Origin gBackEnd )
				)
				( attribute "RELATIVE_PROPAGATION_DELAY" "0.00 MIL,25.00 MIL"
					( Parent
						( matchGroupRef "@baseboard_fab2_lib.baseboard_fab2(sch_1):\MG_DDR_CMD_NEAR_DIMM_NG_DDR_B_DLL_7\" )
					)
					( Units "uMatchProp" "ns" 1.000000)
					( Status sCSetFlattened )
					( Origin gBackEnd )
				)
			)
			( pinPair "@baseboard_fab2_lib.baseboard_fab2(sch_1):\PP3963\"
				( pinRef "@baseboard_fab2_lib.baseboard_fab2(sch_1):page24_i172:DDR1_MA(2)" )
				( pinRef "@baseboard_fab2_lib.baseboard_fab2(sch_1):page45_i111:A2" )
				( attribute "RELATIVE_PROPAGATION_DELAY_SCOPE" "G"
					( Parent
						( matchGroupRef "@crescent_city_bb_fab1_lib.crescent_city_bb_fab1(sch_1):\MG_DDR_FAR_DIMM-CLK0_CLS_DDR_B_CAC-CLKS\" )
					)
					( Status sCSetFlattened )
					( Origin gBackEnd )
				)
				( attribute "RELATIVE_PROPAGATION_DELAY" "0.00 MIL,700.00 MIL"
					( Parent
						( matchGroupRef "@crescent_city_bb_fab1_lib.crescent_city_bb_fab1(sch_1):\MG_DDR_FAR_DIMM-CLK0_CLS_DDR_B_CAC-CLKS\" )
					)
					( Units "uMatchProp" "ns" 1.000000)
					( Status sCSetFlattened )
					( Origin gBackEnd )
				)
				( attribute "RELATIVE_PROPAGATION_DELAY_SCOPE" "G"
					( Parent
						( matchGroupRef "@baseboard_fab2_lib.baseboard_fab2(sch_1):\MG_DDR_FAR_DIMM_CMD_NG_DDR_B_DLL_8\" )
					)
					( Status sCSetFlattened )
					( Origin gBackEnd )
				)
				( attribute "RELATIVE_PROPAGATION_DELAY" "0.00 MIL,25.00 MIL"
					( Parent
						( matchGroupRef "@baseboard_fab2_lib.baseboard_fab2(sch_1):\MG_DDR_FAR_DIMM_CMD_NG_DDR_B_DLL_8\" )
					)
					( Units "uMatchProp" "ns" 1.000000)
					( Status sCSetFlattened )
					( Origin gBackEnd )
				)
			)
			( pinPair "@baseboard_fab2_lib.baseboard_fab2(sch_1):\PP3964\"
				( pinRef "@baseboard_fab2_lib.baseboard_fab2(sch_1):page46_i14:A2" )
				( pinRef "@baseboard_fab2_lib.baseboard_fab2(sch_1):page24_i172:DDR1_MA(2)" )
				( attribute "RELATIVE_PROPAGATION_DELAY_SCOPE" "G"
					( Parent
						( matchGroupRef "@crescent_city_bb_fab1_lib.crescent_city_bb_fab1(sch_1):\MG_DDR_NEAR_DIMM-CLK1_CLS_DDR_B_CAC-CLKS\" )
					)
					( Status sCSetFlattened )
					( Origin gBackEnd )
				)
				( attribute "RELATIVE_PROPAGATION_DELAY" "0.00 MIL,700.00 MIL"
					( Parent
						( matchGroupRef "@crescent_city_bb_fab1_lib.crescent_city_bb_fab1(sch_1):\MG_DDR_NEAR_DIMM-CLK1_CLS_DDR_B_CAC-CLKS\" )
					)
					( Units "uMatchProp" "ns" 1.000000)
					( Status sCSetFlattened )
					( Origin gBackEnd )
				)
				( attribute "RELATIVE_PROPAGATION_DELAY_SCOPE" "G"
					( Parent
						( matchGroupRef "@baseboard_fab2_lib.baseboard_fab2(sch_1):\MG_DDR_CMD_NEAR_DIMM_NG_DDR_B_DLL_8\" )
					)
					( Status sCSetFlattened )
					( Origin gBackEnd )
				)
				( attribute "RELATIVE_PROPAGATION_DELAY" "0.00 MIL,25.00 MIL"
					( Parent
						( matchGroupRef "@baseboard_fab2_lib.baseboard_fab2(sch_1):\MG_DDR_CMD_NEAR_DIMM_NG_DDR_B_DLL_8\" )
					)
					( Units "uMatchProp" "ns" 1.000000)
					( Status sCSetFlattened )
					( Origin gBackEnd )
				)
			)
			( pinPair "@baseboard_fab2_lib.baseboard_fab2(sch_1):\PP3965\"
				( pinRef "@baseboard_fab2_lib.baseboard_fab2(sch_1):page24_i172:DDR1_MA(4)" )
				( pinRef "@baseboard_fab2_lib.baseboard_fab2(sch_1):page45_i111:A4" )
				( attribute "RELATIVE_PROPAGATION_DELAY_SCOPE" "G"
					( Parent
						( matchGroupRef "@crescent_city_bb_fab1_lib.crescent_city_bb_fab1(sch_1):\MG_DDR_FAR_DIMM-CLK0_CLS_DDR_B_CAC-CLKS\" )
					)
					( Status sCSetFlattened )
					( Origin gBackEnd )
				)
				( attribute "RELATIVE_PROPAGATION_DELAY" "0.00 MIL,700.00 MIL"
					( Parent
						( matchGroupRef "@crescent_city_bb_fab1_lib.crescent_city_bb_fab1(sch_1):\MG_DDR_FAR_DIMM-CLK0_CLS_DDR_B_CAC-CLKS\" )
					)
					( Units "uMatchProp" "ns" 1.000000)
					( Status sCSetFlattened )
					( Origin gBackEnd )
				)
				( attribute "RELATIVE_PROPAGATION_DELAY_SCOPE" "G"
					( Parent
						( matchGroupRef "@baseboard_fab2_lib.baseboard_fab2(sch_1):\MG_DDR_FAR_DIMM_CMD_NG_DDR_B_DLL_8\" )
					)
					( Status sCSetFlattened )
					( Origin gBackEnd )
				)
				( attribute "RELATIVE_PROPAGATION_DELAY" "0.00 MIL,25.00 MIL"
					( Parent
						( matchGroupRef "@baseboard_fab2_lib.baseboard_fab2(sch_1):\MG_DDR_FAR_DIMM_CMD_NG_DDR_B_DLL_8\" )
					)
					( Units "uMatchProp" "ns" 1.000000)
					( Status sCSetFlattened )
					( Origin gBackEnd )
				)
			)
			( pinPair "@baseboard_fab2_lib.baseboard_fab2(sch_1):\PP3966\"
				( pinRef "@baseboard_fab2_lib.baseboard_fab2(sch_1):page46_i14:A4" )
				( pinRef "@baseboard_fab2_lib.baseboard_fab2(sch_1):page24_i172:DDR1_MA(4)" )
				( attribute "RELATIVE_PROPAGATION_DELAY_SCOPE" "G"
					( Parent
						( matchGroupRef "@crescent_city_bb_fab1_lib.crescent_city_bb_fab1(sch_1):\MG_DDR_NEAR_DIMM-CLK1_CLS_DDR_B_CAC-CLKS\" )
					)
					( Status sCSetFlattened )
					( Origin gBackEnd )
				)
				( attribute "RELATIVE_PROPAGATION_DELAY" "0.00 MIL,700.00 MIL"
					( Parent
						( matchGroupRef "@crescent_city_bb_fab1_lib.crescent_city_bb_fab1(sch_1):\MG_DDR_NEAR_DIMM-CLK1_CLS_DDR_B_CAC-CLKS\" )
					)
					( Units "uMatchProp" "ns" 1.000000)
					( Status sCSetFlattened )
					( Origin gBackEnd )
				)
				( attribute "RELATIVE_PROPAGATION_DELAY_SCOPE" "G"
					( Parent
						( matchGroupRef "@baseboard_fab2_lib.baseboard_fab2(sch_1):\MG_DDR_CMD_NEAR_DIMM_NG_DDR_B_DLL_8\" )
					)
					( Status sCSetFlattened )
					( Origin gBackEnd )
				)
				( attribute "RELATIVE_PROPAGATION_DELAY" "0.00 MIL,25.00 MIL"
					( Parent
						( matchGroupRef "@baseboard_fab2_lib.baseboard_fab2(sch_1):\MG_DDR_CMD_NEAR_DIMM_NG_DDR_B_DLL_8\" )
					)
					( Units "uMatchProp" "ns" 1.000000)
					( Status sCSetFlattened )
					( Origin gBackEnd )
				)
			)
			( pinPair "@baseboard_fab2_lib.baseboard_fab2(sch_1):\PP3959\"
				( pinRef "@baseboard_fab2_lib.baseboard_fab2(sch_1):page24_i172:DDR1_MA(5)" )
				( pinRef "@baseboard_fab2_lib.baseboard_fab2(sch_1):page45_i111:A5" )
				( attribute "RELATIVE_PROPAGATION_DELAY_SCOPE" "G"
					( Parent
						( matchGroupRef "@crescent_city_bb_fab1_lib.crescent_city_bb_fab1(sch_1):\MG_DDR_FAR_DIMM-CLK0_CLS_DDR_B_CAC-CLKS\" )
					)
					( Status sCSetFlattened )
					( Origin gBackEnd )
				)
				( attribute "RELATIVE_PROPAGATION_DELAY" "0.00 MIL,700.00 MIL"
					( Parent
						( matchGroupRef "@crescent_city_bb_fab1_lib.crescent_city_bb_fab1(sch_1):\MG_DDR_FAR_DIMM-CLK0_CLS_DDR_B_CAC-CLKS\" )
					)
					( Units "uMatchProp" "ns" 1.000000)
					( Status sCSetFlattened )
					( Origin gBackEnd )
				)
				( attribute "RELATIVE_PROPAGATION_DELAY_SCOPE" "G"
					( Parent
						( matchGroupRef "@baseboard_fab2_lib.baseboard_fab2(sch_1):\MG_DDR_FAR_DIMM_CMD_NG_DDR_B_DLL_9\" )
					)
					( Status sCSetFlattened )
					( Origin gBackEnd )
				)
				( attribute "RELATIVE_PROPAGATION_DELAY" "0.00 MIL,25.00 MIL"
					( Parent
						( matchGroupRef "@baseboard_fab2_lib.baseboard_fab2(sch_1):\MG_DDR_FAR_DIMM_CMD_NG_DDR_B_DLL_9\" )
					)
					( Units "uMatchProp" "ns" 1.000000)
					( Status sCSetFlattened )
					( Origin gBackEnd )
				)
			)
			( pinPair "@baseboard_fab2_lib.baseboard_fab2(sch_1):\PP3960\"
				( pinRef "@baseboard_fab2_lib.baseboard_fab2(sch_1):page46_i14:A5" )
				( pinRef "@baseboard_fab2_lib.baseboard_fab2(sch_1):page24_i172:DDR1_MA(5)" )
				( attribute "RELATIVE_PROPAGATION_DELAY_SCOPE" "G"
					( Parent
						( matchGroupRef "@crescent_city_bb_fab1_lib.crescent_city_bb_fab1(sch_1):\MG_DDR_NEAR_DIMM-CLK1_CLS_DDR_B_CAC-CLKS\" )
					)
					( Status sCSetFlattened )
					( Origin gBackEnd )
				)
				( attribute "RELATIVE_PROPAGATION_DELAY" "0.00 MIL,700.00 MIL"
					( Parent
						( matchGroupRef "@crescent_city_bb_fab1_lib.crescent_city_bb_fab1(sch_1):\MG_DDR_NEAR_DIMM-CLK1_CLS_DDR_B_CAC-CLKS\" )
					)
					( Units "uMatchProp" "ns" 1.000000)
					( Status sCSetFlattened )
					( Origin gBackEnd )
				)
				( attribute "RELATIVE_PROPAGATION_DELAY_SCOPE" "G"
					( Parent
						( matchGroupRef "@baseboard_fab2_lib.baseboard_fab2(sch_1):\MG_DDR_CMD_NEAR_DIMM_NG_DDR_B_DLL_9\" )
					)
					( Status sCSetFlattened )
					( Origin gBackEnd )
				)
				( attribute "RELATIVE_PROPAGATION_DELAY" "0.00 MIL,25.00 MIL"
					( Parent
						( matchGroupRef "@baseboard_fab2_lib.baseboard_fab2(sch_1):\MG_DDR_CMD_NEAR_DIMM_NG_DDR_B_DLL_9\" )
					)
					( Units "uMatchProp" "ns" 1.000000)
					( Status sCSetFlattened )
					( Origin gBackEnd )
				)
			)
			( pinPair "@baseboard_fab2_lib.baseboard_fab2(sch_1):\PP3961\"
				( pinRef "@baseboard_fab2_lib.baseboard_fab2(sch_1):page24_i172:DDR1_MA(6)" )
				( pinRef "@baseboard_fab2_lib.baseboard_fab2(sch_1):page45_i111:A6" )
				( attribute "RELATIVE_PROPAGATION_DELAY_SCOPE" "G"
					( Parent
						( matchGroupRef "@crescent_city_bb_fab1_lib.crescent_city_bb_fab1(sch_1):\MG_DDR_FAR_DIMM-CLK0_CLS_DDR_B_CAC-CLKS\" )
					)
					( Status sCSetFlattened )
					( Origin gBackEnd )
				)
				( attribute "RELATIVE_PROPAGATION_DELAY" "0.00 MIL,700.00 MIL"
					( Parent
						( matchGroupRef "@crescent_city_bb_fab1_lib.crescent_city_bb_fab1(sch_1):\MG_DDR_FAR_DIMM-CLK0_CLS_DDR_B_CAC-CLKS\" )
					)
					( Units "uMatchProp" "ns" 1.000000)
					( Status sCSetFlattened )
					( Origin gBackEnd )
				)
				( attribute "RELATIVE_PROPAGATION_DELAY_SCOPE" "G"
					( Parent
						( matchGroupRef "@baseboard_fab2_lib.baseboard_fab2(sch_1):\MG_DDR_FAR_DIMM_CMD_NG_DDR_B_DLL_9\" )
					)
					( Status sCSetFlattened )
					( Origin gBackEnd )
				)
				( attribute "RELATIVE_PROPAGATION_DELAY" "0.00 MIL,25.00 MIL"
					( Parent
						( matchGroupRef "@baseboard_fab2_lib.baseboard_fab2(sch_1):\MG_DDR_FAR_DIMM_CMD_NG_DDR_B_DLL_9\" )
					)
					( Units "uMatchProp" "ns" 1.000000)
					( Status sCSetFlattened )
					( Origin gBackEnd )
				)
			)
			( pinPair "@baseboard_fab2_lib.baseboard_fab2(sch_1):\PP3962\"
				( pinRef "@baseboard_fab2_lib.baseboard_fab2(sch_1):page24_i172:DDR1_MA(6)" )
				( pinRef "@baseboard_fab2_lib.baseboard_fab2(sch_1):page46_i14:A6" )
				( attribute "RELATIVE_PROPAGATION_DELAY_SCOPE" "G"
					( Parent
						( matchGroupRef "@crescent_city_bb_fab1_lib.crescent_city_bb_fab1(sch_1):\MG_DDR_NEAR_DIMM-CLK1_CLS_DDR_B_CAC-CLKS\" )
					)
					( Status sCSetFlattened )
					( Origin gBackEnd )
				)
				( attribute "RELATIVE_PROPAGATION_DELAY" "0.00 MIL,700.00 MIL"
					( Parent
						( matchGroupRef "@crescent_city_bb_fab1_lib.crescent_city_bb_fab1(sch_1):\MG_DDR_NEAR_DIMM-CLK1_CLS_DDR_B_CAC-CLKS\" )
					)
					( Units "uMatchProp" "ns" 1.000000)
					( Status sCSetFlattened )
					( Origin gBackEnd )
				)
				( attribute "RELATIVE_PROPAGATION_DELAY_SCOPE" "G"
					( Parent
						( matchGroupRef "@baseboard_fab2_lib.baseboard_fab2(sch_1):\MG_DDR_CMD_NEAR_DIMM_NG_DDR_B_DLL_9\" )
					)
					( Status sCSetFlattened )
					( Origin gBackEnd )
				)
				( attribute "RELATIVE_PROPAGATION_DELAY" "0.00 MIL,25.00 MIL"
					( Parent
						( matchGroupRef "@baseboard_fab2_lib.baseboard_fab2(sch_1):\MG_DDR_CMD_NEAR_DIMM_NG_DDR_B_DLL_9\" )
					)
					( Units "uMatchProp" "ns" 1.000000)
					( Status sCSetFlattened )
					( Origin gBackEnd )
				)
			)
			( pinPair "@baseboard_fab2_lib.baseboard_fab2(sch_1):\PP3955\"
				( pinRef "@baseboard_fab2_lib.baseboard_fab2(sch_1):page24_i172:DDR1_MA(7)" )
				( pinRef "@baseboard_fab2_lib.baseboard_fab2(sch_1):page45_i111:A7" )
				( attribute "RELATIVE_PROPAGATION_DELAY_SCOPE" "G"
					( Parent
						( matchGroupRef "@crescent_city_bb_fab1_lib.crescent_city_bb_fab1(sch_1):\MG_DDR_FAR_DIMM-CLK0_CLS_DDR_B_CAC-CLKS\" )
					)
					( Status sCSetFlattened )
					( Origin gBackEnd )
				)
				( attribute "RELATIVE_PROPAGATION_DELAY" "0.00 MIL,700.00 MIL"
					( Parent
						( matchGroupRef "@crescent_city_bb_fab1_lib.crescent_city_bb_fab1(sch_1):\MG_DDR_FAR_DIMM-CLK0_CLS_DDR_B_CAC-CLKS\" )
					)
					( Units "uMatchProp" "ns" 1.000000)
					( Status sCSetFlattened )
					( Origin gBackEnd )
				)
				( attribute "RELATIVE_PROPAGATION_DELAY_SCOPE" "G"
					( Parent
						( matchGroupRef "@baseboard_fab2_lib.baseboard_fab2(sch_1):\MG_DDR_FAR_DIMM_CMD_NG_DDR_B_DLL_10\" )
					)
					( Status sCSetFlattened )
					( Origin gBackEnd )
				)
				( attribute "RELATIVE_PROPAGATION_DELAY" "0.00 MIL,25.00 MIL"
					( Parent
						( matchGroupRef "@baseboard_fab2_lib.baseboard_fab2(sch_1):\MG_DDR_FAR_DIMM_CMD_NG_DDR_B_DLL_10\" )
					)
					( Units "uMatchProp" "ns" 1.000000)
					( Status sCSetFlattened )
					( Origin gBackEnd )
				)
			)
			( pinPair "@baseboard_fab2_lib.baseboard_fab2(sch_1):\PP3956\"
				( pinRef "@baseboard_fab2_lib.baseboard_fab2(sch_1):page46_i14:A7" )
				( pinRef "@baseboard_fab2_lib.baseboard_fab2(sch_1):page24_i172:DDR1_MA(7)" )
				( attribute "RELATIVE_PROPAGATION_DELAY_SCOPE" "G"
					( Parent
						( matchGroupRef "@crescent_city_bb_fab1_lib.crescent_city_bb_fab1(sch_1):\MG_DDR_NEAR_DIMM-CLK1_CLS_DDR_B_CAC-CLKS\" )
					)
					( Status sCSetFlattened )
					( Origin gBackEnd )
				)
				( attribute "RELATIVE_PROPAGATION_DELAY" "0.00 MIL,700.00 MIL"
					( Parent
						( matchGroupRef "@crescent_city_bb_fab1_lib.crescent_city_bb_fab1(sch_1):\MG_DDR_NEAR_DIMM-CLK1_CLS_DDR_B_CAC-CLKS\" )
					)
					( Units "uMatchProp" "ns" 1.000000)
					( Status sCSetFlattened )
					( Origin gBackEnd )
				)
				( attribute "RELATIVE_PROPAGATION_DELAY_SCOPE" "G"
					( Parent
						( matchGroupRef "@baseboard_fab2_lib.baseboard_fab2(sch_1):\MG_DDR_CMD_NEAR_DIMM_NG_DDR_B_DLL_10\" )
					)
					( Status sCSetFlattened )
					( Origin gBackEnd )
				)
				( attribute "RELATIVE_PROPAGATION_DELAY" "0.00 MIL,25.00 MIL"
					( Parent
						( matchGroupRef "@baseboard_fab2_lib.baseboard_fab2(sch_1):\MG_DDR_CMD_NEAR_DIMM_NG_DDR_B_DLL_10\" )
					)
					( Units "uMatchProp" "ns" 1.000000)
					( Status sCSetFlattened )
					( Origin gBackEnd )
				)
			)
			( pinPair "@baseboard_fab2_lib.baseboard_fab2(sch_1):\PP3957\"
				( pinRef "@baseboard_fab2_lib.baseboard_fab2(sch_1):page24_i172:DDR1_MA(8)" )
				( pinRef "@baseboard_fab2_lib.baseboard_fab2(sch_1):page45_i111:A8" )
				( attribute "RELATIVE_PROPAGATION_DELAY_SCOPE" "G"
					( Parent
						( matchGroupRef "@crescent_city_bb_fab1_lib.crescent_city_bb_fab1(sch_1):\MG_DDR_FAR_DIMM-CLK0_CLS_DDR_B_CAC-CLKS\" )
					)
					( Status sCSetFlattened )
					( Origin gBackEnd )
				)
				( attribute "RELATIVE_PROPAGATION_DELAY" "0.00 MIL,700.00 MIL"
					( Parent
						( matchGroupRef "@crescent_city_bb_fab1_lib.crescent_city_bb_fab1(sch_1):\MG_DDR_FAR_DIMM-CLK0_CLS_DDR_B_CAC-CLKS\" )
					)
					( Units "uMatchProp" "ns" 1.000000)
					( Status sCSetFlattened )
					( Origin gBackEnd )
				)
				( attribute "RELATIVE_PROPAGATION_DELAY_SCOPE" "G"
					( Parent
						( matchGroupRef "@baseboard_fab2_lib.baseboard_fab2(sch_1):\MG_DDR_FAR_DIMM_CMD_NG_DDR_B_DLL_10\" )
					)
					( Status sCSetFlattened )
					( Origin gBackEnd )
				)
				( attribute "RELATIVE_PROPAGATION_DELAY" "0.00 MIL,25.00 MIL"
					( Parent
						( matchGroupRef "@baseboard_fab2_lib.baseboard_fab2(sch_1):\MG_DDR_FAR_DIMM_CMD_NG_DDR_B_DLL_10\" )
					)
					( Units "uMatchProp" "ns" 1.000000)
					( Status sCSetFlattened )
					( Origin gBackEnd )
				)
			)
			( pinPair "@baseboard_fab2_lib.baseboard_fab2(sch_1):\PP3958\"
				( pinRef "@baseboard_fab2_lib.baseboard_fab2(sch_1):page46_i14:A8" )
				( pinRef "@baseboard_fab2_lib.baseboard_fab2(sch_1):page24_i172:DDR1_MA(8)" )
				( attribute "RELATIVE_PROPAGATION_DELAY_SCOPE" "G"
					( Parent
						( matchGroupRef "@crescent_city_bb_fab1_lib.crescent_city_bb_fab1(sch_1):\MG_DDR_NEAR_DIMM-CLK1_CLS_DDR_B_CAC-CLKS\" )
					)
					( Status sCSetFlattened )
					( Origin gBackEnd )
				)
				( attribute "RELATIVE_PROPAGATION_DELAY" "0.00 MIL,700.00 MIL"
					( Parent
						( matchGroupRef "@crescent_city_bb_fab1_lib.crescent_city_bb_fab1(sch_1):\MG_DDR_NEAR_DIMM-CLK1_CLS_DDR_B_CAC-CLKS\" )
					)
					( Units "uMatchProp" "ns" 1.000000)
					( Status sCSetFlattened )
					( Origin gBackEnd )
				)
				( attribute "RELATIVE_PROPAGATION_DELAY_SCOPE" "G"
					( Parent
						( matchGroupRef "@baseboard_fab2_lib.baseboard_fab2(sch_1):\MG_DDR_CMD_NEAR_DIMM_NG_DDR_B_DLL_10\" )
					)
					( Status sCSetFlattened )
					( Origin gBackEnd )
				)
				( attribute "RELATIVE_PROPAGATION_DELAY" "0.00 MIL,25.00 MIL"
					( Parent
						( matchGroupRef "@baseboard_fab2_lib.baseboard_fab2(sch_1):\MG_DDR_CMD_NEAR_DIMM_NG_DDR_B_DLL_10\" )
					)
					( Units "uMatchProp" "ns" 1.000000)
					( Status sCSetFlattened )
					( Origin gBackEnd )
				)
			)
			( pinPair "@baseboard_fab2_lib.baseboard_fab2(sch_1):\PP3951\"
				( pinRef "@baseboard_fab2_lib.baseboard_fab2(sch_1):page24_i172:DDR1_MA(9)" )
				( pinRef "@baseboard_fab2_lib.baseboard_fab2(sch_1):page45_i111:A9" )
				( attribute "RELATIVE_PROPAGATION_DELAY_SCOPE" "G"
					( Parent
						( matchGroupRef "@crescent_city_bb_fab1_lib.crescent_city_bb_fab1(sch_1):\MG_DDR_FAR_DIMM-CLK0_CLS_DDR_B_CAC-CLKS\" )
					)
					( Status sCSetFlattened )
					( Origin gBackEnd )
				)
				( attribute "RELATIVE_PROPAGATION_DELAY" "0.00 MIL,700.00 MIL"
					( Parent
						( matchGroupRef "@crescent_city_bb_fab1_lib.crescent_city_bb_fab1(sch_1):\MG_DDR_FAR_DIMM-CLK0_CLS_DDR_B_CAC-CLKS\" )
					)
					( Units "uMatchProp" "ns" 1.000000)
					( Status sCSetFlattened )
					( Origin gBackEnd )
				)
				( attribute "RELATIVE_PROPAGATION_DELAY_SCOPE" "G"
					( Parent
						( matchGroupRef "@baseboard_fab2_lib.baseboard_fab2(sch_1):\MG_DDR_FAR_DIMM_CMD_NG_DDR_B_DLL_11\" )
					)
					( Status sCSetFlattened )
					( Origin gBackEnd )
				)
				( attribute "RELATIVE_PROPAGATION_DELAY" "0.00 MIL,25.00 MIL"
					( Parent
						( matchGroupRef "@baseboard_fab2_lib.baseboard_fab2(sch_1):\MG_DDR_FAR_DIMM_CMD_NG_DDR_B_DLL_11\" )
					)
					( Units "uMatchProp" "ns" 1.000000)
					( Status sCSetFlattened )
					( Origin gBackEnd )
				)
			)
			( pinPair "@baseboard_fab2_lib.baseboard_fab2(sch_1):\PP3952\"
				( pinRef "@baseboard_fab2_lib.baseboard_fab2(sch_1):page24_i172:DDR1_MA(9)" )
				( pinRef "@baseboard_fab2_lib.baseboard_fab2(sch_1):page46_i14:A9" )
				( attribute "RELATIVE_PROPAGATION_DELAY_SCOPE" "G"
					( Parent
						( matchGroupRef "@crescent_city_bb_fab1_lib.crescent_city_bb_fab1(sch_1):\MG_DDR_NEAR_DIMM-CLK1_CLS_DDR_B_CAC-CLKS\" )
					)
					( Status sCSetFlattened )
					( Origin gBackEnd )
				)
				( attribute "RELATIVE_PROPAGATION_DELAY" "0.00 MIL,700.00 MIL"
					( Parent
						( matchGroupRef "@crescent_city_bb_fab1_lib.crescent_city_bb_fab1(sch_1):\MG_DDR_NEAR_DIMM-CLK1_CLS_DDR_B_CAC-CLKS\" )
					)
					( Units "uMatchProp" "ns" 1.000000)
					( Status sCSetFlattened )
					( Origin gBackEnd )
				)
				( attribute "RELATIVE_PROPAGATION_DELAY_SCOPE" "G"
					( Parent
						( matchGroupRef "@baseboard_fab2_lib.baseboard_fab2(sch_1):\MG_DDR_CMD_NEAR_DIMM_NG_DDR_B_DLL_11\" )
					)
					( Status sCSetFlattened )
					( Origin gBackEnd )
				)
				( attribute "RELATIVE_PROPAGATION_DELAY" "0.00 MIL,25.00 MIL"
					( Parent
						( matchGroupRef "@baseboard_fab2_lib.baseboard_fab2(sch_1):\MG_DDR_CMD_NEAR_DIMM_NG_DDR_B_DLL_11\" )
					)
					( Units "uMatchProp" "ns" 1.000000)
					( Status sCSetFlattened )
					( Origin gBackEnd )
				)
			)
			( pinPair "@baseboard_fab2_lib.baseboard_fab2(sch_1):\PP3953\"
				( pinRef "@baseboard_fab2_lib.baseboard_fab2(sch_1):page24_i172:DDR1_MA(12)" )
				( pinRef "@baseboard_fab2_lib.baseboard_fab2(sch_1):page45_i111:A12" )
				( attribute "RELATIVE_PROPAGATION_DELAY_SCOPE" "G"
					( Parent
						( matchGroupRef "@crescent_city_bb_fab1_lib.crescent_city_bb_fab1(sch_1):\MG_DDR_FAR_DIMM-CLK0_CLS_DDR_B_CAC-CLKS\" )
					)
					( Status sCSetFlattened )
					( Origin gBackEnd )
				)
				( attribute "RELATIVE_PROPAGATION_DELAY" "0.00 MIL,700.00 MIL"
					( Parent
						( matchGroupRef "@crescent_city_bb_fab1_lib.crescent_city_bb_fab1(sch_1):\MG_DDR_FAR_DIMM-CLK0_CLS_DDR_B_CAC-CLKS\" )
					)
					( Units "uMatchProp" "ns" 1.000000)
					( Status sCSetFlattened )
					( Origin gBackEnd )
				)
				( attribute "RELATIVE_PROPAGATION_DELAY_SCOPE" "G"
					( Parent
						( matchGroupRef "@baseboard_fab2_lib.baseboard_fab2(sch_1):\MG_DDR_FAR_DIMM_CMD_NG_DDR_B_DLL_11\" )
					)
					( Status sCSetFlattened )
					( Origin gBackEnd )
				)
				( attribute "RELATIVE_PROPAGATION_DELAY" "0.00 MIL,25.00 MIL"
					( Parent
						( matchGroupRef "@baseboard_fab2_lib.baseboard_fab2(sch_1):\MG_DDR_FAR_DIMM_CMD_NG_DDR_B_DLL_11\" )
					)
					( Units "uMatchProp" "ns" 1.000000)
					( Status sCSetFlattened )
					( Origin gBackEnd )
				)
			)
			( pinPair "@baseboard_fab2_lib.baseboard_fab2(sch_1):\PP3954\"
				( pinRef "@baseboard_fab2_lib.baseboard_fab2(sch_1):page46_i14:A12" )
				( pinRef "@baseboard_fab2_lib.baseboard_fab2(sch_1):page24_i172:DDR1_MA(12)" )
				( attribute "RELATIVE_PROPAGATION_DELAY_SCOPE" "G"
					( Parent
						( matchGroupRef "@crescent_city_bb_fab1_lib.crescent_city_bb_fab1(sch_1):\MG_DDR_NEAR_DIMM-CLK1_CLS_DDR_B_CAC-CLKS\" )
					)
					( Status sCSetFlattened )
					( Origin gBackEnd )
				)
				( attribute "RELATIVE_PROPAGATION_DELAY" "0.00 MIL,700.00 MIL"
					( Parent
						( matchGroupRef "@crescent_city_bb_fab1_lib.crescent_city_bb_fab1(sch_1):\MG_DDR_NEAR_DIMM-CLK1_CLS_DDR_B_CAC-CLKS\" )
					)
					( Units "uMatchProp" "ns" 1.000000)
					( Status sCSetFlattened )
					( Origin gBackEnd )
				)
				( attribute "RELATIVE_PROPAGATION_DELAY_SCOPE" "G"
					( Parent
						( matchGroupRef "@baseboard_fab2_lib.baseboard_fab2(sch_1):\MG_DDR_CMD_NEAR_DIMM_NG_DDR_B_DLL_11\" )
					)
					( Status sCSetFlattened )
					( Origin gBackEnd )
				)
				( attribute "RELATIVE_PROPAGATION_DELAY" "0.00 MIL,25.00 MIL"
					( Parent
						( matchGroupRef "@baseboard_fab2_lib.baseboard_fab2(sch_1):\MG_DDR_CMD_NEAR_DIMM_NG_DDR_B_DLL_11\" )
					)
					( Units "uMatchProp" "ns" 1.000000)
					( Status sCSetFlattened )
					( Origin gBackEnd )
				)
			)
			( pinPair "@baseboard_fab2_lib.baseboard_fab2(sch_1):\PP3947\"
				( pinRef "@baseboard_fab2_lib.baseboard_fab2(sch_1):page24_i172:DDR1_BG(1)" )
				( pinRef "@baseboard_fab2_lib.baseboard_fab2(sch_1):page45_i111:BG(1)" )
				( attribute "RELATIVE_PROPAGATION_DELAY_SCOPE" "G"
					( Parent
						( matchGroupRef "@crescent_city_bb_fab1_lib.crescent_city_bb_fab1(sch_1):\MG_DDR_FAR_DIMM-CLK0_CLS_DDR_B_CAC-CLKS\" )
					)
					( Status sCSetFlattened )
					( Origin gBackEnd )
				)
				( attribute "RELATIVE_PROPAGATION_DELAY" "0.00 MIL,700.00 MIL"
					( Parent
						( matchGroupRef "@crescent_city_bb_fab1_lib.crescent_city_bb_fab1(sch_1):\MG_DDR_FAR_DIMM-CLK0_CLS_DDR_B_CAC-CLKS\" )
					)
					( Units "uMatchProp" "ns" 1.000000)
					( Status sCSetFlattened )
					( Origin gBackEnd )
				)
				( attribute "RELATIVE_PROPAGATION_DELAY_SCOPE" "G"
					( Parent
						( matchGroupRef "@baseboard_fab2_lib.baseboard_fab2(sch_1):\MG_DDR_FAR_DIMM_CMD_NG_DDR_B_DLL_12\" )
					)
					( Status sCSetFlattened )
					( Origin gBackEnd )
				)
				( attribute "RELATIVE_PROPAGATION_DELAY" "0.00 MIL,25.00 MIL"
					( Parent
						( matchGroupRef "@baseboard_fab2_lib.baseboard_fab2(sch_1):\MG_DDR_FAR_DIMM_CMD_NG_DDR_B_DLL_12\" )
					)
					( Units "uMatchProp" "ns" 1.000000)
					( Status sCSetFlattened )
					( Origin gBackEnd )
				)
			)
			( pinPair "@baseboard_fab2_lib.baseboard_fab2(sch_1):\PP3948\"
				( pinRef "@baseboard_fab2_lib.baseboard_fab2(sch_1):page24_i172:DDR1_BG(1)" )
				( pinRef "@baseboard_fab2_lib.baseboard_fab2(sch_1):page46_i14:BG(1)" )
				( attribute "RELATIVE_PROPAGATION_DELAY_SCOPE" "G"
					( Parent
						( matchGroupRef "@crescent_city_bb_fab1_lib.crescent_city_bb_fab1(sch_1):\MG_DDR_NEAR_DIMM-CLK1_CLS_DDR_B_CAC-CLKS\" )
					)
					( Status sCSetFlattened )
					( Origin gBackEnd )
				)
				( attribute "RELATIVE_PROPAGATION_DELAY" "0.00 MIL,700.00 MIL"
					( Parent
						( matchGroupRef "@crescent_city_bb_fab1_lib.crescent_city_bb_fab1(sch_1):\MG_DDR_NEAR_DIMM-CLK1_CLS_DDR_B_CAC-CLKS\" )
					)
					( Units "uMatchProp" "ns" 1.000000)
					( Status sCSetFlattened )
					( Origin gBackEnd )
				)
				( attribute "RELATIVE_PROPAGATION_DELAY_SCOPE" "G"
					( Parent
						( matchGroupRef "@baseboard_fab2_lib.baseboard_fab2(sch_1):\MG_DDR_CMD_NEAR_DIMM_NG_DDR_B_DLL_12\" )
					)
					( Status sCSetFlattened )
					( Origin gBackEnd )
				)
				( attribute "RELATIVE_PROPAGATION_DELAY" "0.00 MIL,25.00 MIL"
					( Parent
						( matchGroupRef "@baseboard_fab2_lib.baseboard_fab2(sch_1):\MG_DDR_CMD_NEAR_DIMM_NG_DDR_B_DLL_12\" )
					)
					( Units "uMatchProp" "ns" 1.000000)
					( Status sCSetFlattened )
					( Origin gBackEnd )
				)
			)
			( pinPair "@baseboard_fab2_lib.baseboard_fab2(sch_1):\PP3949\"
				( pinRef "@baseboard_fab2_lib.baseboard_fab2(sch_1):page24_i172:DDR1_MA(11)" )
				( pinRef "@baseboard_fab2_lib.baseboard_fab2(sch_1):page45_i111:A11" )
				( attribute "RELATIVE_PROPAGATION_DELAY_SCOPE" "G"
					( Parent
						( matchGroupRef "@crescent_city_bb_fab1_lib.crescent_city_bb_fab1(sch_1):\MG_DDR_FAR_DIMM-CLK0_CLS_DDR_B_CAC-CLKS\" )
					)
					( Status sCSetFlattened )
					( Origin gBackEnd )
				)
				( attribute "RELATIVE_PROPAGATION_DELAY" "0.00 MIL,700.00 MIL"
					( Parent
						( matchGroupRef "@crescent_city_bb_fab1_lib.crescent_city_bb_fab1(sch_1):\MG_DDR_FAR_DIMM-CLK0_CLS_DDR_B_CAC-CLKS\" )
					)
					( Units "uMatchProp" "ns" 1.000000)
					( Status sCSetFlattened )
					( Origin gBackEnd )
				)
				( attribute "RELATIVE_PROPAGATION_DELAY_SCOPE" "G"
					( Parent
						( matchGroupRef "@baseboard_fab2_lib.baseboard_fab2(sch_1):\MG_DDR_FAR_DIMM_CMD_NG_DDR_B_DLL_12\" )
					)
					( Status sCSetFlattened )
					( Origin gBackEnd )
				)
				( attribute "RELATIVE_PROPAGATION_DELAY" "0.00 MIL,25.00 MIL"
					( Parent
						( matchGroupRef "@baseboard_fab2_lib.baseboard_fab2(sch_1):\MG_DDR_FAR_DIMM_CMD_NG_DDR_B_DLL_12\" )
					)
					( Units "uMatchProp" "ns" 1.000000)
					( Status sCSetFlattened )
					( Origin gBackEnd )
				)
			)
			( pinPair "@baseboard_fab2_lib.baseboard_fab2(sch_1):\PP3950\"
				( pinRef "@baseboard_fab2_lib.baseboard_fab2(sch_1):page46_i14:A11" )
				( pinRef "@baseboard_fab2_lib.baseboard_fab2(sch_1):page24_i172:DDR1_MA(11)" )
				( attribute "RELATIVE_PROPAGATION_DELAY_SCOPE" "G"
					( Parent
						( matchGroupRef "@crescent_city_bb_fab1_lib.crescent_city_bb_fab1(sch_1):\MG_DDR_NEAR_DIMM-CLK1_CLS_DDR_B_CAC-CLKS\" )
					)
					( Status sCSetFlattened )
					( Origin gBackEnd )
				)
				( attribute "RELATIVE_PROPAGATION_DELAY" "0.00 MIL,700.00 MIL"
					( Parent
						( matchGroupRef "@crescent_city_bb_fab1_lib.crescent_city_bb_fab1(sch_1):\MG_DDR_NEAR_DIMM-CLK1_CLS_DDR_B_CAC-CLKS\" )
					)
					( Units "uMatchProp" "ns" 1.000000)
					( Status sCSetFlattened )
					( Origin gBackEnd )
				)
				( attribute "RELATIVE_PROPAGATION_DELAY_SCOPE" "G"
					( Parent
						( matchGroupRef "@baseboard_fab2_lib.baseboard_fab2(sch_1):\MG_DDR_CMD_NEAR_DIMM_NG_DDR_B_DLL_12\" )
					)
					( Status sCSetFlattened )
					( Origin gBackEnd )
				)
				( attribute "RELATIVE_PROPAGATION_DELAY" "0.00 MIL,25.00 MIL"
					( Parent
						( matchGroupRef "@baseboard_fab2_lib.baseboard_fab2(sch_1):\MG_DDR_CMD_NEAR_DIMM_NG_DDR_B_DLL_12\" )
					)
					( Units "uMatchProp" "ns" 1.000000)
					( Status sCSetFlattened )
					( Origin gBackEnd )
				)
			)
			( pinPair "@baseboard_fab2_lib.baseboard_fab2(sch_1):\PP3943\"
				( pinRef "@baseboard_fab2_lib.baseboard_fab2(sch_1):page24_i172:DDR1_ACT_N" )
				( pinRef "@baseboard_fab2_lib.baseboard_fab2(sch_1):page45_i111:ACT_N" )
				( attribute "RELATIVE_PROPAGATION_DELAY_SCOPE" "G"
					( Parent
						( matchGroupRef "@crescent_city_bb_fab1_lib.crescent_city_bb_fab1(sch_1):\MG_DDR_FAR_DIMM-CLK0_CLS_DDR_B_CAC-CLKS\" )
					)
					( Status sCSetFlattened )
					( Origin gBackEnd )
				)
				( attribute "RELATIVE_PROPAGATION_DELAY" "0.00 MIL,700.00 MIL"
					( Parent
						( matchGroupRef "@crescent_city_bb_fab1_lib.crescent_city_bb_fab1(sch_1):\MG_DDR_FAR_DIMM-CLK0_CLS_DDR_B_CAC-CLKS\" )
					)
					( Units "uMatchProp" "ns" 1.000000)
					( Status sCSetFlattened )
					( Origin gBackEnd )
				)
				( attribute "RELATIVE_PROPAGATION_DELAY_SCOPE" "G"
					( Parent
						( matchGroupRef "@baseboard_fab2_lib.baseboard_fab2(sch_1):\MG_DDR_FAR_DIMM_CMD_NG_DDR_B_DLL_13\" )
					)
					( Status sCSetFlattened )
					( Origin gBackEnd )
				)
				( attribute "RELATIVE_PROPAGATION_DELAY" "0.00 MIL,25.00 MIL"
					( Parent
						( matchGroupRef "@baseboard_fab2_lib.baseboard_fab2(sch_1):\MG_DDR_FAR_DIMM_CMD_NG_DDR_B_DLL_13\" )
					)
					( Units "uMatchProp" "ns" 1.000000)
					( Status sCSetFlattened )
					( Origin gBackEnd )
				)
			)
			( pinPair "@baseboard_fab2_lib.baseboard_fab2(sch_1):\PP3944\"
				( pinRef "@baseboard_fab2_lib.baseboard_fab2(sch_1):page46_i14:ACT_N" )
				( pinRef "@baseboard_fab2_lib.baseboard_fab2(sch_1):page24_i172:DDR1_ACT_N" )
				( attribute "RELATIVE_PROPAGATION_DELAY_SCOPE" "G"
					( Parent
						( matchGroupRef "@crescent_city_bb_fab1_lib.crescent_city_bb_fab1(sch_1):\MG_DDR_NEAR_DIMM-CLK1_CLS_DDR_B_CAC-CLKS\" )
					)
					( Status sCSetFlattened )
					( Origin gBackEnd )
				)
				( attribute "RELATIVE_PROPAGATION_DELAY" "0.00 MIL,700.00 MIL"
					( Parent
						( matchGroupRef "@crescent_city_bb_fab1_lib.crescent_city_bb_fab1(sch_1):\MG_DDR_NEAR_DIMM-CLK1_CLS_DDR_B_CAC-CLKS\" )
					)
					( Units "uMatchProp" "ns" 1.000000)
					( Status sCSetFlattened )
					( Origin gBackEnd )
				)
				( attribute "RELATIVE_PROPAGATION_DELAY_SCOPE" "G"
					( Parent
						( matchGroupRef "@baseboard_fab2_lib.baseboard_fab2(sch_1):\MG_DDR_CMD_NEAR_DIMM_NG_DDR_B_DLL_13\" )
					)
					( Status sCSetFlattened )
					( Origin gBackEnd )
				)
				( attribute "RELATIVE_PROPAGATION_DELAY" "0.00 MIL,25.00 MIL"
					( Parent
						( matchGroupRef "@baseboard_fab2_lib.baseboard_fab2(sch_1):\MG_DDR_CMD_NEAR_DIMM_NG_DDR_B_DLL_13\" )
					)
					( Units "uMatchProp" "ns" 1.000000)
					( Status sCSetFlattened )
					( Origin gBackEnd )
				)
			)
			( pinPair "@baseboard_fab2_lib.baseboard_fab2(sch_1):\PP3945\"
				( pinRef "@baseboard_fab2_lib.baseboard_fab2(sch_1):page24_i172:DDR1_BG(0)" )
				( pinRef "@baseboard_fab2_lib.baseboard_fab2(sch_1):page45_i111:BG(0)" )
				( attribute "RELATIVE_PROPAGATION_DELAY_SCOPE" "G"
					( Parent
						( matchGroupRef "@crescent_city_bb_fab1_lib.crescent_city_bb_fab1(sch_1):\MG_DDR_FAR_DIMM-CLK0_CLS_DDR_B_CAC-CLKS\" )
					)
					( Status sCSetFlattened )
					( Origin gBackEnd )
				)
				( attribute "RELATIVE_PROPAGATION_DELAY" "0.00 MIL,700.00 MIL"
					( Parent
						( matchGroupRef "@crescent_city_bb_fab1_lib.crescent_city_bb_fab1(sch_1):\MG_DDR_FAR_DIMM-CLK0_CLS_DDR_B_CAC-CLKS\" )
					)
					( Units "uMatchProp" "ns" 1.000000)
					( Status sCSetFlattened )
					( Origin gBackEnd )
				)
				( attribute "RELATIVE_PROPAGATION_DELAY_SCOPE" "G"
					( Parent
						( matchGroupRef "@baseboard_fab2_lib.baseboard_fab2(sch_1):\MG_DDR_FAR_DIMM_CMD_NG_DDR_B_DLL_13\" )
					)
					( Status sCSetFlattened )
					( Origin gBackEnd )
				)
				( attribute "RELATIVE_PROPAGATION_DELAY" "0.00 MIL,25.00 MIL"
					( Parent
						( matchGroupRef "@baseboard_fab2_lib.baseboard_fab2(sch_1):\MG_DDR_FAR_DIMM_CMD_NG_DDR_B_DLL_13\" )
					)
					( Units "uMatchProp" "ns" 1.000000)
					( Status sCSetFlattened )
					( Origin gBackEnd )
				)
			)
			( pinPair "@baseboard_fab2_lib.baseboard_fab2(sch_1):\PP3946\"
				( pinRef "@baseboard_fab2_lib.baseboard_fab2(sch_1):page24_i172:DDR1_BG(0)" )
				( pinRef "@baseboard_fab2_lib.baseboard_fab2(sch_1):page46_i14:BG(0)" )
				( attribute "RELATIVE_PROPAGATION_DELAY_SCOPE" "G"
					( Parent
						( matchGroupRef "@crescent_city_bb_fab1_lib.crescent_city_bb_fab1(sch_1):\MG_DDR_NEAR_DIMM-CLK1_CLS_DDR_B_CAC-CLKS\" )
					)
					( Status sCSetFlattened )
					( Origin gBackEnd )
				)
				( attribute "RELATIVE_PROPAGATION_DELAY" "0.00 MIL,700.00 MIL"
					( Parent
						( matchGroupRef "@crescent_city_bb_fab1_lib.crescent_city_bb_fab1(sch_1):\MG_DDR_NEAR_DIMM-CLK1_CLS_DDR_B_CAC-CLKS\" )
					)
					( Units "uMatchProp" "ns" 1.000000)
					( Status sCSetFlattened )
					( Origin gBackEnd )
				)
				( attribute "RELATIVE_PROPAGATION_DELAY_SCOPE" "G"
					( Parent
						( matchGroupRef "@baseboard_fab2_lib.baseboard_fab2(sch_1):\MG_DDR_CMD_NEAR_DIMM_NG_DDR_B_DLL_13\" )
					)
					( Status sCSetFlattened )
					( Origin gBackEnd )
				)
				( attribute "RELATIVE_PROPAGATION_DELAY" "0.00 MIL,25.00 MIL"
					( Parent
						( matchGroupRef "@baseboard_fab2_lib.baseboard_fab2(sch_1):\MG_DDR_CMD_NEAR_DIMM_NG_DDR_B_DLL_13\" )
					)
					( Units "uMatchProp" "ns" 1.000000)
					( Status sCSetFlattened )
					( Origin gBackEnd )
				)
			)
			( pinPair "@baseboard_fab2_lib.baseboard_fab2(sch_1):\PP3941\"
				( pinRef "@baseboard_fab2_lib.baseboard_fab2(sch_1):page24_i172:DDR1_CS_N(0)" )
				( pinRef "@baseboard_fab2_lib.baseboard_fab2(sch_1):page45_i111:S0_N" )
				( attribute "RELATIVE_PROPAGATION_DELAY_SCOPE" "G"
					( Parent
						( matchGroupRef "@crescent_city_bb_fab1_lib.crescent_city_bb_fab1(sch_1):\MG_DDR_FAR_DIMM-CLK0_CLS_DDR_B_CAC-CLKS\" )
					)
					( Status sCSetFlattened )
					( Origin gBackEnd )
				)
				( attribute "RELATIVE_PROPAGATION_DELAY" "0.00 MIL,300.00 MIL"
					( Parent
						( matchGroupRef "@crescent_city_bb_fab1_lib.crescent_city_bb_fab1(sch_1):\MG_DDR_FAR_DIMM-CLK0_CLS_DDR_B_CAC-CLKS\" )
					)
					( Units "uMatchProp" "ns" 1.000000)
					( Status sCSetFlattened )
					( Origin gBackEnd )
				)
				( attribute "RELATIVE_PROPAGATION_DELAY_SCOPE" "G"
					( Parent
						( matchGroupRef "@baseboard_fab2_lib.baseboard_fab2(sch_1):\MG_DDR_CTRL_NG_DDR_B_DLL_14\" )
					)
					( Status sCSetFlattened )
					( Origin gBackEnd )
				)
				( attribute "RELATIVE_PROPAGATION_DELAY" "0.00 MIL,25.00 MIL"
					( Parent
						( matchGroupRef "@baseboard_fab2_lib.baseboard_fab2(sch_1):\MG_DDR_CTRL_NG_DDR_B_DLL_14\" )
					)
					( Units "uMatchProp" "ns" 1.000000)
					( Status sCSetFlattened )
					( Origin gBackEnd )
				)
			)
			( pinPair "@baseboard_fab2_lib.baseboard_fab2(sch_1):\PP3942\"
				( pinRef "@baseboard_fab2_lib.baseboard_fab2(sch_1):page24_i172:DDR1_ODT(0)" )
				( pinRef "@baseboard_fab2_lib.baseboard_fab2(sch_1):page45_i111:ODT(0)" )
				( attribute "RELATIVE_PROPAGATION_DELAY_SCOPE" "G"
					( Parent
						( matchGroupRef "@crescent_city_bb_fab1_lib.crescent_city_bb_fab1(sch_1):\MG_DDR_FAR_DIMM-CLK0_CLS_DDR_B_CAC-CLKS\" )
					)
					( Status sCSetFlattened )
					( Origin gBackEnd )
				)
				( attribute "RELATIVE_PROPAGATION_DELAY" "0.00 MIL,300.00 MIL"
					( Parent
						( matchGroupRef "@crescent_city_bb_fab1_lib.crescent_city_bb_fab1(sch_1):\MG_DDR_FAR_DIMM-CLK0_CLS_DDR_B_CAC-CLKS\" )
					)
					( Units "uMatchProp" "ns" 1.000000)
					( Status sCSetFlattened )
					( Origin gBackEnd )
				)
				( attribute "RELATIVE_PROPAGATION_DELAY_SCOPE" "G"
					( Parent
						( matchGroupRef "@baseboard_fab2_lib.baseboard_fab2(sch_1):\MG_DDR_CTRL_NG_DDR_B_DLL_14\" )
					)
					( Status sCSetFlattened )
					( Origin gBackEnd )
				)
				( attribute "RELATIVE_PROPAGATION_DELAY" "0.00 MIL,25.00 MIL"
					( Parent
						( matchGroupRef "@baseboard_fab2_lib.baseboard_fab2(sch_1):\MG_DDR_CTRL_NG_DDR_B_DLL_14\" )
					)
					( Units "uMatchProp" "ns" 1.000000)
					( Status sCSetFlattened )
					( Origin gBackEnd )
				)
			)
			( pinPair "@baseboard_fab2_lib.baseboard_fab2(sch_1):\PP3940\"
				( pinRef "@baseboard_fab2_lib.baseboard_fab2(sch_1):page24_i172:DDR1_CKE(0)" )
				( pinRef "@baseboard_fab2_lib.baseboard_fab2(sch_1):page45_i111:CKE(0)" )
				( attribute "RELATIVE_PROPAGATION_DELAY_SCOPE" "G"
					( Parent
						( matchGroupRef "@crescent_city_bb_fab1_lib.crescent_city_bb_fab1(sch_1):\MG_DDR_FAR_DIMM-CLK0_CLS_DDR_B_CAC-CLKS\" )
					)
					( Status sCSetFlattened )
					( Origin gBackEnd )
				)
				( attribute "RELATIVE_PROPAGATION_DELAY" "0.00 MIL,300.00 MIL"
					( Parent
						( matchGroupRef "@crescent_city_bb_fab1_lib.crescent_city_bb_fab1(sch_1):\MG_DDR_FAR_DIMM-CLK0_CLS_DDR_B_CAC-CLKS\" )
					)
					( Units "uMatchProp" "ns" 1.000000)
					( Status sCSetFlattened )
					( Origin gBackEnd )
				)
				( attribute "RELATIVE_PROPAGATION_DELAY_SCOPE" "G"
					( Parent
						( matchGroupRef "@baseboard_fab2_lib.baseboard_fab2(sch_1):\MG_DDR_CTRL_NG_DDR_B_DLL_15\" )
					)
					( Status sCSetFlattened )
					( Origin gBackEnd )
				)
				( attribute "RELATIVE_PROPAGATION_DELAY" "0.00 MIL,25.00 MIL"
					( Parent
						( matchGroupRef "@baseboard_fab2_lib.baseboard_fab2(sch_1):\MG_DDR_CTRL_NG_DDR_B_DLL_15\" )
					)
					( Units "uMatchProp" "ns" 1.000000)
					( Status sCSetFlattened )
					( Origin gBackEnd )
				)
			)
			( pinPair "@baseboard_fab2_lib.baseboard_fab2(sch_1):\PP3939\"
				( pinRef "@baseboard_fab2_lib.baseboard_fab2(sch_1):page24_i172:DDR1_CS_N(2)" )
				( pinRef "@baseboard_fab2_lib.baseboard_fab2(sch_1):page45_i111:S2_N_C(0)" )
				( attribute "RELATIVE_PROPAGATION_DELAY_SCOPE" "G"
					( Parent
						( matchGroupRef "@crescent_city_bb_fab1_lib.crescent_city_bb_fab1(sch_1):\MG_DDR_FAR_DIMM-CLK0_CLS_DDR_B_CAC-CLKS\" )
					)
					( Status sCSetFlattened )
					( Origin gBackEnd )
				)
				( attribute "RELATIVE_PROPAGATION_DELAY" "0.00 MIL,300.00 MIL"
					( Parent
						( matchGroupRef "@crescent_city_bb_fab1_lib.crescent_city_bb_fab1(sch_1):\MG_DDR_FAR_DIMM-CLK0_CLS_DDR_B_CAC-CLKS\" )
					)
					( Units "uMatchProp" "ns" 1.000000)
					( Status sCSetFlattened )
					( Origin gBackEnd )
				)
				( attribute "RELATIVE_PROPAGATION_DELAY_SCOPE" "G"
					( Parent
						( matchGroupRef "@baseboard_fab2_lib.baseboard_fab2(sch_1):\MG_DDR_CTRL_NG_DDR_B_DLL_16\" )
					)
					( Status sCSetFlattened )
					( Origin gBackEnd )
				)
				( attribute "RELATIVE_PROPAGATION_DELAY" "0.00 MIL,25.00 MIL"
					( Parent
						( matchGroupRef "@baseboard_fab2_lib.baseboard_fab2(sch_1):\MG_DDR_CTRL_NG_DDR_B_DLL_16\" )
					)
					( Units "uMatchProp" "ns" 1.000000)
					( Status sCSetFlattened )
					( Origin gBackEnd )
				)
			)
			( pinPair "@baseboard_fab2_lib.baseboard_fab2(sch_1):\PP3938\"
				( pinRef "@baseboard_fab2_lib.baseboard_fab2(sch_1):page24_i172:DDR1_CS_N(3)" )
				( pinRef "@baseboard_fab2_lib.baseboard_fab2(sch_1):page45_i111:S3_N_C(1)" )
				( attribute "RELATIVE_PROPAGATION_DELAY_SCOPE" "G"
					( Parent
						( matchGroupRef "@crescent_city_bb_fab1_lib.crescent_city_bb_fab1(sch_1):\MG_DDR_FAR_DIMM-CLK0_CLS_DDR_B_CAC-CLKS\" )
					)
					( Status sCSetFlattened )
					( Origin gBackEnd )
				)
				( attribute "RELATIVE_PROPAGATION_DELAY" "0.00 MIL,300.00 MIL"
					( Parent
						( matchGroupRef "@crescent_city_bb_fab1_lib.crescent_city_bb_fab1(sch_1):\MG_DDR_FAR_DIMM-CLK0_CLS_DDR_B_CAC-CLKS\" )
					)
					( Units "uMatchProp" "ns" 1.000000)
					( Status sCSetFlattened )
					( Origin gBackEnd )
				)
				( attribute "RELATIVE_PROPAGATION_DELAY_SCOPE" "G"
					( Parent
						( matchGroupRef "@baseboard_fab2_lib.baseboard_fab2(sch_1):\MG_DDR_CTRL_NG_DDR_B_DLL_17\" )
					)
					( Status sCSetFlattened )
					( Origin gBackEnd )
				)
				( attribute "RELATIVE_PROPAGATION_DELAY" "0.00 MIL,25.00 MIL"
					( Parent
						( matchGroupRef "@baseboard_fab2_lib.baseboard_fab2(sch_1):\MG_DDR_CTRL_NG_DDR_B_DLL_17\" )
					)
					( Units "uMatchProp" "ns" 1.000000)
					( Status sCSetFlattened )
					( Origin gBackEnd )
				)
			)
			( pinPair "@baseboard_fab2_lib.baseboard_fab2(sch_1):\PP3936\"
				( pinRef "@baseboard_fab2_lib.baseboard_fab2(sch_1):page24_i172:DDR1_ODT(1)" )
				( pinRef "@baseboard_fab2_lib.baseboard_fab2(sch_1):page45_i111:ODT(1)" )
				( attribute "RELATIVE_PROPAGATION_DELAY_SCOPE" "G"
					( Parent
						( matchGroupRef "@crescent_city_bb_fab1_lib.crescent_city_bb_fab1(sch_1):\MG_DDR_FAR_DIMM-CLK0_CLS_DDR_B_CAC-CLKS\" )
					)
					( Status sCSetFlattened )
					( Origin gBackEnd )
				)
				( attribute "RELATIVE_PROPAGATION_DELAY" "0.00 MIL,300.00 MIL"
					( Parent
						( matchGroupRef "@crescent_city_bb_fab1_lib.crescent_city_bb_fab1(sch_1):\MG_DDR_FAR_DIMM-CLK0_CLS_DDR_B_CAC-CLKS\" )
					)
					( Units "uMatchProp" "ns" 1.000000)
					( Status sCSetFlattened )
					( Origin gBackEnd )
				)
				( attribute "RELATIVE_PROPAGATION_DELAY_SCOPE" "G"
					( Parent
						( matchGroupRef "@baseboard_fab2_lib.baseboard_fab2(sch_1):\MG_DDR_CTRL_NG_DDR_B_DLL_18\" )
					)
					( Status sCSetFlattened )
					( Origin gBackEnd )
				)
				( attribute "RELATIVE_PROPAGATION_DELAY" "0.00 MIL,25.00 MIL"
					( Parent
						( matchGroupRef "@baseboard_fab2_lib.baseboard_fab2(sch_1):\MG_DDR_CTRL_NG_DDR_B_DLL_18\" )
					)
					( Units "uMatchProp" "ns" 1.000000)
					( Status sCSetFlattened )
					( Origin gBackEnd )
				)
			)
			( pinPair "@baseboard_fab2_lib.baseboard_fab2(sch_1):\PP3937\"
				( pinRef "@baseboard_fab2_lib.baseboard_fab2(sch_1):page24_i172:DDR1_CS_N(1)" )
				( pinRef "@baseboard_fab2_lib.baseboard_fab2(sch_1):page45_i111:S1_N" )
				( attribute "RELATIVE_PROPAGATION_DELAY_SCOPE" "G"
					( Parent
						( matchGroupRef "@crescent_city_bb_fab1_lib.crescent_city_bb_fab1(sch_1):\MG_DDR_FAR_DIMM-CLK0_CLS_DDR_B_CAC-CLKS\" )
					)
					( Status sCSetFlattened )
					( Origin gBackEnd )
				)
				( attribute "RELATIVE_PROPAGATION_DELAY" "0.00 MIL,300.00 MIL"
					( Parent
						( matchGroupRef "@crescent_city_bb_fab1_lib.crescent_city_bb_fab1(sch_1):\MG_DDR_FAR_DIMM-CLK0_CLS_DDR_B_CAC-CLKS\" )
					)
					( Units "uMatchProp" "ns" 1.000000)
					( Status sCSetFlattened )
					( Origin gBackEnd )
				)
				( attribute "RELATIVE_PROPAGATION_DELAY_SCOPE" "G"
					( Parent
						( matchGroupRef "@baseboard_fab2_lib.baseboard_fab2(sch_1):\MG_DDR_CTRL_NG_DDR_B_DLL_18\" )
					)
					( Status sCSetFlattened )
					( Origin gBackEnd )
				)
				( attribute "RELATIVE_PROPAGATION_DELAY" "0.00 MIL,25.00 MIL"
					( Parent
						( matchGroupRef "@baseboard_fab2_lib.baseboard_fab2(sch_1):\MG_DDR_CTRL_NG_DDR_B_DLL_18\" )
					)
					( Units "uMatchProp" "ns" 1.000000)
					( Status sCSetFlattened )
					( Origin gBackEnd )
				)
			)
			( pinPair "@baseboard_fab2_lib.baseboard_fab2(sch_1):\PP3935\"
				( pinRef "@baseboard_fab2_lib.baseboard_fab2(sch_1):page45_i111:CKE(1)" )
				( pinRef "@baseboard_fab2_lib.baseboard_fab2(sch_1):page24_i172:DDR1_CKE(1)" )
				( attribute "RELATIVE_PROPAGATION_DELAY_SCOPE" "G"
					( Parent
						( matchGroupRef "@crescent_city_bb_fab1_lib.crescent_city_bb_fab1(sch_1):\MG_DDR_FAR_DIMM-CLK0_CLS_DDR_B_CAC-CLKS\" )
					)
					( Status sCSetFlattened )
					( Origin gBackEnd )
				)
				( attribute "RELATIVE_PROPAGATION_DELAY" "0.00 MIL,300.00 MIL"
					( Parent
						( matchGroupRef "@crescent_city_bb_fab1_lib.crescent_city_bb_fab1(sch_1):\MG_DDR_FAR_DIMM-CLK0_CLS_DDR_B_CAC-CLKS\" )
					)
					( Units "uMatchProp" "ns" 1.000000)
					( Status sCSetFlattened )
					( Origin gBackEnd )
				)
				( attribute "RELATIVE_PROPAGATION_DELAY_SCOPE" "G"
					( Parent
						( matchGroupRef "@baseboard_fab2_lib.baseboard_fab2(sch_1):\MG_DDR_CTRL_NG_DDR_B_DLL_19\" )
					)
					( Status sCSetFlattened )
					( Origin gBackEnd )
				)
				( attribute "RELATIVE_PROPAGATION_DELAY" "0.00 MIL,25.00 MIL"
					( Parent
						( matchGroupRef "@baseboard_fab2_lib.baseboard_fab2(sch_1):\MG_DDR_CTRL_NG_DDR_B_DLL_19\" )
					)
					( Units "uMatchProp" "ns" 1.000000)
					( Status sCSetFlattened )
					( Origin gBackEnd )
				)
			)
			( pinPair "@baseboard_fab2_lib.baseboard_fab2(sch_1):\PP3933\"
				( pinRef "@baseboard_fab2_lib.baseboard_fab2(sch_1):page46_i14:S0_N" )
				( pinRef "@baseboard_fab2_lib.baseboard_fab2(sch_1):page24_i172:DDR1_CS_N(4)" )
				( attribute "RELATIVE_PROPAGATION_DELAY_SCOPE" "G"
					( Parent
						( matchGroupRef "@crescent_city_bb_fab1_lib.crescent_city_bb_fab1(sch_1):\MG_DDR_NEAR_DIMM-CLK1_CLS_DDR_B_CAC-CLKS\" )
					)
					( Status sCSetFlattened )
					( Origin gBackEnd )
				)
				( attribute "RELATIVE_PROPAGATION_DELAY" "0.00 MIL,300.00 MIL"
					( Parent
						( matchGroupRef "@crescent_city_bb_fab1_lib.crescent_city_bb_fab1(sch_1):\MG_DDR_NEAR_DIMM-CLK1_CLS_DDR_B_CAC-CLKS\" )
					)
					( Units "uMatchProp" "ns" 1.000000)
					( Status sCSetFlattened )
					( Origin gBackEnd )
				)
				( attribute "RELATIVE_PROPAGATION_DELAY_SCOPE" "G"
					( Parent
						( matchGroupRef "@baseboard_fab2_lib.baseboard_fab2(sch_1):\MG_DDR_CTRL_NG_DDR_B_DLL_20\" )
					)
					( Status sCSetFlattened )
					( Origin gBackEnd )
				)
				( attribute "RELATIVE_PROPAGATION_DELAY" "0.00 MIL,25.00 MIL"
					( Parent
						( matchGroupRef "@baseboard_fab2_lib.baseboard_fab2(sch_1):\MG_DDR_CTRL_NG_DDR_B_DLL_20\" )
					)
					( Units "uMatchProp" "ns" 1.000000)
					( Status sCSetFlattened )
					( Origin gBackEnd )
				)
			)
			( pinPair "@baseboard_fab2_lib.baseboard_fab2(sch_1):\PP3934\"
				( pinRef "@baseboard_fab2_lib.baseboard_fab2(sch_1):page24_i172:DDR1_ODT(2)" )
				( pinRef "@baseboard_fab2_lib.baseboard_fab2(sch_1):page46_i14:ODT(0)" )
				( attribute "RELATIVE_PROPAGATION_DELAY_SCOPE" "G"
					( Parent
						( matchGroupRef "@crescent_city_bb_fab1_lib.crescent_city_bb_fab1(sch_1):\MG_DDR_NEAR_DIMM-CLK1_CLS_DDR_B_CAC-CLKS\" )
					)
					( Status sCSetFlattened )
					( Origin gBackEnd )
				)
				( attribute "RELATIVE_PROPAGATION_DELAY" "0.00 MIL,300.00 MIL"
					( Parent
						( matchGroupRef "@crescent_city_bb_fab1_lib.crescent_city_bb_fab1(sch_1):\MG_DDR_NEAR_DIMM-CLK1_CLS_DDR_B_CAC-CLKS\" )
					)
					( Units "uMatchProp" "ns" 1.000000)
					( Status sCSetFlattened )
					( Origin gBackEnd )
				)
				( attribute "RELATIVE_PROPAGATION_DELAY_SCOPE" "G"
					( Parent
						( matchGroupRef "@baseboard_fab2_lib.baseboard_fab2(sch_1):\MG_DDR_CTRL_NG_DDR_B_DLL_20\" )
					)
					( Status sCSetFlattened )
					( Origin gBackEnd )
				)
				( attribute "RELATIVE_PROPAGATION_DELAY" "0.00 MIL,25.00 MIL"
					( Parent
						( matchGroupRef "@baseboard_fab2_lib.baseboard_fab2(sch_1):\MG_DDR_CTRL_NG_DDR_B_DLL_20\" )
					)
					( Units "uMatchProp" "ns" 1.000000)
					( Status sCSetFlattened )
					( Origin gBackEnd )
				)
			)
			( pinPair "@baseboard_fab2_lib.baseboard_fab2(sch_1):\PP3932\"
				( pinRef "@baseboard_fab2_lib.baseboard_fab2(sch_1):page24_i172:DDR1_CKE(2)" )
				( pinRef "@baseboard_fab2_lib.baseboard_fab2(sch_1):page46_i14:CKE(0)" )
				( attribute "RELATIVE_PROPAGATION_DELAY_SCOPE" "G"
					( Parent
						( matchGroupRef "@crescent_city_bb_fab1_lib.crescent_city_bb_fab1(sch_1):\MG_DDR_NEAR_DIMM-CLK1_CLS_DDR_B_CAC-CLKS\" )
					)
					( Status sCSetFlattened )
					( Origin gBackEnd )
				)
				( attribute "RELATIVE_PROPAGATION_DELAY" "0.00 MIL,300.00 MIL"
					( Parent
						( matchGroupRef "@crescent_city_bb_fab1_lib.crescent_city_bb_fab1(sch_1):\MG_DDR_NEAR_DIMM-CLK1_CLS_DDR_B_CAC-CLKS\" )
					)
					( Units "uMatchProp" "ns" 1.000000)
					( Status sCSetFlattened )
					( Origin gBackEnd )
				)
				( attribute "RELATIVE_PROPAGATION_DELAY_SCOPE" "G"
					( Parent
						( matchGroupRef "@baseboard_fab2_lib.baseboard_fab2(sch_1):\MG_DDR_CTRL_NG_DDR_B_DLL_21\" )
					)
					( Status sCSetFlattened )
					( Origin gBackEnd )
				)
				( attribute "RELATIVE_PROPAGATION_DELAY" "0.00 MIL,25.00 MIL"
					( Parent
						( matchGroupRef "@baseboard_fab2_lib.baseboard_fab2(sch_1):\MG_DDR_CTRL_NG_DDR_B_DLL_21\" )
					)
					( Units "uMatchProp" "ns" 1.000000)
					( Status sCSetFlattened )
					( Origin gBackEnd )
				)
			)
			( pinPair "@baseboard_fab2_lib.baseboard_fab2(sch_1):\PP3930\"
				( pinRef "@baseboard_fab2_lib.baseboard_fab2(sch_1):page46_i14:S2_N_C(0)" )
				( pinRef "@baseboard_fab2_lib.baseboard_fab2(sch_1):page24_i172:DDR1_CS_N(6)" )
				( attribute "RELATIVE_PROPAGATION_DELAY_SCOPE" "G"
					( Parent
						( matchGroupRef "@crescent_city_bb_fab1_lib.crescent_city_bb_fab1(sch_1):\MG_DDR_NEAR_DIMM-CLK1_CLS_DDR_B_CAC-CLKS\" )
					)
					( Status sCSetFlattened )
					( Origin gBackEnd )
				)
				( attribute "RELATIVE_PROPAGATION_DELAY" "0.00 MIL,300.00 MIL"
					( Parent
						( matchGroupRef "@crescent_city_bb_fab1_lib.crescent_city_bb_fab1(sch_1):\MG_DDR_NEAR_DIMM-CLK1_CLS_DDR_B_CAC-CLKS\" )
					)
					( Units "uMatchProp" "ns" 1.000000)
					( Status sCSetFlattened )
					( Origin gBackEnd )
				)
				( attribute "RELATIVE_PROPAGATION_DELAY_SCOPE" "G"
					( Parent
						( matchGroupRef "@baseboard_fab2_lib.baseboard_fab2(sch_1):\MG_DDR_CTRL_NG_DDR_B_DLL_22\" )
					)
					( Status sCSetFlattened )
					( Origin gBackEnd )
				)
				( attribute "RELATIVE_PROPAGATION_DELAY" "0.00 MIL,25.00 MIL"
					( Parent
						( matchGroupRef "@baseboard_fab2_lib.baseboard_fab2(sch_1):\MG_DDR_CTRL_NG_DDR_B_DLL_22\" )
					)
					( Units "uMatchProp" "ns" 1.000000)
					( Status sCSetFlattened )
					( Origin gBackEnd )
				)
			)
			( pinPair "@baseboard_fab2_lib.baseboard_fab2(sch_1):\PP3931\"
				( pinRef "@baseboard_fab2_lib.baseboard_fab2(sch_1):page46_i14:S3_N_C(1)" )
				( pinRef "@baseboard_fab2_lib.baseboard_fab2(sch_1):page24_i172:DDR1_CS_N(7)" )
				( attribute "RELATIVE_PROPAGATION_DELAY_SCOPE" "G"
					( Parent
						( matchGroupRef "@crescent_city_bb_fab1_lib.crescent_city_bb_fab1(sch_1):\MG_DDR_NEAR_DIMM-CLK1_CLS_DDR_B_CAC-CLKS\" )
					)
					( Status sCSetFlattened )
					( Origin gBackEnd )
				)
				( attribute "RELATIVE_PROPAGATION_DELAY" "0.00 MIL,300.00 MIL"
					( Parent
						( matchGroupRef "@crescent_city_bb_fab1_lib.crescent_city_bb_fab1(sch_1):\MG_DDR_NEAR_DIMM-CLK1_CLS_DDR_B_CAC-CLKS\" )
					)
					( Units "uMatchProp" "ns" 1.000000)
					( Status sCSetFlattened )
					( Origin gBackEnd )
				)
				( attribute "RELATIVE_PROPAGATION_DELAY_SCOPE" "G"
					( Parent
						( matchGroupRef "@baseboard_fab2_lib.baseboard_fab2(sch_1):\MG_DDR_CTRL_NG_DDR_B_DLL_22\" )
					)
					( Status sCSetFlattened )
					( Origin gBackEnd )
				)
				( attribute "RELATIVE_PROPAGATION_DELAY" "0.00 MIL,25.00 MIL"
					( Parent
						( matchGroupRef "@baseboard_fab2_lib.baseboard_fab2(sch_1):\MG_DDR_CTRL_NG_DDR_B_DLL_22\" )
					)
					( Units "uMatchProp" "ns" 1.000000)
					( Status sCSetFlattened )
					( Origin gBackEnd )
				)
			)
			( pinPair "@baseboard_fab2_lib.baseboard_fab2(sch_1):\PP3928\"
				( pinRef "@baseboard_fab2_lib.baseboard_fab2(sch_1):page46_i14:S1_N" )
				( pinRef "@baseboard_fab2_lib.baseboard_fab2(sch_1):page24_i172:DDR1_CS_N(5)" )
				( attribute "RELATIVE_PROPAGATION_DELAY_SCOPE" "G"
					( Parent
						( matchGroupRef "@crescent_city_bb_fab1_lib.crescent_city_bb_fab1(sch_1):\MG_DDR_NEAR_DIMM-CLK1_CLS_DDR_B_CAC-CLKS\" )
					)
					( Status sCSetFlattened )
					( Origin gBackEnd )
				)
				( attribute "RELATIVE_PROPAGATION_DELAY" "0.00 MIL,300.00 MIL"
					( Parent
						( matchGroupRef "@crescent_city_bb_fab1_lib.crescent_city_bb_fab1(sch_1):\MG_DDR_NEAR_DIMM-CLK1_CLS_DDR_B_CAC-CLKS\" )
					)
					( Units "uMatchProp" "ns" 1.000000)
					( Status sCSetFlattened )
					( Origin gBackEnd )
				)
				( attribute "RELATIVE_PROPAGATION_DELAY_SCOPE" "G"
					( Parent
						( matchGroupRef "@baseboard_fab2_lib.baseboard_fab2(sch_1):\MG_DDR_CTRL_NG_DDR_B_DLL_23\" )
					)
					( Status sCSetFlattened )
					( Origin gBackEnd )
				)
				( attribute "RELATIVE_PROPAGATION_DELAY" "0.00 MIL,25.00 MIL"
					( Parent
						( matchGroupRef "@baseboard_fab2_lib.baseboard_fab2(sch_1):\MG_DDR_CTRL_NG_DDR_B_DLL_23\" )
					)
					( Units "uMatchProp" "ns" 1.000000)
					( Status sCSetFlattened )
					( Origin gBackEnd )
				)
			)
			( pinPair "@baseboard_fab2_lib.baseboard_fab2(sch_1):\PP3929\"
				( pinRef "@baseboard_fab2_lib.baseboard_fab2(sch_1):page46_i14:ODT(1)" )
				( pinRef "@baseboard_fab2_lib.baseboard_fab2(sch_1):page24_i172:DDR1_ODT(3)" )
				( attribute "RELATIVE_PROPAGATION_DELAY_SCOPE" "G"
					( Parent
						( matchGroupRef "@crescent_city_bb_fab1_lib.crescent_city_bb_fab1(sch_1):\MG_DDR_NEAR_DIMM-CLK1_CLS_DDR_B_CAC-CLKS\" )
					)
					( Status sCSetFlattened )
					( Origin gBackEnd )
				)
				( attribute "RELATIVE_PROPAGATION_DELAY" "0.00 MIL,300.00 MIL"
					( Parent
						( matchGroupRef "@crescent_city_bb_fab1_lib.crescent_city_bb_fab1(sch_1):\MG_DDR_NEAR_DIMM-CLK1_CLS_DDR_B_CAC-CLKS\" )
					)
					( Units "uMatchProp" "ns" 1.000000)
					( Status sCSetFlattened )
					( Origin gBackEnd )
				)
				( attribute "RELATIVE_PROPAGATION_DELAY_SCOPE" "G"
					( Parent
						( matchGroupRef "@baseboard_fab2_lib.baseboard_fab2(sch_1):\MG_DDR_CTRL_NG_DDR_B_DLL_23\" )
					)
					( Status sCSetFlattened )
					( Origin gBackEnd )
				)
				( attribute "RELATIVE_PROPAGATION_DELAY" "0.00 MIL,25.00 MIL"
					( Parent
						( matchGroupRef "@baseboard_fab2_lib.baseboard_fab2(sch_1):\MG_DDR_CTRL_NG_DDR_B_DLL_23\" )
					)
					( Units "uMatchProp" "ns" 1.000000)
					( Status sCSetFlattened )
					( Origin gBackEnd )
				)
			)
			( pinPair "@baseboard_fab2_lib.baseboard_fab2(sch_1):\PP3927\"
				( pinRef "@baseboard_fab2_lib.baseboard_fab2(sch_1):page46_i14:CKE(1)" )
				( pinRef "@baseboard_fab2_lib.baseboard_fab2(sch_1):page24_i172:DDR1_CKE(3)" )
				( attribute "RELATIVE_PROPAGATION_DELAY_SCOPE" "G"
					( Parent
						( matchGroupRef "@crescent_city_bb_fab1_lib.crescent_city_bb_fab1(sch_1):\MG_DDR_NEAR_DIMM-CLK1_CLS_DDR_B_CAC-CLKS\" )
					)
					( Status sCSetFlattened )
					( Origin gBackEnd )
				)
				( attribute "RELATIVE_PROPAGATION_DELAY" "0.00 MIL,300.00 MIL"
					( Parent
						( matchGroupRef "@crescent_city_bb_fab1_lib.crescent_city_bb_fab1(sch_1):\MG_DDR_NEAR_DIMM-CLK1_CLS_DDR_B_CAC-CLKS\" )
					)
					( Units "uMatchProp" "ns" 1.000000)
					( Status sCSetFlattened )
					( Origin gBackEnd )
				)
				( attribute "RELATIVE_PROPAGATION_DELAY_SCOPE" "G"
					( Parent
						( matchGroupRef "@baseboard_fab2_lib.baseboard_fab2(sch_1):\MG_DDR_CTRL_NG_DDR_B_DLL_24\" )
					)
					( Status sCSetFlattened )
					( Origin gBackEnd )
				)
				( attribute "RELATIVE_PROPAGATION_DELAY" "0.00 MIL,25.00 MIL"
					( Parent
						( matchGroupRef "@baseboard_fab2_lib.baseboard_fab2(sch_1):\MG_DDR_CTRL_NG_DDR_B_DLL_24\" )
					)
					( Units "uMatchProp" "ns" 1.000000)
					( Status sCSetFlattened )
					( Origin gBackEnd )
				)
			)
			( pinPair "@baseboard_fab2_lib.baseboard_fab2(sch_1):\PP4055\"
				( pinRef "@baseboard_fab2_lib.baseboard_fab2(sch_1):page23_i172:DDR0_CID(2)" )
				( pinRef "@baseboard_fab2_lib.baseboard_fab2(sch_1):page43_i1:C(2)" )
				( attribute "RELATIVE_PROPAGATION_DELAY_SCOPE" "G"
					( Parent
						( matchGroupRef "@baseboard_fab2_lib.baseboard_fab2(sch_1):\MG_DDR_FAR_DIMM_CMD_NG_DDR_A_DLL_1\" )
					)
					( Status sCSetFlattened )
					( Origin gBackEnd )
				)
				( attribute "RELATIVE_PROPAGATION_DELAY" "0.00 MIL,25.00 MIL"
					( Parent
						( matchGroupRef "@baseboard_fab2_lib.baseboard_fab2(sch_1):\MG_DDR_FAR_DIMM_CMD_NG_DDR_A_DLL_1\" )
					)
					( Units "uMatchProp" "ns" 1.000000)
					( Status sCSetFlattened )
					( Origin gBackEnd )
				)
				( attribute "RELATIVE_PROPAGATION_DELAY_SCOPE" "G"
					( Parent
						( matchGroupRef "@crescent_city_bb_fab1_lib.crescent_city_bb_fab1(sch_1):\MG_DDR_FAR_DIMM-CLK0_CLS_DDR_A_CAC-CLKS\" )
					)
					( Status sCSetFlattened )
					( Origin gBackEnd )
				)
				( attribute "RELATIVE_PROPAGATION_DELAY" "0.00 MIL,700.00 MIL"
					( Parent
						( matchGroupRef "@crescent_city_bb_fab1_lib.crescent_city_bb_fab1(sch_1):\MG_DDR_FAR_DIMM-CLK0_CLS_DDR_A_CAC-CLKS\" )
					)
					( Units "uMatchProp" "ns" 1.000000)
					( Status sCSetFlattened )
					( Origin gBackEnd )
				)
			)
			( pinPair "@baseboard_fab2_lib.baseboard_fab2(sch_1):\PP4056\"
				( pinRef "@baseboard_fab2_lib.baseboard_fab2(sch_1):page23_i172:DDR0_CID(2)" )
				( pinRef "@baseboard_fab2_lib.baseboard_fab2(sch_1):page44_i13:C(2)" )
				( attribute "RELATIVE_PROPAGATION_DELAY_SCOPE" "G"
					( Parent
						( matchGroupRef "@crescent_city_bb_fab1_lib.crescent_city_bb_fab1(sch_1):\MG_DDR_NEAR_DIMM-CLK1_CLS_DDR_A_CAC-CLKS\" )
					)
					( Status sCSetFlattened )
					( Origin gBackEnd )
				)
				( attribute "RELATIVE_PROPAGATION_DELAY" "0.00 MIL,700.00 MIL"
					( Parent
						( matchGroupRef "@crescent_city_bb_fab1_lib.crescent_city_bb_fab1(sch_1):\MG_DDR_NEAR_DIMM-CLK1_CLS_DDR_A_CAC-CLKS\" )
					)
					( Units "uMatchProp" "ns" 1.000000)
					( Status sCSetFlattened )
					( Origin gBackEnd )
				)
				( attribute "RELATIVE_PROPAGATION_DELAY_SCOPE" "G"
					( Parent
						( matchGroupRef "@baseboard_fab2_lib.baseboard_fab2(sch_1):\MG_DDR_CMD_NEAR_DIMM_NG_DDR_A_DLL_1\" )
					)
					( Status sCSetFlattened )
					( Origin gBackEnd )
				)
				( attribute "RELATIVE_PROPAGATION_DELAY" "0.00 MIL,25.00 MIL"
					( Parent
						( matchGroupRef "@baseboard_fab2_lib.baseboard_fab2(sch_1):\MG_DDR_CMD_NEAR_DIMM_NG_DDR_A_DLL_1\" )
					)
					( Units "uMatchProp" "ns" 1.000000)
					( Status sCSetFlattened )
					( Origin gBackEnd )
				)
			)
			( pinPair "@baseboard_fab2_lib.baseboard_fab2(sch_1):\PP4057\"
				( pinRef "@baseboard_fab2_lib.baseboard_fab2(sch_1):page23_i172:DDR0_MA(17)" )
				( pinRef "@baseboard_fab2_lib.baseboard_fab2(sch_1):page43_i1:A17" )
				( attribute "RELATIVE_PROPAGATION_DELAY_SCOPE" "G"
					( Parent
						( matchGroupRef "@baseboard_fab2_lib.baseboard_fab2(sch_1):\MG_DDR_FAR_DIMM_CMD_NG_DDR_A_DLL_1\" )
					)
					( Status sCSetFlattened )
					( Origin gBackEnd )
				)
				( attribute "RELATIVE_PROPAGATION_DELAY" "0.00 MIL,25.00 MIL"
					( Parent
						( matchGroupRef "@baseboard_fab2_lib.baseboard_fab2(sch_1):\MG_DDR_FAR_DIMM_CMD_NG_DDR_A_DLL_1\" )
					)
					( Units "uMatchProp" "ns" 1.000000)
					( Status sCSetFlattened )
					( Origin gBackEnd )
				)
				( attribute "RELATIVE_PROPAGATION_DELAY_SCOPE" "G"
					( Parent
						( matchGroupRef "@crescent_city_bb_fab1_lib.crescent_city_bb_fab1(sch_1):\MG_DDR_FAR_DIMM-CLK0_CLS_DDR_A_CAC-CLKS\" )
					)
					( Status sCSetFlattened )
					( Origin gBackEnd )
				)
				( attribute "RELATIVE_PROPAGATION_DELAY" "0.00 MIL,700.00 MIL"
					( Parent
						( matchGroupRef "@crescent_city_bb_fab1_lib.crescent_city_bb_fab1(sch_1):\MG_DDR_FAR_DIMM-CLK0_CLS_DDR_A_CAC-CLKS\" )
					)
					( Units "uMatchProp" "ns" 1.000000)
					( Status sCSetFlattened )
					( Origin gBackEnd )
				)
			)
			( pinPair "@baseboard_fab2_lib.baseboard_fab2(sch_1):\PP4058\"
				( pinRef "@baseboard_fab2_lib.baseboard_fab2(sch_1):page23_i172:DDR0_MA(17)" )
				( pinRef "@baseboard_fab2_lib.baseboard_fab2(sch_1):page44_i13:A17" )
				( attribute "RELATIVE_PROPAGATION_DELAY_SCOPE" "G"
					( Parent
						( matchGroupRef "@crescent_city_bb_fab1_lib.crescent_city_bb_fab1(sch_1):\MG_DDR_NEAR_DIMM-CLK1_CLS_DDR_A_CAC-CLKS\" )
					)
					( Status sCSetFlattened )
					( Origin gBackEnd )
				)
				( attribute "RELATIVE_PROPAGATION_DELAY" "0.00 MIL,700.00 MIL"
					( Parent
						( matchGroupRef "@crescent_city_bb_fab1_lib.crescent_city_bb_fab1(sch_1):\MG_DDR_NEAR_DIMM-CLK1_CLS_DDR_A_CAC-CLKS\" )
					)
					( Units "uMatchProp" "ns" 1.000000)
					( Status sCSetFlattened )
					( Origin gBackEnd )
				)
				( attribute "RELATIVE_PROPAGATION_DELAY_SCOPE" "G"
					( Parent
						( matchGroupRef "@baseboard_fab2_lib.baseboard_fab2(sch_1):\MG_DDR_CMD_NEAR_DIMM_NG_DDR_A_DLL_1\" )
					)
					( Status sCSetFlattened )
					( Origin gBackEnd )
				)
				( attribute "RELATIVE_PROPAGATION_DELAY" "0.00 MIL,25.00 MIL"
					( Parent
						( matchGroupRef "@baseboard_fab2_lib.baseboard_fab2(sch_1):\MG_DDR_CMD_NEAR_DIMM_NG_DDR_A_DLL_1\" )
					)
					( Units "uMatchProp" "ns" 1.000000)
					( Status sCSetFlattened )
					( Origin gBackEnd )
				)
			)
			( pinPair "@baseboard_fab2_lib.baseboard_fab2(sch_1):\PP4051\"
				( pinRef "@baseboard_fab2_lib.baseboard_fab2(sch_1):page23_i172:DDR0_MA(13)" )
				( pinRef "@baseboard_fab2_lib.baseboard_fab2(sch_1):page43_i1:A13" )
				( attribute "RELATIVE_PROPAGATION_DELAY_SCOPE" "G"
					( Parent
						( matchGroupRef "@crescent_city_bb_fab1_lib.crescent_city_bb_fab1(sch_1):\MG_DDR_FAR_DIMM-CLK0_CLS_DDR_A_CAC-CLKS\" )
					)
					( Status sCSetFlattened )
					( Origin gBackEnd )
				)
				( attribute "RELATIVE_PROPAGATION_DELAY" "0.00 MIL,700.00 MIL"
					( Parent
						( matchGroupRef "@crescent_city_bb_fab1_lib.crescent_city_bb_fab1(sch_1):\MG_DDR_FAR_DIMM-CLK0_CLS_DDR_A_CAC-CLKS\" )
					)
					( Units "uMatchProp" "ns" 1.000000)
					( Status sCSetFlattened )
					( Origin gBackEnd )
				)
				( attribute "RELATIVE_PROPAGATION_DELAY_SCOPE" "G"
					( Parent
						( matchGroupRef "@baseboard_fab2_lib.baseboard_fab2(sch_1):\MG_DDR_FAR_DIMM_CMD_NG_DDR_A_DLL_2\" )
					)
					( Status sCSetFlattened )
					( Origin gBackEnd )
				)
				( attribute "RELATIVE_PROPAGATION_DELAY" "0.00 MIL,25.00 MIL"
					( Parent
						( matchGroupRef "@baseboard_fab2_lib.baseboard_fab2(sch_1):\MG_DDR_FAR_DIMM_CMD_NG_DDR_A_DLL_2\" )
					)
					( Units "uMatchProp" "ns" 1.000000)
					( Status sCSetFlattened )
					( Origin gBackEnd )
				)
			)
			( pinPair "@baseboard_fab2_lib.baseboard_fab2(sch_1):\PP4052\"
				( pinRef "@baseboard_fab2_lib.baseboard_fab2(sch_1):page23_i172:DDR0_MA(13)" )
				( pinRef "@baseboard_fab2_lib.baseboard_fab2(sch_1):page44_i13:A13" )
				( attribute "RELATIVE_PROPAGATION_DELAY_SCOPE" "G"
					( Parent
						( matchGroupRef "@crescent_city_bb_fab1_lib.crescent_city_bb_fab1(sch_1):\MG_DDR_NEAR_DIMM-CLK1_CLS_DDR_A_CAC-CLKS\" )
					)
					( Status sCSetFlattened )
					( Origin gBackEnd )
				)
				( attribute "RELATIVE_PROPAGATION_DELAY" "0.00 MIL,700.00 MIL"
					( Parent
						( matchGroupRef "@crescent_city_bb_fab1_lib.crescent_city_bb_fab1(sch_1):\MG_DDR_NEAR_DIMM-CLK1_CLS_DDR_A_CAC-CLKS\" )
					)
					( Units "uMatchProp" "ns" 1.000000)
					( Status sCSetFlattened )
					( Origin gBackEnd )
				)
				( attribute "RELATIVE_PROPAGATION_DELAY_SCOPE" "G"
					( Parent
						( matchGroupRef "@baseboard_fab2_lib.baseboard_fab2(sch_1):\MG_DDR_CMD_NEAR_DIMM_NG_DDR_A_DLL_2\" )
					)
					( Status sCSetFlattened )
					( Origin gBackEnd )
				)
				( attribute "RELATIVE_PROPAGATION_DELAY" "0.00 MIL,25.00 MIL"
					( Parent
						( matchGroupRef "@baseboard_fab2_lib.baseboard_fab2(sch_1):\MG_DDR_CMD_NEAR_DIMM_NG_DDR_A_DLL_2\" )
					)
					( Units "uMatchProp" "ns" 1.000000)
					( Status sCSetFlattened )
					( Origin gBackEnd )
				)
			)
			( pinPair "@baseboard_fab2_lib.baseboard_fab2(sch_1):\PP4053\"
				( pinRef "@baseboard_fab2_lib.baseboard_fab2(sch_1):page23_i172:DDR0_MA(15)" )
				( pinRef "@baseboard_fab2_lib.baseboard_fab2(sch_1):page43_i1:A15_CAS_N" )
				( attribute "RELATIVE_PROPAGATION_DELAY_SCOPE" "G"
					( Parent
						( matchGroupRef "@crescent_city_bb_fab1_lib.crescent_city_bb_fab1(sch_1):\MG_DDR_FAR_DIMM-CLK0_CLS_DDR_A_CAC-CLKS\" )
					)
					( Status sCSetFlattened )
					( Origin gBackEnd )
				)
				( attribute "RELATIVE_PROPAGATION_DELAY" "0.00 MIL,700.00 MIL"
					( Parent
						( matchGroupRef "@crescent_city_bb_fab1_lib.crescent_city_bb_fab1(sch_1):\MG_DDR_FAR_DIMM-CLK0_CLS_DDR_A_CAC-CLKS\" )
					)
					( Units "uMatchProp" "ns" 1.000000)
					( Status sCSetFlattened )
					( Origin gBackEnd )
				)
				( attribute "RELATIVE_PROPAGATION_DELAY_SCOPE" "G"
					( Parent
						( matchGroupRef "@baseboard_fab2_lib.baseboard_fab2(sch_1):\MG_DDR_FAR_DIMM_CMD_NG_DDR_A_DLL_2\" )
					)
					( Status sCSetFlattened )
					( Origin gBackEnd )
				)
				( attribute "RELATIVE_PROPAGATION_DELAY" "0.00 MIL,25.00 MIL"
					( Parent
						( matchGroupRef "@baseboard_fab2_lib.baseboard_fab2(sch_1):\MG_DDR_FAR_DIMM_CMD_NG_DDR_A_DLL_2\" )
					)
					( Units "uMatchProp" "ns" 1.000000)
					( Status sCSetFlattened )
					( Origin gBackEnd )
				)
			)
			( pinPair "@baseboard_fab2_lib.baseboard_fab2(sch_1):\PP4054\"
				( pinRef "@baseboard_fab2_lib.baseboard_fab2(sch_1):page23_i172:DDR0_MA(15)" )
				( pinRef "@baseboard_fab2_lib.baseboard_fab2(sch_1):page44_i13:A15_CAS_N" )
				( attribute "RELATIVE_PROPAGATION_DELAY_SCOPE" "G"
					( Parent
						( matchGroupRef "@crescent_city_bb_fab1_lib.crescent_city_bb_fab1(sch_1):\MG_DDR_NEAR_DIMM-CLK1_CLS_DDR_A_CAC-CLKS\" )
					)
					( Status sCSetFlattened )
					( Origin gBackEnd )
				)
				( attribute "RELATIVE_PROPAGATION_DELAY" "0.00 MIL,700.00 MIL"
					( Parent
						( matchGroupRef "@crescent_city_bb_fab1_lib.crescent_city_bb_fab1(sch_1):\MG_DDR_NEAR_DIMM-CLK1_CLS_DDR_A_CAC-CLKS\" )
					)
					( Units "uMatchProp" "ns" 1.000000)
					( Status sCSetFlattened )
					( Origin gBackEnd )
				)
				( attribute "RELATIVE_PROPAGATION_DELAY_SCOPE" "G"
					( Parent
						( matchGroupRef "@baseboard_fab2_lib.baseboard_fab2(sch_1):\MG_DDR_CMD_NEAR_DIMM_NG_DDR_A_DLL_2\" )
					)
					( Status sCSetFlattened )
					( Origin gBackEnd )
				)
				( attribute "RELATIVE_PROPAGATION_DELAY" "0.00 MIL,25.00 MIL"
					( Parent
						( matchGroupRef "@baseboard_fab2_lib.baseboard_fab2(sch_1):\MG_DDR_CMD_NEAR_DIMM_NG_DDR_A_DLL_2\" )
					)
					( Units "uMatchProp" "ns" 1.000000)
					( Status sCSetFlattened )
					( Origin gBackEnd )
				)
			)
			( pinPair "@baseboard_fab2_lib.baseboard_fab2(sch_1):\PP4047\"
				( pinRef "@baseboard_fab2_lib.baseboard_fab2(sch_1):page23_i172:DDR0_MA(14)" )
				( pinRef "@baseboard_fab2_lib.baseboard_fab2(sch_1):page43_i1:A14_WE_N" )
				( attribute "RELATIVE_PROPAGATION_DELAY_SCOPE" "G"
					( Parent
						( matchGroupRef "@crescent_city_bb_fab1_lib.crescent_city_bb_fab1(sch_1):\MG_DDR_FAR_DIMM-CLK0_CLS_DDR_A_CAC-CLKS\" )
					)
					( Status sCSetFlattened )
					( Origin gBackEnd )
				)
				( attribute "RELATIVE_PROPAGATION_DELAY" "0.00 MIL,700.00 MIL"
					( Parent
						( matchGroupRef "@crescent_city_bb_fab1_lib.crescent_city_bb_fab1(sch_1):\MG_DDR_FAR_DIMM-CLK0_CLS_DDR_A_CAC-CLKS\" )
					)
					( Units "uMatchProp" "ns" 1.000000)
					( Status sCSetFlattened )
					( Origin gBackEnd )
				)
				( attribute "RELATIVE_PROPAGATION_DELAY_SCOPE" "G"
					( Parent
						( matchGroupRef "@baseboard_fab2_lib.baseboard_fab2(sch_1):\MG_DDR_FAR_DIMM_CMD_NG_DDR_A_DLL_3\" )
					)
					( Status sCSetFlattened )
					( Origin gBackEnd )
				)
				( attribute "RELATIVE_PROPAGATION_DELAY" "0.00 MIL,25.00 MIL"
					( Parent
						( matchGroupRef "@baseboard_fab2_lib.baseboard_fab2(sch_1):\MG_DDR_FAR_DIMM_CMD_NG_DDR_A_DLL_3\" )
					)
					( Units "uMatchProp" "ns" 1.000000)
					( Status sCSetFlattened )
					( Origin gBackEnd )
				)
			)
			( pinPair "@baseboard_fab2_lib.baseboard_fab2(sch_1):\PP4048\"
				( pinRef "@baseboard_fab2_lib.baseboard_fab2(sch_1):page44_i13:A14_WE_N" )
				( pinRef "@baseboard_fab2_lib.baseboard_fab2(sch_1):page23_i172:DDR0_MA(14)" )
				( attribute "RELATIVE_PROPAGATION_DELAY_SCOPE" "G"
					( Parent
						( matchGroupRef "@crescent_city_bb_fab1_lib.crescent_city_bb_fab1(sch_1):\MG_DDR_NEAR_DIMM-CLK1_CLS_DDR_A_CAC-CLKS\" )
					)
					( Status sCSetFlattened )
					( Origin gBackEnd )
				)
				( attribute "RELATIVE_PROPAGATION_DELAY" "0.00 MIL,700.00 MIL"
					( Parent
						( matchGroupRef "@crescent_city_bb_fab1_lib.crescent_city_bb_fab1(sch_1):\MG_DDR_NEAR_DIMM-CLK1_CLS_DDR_A_CAC-CLKS\" )
					)
					( Units "uMatchProp" "ns" 1.000000)
					( Status sCSetFlattened )
					( Origin gBackEnd )
				)
				( attribute "RELATIVE_PROPAGATION_DELAY_SCOPE" "G"
					( Parent
						( matchGroupRef "@baseboard_fab2_lib.baseboard_fab2(sch_1):\MG_DDR_CMD_NEAR_DIMM_NG_DDR_A_DLL_3\" )
					)
					( Status sCSetFlattened )
					( Origin gBackEnd )
				)
				( attribute "RELATIVE_PROPAGATION_DELAY" "0.00 MIL,25.00 MIL"
					( Parent
						( matchGroupRef "@baseboard_fab2_lib.baseboard_fab2(sch_1):\MG_DDR_CMD_NEAR_DIMM_NG_DDR_A_DLL_3\" )
					)
					( Units "uMatchProp" "ns" 1.000000)
					( Status sCSetFlattened )
					( Origin gBackEnd )
				)
			)
			( pinPair "@baseboard_fab2_lib.baseboard_fab2(sch_1):\PP4049\"
				( pinRef "@baseboard_fab2_lib.baseboard_fab2(sch_1):page23_i172:DDR0_MA(16)" )
				( pinRef "@baseboard_fab2_lib.baseboard_fab2(sch_1):page43_i1:A16_RAS_N" )
				( attribute "RELATIVE_PROPAGATION_DELAY_SCOPE" "G"
					( Parent
						( matchGroupRef "@crescent_city_bb_fab1_lib.crescent_city_bb_fab1(sch_1):\MG_DDR_FAR_DIMM-CLK0_CLS_DDR_A_CAC-CLKS\" )
					)
					( Status sCSetFlattened )
					( Origin gBackEnd )
				)
				( attribute "RELATIVE_PROPAGATION_DELAY" "0.00 MIL,700.00 MIL"
					( Parent
						( matchGroupRef "@crescent_city_bb_fab1_lib.crescent_city_bb_fab1(sch_1):\MG_DDR_FAR_DIMM-CLK0_CLS_DDR_A_CAC-CLKS\" )
					)
					( Units "uMatchProp" "ns" 1.000000)
					( Status sCSetFlattened )
					( Origin gBackEnd )
				)
				( attribute "RELATIVE_PROPAGATION_DELAY_SCOPE" "G"
					( Parent
						( matchGroupRef "@baseboard_fab2_lib.baseboard_fab2(sch_1):\MG_DDR_FAR_DIMM_CMD_NG_DDR_A_DLL_3\" )
					)
					( Status sCSetFlattened )
					( Origin gBackEnd )
				)
				( attribute "RELATIVE_PROPAGATION_DELAY" "0.00 MIL,25.00 MIL"
					( Parent
						( matchGroupRef "@baseboard_fab2_lib.baseboard_fab2(sch_1):\MG_DDR_FAR_DIMM_CMD_NG_DDR_A_DLL_3\" )
					)
					( Units "uMatchProp" "ns" 1.000000)
					( Status sCSetFlattened )
					( Origin gBackEnd )
				)
			)
			( pinPair "@baseboard_fab2_lib.baseboard_fab2(sch_1):\PP4050\"
				( pinRef "@baseboard_fab2_lib.baseboard_fab2(sch_1):page23_i172:DDR0_MA(16)" )
				( pinRef "@baseboard_fab2_lib.baseboard_fab2(sch_1):page44_i13:A16_RAS_N" )
				( attribute "RELATIVE_PROPAGATION_DELAY_SCOPE" "G"
					( Parent
						( matchGroupRef "@crescent_city_bb_fab1_lib.crescent_city_bb_fab1(sch_1):\MG_DDR_NEAR_DIMM-CLK1_CLS_DDR_A_CAC-CLKS\" )
					)
					( Status sCSetFlattened )
					( Origin gBackEnd )
				)
				( attribute "RELATIVE_PROPAGATION_DELAY" "0.00 MIL,700.00 MIL"
					( Parent
						( matchGroupRef "@crescent_city_bb_fab1_lib.crescent_city_bb_fab1(sch_1):\MG_DDR_NEAR_DIMM-CLK1_CLS_DDR_A_CAC-CLKS\" )
					)
					( Units "uMatchProp" "ns" 1.000000)
					( Status sCSetFlattened )
					( Origin gBackEnd )
				)
				( attribute "RELATIVE_PROPAGATION_DELAY_SCOPE" "G"
					( Parent
						( matchGroupRef "@baseboard_fab2_lib.baseboard_fab2(sch_1):\MG_DDR_CMD_NEAR_DIMM_NG_DDR_A_DLL_3\" )
					)
					( Status sCSetFlattened )
					( Origin gBackEnd )
				)
				( attribute "RELATIVE_PROPAGATION_DELAY" "0.00 MIL,25.00 MIL"
					( Parent
						( matchGroupRef "@baseboard_fab2_lib.baseboard_fab2(sch_1):\MG_DDR_CMD_NEAR_DIMM_NG_DDR_A_DLL_3\" )
					)
					( Units "uMatchProp" "ns" 1.000000)
					( Status sCSetFlattened )
					( Origin gBackEnd )
				)
			)
			( pinPair "@baseboard_fab2_lib.baseboard_fab2(sch_1):\PP4043\"
				( pinRef "@baseboard_fab2_lib.baseboard_fab2(sch_1):page23_i172:DDR0_MA(10)" )
				( pinRef "@baseboard_fab2_lib.baseboard_fab2(sch_1):page43_i1:A10" )
				( attribute "RELATIVE_PROPAGATION_DELAY_SCOPE" "G"
					( Parent
						( matchGroupRef "@crescent_city_bb_fab1_lib.crescent_city_bb_fab1(sch_1):\MG_DDR_FAR_DIMM-CLK0_CLS_DDR_A_CAC-CLKS\" )
					)
					( Status sCSetFlattened )
					( Origin gBackEnd )
				)
				( attribute "RELATIVE_PROPAGATION_DELAY" "0.00 MIL,700.00 MIL"
					( Parent
						( matchGroupRef "@crescent_city_bb_fab1_lib.crescent_city_bb_fab1(sch_1):\MG_DDR_FAR_DIMM-CLK0_CLS_DDR_A_CAC-CLKS\" )
					)
					( Units "uMatchProp" "ns" 1.000000)
					( Status sCSetFlattened )
					( Origin gBackEnd )
				)
				( attribute "RELATIVE_PROPAGATION_DELAY_SCOPE" "G"
					( Parent
						( matchGroupRef "@baseboard_fab2_lib.baseboard_fab2(sch_1):\MG_DDR_FAR_DIMM_CMD_NG_DDR_A_DLL_4\" )
					)
					( Status sCSetFlattened )
					( Origin gBackEnd )
				)
				( attribute "RELATIVE_PROPAGATION_DELAY" "0.00 MIL,25.00 MIL"
					( Parent
						( matchGroupRef "@baseboard_fab2_lib.baseboard_fab2(sch_1):\MG_DDR_FAR_DIMM_CMD_NG_DDR_A_DLL_4\" )
					)
					( Units "uMatchProp" "ns" 1.000000)
					( Status sCSetFlattened )
					( Origin gBackEnd )
				)
			)
			( pinPair "@baseboard_fab2_lib.baseboard_fab2(sch_1):\PP4044\"
				( pinRef "@baseboard_fab2_lib.baseboard_fab2(sch_1):page23_i172:DDR0_MA(10)" )
				( pinRef "@baseboard_fab2_lib.baseboard_fab2(sch_1):page44_i13:A10" )
				( attribute "RELATIVE_PROPAGATION_DELAY_SCOPE" "G"
					( Parent
						( matchGroupRef "@crescent_city_bb_fab1_lib.crescent_city_bb_fab1(sch_1):\MG_DDR_NEAR_DIMM-CLK1_CLS_DDR_A_CAC-CLKS\" )
					)
					( Status sCSetFlattened )
					( Origin gBackEnd )
				)
				( attribute "RELATIVE_PROPAGATION_DELAY" "0.00 MIL,700.00 MIL"
					( Parent
						( matchGroupRef "@crescent_city_bb_fab1_lib.crescent_city_bb_fab1(sch_1):\MG_DDR_NEAR_DIMM-CLK1_CLS_DDR_A_CAC-CLKS\" )
					)
					( Units "uMatchProp" "ns" 1.000000)
					( Status sCSetFlattened )
					( Origin gBackEnd )
				)
				( attribute "RELATIVE_PROPAGATION_DELAY_SCOPE" "G"
					( Parent
						( matchGroupRef "@baseboard_fab2_lib.baseboard_fab2(sch_1):\MG_DDR_CMD_NEAR_DIMM_NG_DDR_A_DLL_4\" )
					)
					( Status sCSetFlattened )
					( Origin gBackEnd )
				)
				( attribute "RELATIVE_PROPAGATION_DELAY" "0.00 MIL,25.00 MIL"
					( Parent
						( matchGroupRef "@baseboard_fab2_lib.baseboard_fab2(sch_1):\MG_DDR_CMD_NEAR_DIMM_NG_DDR_A_DLL_4\" )
					)
					( Units "uMatchProp" "ns" 1.000000)
					( Status sCSetFlattened )
					( Origin gBackEnd )
				)
			)
			( pinPair "@baseboard_fab2_lib.baseboard_fab2(sch_1):\PP4045\"
				( pinRef "@baseboard_fab2_lib.baseboard_fab2(sch_1):page23_i172:DDR0_BA(1)" )
				( pinRef "@baseboard_fab2_lib.baseboard_fab2(sch_1):page43_i1:BA(1)" )
				( attribute "RELATIVE_PROPAGATION_DELAY_SCOPE" "G"
					( Parent
						( matchGroupRef "@crescent_city_bb_fab1_lib.crescent_city_bb_fab1(sch_1):\MG_DDR_FAR_DIMM-CLK0_CLS_DDR_A_CAC-CLKS\" )
					)
					( Status sCSetFlattened )
					( Origin gBackEnd )
				)
				( attribute "RELATIVE_PROPAGATION_DELAY" "0.00 MIL,700.00 MIL"
					( Parent
						( matchGroupRef "@crescent_city_bb_fab1_lib.crescent_city_bb_fab1(sch_1):\MG_DDR_FAR_DIMM-CLK0_CLS_DDR_A_CAC-CLKS\" )
					)
					( Units "uMatchProp" "ns" 1.000000)
					( Status sCSetFlattened )
					( Origin gBackEnd )
				)
				( attribute "RELATIVE_PROPAGATION_DELAY_SCOPE" "G"
					( Parent
						( matchGroupRef "@baseboard_fab2_lib.baseboard_fab2(sch_1):\MG_DDR_FAR_DIMM_CMD_NG_DDR_A_DLL_4\" )
					)
					( Status sCSetFlattened )
					( Origin gBackEnd )
				)
				( attribute "RELATIVE_PROPAGATION_DELAY" "0.00 MIL,25.00 MIL"
					( Parent
						( matchGroupRef "@baseboard_fab2_lib.baseboard_fab2(sch_1):\MG_DDR_FAR_DIMM_CMD_NG_DDR_A_DLL_4\" )
					)
					( Units "uMatchProp" "ns" 1.000000)
					( Status sCSetFlattened )
					( Origin gBackEnd )
				)
			)
			( pinPair "@baseboard_fab2_lib.baseboard_fab2(sch_1):\PP4046\"
				( pinRef "@baseboard_fab2_lib.baseboard_fab2(sch_1):page44_i13:BA(1)" )
				( pinRef "@baseboard_fab2_lib.baseboard_fab2(sch_1):page23_i172:DDR0_BA(1)" )
				( attribute "RELATIVE_PROPAGATION_DELAY_SCOPE" "G"
					( Parent
						( matchGroupRef "@crescent_city_bb_fab1_lib.crescent_city_bb_fab1(sch_1):\MG_DDR_NEAR_DIMM-CLK1_CLS_DDR_A_CAC-CLKS\" )
					)
					( Status sCSetFlattened )
					( Origin gBackEnd )
				)
				( attribute "RELATIVE_PROPAGATION_DELAY" "0.00 MIL,700.00 MIL"
					( Parent
						( matchGroupRef "@crescent_city_bb_fab1_lib.crescent_city_bb_fab1(sch_1):\MG_DDR_NEAR_DIMM-CLK1_CLS_DDR_A_CAC-CLKS\" )
					)
					( Units "uMatchProp" "ns" 1.000000)
					( Status sCSetFlattened )
					( Origin gBackEnd )
				)
				( attribute "RELATIVE_PROPAGATION_DELAY_SCOPE" "G"
					( Parent
						( matchGroupRef "@baseboard_fab2_lib.baseboard_fab2(sch_1):\MG_DDR_CMD_NEAR_DIMM_NG_DDR_A_DLL_4\" )
					)
					( Status sCSetFlattened )
					( Origin gBackEnd )
				)
				( attribute "RELATIVE_PROPAGATION_DELAY" "0.00 MIL,25.00 MIL"
					( Parent
						( matchGroupRef "@baseboard_fab2_lib.baseboard_fab2(sch_1):\MG_DDR_CMD_NEAR_DIMM_NG_DDR_A_DLL_4\" )
					)
					( Units "uMatchProp" "ns" 1.000000)
					( Status sCSetFlattened )
					( Origin gBackEnd )
				)
			)
			( pinPair "@baseboard_fab2_lib.baseboard_fab2(sch_1):\PP4039\"
				( pinRef "@baseboard_fab2_lib.baseboard_fab2(sch_1):page23_i172:DDR0_BA(0)" )
				( pinRef "@baseboard_fab2_lib.baseboard_fab2(sch_1):page43_i1:BA(0)" )
				( attribute "RELATIVE_PROPAGATION_DELAY_SCOPE" "G"
					( Parent
						( matchGroupRef "@crescent_city_bb_fab1_lib.crescent_city_bb_fab1(sch_1):\MG_DDR_FAR_DIMM-CLK0_CLS_DDR_A_CAC-CLKS\" )
					)
					( Status sCSetFlattened )
					( Origin gBackEnd )
				)
				( attribute "RELATIVE_PROPAGATION_DELAY" "0.00 MIL,700.00 MIL"
					( Parent
						( matchGroupRef "@crescent_city_bb_fab1_lib.crescent_city_bb_fab1(sch_1):\MG_DDR_FAR_DIMM-CLK0_CLS_DDR_A_CAC-CLKS\" )
					)
					( Units "uMatchProp" "ns" 1.000000)
					( Status sCSetFlattened )
					( Origin gBackEnd )
				)
				( attribute "RELATIVE_PROPAGATION_DELAY_SCOPE" "G"
					( Parent
						( matchGroupRef "@baseboard_fab2_lib.baseboard_fab2(sch_1):\MG_DDR_FAR_DIMM_CMD_NG_DDR_A_DLL_5\" )
					)
					( Status sCSetFlattened )
					( Origin gBackEnd )
				)
				( attribute "RELATIVE_PROPAGATION_DELAY" "0.00 MIL,25.00 MIL"
					( Parent
						( matchGroupRef "@baseboard_fab2_lib.baseboard_fab2(sch_1):\MG_DDR_FAR_DIMM_CMD_NG_DDR_A_DLL_5\" )
					)
					( Units "uMatchProp" "ns" 1.000000)
					( Status sCSetFlattened )
					( Origin gBackEnd )
				)
			)
			( pinPair "@baseboard_fab2_lib.baseboard_fab2(sch_1):\PP4040\"
				( pinRef "@baseboard_fab2_lib.baseboard_fab2(sch_1):page44_i13:BA(0)" )
				( pinRef "@baseboard_fab2_lib.baseboard_fab2(sch_1):page23_i172:DDR0_BA(0)" )
				( attribute "RELATIVE_PROPAGATION_DELAY_SCOPE" "G"
					( Parent
						( matchGroupRef "@crescent_city_bb_fab1_lib.crescent_city_bb_fab1(sch_1):\MG_DDR_NEAR_DIMM-CLK1_CLS_DDR_A_CAC-CLKS\" )
					)
					( Status sCSetFlattened )
					( Origin gBackEnd )
				)
				( attribute "RELATIVE_PROPAGATION_DELAY" "0.00 MIL,700.00 MIL"
					( Parent
						( matchGroupRef "@crescent_city_bb_fab1_lib.crescent_city_bb_fab1(sch_1):\MG_DDR_NEAR_DIMM-CLK1_CLS_DDR_A_CAC-CLKS\" )
					)
					( Units "uMatchProp" "ns" 1.000000)
					( Status sCSetFlattened )
					( Origin gBackEnd )
				)
				( attribute "RELATIVE_PROPAGATION_DELAY_SCOPE" "G"
					( Parent
						( matchGroupRef "@baseboard_fab2_lib.baseboard_fab2(sch_1):\MG_DDR_CMD_NEAR_DIMM_NG_DDR_A_DLL_5\" )
					)
					( Status sCSetFlattened )
					( Origin gBackEnd )
				)
				( attribute "RELATIVE_PROPAGATION_DELAY" "0.00 MIL,25.00 MIL"
					( Parent
						( matchGroupRef "@baseboard_fab2_lib.baseboard_fab2(sch_1):\MG_DDR_CMD_NEAR_DIMM_NG_DDR_A_DLL_5\" )
					)
					( Units "uMatchProp" "ns" 1.000000)
					( Status sCSetFlattened )
					( Origin gBackEnd )
				)
			)
			( pinPair "@baseboard_fab2_lib.baseboard_fab2(sch_1):\PP4041\"
				( pinRef "@baseboard_fab2_lib.baseboard_fab2(sch_1):page23_i172:DDR0_MA(0)" )
				( pinRef "@baseboard_fab2_lib.baseboard_fab2(sch_1):page43_i1:A0" )
				( attribute "RELATIVE_PROPAGATION_DELAY_SCOPE" "G"
					( Parent
						( matchGroupRef "@crescent_city_bb_fab1_lib.crescent_city_bb_fab1(sch_1):\MG_DDR_FAR_DIMM-CLK0_CLS_DDR_A_CAC-CLKS\" )
					)
					( Status sCSetFlattened )
					( Origin gBackEnd )
				)
				( attribute "RELATIVE_PROPAGATION_DELAY" "0.00 MIL,700.00 MIL"
					( Parent
						( matchGroupRef "@crescent_city_bb_fab1_lib.crescent_city_bb_fab1(sch_1):\MG_DDR_FAR_DIMM-CLK0_CLS_DDR_A_CAC-CLKS\" )
					)
					( Units "uMatchProp" "ns" 1.000000)
					( Status sCSetFlattened )
					( Origin gBackEnd )
				)
				( attribute "RELATIVE_PROPAGATION_DELAY_SCOPE" "G"
					( Parent
						( matchGroupRef "@baseboard_fab2_lib.baseboard_fab2(sch_1):\MG_DDR_FAR_DIMM_CMD_NG_DDR_A_DLL_5\" )
					)
					( Status sCSetFlattened )
					( Origin gBackEnd )
				)
				( attribute "RELATIVE_PROPAGATION_DELAY" "0.00 MIL,25.00 MIL"
					( Parent
						( matchGroupRef "@baseboard_fab2_lib.baseboard_fab2(sch_1):\MG_DDR_FAR_DIMM_CMD_NG_DDR_A_DLL_5\" )
					)
					( Units "uMatchProp" "ns" 1.000000)
					( Status sCSetFlattened )
					( Origin gBackEnd )
				)
			)
			( pinPair "@baseboard_fab2_lib.baseboard_fab2(sch_1):\PP4042\"
				( pinRef "@baseboard_fab2_lib.baseboard_fab2(sch_1):page44_i13:A0" )
				( pinRef "@baseboard_fab2_lib.baseboard_fab2(sch_1):page23_i172:DDR0_MA(0)" )
				( attribute "RELATIVE_PROPAGATION_DELAY_SCOPE" "G"
					( Parent
						( matchGroupRef "@crescent_city_bb_fab1_lib.crescent_city_bb_fab1(sch_1):\MG_DDR_NEAR_DIMM-CLK1_CLS_DDR_A_CAC-CLKS\" )
					)
					( Status sCSetFlattened )
					( Origin gBackEnd )
				)
				( attribute "RELATIVE_PROPAGATION_DELAY" "0.00 MIL,700.00 MIL"
					( Parent
						( matchGroupRef "@crescent_city_bb_fab1_lib.crescent_city_bb_fab1(sch_1):\MG_DDR_NEAR_DIMM-CLK1_CLS_DDR_A_CAC-CLKS\" )
					)
					( Units "uMatchProp" "ns" 1.000000)
					( Status sCSetFlattened )
					( Origin gBackEnd )
				)
				( attribute "RELATIVE_PROPAGATION_DELAY_SCOPE" "G"
					( Parent
						( matchGroupRef "@baseboard_fab2_lib.baseboard_fab2(sch_1):\MG_DDR_CMD_NEAR_DIMM_NG_DDR_A_DLL_5\" )
					)
					( Status sCSetFlattened )
					( Origin gBackEnd )
				)
				( attribute "RELATIVE_PROPAGATION_DELAY" "0.00 MIL,25.00 MIL"
					( Parent
						( matchGroupRef "@baseboard_fab2_lib.baseboard_fab2(sch_1):\MG_DDR_CMD_NEAR_DIMM_NG_DDR_A_DLL_5\" )
					)
					( Units "uMatchProp" "ns" 1.000000)
					( Status sCSetFlattened )
					( Origin gBackEnd )
				)
			)
			( pinPair "@baseboard_fab2_lib.baseboard_fab2(sch_1):\PP4037\"
				( pinRef "@baseboard_fab2_lib.baseboard_fab2(sch_1):page23_i172:DDR0_PAR" )
				( pinRef "@baseboard_fab2_lib.baseboard_fab2(sch_1):page43_i1:PAR" )
				( attribute "RELATIVE_PROPAGATION_DELAY_SCOPE" "G"
					( Parent
						( matchGroupRef "@crescent_city_bb_fab1_lib.crescent_city_bb_fab1(sch_1):\MG_DDR_FAR_DIMM-CLK0_CLS_DDR_A_CAC-CLKS\" )
					)
					( Status sCSetFlattened )
					( Origin gBackEnd )
				)
				( attribute "RELATIVE_PROPAGATION_DELAY" "0.00 MIL,700.00 MIL"
					( Parent
						( matchGroupRef "@crescent_city_bb_fab1_lib.crescent_city_bb_fab1(sch_1):\MG_DDR_FAR_DIMM-CLK0_CLS_DDR_A_CAC-CLKS\" )
					)
					( Units "uMatchProp" "ns" 1.000000)
					( Status sCSetFlattened )
					( Origin gBackEnd )
				)
				( attribute "RELATIVE_PROPAGATION_DELAY_SCOPE" "G"
					( Parent
						( matchGroupRef "@baseboard_fab2_lib.baseboard_fab2(sch_1):\MG_DDR_FAR_DIMM_CMD_NG_DDR_A_DLL_6\" )
					)
					( Status sCSetFlattened )
					( Origin gBackEnd )
				)
				( attribute "RELATIVE_PROPAGATION_DELAY" "0.00 MIL,25.00 MIL"
					( Parent
						( matchGroupRef "@baseboard_fab2_lib.baseboard_fab2(sch_1):\MG_DDR_FAR_DIMM_CMD_NG_DDR_A_DLL_6\" )
					)
					( Units "uMatchProp" "ns" 1.000000)
					( Status sCSetFlattened )
					( Origin gBackEnd )
				)
			)
			( pinPair "@baseboard_fab2_lib.baseboard_fab2(sch_1):\PP4038\"
				( pinRef "@baseboard_fab2_lib.baseboard_fab2(sch_1):page44_i13:PAR" )
				( pinRef "@baseboard_fab2_lib.baseboard_fab2(sch_1):page23_i172:DDR0_PAR" )
				( attribute "RELATIVE_PROPAGATION_DELAY_SCOPE" "G"
					( Parent
						( matchGroupRef "@crescent_city_bb_fab1_lib.crescent_city_bb_fab1(sch_1):\MG_DDR_NEAR_DIMM-CLK1_CLS_DDR_A_CAC-CLKS\" )
					)
					( Status sCSetFlattened )
					( Origin gBackEnd )
				)
				( attribute "RELATIVE_PROPAGATION_DELAY" "0.00 MIL,700.00 MIL"
					( Parent
						( matchGroupRef "@crescent_city_bb_fab1_lib.crescent_city_bb_fab1(sch_1):\MG_DDR_NEAR_DIMM-CLK1_CLS_DDR_A_CAC-CLKS\" )
					)
					( Units "uMatchProp" "ns" 1.000000)
					( Status sCSetFlattened )
					( Origin gBackEnd )
				)
				( attribute "RELATIVE_PROPAGATION_DELAY_SCOPE" "G"
					( Parent
						( matchGroupRef "@baseboard_fab2_lib.baseboard_fab2(sch_1):\MG_DDR_CMD_NEAR_DIMM_NG_DDR_A_DLL_6\" )
					)
					( Status sCSetFlattened )
					( Origin gBackEnd )
				)
				( attribute "RELATIVE_PROPAGATION_DELAY" "0.00 MIL,25.00 MIL"
					( Parent
						( matchGroupRef "@baseboard_fab2_lib.baseboard_fab2(sch_1):\MG_DDR_CMD_NEAR_DIMM_NG_DDR_A_DLL_6\" )
					)
					( Units "uMatchProp" "ns" 1.000000)
					( Status sCSetFlattened )
					( Origin gBackEnd )
				)
			)
			( pinPair "@baseboard_fab2_lib.baseboard_fab2(sch_1):\PP4033\"
				( pinRef "@baseboard_fab2_lib.baseboard_fab2(sch_1):page23_i172:DDR0_MA(1)" )
				( pinRef "@baseboard_fab2_lib.baseboard_fab2(sch_1):page43_i1:A1" )
				( attribute "RELATIVE_PROPAGATION_DELAY_SCOPE" "G"
					( Parent
						( matchGroupRef "@crescent_city_bb_fab1_lib.crescent_city_bb_fab1(sch_1):\MG_DDR_FAR_DIMM-CLK0_CLS_DDR_A_CAC-CLKS\" )
					)
					( Status sCSetFlattened )
					( Origin gBackEnd )
				)
				( attribute "RELATIVE_PROPAGATION_DELAY" "0.00 MIL,700.00 MIL"
					( Parent
						( matchGroupRef "@crescent_city_bb_fab1_lib.crescent_city_bb_fab1(sch_1):\MG_DDR_FAR_DIMM-CLK0_CLS_DDR_A_CAC-CLKS\" )
					)
					( Units "uMatchProp" "ns" 1.000000)
					( Status sCSetFlattened )
					( Origin gBackEnd )
				)
				( attribute "RELATIVE_PROPAGATION_DELAY_SCOPE" "G"
					( Parent
						( matchGroupRef "@baseboard_fab2_lib.baseboard_fab2(sch_1):\MG_DDR_FAR_DIMM_CMD_NG_DDR_A_DLL_7\" )
					)
					( Status sCSetFlattened )
					( Origin gBackEnd )
				)
				( attribute "RELATIVE_PROPAGATION_DELAY" "0.00 MIL,25.00 MIL"
					( Parent
						( matchGroupRef "@baseboard_fab2_lib.baseboard_fab2(sch_1):\MG_DDR_FAR_DIMM_CMD_NG_DDR_A_DLL_7\" )
					)
					( Units "uMatchProp" "ns" 1.000000)
					( Status sCSetFlattened )
					( Origin gBackEnd )
				)
			)
			( pinPair "@baseboard_fab2_lib.baseboard_fab2(sch_1):\PP4034\"
				( pinRef "@baseboard_fab2_lib.baseboard_fab2(sch_1):page44_i13:A1" )
				( pinRef "@baseboard_fab2_lib.baseboard_fab2(sch_1):page23_i172:DDR0_MA(1)" )
				( attribute "RELATIVE_PROPAGATION_DELAY_SCOPE" "G"
					( Parent
						( matchGroupRef "@crescent_city_bb_fab1_lib.crescent_city_bb_fab1(sch_1):\MG_DDR_NEAR_DIMM-CLK1_CLS_DDR_A_CAC-CLKS\" )
					)
					( Status sCSetFlattened )
					( Origin gBackEnd )
				)
				( attribute "RELATIVE_PROPAGATION_DELAY" "0.00 MIL,700.00 MIL"
					( Parent
						( matchGroupRef "@crescent_city_bb_fab1_lib.crescent_city_bb_fab1(sch_1):\MG_DDR_NEAR_DIMM-CLK1_CLS_DDR_A_CAC-CLKS\" )
					)
					( Units "uMatchProp" "ns" 1.000000)
					( Status sCSetFlattened )
					( Origin gBackEnd )
				)
				( attribute "RELATIVE_PROPAGATION_DELAY_SCOPE" "G"
					( Parent
						( matchGroupRef "@baseboard_fab2_lib.baseboard_fab2(sch_1):\MG_DDR_CMD_NEAR_DIMM_NG_DDR_A_DLL_7\" )
					)
					( Status sCSetFlattened )
					( Origin gBackEnd )
				)
				( attribute "RELATIVE_PROPAGATION_DELAY" "0.00 MIL,25.00 MIL"
					( Parent
						( matchGroupRef "@baseboard_fab2_lib.baseboard_fab2(sch_1):\MG_DDR_CMD_NEAR_DIMM_NG_DDR_A_DLL_7\" )
					)
					( Units "uMatchProp" "ns" 1.000000)
					( Status sCSetFlattened )
					( Origin gBackEnd )
				)
			)
			( pinPair "@baseboard_fab2_lib.baseboard_fab2(sch_1):\PP4035\"
				( pinRef "@baseboard_fab2_lib.baseboard_fab2(sch_1):page23_i172:DDR0_MA(3)" )
				( pinRef "@baseboard_fab2_lib.baseboard_fab2(sch_1):page43_i1:A3" )
				( attribute "RELATIVE_PROPAGATION_DELAY_SCOPE" "G"
					( Parent
						( matchGroupRef "@crescent_city_bb_fab1_lib.crescent_city_bb_fab1(sch_1):\MG_DDR_FAR_DIMM-CLK0_CLS_DDR_A_CAC-CLKS\" )
					)
					( Status sCSetFlattened )
					( Origin gBackEnd )
				)
				( attribute "RELATIVE_PROPAGATION_DELAY" "0.00 MIL,700.00 MIL"
					( Parent
						( matchGroupRef "@crescent_city_bb_fab1_lib.crescent_city_bb_fab1(sch_1):\MG_DDR_FAR_DIMM-CLK0_CLS_DDR_A_CAC-CLKS\" )
					)
					( Units "uMatchProp" "ns" 1.000000)
					( Status sCSetFlattened )
					( Origin gBackEnd )
				)
				( attribute "RELATIVE_PROPAGATION_DELAY_SCOPE" "G"
					( Parent
						( matchGroupRef "@baseboard_fab2_lib.baseboard_fab2(sch_1):\MG_DDR_FAR_DIMM_CMD_NG_DDR_A_DLL_7\" )
					)
					( Status sCSetFlattened )
					( Origin gBackEnd )
				)
				( attribute "RELATIVE_PROPAGATION_DELAY" "0.00 MIL,25.00 MIL"
					( Parent
						( matchGroupRef "@baseboard_fab2_lib.baseboard_fab2(sch_1):\MG_DDR_FAR_DIMM_CMD_NG_DDR_A_DLL_7\" )
					)
					( Units "uMatchProp" "ns" 1.000000)
					( Status sCSetFlattened )
					( Origin gBackEnd )
				)
			)
			( pinPair "@baseboard_fab2_lib.baseboard_fab2(sch_1):\PP4036\"
				( pinRef "@baseboard_fab2_lib.baseboard_fab2(sch_1):page44_i13:A3" )
				( pinRef "@baseboard_fab2_lib.baseboard_fab2(sch_1):page23_i172:DDR0_MA(3)" )
				( attribute "RELATIVE_PROPAGATION_DELAY_SCOPE" "G"
					( Parent
						( matchGroupRef "@crescent_city_bb_fab1_lib.crescent_city_bb_fab1(sch_1):\MG_DDR_NEAR_DIMM-CLK1_CLS_DDR_A_CAC-CLKS\" )
					)
					( Status sCSetFlattened )
					( Origin gBackEnd )
				)
				( attribute "RELATIVE_PROPAGATION_DELAY" "0.00 MIL,700.00 MIL"
					( Parent
						( matchGroupRef "@crescent_city_bb_fab1_lib.crescent_city_bb_fab1(sch_1):\MG_DDR_NEAR_DIMM-CLK1_CLS_DDR_A_CAC-CLKS\" )
					)
					( Units "uMatchProp" "ns" 1.000000)
					( Status sCSetFlattened )
					( Origin gBackEnd )
				)
				( attribute "RELATIVE_PROPAGATION_DELAY_SCOPE" "G"
					( Parent
						( matchGroupRef "@baseboard_fab2_lib.baseboard_fab2(sch_1):\MG_DDR_CMD_NEAR_DIMM_NG_DDR_A_DLL_7\" )
					)
					( Status sCSetFlattened )
					( Origin gBackEnd )
				)
				( attribute "RELATIVE_PROPAGATION_DELAY" "0.00 MIL,25.00 MIL"
					( Parent
						( matchGroupRef "@baseboard_fab2_lib.baseboard_fab2(sch_1):\MG_DDR_CMD_NEAR_DIMM_NG_DDR_A_DLL_7\" )
					)
					( Units "uMatchProp" "ns" 1.000000)
					( Status sCSetFlattened )
					( Origin gBackEnd )
				)
			)
			( pinPair "@baseboard_fab2_lib.baseboard_fab2(sch_1):\PP4029\"
				( pinRef "@baseboard_fab2_lib.baseboard_fab2(sch_1):page23_i172:DDR0_MA(2)" )
				( pinRef "@baseboard_fab2_lib.baseboard_fab2(sch_1):page43_i1:A2" )
				( attribute "RELATIVE_PROPAGATION_DELAY_SCOPE" "G"
					( Parent
						( matchGroupRef "@crescent_city_bb_fab1_lib.crescent_city_bb_fab1(sch_1):\MG_DDR_FAR_DIMM-CLK0_CLS_DDR_A_CAC-CLKS\" )
					)
					( Status sCSetFlattened )
					( Origin gBackEnd )
				)
				( attribute "RELATIVE_PROPAGATION_DELAY" "0.00 MIL,700.00 MIL"
					( Parent
						( matchGroupRef "@crescent_city_bb_fab1_lib.crescent_city_bb_fab1(sch_1):\MG_DDR_FAR_DIMM-CLK0_CLS_DDR_A_CAC-CLKS\" )
					)
					( Units "uMatchProp" "ns" 1.000000)
					( Status sCSetFlattened )
					( Origin gBackEnd )
				)
				( attribute "RELATIVE_PROPAGATION_DELAY_SCOPE" "G"
					( Parent
						( matchGroupRef "@baseboard_fab2_lib.baseboard_fab2(sch_1):\MG_DDR_FAR_DIMM_CMD_NG_DDR_A_DLL_8\" )
					)
					( Status sCSetFlattened )
					( Origin gBackEnd )
				)
				( attribute "RELATIVE_PROPAGATION_DELAY" "0.00 MIL,25.00 MIL"
					( Parent
						( matchGroupRef "@baseboard_fab2_lib.baseboard_fab2(sch_1):\MG_DDR_FAR_DIMM_CMD_NG_DDR_A_DLL_8\" )
					)
					( Units "uMatchProp" "ns" 1.000000)
					( Status sCSetFlattened )
					( Origin gBackEnd )
				)
			)
			( pinPair "@baseboard_fab2_lib.baseboard_fab2(sch_1):\PP4030\"
				( pinRef "@baseboard_fab2_lib.baseboard_fab2(sch_1):page44_i13:A2" )
				( pinRef "@baseboard_fab2_lib.baseboard_fab2(sch_1):page23_i172:DDR0_MA(2)" )
				( attribute "RELATIVE_PROPAGATION_DELAY_SCOPE" "G"
					( Parent
						( matchGroupRef "@crescent_city_bb_fab1_lib.crescent_city_bb_fab1(sch_1):\MG_DDR_NEAR_DIMM-CLK1_CLS_DDR_A_CAC-CLKS\" )
					)
					( Status sCSetFlattened )
					( Origin gBackEnd )
				)
				( attribute "RELATIVE_PROPAGATION_DELAY" "0.00 MIL,700.00 MIL"
					( Parent
						( matchGroupRef "@crescent_city_bb_fab1_lib.crescent_city_bb_fab1(sch_1):\MG_DDR_NEAR_DIMM-CLK1_CLS_DDR_A_CAC-CLKS\" )
					)
					( Units "uMatchProp" "ns" 1.000000)
					( Status sCSetFlattened )
					( Origin gBackEnd )
				)
				( attribute "RELATIVE_PROPAGATION_DELAY_SCOPE" "G"
					( Parent
						( matchGroupRef "@baseboard_fab2_lib.baseboard_fab2(sch_1):\MG_DDR_CMD_NEAR_DIMM_NG_DDR_A_DLL_8\" )
					)
					( Status sCSetFlattened )
					( Origin gBackEnd )
				)
				( attribute "RELATIVE_PROPAGATION_DELAY" "0.00 MIL,25.00 MIL"
					( Parent
						( matchGroupRef "@baseboard_fab2_lib.baseboard_fab2(sch_1):\MG_DDR_CMD_NEAR_DIMM_NG_DDR_A_DLL_8\" )
					)
					( Units "uMatchProp" "ns" 1.000000)
					( Status sCSetFlattened )
					( Origin gBackEnd )
				)
			)
			( pinPair "@baseboard_fab2_lib.baseboard_fab2(sch_1):\PP4031\"
				( pinRef "@baseboard_fab2_lib.baseboard_fab2(sch_1):page23_i172:DDR0_MA(4)" )
				( pinRef "@baseboard_fab2_lib.baseboard_fab2(sch_1):page43_i1:A4" )
				( attribute "RELATIVE_PROPAGATION_DELAY_SCOPE" "G"
					( Parent
						( matchGroupRef "@crescent_city_bb_fab1_lib.crescent_city_bb_fab1(sch_1):\MG_DDR_FAR_DIMM-CLK0_CLS_DDR_A_CAC-CLKS\" )
					)
					( Status sCSetFlattened )
					( Origin gBackEnd )
				)
				( attribute "RELATIVE_PROPAGATION_DELAY" "0.00 MIL,700.00 MIL"
					( Parent
						( matchGroupRef "@crescent_city_bb_fab1_lib.crescent_city_bb_fab1(sch_1):\MG_DDR_FAR_DIMM-CLK0_CLS_DDR_A_CAC-CLKS\" )
					)
					( Units "uMatchProp" "ns" 1.000000)
					( Status sCSetFlattened )
					( Origin gBackEnd )
				)
				( attribute "RELATIVE_PROPAGATION_DELAY_SCOPE" "G"
					( Parent
						( matchGroupRef "@baseboard_fab2_lib.baseboard_fab2(sch_1):\MG_DDR_FAR_DIMM_CMD_NG_DDR_A_DLL_8\" )
					)
					( Status sCSetFlattened )
					( Origin gBackEnd )
				)
				( attribute "RELATIVE_PROPAGATION_DELAY" "0.00 MIL,25.00 MIL"
					( Parent
						( matchGroupRef "@baseboard_fab2_lib.baseboard_fab2(sch_1):\MG_DDR_FAR_DIMM_CMD_NG_DDR_A_DLL_8\" )
					)
					( Units "uMatchProp" "ns" 1.000000)
					( Status sCSetFlattened )
					( Origin gBackEnd )
				)
			)
			( pinPair "@baseboard_fab2_lib.baseboard_fab2(sch_1):\PP4032\"
				( pinRef "@baseboard_fab2_lib.baseboard_fab2(sch_1):page44_i13:A4" )
				( pinRef "@baseboard_fab2_lib.baseboard_fab2(sch_1):page23_i172:DDR0_MA(4)" )
				( attribute "RELATIVE_PROPAGATION_DELAY_SCOPE" "G"
					( Parent
						( matchGroupRef "@crescent_city_bb_fab1_lib.crescent_city_bb_fab1(sch_1):\MG_DDR_NEAR_DIMM-CLK1_CLS_DDR_A_CAC-CLKS\" )
					)
					( Status sCSetFlattened )
					( Origin gBackEnd )
				)
				( attribute "RELATIVE_PROPAGATION_DELAY" "0.00 MIL,700.00 MIL"
					( Parent
						( matchGroupRef "@crescent_city_bb_fab1_lib.crescent_city_bb_fab1(sch_1):\MG_DDR_NEAR_DIMM-CLK1_CLS_DDR_A_CAC-CLKS\" )
					)
					( Units "uMatchProp" "ns" 1.000000)
					( Status sCSetFlattened )
					( Origin gBackEnd )
				)
				( attribute "RELATIVE_PROPAGATION_DELAY_SCOPE" "G"
					( Parent
						( matchGroupRef "@baseboard_fab2_lib.baseboard_fab2(sch_1):\MG_DDR_CMD_NEAR_DIMM_NG_DDR_A_DLL_8\" )
					)
					( Status sCSetFlattened )
					( Origin gBackEnd )
				)
				( attribute "RELATIVE_PROPAGATION_DELAY" "0.00 MIL,25.00 MIL"
					( Parent
						( matchGroupRef "@baseboard_fab2_lib.baseboard_fab2(sch_1):\MG_DDR_CMD_NEAR_DIMM_NG_DDR_A_DLL_8\" )
					)
					( Units "uMatchProp" "ns" 1.000000)
					( Status sCSetFlattened )
					( Origin gBackEnd )
				)
			)
			( pinPair "@baseboard_fab2_lib.baseboard_fab2(sch_1):\PP4025\"
				( pinRef "@baseboard_fab2_lib.baseboard_fab2(sch_1):page23_i172:DDR0_MA(5)" )
				( pinRef "@baseboard_fab2_lib.baseboard_fab2(sch_1):page43_i1:A5" )
				( attribute "RELATIVE_PROPAGATION_DELAY_SCOPE" "G"
					( Parent
						( matchGroupRef "@crescent_city_bb_fab1_lib.crescent_city_bb_fab1(sch_1):\MG_DDR_FAR_DIMM-CLK0_CLS_DDR_A_CAC-CLKS\" )
					)
					( Status sCSetFlattened )
					( Origin gBackEnd )
				)
				( attribute "RELATIVE_PROPAGATION_DELAY" "0.00 MIL,700.00 MIL"
					( Parent
						( matchGroupRef "@crescent_city_bb_fab1_lib.crescent_city_bb_fab1(sch_1):\MG_DDR_FAR_DIMM-CLK0_CLS_DDR_A_CAC-CLKS\" )
					)
					( Units "uMatchProp" "ns" 1.000000)
					( Status sCSetFlattened )
					( Origin gBackEnd )
				)
				( attribute "RELATIVE_PROPAGATION_DELAY_SCOPE" "G"
					( Parent
						( matchGroupRef "@baseboard_fab2_lib.baseboard_fab2(sch_1):\MG_DDR_FAR_DIMM_CMD_NG_DDR_A_DLL_9\" )
					)
					( Status sCSetFlattened )
					( Origin gBackEnd )
				)
				( attribute "RELATIVE_PROPAGATION_DELAY" "0.00 MIL,25.00 MIL"
					( Parent
						( matchGroupRef "@baseboard_fab2_lib.baseboard_fab2(sch_1):\MG_DDR_FAR_DIMM_CMD_NG_DDR_A_DLL_9\" )
					)
					( Units "uMatchProp" "ns" 1.000000)
					( Status sCSetFlattened )
					( Origin gBackEnd )
				)
			)
			( pinPair "@baseboard_fab2_lib.baseboard_fab2(sch_1):\PP4026\"
				( pinRef "@baseboard_fab2_lib.baseboard_fab2(sch_1):page44_i13:A5" )
				( pinRef "@baseboard_fab2_lib.baseboard_fab2(sch_1):page23_i172:DDR0_MA(5)" )
				( attribute "RELATIVE_PROPAGATION_DELAY_SCOPE" "G"
					( Parent
						( matchGroupRef "@crescent_city_bb_fab1_lib.crescent_city_bb_fab1(sch_1):\MG_DDR_NEAR_DIMM-CLK1_CLS_DDR_A_CAC-CLKS\" )
					)
					( Status sCSetFlattened )
					( Origin gBackEnd )
				)
				( attribute "RELATIVE_PROPAGATION_DELAY" "0.00 MIL,700.00 MIL"
					( Parent
						( matchGroupRef "@crescent_city_bb_fab1_lib.crescent_city_bb_fab1(sch_1):\MG_DDR_NEAR_DIMM-CLK1_CLS_DDR_A_CAC-CLKS\" )
					)
					( Units "uMatchProp" "ns" 1.000000)
					( Status sCSetFlattened )
					( Origin gBackEnd )
				)
				( attribute "RELATIVE_PROPAGATION_DELAY_SCOPE" "G"
					( Parent
						( matchGroupRef "@baseboard_fab2_lib.baseboard_fab2(sch_1):\MG_DDR_CMD_NEAR_DIMM_NG_DDR_A_DLL_9\" )
					)
					( Status sCSetFlattened )
					( Origin gBackEnd )
				)
				( attribute "RELATIVE_PROPAGATION_DELAY" "0.00 MIL,25.00 MIL"
					( Parent
						( matchGroupRef "@baseboard_fab2_lib.baseboard_fab2(sch_1):\MG_DDR_CMD_NEAR_DIMM_NG_DDR_A_DLL_9\" )
					)
					( Units "uMatchProp" "ns" 1.000000)
					( Status sCSetFlattened )
					( Origin gBackEnd )
				)
			)
			( pinPair "@baseboard_fab2_lib.baseboard_fab2(sch_1):\PP4027\"
				( pinRef "@baseboard_fab2_lib.baseboard_fab2(sch_1):page23_i172:DDR0_MA(6)" )
				( pinRef "@baseboard_fab2_lib.baseboard_fab2(sch_1):page43_i1:A6" )
				( attribute "RELATIVE_PROPAGATION_DELAY_SCOPE" "G"
					( Parent
						( matchGroupRef "@crescent_city_bb_fab1_lib.crescent_city_bb_fab1(sch_1):\MG_DDR_FAR_DIMM-CLK0_CLS_DDR_A_CAC-CLKS\" )
					)
					( Status sCSetFlattened )
					( Origin gBackEnd )
				)
				( attribute "RELATIVE_PROPAGATION_DELAY" "0.00 MIL,700.00 MIL"
					( Parent
						( matchGroupRef "@crescent_city_bb_fab1_lib.crescent_city_bb_fab1(sch_1):\MG_DDR_FAR_DIMM-CLK0_CLS_DDR_A_CAC-CLKS\" )
					)
					( Units "uMatchProp" "ns" 1.000000)
					( Status sCSetFlattened )
					( Origin gBackEnd )
				)
				( attribute "RELATIVE_PROPAGATION_DELAY_SCOPE" "G"
					( Parent
						( matchGroupRef "@baseboard_fab2_lib.baseboard_fab2(sch_1):\MG_DDR_FAR_DIMM_CMD_NG_DDR_A_DLL_9\" )
					)
					( Status sCSetFlattened )
					( Origin gBackEnd )
				)
				( attribute "RELATIVE_PROPAGATION_DELAY" "0.00 MIL,25.00 MIL"
					( Parent
						( matchGroupRef "@baseboard_fab2_lib.baseboard_fab2(sch_1):\MG_DDR_FAR_DIMM_CMD_NG_DDR_A_DLL_9\" )
					)
					( Units "uMatchProp" "ns" 1.000000)
					( Status sCSetFlattened )
					( Origin gBackEnd )
				)
			)
			( pinPair "@baseboard_fab2_lib.baseboard_fab2(sch_1):\PP4028\"
				( pinRef "@baseboard_fab2_lib.baseboard_fab2(sch_1):page44_i13:A6" )
				( pinRef "@baseboard_fab2_lib.baseboard_fab2(sch_1):page23_i172:DDR0_MA(6)" )
				( attribute "RELATIVE_PROPAGATION_DELAY_SCOPE" "G"
					( Parent
						( matchGroupRef "@crescent_city_bb_fab1_lib.crescent_city_bb_fab1(sch_1):\MG_DDR_NEAR_DIMM-CLK1_CLS_DDR_A_CAC-CLKS\" )
					)
					( Status sCSetFlattened )
					( Origin gBackEnd )
				)
				( attribute "RELATIVE_PROPAGATION_DELAY" "0.00 MIL,700.00 MIL"
					( Parent
						( matchGroupRef "@crescent_city_bb_fab1_lib.crescent_city_bb_fab1(sch_1):\MG_DDR_NEAR_DIMM-CLK1_CLS_DDR_A_CAC-CLKS\" )
					)
					( Units "uMatchProp" "ns" 1.000000)
					( Status sCSetFlattened )
					( Origin gBackEnd )
				)
				( attribute "RELATIVE_PROPAGATION_DELAY_SCOPE" "G"
					( Parent
						( matchGroupRef "@baseboard_fab2_lib.baseboard_fab2(sch_1):\MG_DDR_CMD_NEAR_DIMM_NG_DDR_A_DLL_9\" )
					)
					( Status sCSetFlattened )
					( Origin gBackEnd )
				)
				( attribute "RELATIVE_PROPAGATION_DELAY" "0.00 MIL,25.00 MIL"
					( Parent
						( matchGroupRef "@baseboard_fab2_lib.baseboard_fab2(sch_1):\MG_DDR_CMD_NEAR_DIMM_NG_DDR_A_DLL_9\" )
					)
					( Units "uMatchProp" "ns" 1.000000)
					( Status sCSetFlattened )
					( Origin gBackEnd )
				)
			)
			( pinPair "@baseboard_fab2_lib.baseboard_fab2(sch_1):\PP4021\"
				( pinRef "@baseboard_fab2_lib.baseboard_fab2(sch_1):page23_i172:DDR0_MA(7)" )
				( pinRef "@baseboard_fab2_lib.baseboard_fab2(sch_1):page43_i1:A7" )
				( attribute "RELATIVE_PROPAGATION_DELAY_SCOPE" "G"
					( Parent
						( matchGroupRef "@crescent_city_bb_fab1_lib.crescent_city_bb_fab1(sch_1):\MG_DDR_FAR_DIMM-CLK0_CLS_DDR_A_CAC-CLKS\" )
					)
					( Status sCSetFlattened )
					( Origin gBackEnd )
				)
				( attribute "RELATIVE_PROPAGATION_DELAY" "0.00 MIL,700.00 MIL"
					( Parent
						( matchGroupRef "@crescent_city_bb_fab1_lib.crescent_city_bb_fab1(sch_1):\MG_DDR_FAR_DIMM-CLK0_CLS_DDR_A_CAC-CLKS\" )
					)
					( Units "uMatchProp" "ns" 1.000000)
					( Status sCSetFlattened )
					( Origin gBackEnd )
				)
				( attribute "RELATIVE_PROPAGATION_DELAY_SCOPE" "G"
					( Parent
						( matchGroupRef "@baseboard_fab2_lib.baseboard_fab2(sch_1):\MG_DDR_FAR_DIMM_CMD_NG_DDR_A_DLL_10\" )
					)
					( Status sCSetFlattened )
					( Origin gBackEnd )
				)
				( attribute "RELATIVE_PROPAGATION_DELAY" "0.00 MIL,25.00 MIL"
					( Parent
						( matchGroupRef "@baseboard_fab2_lib.baseboard_fab2(sch_1):\MG_DDR_FAR_DIMM_CMD_NG_DDR_A_DLL_10\" )
					)
					( Units "uMatchProp" "ns" 1.000000)
					( Status sCSetFlattened )
					( Origin gBackEnd )
				)
			)
			( pinPair "@baseboard_fab2_lib.baseboard_fab2(sch_1):\PP4022\"
				( pinRef "@baseboard_fab2_lib.baseboard_fab2(sch_1):page44_i13:A7" )
				( pinRef "@baseboard_fab2_lib.baseboard_fab2(sch_1):page23_i172:DDR0_MA(7)" )
				( attribute "RELATIVE_PROPAGATION_DELAY_SCOPE" "G"
					( Parent
						( matchGroupRef "@crescent_city_bb_fab1_lib.crescent_city_bb_fab1(sch_1):\MG_DDR_NEAR_DIMM-CLK1_CLS_DDR_A_CAC-CLKS\" )
					)
					( Status sCSetFlattened )
					( Origin gBackEnd )
				)
				( attribute "RELATIVE_PROPAGATION_DELAY" "0.00 MIL,700.00 MIL"
					( Parent
						( matchGroupRef "@crescent_city_bb_fab1_lib.crescent_city_bb_fab1(sch_1):\MG_DDR_NEAR_DIMM-CLK1_CLS_DDR_A_CAC-CLKS\" )
					)
					( Units "uMatchProp" "ns" 1.000000)
					( Status sCSetFlattened )
					( Origin gBackEnd )
				)
				( attribute "RELATIVE_PROPAGATION_DELAY_SCOPE" "G"
					( Parent
						( matchGroupRef "@baseboard_fab2_lib.baseboard_fab2(sch_1):\MG_DDR_CMD_NEAR_DIMM_NG_DDR_A_DLL_10\" )
					)
					( Status sCSetFlattened )
					( Origin gBackEnd )
				)
				( attribute "RELATIVE_PROPAGATION_DELAY" "0.00 MIL,25.00 MIL"
					( Parent
						( matchGroupRef "@baseboard_fab2_lib.baseboard_fab2(sch_1):\MG_DDR_CMD_NEAR_DIMM_NG_DDR_A_DLL_10\" )
					)
					( Units "uMatchProp" "ns" 1.000000)
					( Status sCSetFlattened )
					( Origin gBackEnd )
				)
			)
			( pinPair "@baseboard_fab2_lib.baseboard_fab2(sch_1):\PP4023\"
				( pinRef "@baseboard_fab2_lib.baseboard_fab2(sch_1):page23_i172:DDR0_MA(8)" )
				( pinRef "@baseboard_fab2_lib.baseboard_fab2(sch_1):page43_i1:A8" )
				( attribute "RELATIVE_PROPAGATION_DELAY_SCOPE" "G"
					( Parent
						( matchGroupRef "@crescent_city_bb_fab1_lib.crescent_city_bb_fab1(sch_1):\MG_DDR_FAR_DIMM-CLK0_CLS_DDR_A_CAC-CLKS\" )
					)
					( Status sCSetFlattened )
					( Origin gBackEnd )
				)
				( attribute "RELATIVE_PROPAGATION_DELAY" "0.00 MIL,700.00 MIL"
					( Parent
						( matchGroupRef "@crescent_city_bb_fab1_lib.crescent_city_bb_fab1(sch_1):\MG_DDR_FAR_DIMM-CLK0_CLS_DDR_A_CAC-CLKS\" )
					)
					( Units "uMatchProp" "ns" 1.000000)
					( Status sCSetFlattened )
					( Origin gBackEnd )
				)
				( attribute "RELATIVE_PROPAGATION_DELAY_SCOPE" "G"
					( Parent
						( matchGroupRef "@baseboard_fab2_lib.baseboard_fab2(sch_1):\MG_DDR_FAR_DIMM_CMD_NG_DDR_A_DLL_10\" )
					)
					( Status sCSetFlattened )
					( Origin gBackEnd )
				)
				( attribute "RELATIVE_PROPAGATION_DELAY" "0.00 MIL,25.00 MIL"
					( Parent
						( matchGroupRef "@baseboard_fab2_lib.baseboard_fab2(sch_1):\MG_DDR_FAR_DIMM_CMD_NG_DDR_A_DLL_10\" )
					)
					( Units "uMatchProp" "ns" 1.000000)
					( Status sCSetFlattened )
					( Origin gBackEnd )
				)
			)
			( pinPair "@baseboard_fab2_lib.baseboard_fab2(sch_1):\PP4024\"
				( pinRef "@baseboard_fab2_lib.baseboard_fab2(sch_1):page44_i13:A8" )
				( pinRef "@baseboard_fab2_lib.baseboard_fab2(sch_1):page23_i172:DDR0_MA(8)" )
				( attribute "RELATIVE_PROPAGATION_DELAY_SCOPE" "G"
					( Parent
						( matchGroupRef "@crescent_city_bb_fab1_lib.crescent_city_bb_fab1(sch_1):\MG_DDR_NEAR_DIMM-CLK1_CLS_DDR_A_CAC-CLKS\" )
					)
					( Status sCSetFlattened )
					( Origin gBackEnd )
				)
				( attribute "RELATIVE_PROPAGATION_DELAY" "0.00 MIL,700.00 MIL"
					( Parent
						( matchGroupRef "@crescent_city_bb_fab1_lib.crescent_city_bb_fab1(sch_1):\MG_DDR_NEAR_DIMM-CLK1_CLS_DDR_A_CAC-CLKS\" )
					)
					( Units "uMatchProp" "ns" 1.000000)
					( Status sCSetFlattened )
					( Origin gBackEnd )
				)
				( attribute "RELATIVE_PROPAGATION_DELAY_SCOPE" "G"
					( Parent
						( matchGroupRef "@baseboard_fab2_lib.baseboard_fab2(sch_1):\MG_DDR_CMD_NEAR_DIMM_NG_DDR_A_DLL_10\" )
					)
					( Status sCSetFlattened )
					( Origin gBackEnd )
				)
				( attribute "RELATIVE_PROPAGATION_DELAY" "0.00 MIL,25.00 MIL"
					( Parent
						( matchGroupRef "@baseboard_fab2_lib.baseboard_fab2(sch_1):\MG_DDR_CMD_NEAR_DIMM_NG_DDR_A_DLL_10\" )
					)
					( Units "uMatchProp" "ns" 1.000000)
					( Status sCSetFlattened )
					( Origin gBackEnd )
				)
			)
			( pinPair "@baseboard_fab2_lib.baseboard_fab2(sch_1):\PP4017\"
				( pinRef "@baseboard_fab2_lib.baseboard_fab2(sch_1):page23_i172:DDR0_MA(9)" )
				( pinRef "@baseboard_fab2_lib.baseboard_fab2(sch_1):page43_i1:A9" )
				( attribute "RELATIVE_PROPAGATION_DELAY_SCOPE" "G"
					( Parent
						( matchGroupRef "@crescent_city_bb_fab1_lib.crescent_city_bb_fab1(sch_1):\MG_DDR_FAR_DIMM-CLK0_CLS_DDR_A_CAC-CLKS\" )
					)
					( Status sCSetFlattened )
					( Origin gBackEnd )
				)
				( attribute "RELATIVE_PROPAGATION_DELAY" "0.00 MIL,700.00 MIL"
					( Parent
						( matchGroupRef "@crescent_city_bb_fab1_lib.crescent_city_bb_fab1(sch_1):\MG_DDR_FAR_DIMM-CLK0_CLS_DDR_A_CAC-CLKS\" )
					)
					( Units "uMatchProp" "ns" 1.000000)
					( Status sCSetFlattened )
					( Origin gBackEnd )
				)
				( attribute "RELATIVE_PROPAGATION_DELAY_SCOPE" "G"
					( Parent
						( matchGroupRef "@baseboard_fab2_lib.baseboard_fab2(sch_1):\MG_DDR_FAR_DIMM_CMD_NG_DDR_A_DLL_11\" )
					)
					( Status sCSetFlattened )
					( Origin gBackEnd )
				)
				( attribute "RELATIVE_PROPAGATION_DELAY" "0.00 MIL,25.00 MIL"
					( Parent
						( matchGroupRef "@baseboard_fab2_lib.baseboard_fab2(sch_1):\MG_DDR_FAR_DIMM_CMD_NG_DDR_A_DLL_11\" )
					)
					( Units "uMatchProp" "ns" 1.000000)
					( Status sCSetFlattened )
					( Origin gBackEnd )
				)
			)
			( pinPair "@baseboard_fab2_lib.baseboard_fab2(sch_1):\PP4018\"
				( pinRef "@baseboard_fab2_lib.baseboard_fab2(sch_1):page23_i172:DDR0_MA(9)" )
				( pinRef "@baseboard_fab2_lib.baseboard_fab2(sch_1):page44_i13:A9" )
				( attribute "RELATIVE_PROPAGATION_DELAY_SCOPE" "G"
					( Parent
						( matchGroupRef "@crescent_city_bb_fab1_lib.crescent_city_bb_fab1(sch_1):\MG_DDR_NEAR_DIMM-CLK1_CLS_DDR_A_CAC-CLKS\" )
					)
					( Status sCSetFlattened )
					( Origin gBackEnd )
				)
				( attribute "RELATIVE_PROPAGATION_DELAY" "0.00 MIL,700.00 MIL"
					( Parent
						( matchGroupRef "@crescent_city_bb_fab1_lib.crescent_city_bb_fab1(sch_1):\MG_DDR_NEAR_DIMM-CLK1_CLS_DDR_A_CAC-CLKS\" )
					)
					( Units "uMatchProp" "ns" 1.000000)
					( Status sCSetFlattened )
					( Origin gBackEnd )
				)
				( attribute "RELATIVE_PROPAGATION_DELAY_SCOPE" "G"
					( Parent
						( matchGroupRef "@baseboard_fab2_lib.baseboard_fab2(sch_1):\MG_DDR_CMD_NEAR_DIMM_NG_DDR_A_DLL_11\" )
					)
					( Status sCSetFlattened )
					( Origin gBackEnd )
				)
				( attribute "RELATIVE_PROPAGATION_DELAY" "0.00 MIL,25.00 MIL"
					( Parent
						( matchGroupRef "@baseboard_fab2_lib.baseboard_fab2(sch_1):\MG_DDR_CMD_NEAR_DIMM_NG_DDR_A_DLL_11\" )
					)
					( Units "uMatchProp" "ns" 1.000000)
					( Status sCSetFlattened )
					( Origin gBackEnd )
				)
			)
			( pinPair "@baseboard_fab2_lib.baseboard_fab2(sch_1):\PP4019\"
				( pinRef "@baseboard_fab2_lib.baseboard_fab2(sch_1):page23_i172:DDR0_MA(12)" )
				( pinRef "@baseboard_fab2_lib.baseboard_fab2(sch_1):page43_i1:A12" )
				( attribute "RELATIVE_PROPAGATION_DELAY_SCOPE" "G"
					( Parent
						( matchGroupRef "@crescent_city_bb_fab1_lib.crescent_city_bb_fab1(sch_1):\MG_DDR_FAR_DIMM-CLK0_CLS_DDR_A_CAC-CLKS\" )
					)
					( Status sCSetFlattened )
					( Origin gBackEnd )
				)
				( attribute "RELATIVE_PROPAGATION_DELAY" "0.00 MIL,700.00 MIL"
					( Parent
						( matchGroupRef "@crescent_city_bb_fab1_lib.crescent_city_bb_fab1(sch_1):\MG_DDR_FAR_DIMM-CLK0_CLS_DDR_A_CAC-CLKS\" )
					)
					( Units "uMatchProp" "ns" 1.000000)
					( Status sCSetFlattened )
					( Origin gBackEnd )
				)
				( attribute "RELATIVE_PROPAGATION_DELAY_SCOPE" "G"
					( Parent
						( matchGroupRef "@baseboard_fab2_lib.baseboard_fab2(sch_1):\MG_DDR_FAR_DIMM_CMD_NG_DDR_A_DLL_11\" )
					)
					( Status sCSetFlattened )
					( Origin gBackEnd )
				)
				( attribute "RELATIVE_PROPAGATION_DELAY" "0.00 MIL,25.00 MIL"
					( Parent
						( matchGroupRef "@baseboard_fab2_lib.baseboard_fab2(sch_1):\MG_DDR_FAR_DIMM_CMD_NG_DDR_A_DLL_11\" )
					)
					( Units "uMatchProp" "ns" 1.000000)
					( Status sCSetFlattened )
					( Origin gBackEnd )
				)
			)
			( pinPair "@baseboard_fab2_lib.baseboard_fab2(sch_1):\PP4020\"
				( pinRef "@baseboard_fab2_lib.baseboard_fab2(sch_1):page23_i172:DDR0_MA(12)" )
				( pinRef "@baseboard_fab2_lib.baseboard_fab2(sch_1):page44_i13:A12" )
				( attribute "RELATIVE_PROPAGATION_DELAY_SCOPE" "G"
					( Parent
						( matchGroupRef "@crescent_city_bb_fab1_lib.crescent_city_bb_fab1(sch_1):\MG_DDR_NEAR_DIMM-CLK1_CLS_DDR_A_CAC-CLKS\" )
					)
					( Status sCSetFlattened )
					( Origin gBackEnd )
				)
				( attribute "RELATIVE_PROPAGATION_DELAY" "0.00 MIL,700.00 MIL"
					( Parent
						( matchGroupRef "@crescent_city_bb_fab1_lib.crescent_city_bb_fab1(sch_1):\MG_DDR_NEAR_DIMM-CLK1_CLS_DDR_A_CAC-CLKS\" )
					)
					( Units "uMatchProp" "ns" 1.000000)
					( Status sCSetFlattened )
					( Origin gBackEnd )
				)
				( attribute "RELATIVE_PROPAGATION_DELAY_SCOPE" "G"
					( Parent
						( matchGroupRef "@baseboard_fab2_lib.baseboard_fab2(sch_1):\MG_DDR_CMD_NEAR_DIMM_NG_DDR_A_DLL_11\" )
					)
					( Status sCSetFlattened )
					( Origin gBackEnd )
				)
				( attribute "RELATIVE_PROPAGATION_DELAY" "0.00 MIL,25.00 MIL"
					( Parent
						( matchGroupRef "@baseboard_fab2_lib.baseboard_fab2(sch_1):\MG_DDR_CMD_NEAR_DIMM_NG_DDR_A_DLL_11\" )
					)
					( Units "uMatchProp" "ns" 1.000000)
					( Status sCSetFlattened )
					( Origin gBackEnd )
				)
			)
			( pinPair "@baseboard_fab2_lib.baseboard_fab2(sch_1):\PP4013\"
				( pinRef "@baseboard_fab2_lib.baseboard_fab2(sch_1):page23_i172:DDR0_BG(1)" )
				( pinRef "@baseboard_fab2_lib.baseboard_fab2(sch_1):page43_i1:BG(1)" )
				( attribute "RELATIVE_PROPAGATION_DELAY_SCOPE" "G"
					( Parent
						( matchGroupRef "@crescent_city_bb_fab1_lib.crescent_city_bb_fab1(sch_1):\MG_DDR_FAR_DIMM-CLK0_CLS_DDR_A_CAC-CLKS\" )
					)
					( Status sCSetFlattened )
					( Origin gBackEnd )
				)
				( attribute "RELATIVE_PROPAGATION_DELAY" "0.00 MIL,700.00 MIL"
					( Parent
						( matchGroupRef "@crescent_city_bb_fab1_lib.crescent_city_bb_fab1(sch_1):\MG_DDR_FAR_DIMM-CLK0_CLS_DDR_A_CAC-CLKS\" )
					)
					( Units "uMatchProp" "ns" 1.000000)
					( Status sCSetFlattened )
					( Origin gBackEnd )
				)
				( attribute "RELATIVE_PROPAGATION_DELAY_SCOPE" "G"
					( Parent
						( matchGroupRef "@baseboard_fab2_lib.baseboard_fab2(sch_1):\MG_DDR_FAR_DIMM_CMD_NG_DDR_A_DLL_12\" )
					)
					( Status sCSetFlattened )
					( Origin gBackEnd )
				)
				( attribute "RELATIVE_PROPAGATION_DELAY" "0.00 MIL,25.00 MIL"
					( Parent
						( matchGroupRef "@baseboard_fab2_lib.baseboard_fab2(sch_1):\MG_DDR_FAR_DIMM_CMD_NG_DDR_A_DLL_12\" )
					)
					( Units "uMatchProp" "ns" 1.000000)
					( Status sCSetFlattened )
					( Origin gBackEnd )
				)
			)
			( pinPair "@baseboard_fab2_lib.baseboard_fab2(sch_1):\PP4014\"
				( pinRef "@baseboard_fab2_lib.baseboard_fab2(sch_1):page23_i172:DDR0_BG(1)" )
				( pinRef "@baseboard_fab2_lib.baseboard_fab2(sch_1):page44_i13:BG(1)" )
				( attribute "RELATIVE_PROPAGATION_DELAY_SCOPE" "G"
					( Parent
						( matchGroupRef "@crescent_city_bb_fab1_lib.crescent_city_bb_fab1(sch_1):\MG_DDR_NEAR_DIMM-CLK1_CLS_DDR_A_CAC-CLKS\" )
					)
					( Status sCSetFlattened )
					( Origin gBackEnd )
				)
				( attribute "RELATIVE_PROPAGATION_DELAY" "0.00 MIL,700.00 MIL"
					( Parent
						( matchGroupRef "@crescent_city_bb_fab1_lib.crescent_city_bb_fab1(sch_1):\MG_DDR_NEAR_DIMM-CLK1_CLS_DDR_A_CAC-CLKS\" )
					)
					( Units "uMatchProp" "ns" 1.000000)
					( Status sCSetFlattened )
					( Origin gBackEnd )
				)
				( attribute "RELATIVE_PROPAGATION_DELAY_SCOPE" "G"
					( Parent
						( matchGroupRef "@baseboard_fab2_lib.baseboard_fab2(sch_1):\MG_DDR_CMD_NEAR_DIMM_NG_DDR_A_DLL_12\" )
					)
					( Status sCSetFlattened )
					( Origin gBackEnd )
				)
				( attribute "RELATIVE_PROPAGATION_DELAY" "0.00 MIL,25.00 MIL"
					( Parent
						( matchGroupRef "@baseboard_fab2_lib.baseboard_fab2(sch_1):\MG_DDR_CMD_NEAR_DIMM_NG_DDR_A_DLL_12\" )
					)
					( Units "uMatchProp" "ns" 1.000000)
					( Status sCSetFlattened )
					( Origin gBackEnd )
				)
			)
			( pinPair "@baseboard_fab2_lib.baseboard_fab2(sch_1):\PP4015\"
				( pinRef "@baseboard_fab2_lib.baseboard_fab2(sch_1):page23_i172:DDR0_MA(11)" )
				( pinRef "@baseboard_fab2_lib.baseboard_fab2(sch_1):page43_i1:A11" )
				( attribute "RELATIVE_PROPAGATION_DELAY_SCOPE" "G"
					( Parent
						( matchGroupRef "@crescent_city_bb_fab1_lib.crescent_city_bb_fab1(sch_1):\MG_DDR_FAR_DIMM-CLK0_CLS_DDR_A_CAC-CLKS\" )
					)
					( Status sCSetFlattened )
					( Origin gBackEnd )
				)
				( attribute "RELATIVE_PROPAGATION_DELAY" "0.00 MIL,700.00 MIL"
					( Parent
						( matchGroupRef "@crescent_city_bb_fab1_lib.crescent_city_bb_fab1(sch_1):\MG_DDR_FAR_DIMM-CLK0_CLS_DDR_A_CAC-CLKS\" )
					)
					( Units "uMatchProp" "ns" 1.000000)
					( Status sCSetFlattened )
					( Origin gBackEnd )
				)
				( attribute "RELATIVE_PROPAGATION_DELAY_SCOPE" "G"
					( Parent
						( matchGroupRef "@baseboard_fab2_lib.baseboard_fab2(sch_1):\MG_DDR_FAR_DIMM_CMD_NG_DDR_A_DLL_12\" )
					)
					( Status sCSetFlattened )
					( Origin gBackEnd )
				)
				( attribute "RELATIVE_PROPAGATION_DELAY" "0.00 MIL,25.00 MIL"
					( Parent
						( matchGroupRef "@baseboard_fab2_lib.baseboard_fab2(sch_1):\MG_DDR_FAR_DIMM_CMD_NG_DDR_A_DLL_12\" )
					)
					( Units "uMatchProp" "ns" 1.000000)
					( Status sCSetFlattened )
					( Origin gBackEnd )
				)
			)
			( pinPair "@baseboard_fab2_lib.baseboard_fab2(sch_1):\PP4016\"
				( pinRef "@baseboard_fab2_lib.baseboard_fab2(sch_1):page23_i172:DDR0_MA(11)" )
				( pinRef "@baseboard_fab2_lib.baseboard_fab2(sch_1):page44_i13:A11" )
				( attribute "RELATIVE_PROPAGATION_DELAY_SCOPE" "G"
					( Parent
						( matchGroupRef "@crescent_city_bb_fab1_lib.crescent_city_bb_fab1(sch_1):\MG_DDR_NEAR_DIMM-CLK1_CLS_DDR_A_CAC-CLKS\" )
					)
					( Status sCSetFlattened )
					( Origin gBackEnd )
				)
				( attribute "RELATIVE_PROPAGATION_DELAY" "0.00 MIL,700.00 MIL"
					( Parent
						( matchGroupRef "@crescent_city_bb_fab1_lib.crescent_city_bb_fab1(sch_1):\MG_DDR_NEAR_DIMM-CLK1_CLS_DDR_A_CAC-CLKS\" )
					)
					( Units "uMatchProp" "ns" 1.000000)
					( Status sCSetFlattened )
					( Origin gBackEnd )
				)
				( attribute "RELATIVE_PROPAGATION_DELAY_SCOPE" "G"
					( Parent
						( matchGroupRef "@baseboard_fab2_lib.baseboard_fab2(sch_1):\MG_DDR_CMD_NEAR_DIMM_NG_DDR_A_DLL_12\" )
					)
					( Status sCSetFlattened )
					( Origin gBackEnd )
				)
				( attribute "RELATIVE_PROPAGATION_DELAY" "0.00 MIL,25.00 MIL"
					( Parent
						( matchGroupRef "@baseboard_fab2_lib.baseboard_fab2(sch_1):\MG_DDR_CMD_NEAR_DIMM_NG_DDR_A_DLL_12\" )
					)
					( Units "uMatchProp" "ns" 1.000000)
					( Status sCSetFlattened )
					( Origin gBackEnd )
				)
			)
			( pinPair "@baseboard_fab2_lib.baseboard_fab2(sch_1):\PP4009\"
				( pinRef "@baseboard_fab2_lib.baseboard_fab2(sch_1):page23_i172:DDR0_ACT_N" )
				( pinRef "@baseboard_fab2_lib.baseboard_fab2(sch_1):page43_i1:ACT_N" )
				( attribute "RELATIVE_PROPAGATION_DELAY_SCOPE" "G"
					( Parent
						( matchGroupRef "@crescent_city_bb_fab1_lib.crescent_city_bb_fab1(sch_1):\MG_DDR_FAR_DIMM-CLK0_CLS_DDR_A_CAC-CLKS\" )
					)
					( Status sCSetFlattened )
					( Origin gBackEnd )
				)
				( attribute "RELATIVE_PROPAGATION_DELAY" "0.00 MIL,700.00 MIL"
					( Parent
						( matchGroupRef "@crescent_city_bb_fab1_lib.crescent_city_bb_fab1(sch_1):\MG_DDR_FAR_DIMM-CLK0_CLS_DDR_A_CAC-CLKS\" )
					)
					( Units "uMatchProp" "ns" 1.000000)
					( Status sCSetFlattened )
					( Origin gBackEnd )
				)
				( attribute "RELATIVE_PROPAGATION_DELAY_SCOPE" "G"
					( Parent
						( matchGroupRef "@baseboard_fab2_lib.baseboard_fab2(sch_1):\MG_DDR_FAR_DIMM_CMD_NG_DDR_A_DLL_13\" )
					)
					( Status sCSetFlattened )
					( Origin gBackEnd )
				)
				( attribute "RELATIVE_PROPAGATION_DELAY" "0.00 MIL,25.00 MIL"
					( Parent
						( matchGroupRef "@baseboard_fab2_lib.baseboard_fab2(sch_1):\MG_DDR_FAR_DIMM_CMD_NG_DDR_A_DLL_13\" )
					)
					( Units "uMatchProp" "ns" 1.000000)
					( Status sCSetFlattened )
					( Origin gBackEnd )
				)
			)
			( pinPair "@baseboard_fab2_lib.baseboard_fab2(sch_1):\PP4010\"
				( pinRef "@baseboard_fab2_lib.baseboard_fab2(sch_1):page23_i172:DDR0_ACT_N" )
				( pinRef "@baseboard_fab2_lib.baseboard_fab2(sch_1):page44_i13:ACT_N" )
				( attribute "RELATIVE_PROPAGATION_DELAY_SCOPE" "G"
					( Parent
						( matchGroupRef "@crescent_city_bb_fab1_lib.crescent_city_bb_fab1(sch_1):\MG_DDR_NEAR_DIMM-CLK1_CLS_DDR_A_CAC-CLKS\" )
					)
					( Status sCSetFlattened )
					( Origin gBackEnd )
				)
				( attribute "RELATIVE_PROPAGATION_DELAY" "0.00 MIL,700.00 MIL"
					( Parent
						( matchGroupRef "@crescent_city_bb_fab1_lib.crescent_city_bb_fab1(sch_1):\MG_DDR_NEAR_DIMM-CLK1_CLS_DDR_A_CAC-CLKS\" )
					)
					( Units "uMatchProp" "ns" 1.000000)
					( Status sCSetFlattened )
					( Origin gBackEnd )
				)
				( attribute "RELATIVE_PROPAGATION_DELAY_SCOPE" "G"
					( Parent
						( matchGroupRef "@baseboard_fab2_lib.baseboard_fab2(sch_1):\MG_DDR_CMD_NEAR_DIMM_NG_DDR_A_DLL_13\" )
					)
					( Status sCSetFlattened )
					( Origin gBackEnd )
				)
				( attribute "RELATIVE_PROPAGATION_DELAY" "0.00 MIL,25.00 MIL"
					( Parent
						( matchGroupRef "@baseboard_fab2_lib.baseboard_fab2(sch_1):\MG_DDR_CMD_NEAR_DIMM_NG_DDR_A_DLL_13\" )
					)
					( Units "uMatchProp" "ns" 1.000000)
					( Status sCSetFlattened )
					( Origin gBackEnd )
				)
			)
			( pinPair "@baseboard_fab2_lib.baseboard_fab2(sch_1):\PP4011\"
				( pinRef "@baseboard_fab2_lib.baseboard_fab2(sch_1):page23_i172:DDR0_BG(0)" )
				( pinRef "@baseboard_fab2_lib.baseboard_fab2(sch_1):page43_i1:BG(0)" )
				( attribute "RELATIVE_PROPAGATION_DELAY_SCOPE" "G"
					( Parent
						( matchGroupRef "@crescent_city_bb_fab1_lib.crescent_city_bb_fab1(sch_1):\MG_DDR_FAR_DIMM-CLK0_CLS_DDR_A_CAC-CLKS\" )
					)
					( Status sCSetFlattened )
					( Origin gBackEnd )
				)
				( attribute "RELATIVE_PROPAGATION_DELAY" "0.00 MIL,700.00 MIL"
					( Parent
						( matchGroupRef "@crescent_city_bb_fab1_lib.crescent_city_bb_fab1(sch_1):\MG_DDR_FAR_DIMM-CLK0_CLS_DDR_A_CAC-CLKS\" )
					)
					( Units "uMatchProp" "ns" 1.000000)
					( Status sCSetFlattened )
					( Origin gBackEnd )
				)
				( attribute "RELATIVE_PROPAGATION_DELAY_SCOPE" "G"
					( Parent
						( matchGroupRef "@baseboard_fab2_lib.baseboard_fab2(sch_1):\MG_DDR_FAR_DIMM_CMD_NG_DDR_A_DLL_13\" )
					)
					( Status sCSetFlattened )
					( Origin gBackEnd )
				)
				( attribute "RELATIVE_PROPAGATION_DELAY" "0.00 MIL,25.00 MIL"
					( Parent
						( matchGroupRef "@baseboard_fab2_lib.baseboard_fab2(sch_1):\MG_DDR_FAR_DIMM_CMD_NG_DDR_A_DLL_13\" )
					)
					( Units "uMatchProp" "ns" 1.000000)
					( Status sCSetFlattened )
					( Origin gBackEnd )
				)
			)
			( pinPair "@baseboard_fab2_lib.baseboard_fab2(sch_1):\PP4012\"
				( pinRef "@baseboard_fab2_lib.baseboard_fab2(sch_1):page44_i13:BG(0)" )
				( pinRef "@baseboard_fab2_lib.baseboard_fab2(sch_1):page23_i172:DDR0_BG(0)" )
				( attribute "RELATIVE_PROPAGATION_DELAY_SCOPE" "G"
					( Parent
						( matchGroupRef "@crescent_city_bb_fab1_lib.crescent_city_bb_fab1(sch_1):\MG_DDR_NEAR_DIMM-CLK1_CLS_DDR_A_CAC-CLKS\" )
					)
					( Status sCSetFlattened )
					( Origin gBackEnd )
				)
				( attribute "RELATIVE_PROPAGATION_DELAY" "0.00 MIL,700.00 MIL"
					( Parent
						( matchGroupRef "@crescent_city_bb_fab1_lib.crescent_city_bb_fab1(sch_1):\MG_DDR_NEAR_DIMM-CLK1_CLS_DDR_A_CAC-CLKS\" )
					)
					( Units "uMatchProp" "ns" 1.000000)
					( Status sCSetFlattened )
					( Origin gBackEnd )
				)
				( attribute "RELATIVE_PROPAGATION_DELAY_SCOPE" "G"
					( Parent
						( matchGroupRef "@baseboard_fab2_lib.baseboard_fab2(sch_1):\MG_DDR_CMD_NEAR_DIMM_NG_DDR_A_DLL_13\" )
					)
					( Status sCSetFlattened )
					( Origin gBackEnd )
				)
				( attribute "RELATIVE_PROPAGATION_DELAY" "0.00 MIL,25.00 MIL"
					( Parent
						( matchGroupRef "@baseboard_fab2_lib.baseboard_fab2(sch_1):\MG_DDR_CMD_NEAR_DIMM_NG_DDR_A_DLL_13\" )
					)
					( Units "uMatchProp" "ns" 1.000000)
					( Status sCSetFlattened )
					( Origin gBackEnd )
				)
			)
			( pinPair "@baseboard_fab2_lib.baseboard_fab2(sch_1):\PP4007\"
				( pinRef "@baseboard_fab2_lib.baseboard_fab2(sch_1):page43_i1:S0_N" )
				( pinRef "@baseboard_fab2_lib.baseboard_fab2(sch_1):page23_i172:DDR0_CS_N(0)" )
				( attribute "RELATIVE_PROPAGATION_DELAY_SCOPE" "G"
					( Parent
						( matchGroupRef "@crescent_city_bb_fab1_lib.crescent_city_bb_fab1(sch_1):\MG_DDR_FAR_DIMM-CLK0_CLS_DDR_A_CAC-CLKS\" )
					)
					( Status sCSetFlattened )
					( Origin gBackEnd )
				)
				( attribute "RELATIVE_PROPAGATION_DELAY" "0.00 MIL,300.00 MIL"
					( Parent
						( matchGroupRef "@crescent_city_bb_fab1_lib.crescent_city_bb_fab1(sch_1):\MG_DDR_FAR_DIMM-CLK0_CLS_DDR_A_CAC-CLKS\" )
					)
					( Units "uMatchProp" "ns" 1.000000)
					( Status sCSetFlattened )
					( Origin gBackEnd )
				)
				( attribute "RELATIVE_PROPAGATION_DELAY_SCOPE" "G"
					( Parent
						( matchGroupRef "@baseboard_fab2_lib.baseboard_fab2(sch_1):\MG_DDR_CTRL_NG_DDR_A_DLL_14\" )
					)
					( Status sCSetFlattened )
					( Origin gBackEnd )
				)
				( attribute "RELATIVE_PROPAGATION_DELAY" "0.00 MIL,25.00 MIL"
					( Parent
						( matchGroupRef "@baseboard_fab2_lib.baseboard_fab2(sch_1):\MG_DDR_CTRL_NG_DDR_A_DLL_14\" )
					)
					( Units "uMatchProp" "ns" 1.000000)
					( Status sCSetFlattened )
					( Origin gBackEnd )
				)
			)
			( pinPair "@baseboard_fab2_lib.baseboard_fab2(sch_1):\PP4008\"
				( pinRef "@baseboard_fab2_lib.baseboard_fab2(sch_1):page23_i172:DDR0_ODT(0)" )
				( pinRef "@baseboard_fab2_lib.baseboard_fab2(sch_1):page43_i1:ODT(0)" )
				( attribute "RELATIVE_PROPAGATION_DELAY_SCOPE" "G"
					( Parent
						( matchGroupRef "@crescent_city_bb_fab1_lib.crescent_city_bb_fab1(sch_1):\MG_DDR_FAR_DIMM-CLK0_CLS_DDR_A_CAC-CLKS\" )
					)
					( Status sCSetFlattened )
					( Origin gBackEnd )
				)
				( attribute "RELATIVE_PROPAGATION_DELAY" "0.00 MIL,300.00 MIL"
					( Parent
						( matchGroupRef "@crescent_city_bb_fab1_lib.crescent_city_bb_fab1(sch_1):\MG_DDR_FAR_DIMM-CLK0_CLS_DDR_A_CAC-CLKS\" )
					)
					( Units "uMatchProp" "ns" 1.000000)
					( Status sCSetFlattened )
					( Origin gBackEnd )
				)
				( attribute "RELATIVE_PROPAGATION_DELAY_SCOPE" "G"
					( Parent
						( matchGroupRef "@baseboard_fab2_lib.baseboard_fab2(sch_1):\MG_DDR_CTRL_NG_DDR_A_DLL_14\" )
					)
					( Status sCSetFlattened )
					( Origin gBackEnd )
				)
				( attribute "RELATIVE_PROPAGATION_DELAY" "0.00 MIL,25.00 MIL"
					( Parent
						( matchGroupRef "@baseboard_fab2_lib.baseboard_fab2(sch_1):\MG_DDR_CTRL_NG_DDR_A_DLL_14\" )
					)
					( Units "uMatchProp" "ns" 1.000000)
					( Status sCSetFlattened )
					( Origin gBackEnd )
				)
			)
			( pinPair "@baseboard_fab2_lib.baseboard_fab2(sch_1):\PP4006\"
				( pinRef "@baseboard_fab2_lib.baseboard_fab2(sch_1):page23_i172:DDR0_CKE(0)" )
				( pinRef "@baseboard_fab2_lib.baseboard_fab2(sch_1):page43_i1:CKE(0)" )
				( attribute "RELATIVE_PROPAGATION_DELAY_SCOPE" "G"
					( Parent
						( matchGroupRef "@crescent_city_bb_fab1_lib.crescent_city_bb_fab1(sch_1):\MG_DDR_FAR_DIMM-CLK0_CLS_DDR_A_CAC-CLKS\" )
					)
					( Status sCSetFlattened )
					( Origin gBackEnd )
				)
				( attribute "RELATIVE_PROPAGATION_DELAY" "0.00 MIL,300.00 MIL"
					( Parent
						( matchGroupRef "@crescent_city_bb_fab1_lib.crescent_city_bb_fab1(sch_1):\MG_DDR_FAR_DIMM-CLK0_CLS_DDR_A_CAC-CLKS\" )
					)
					( Units "uMatchProp" "ns" 1.000000)
					( Status sCSetFlattened )
					( Origin gBackEnd )
				)
				( attribute "RELATIVE_PROPAGATION_DELAY_SCOPE" "G"
					( Parent
						( matchGroupRef "@baseboard_fab2_lib.baseboard_fab2(sch_1):\MG_DDR_CTRL_NG_DDR_A_DLL_15\" )
					)
					( Status sCSetFlattened )
					( Origin gBackEnd )
				)
				( attribute "RELATIVE_PROPAGATION_DELAY" "0.00 MIL,25.00 MIL"
					( Parent
						( matchGroupRef "@baseboard_fab2_lib.baseboard_fab2(sch_1):\MG_DDR_CTRL_NG_DDR_A_DLL_15\" )
					)
					( Units "uMatchProp" "ns" 1.000000)
					( Status sCSetFlattened )
					( Origin gBackEnd )
				)
			)
			( pinPair "@baseboard_fab2_lib.baseboard_fab2(sch_1):\PP4005\"
				( pinRef "@baseboard_fab2_lib.baseboard_fab2(sch_1):page43_i1:S2_N_C(0)" )
				( pinRef "@baseboard_fab2_lib.baseboard_fab2(sch_1):page23_i172:DDR0_CS_N(2)" )
				( attribute "RELATIVE_PROPAGATION_DELAY_SCOPE" "G"
					( Parent
						( matchGroupRef "@crescent_city_bb_fab1_lib.crescent_city_bb_fab1(sch_1):\MG_DDR_FAR_DIMM-CLK0_CLS_DDR_A_CAC-CLKS\" )
					)
					( Status sCSetFlattened )
					( Origin gBackEnd )
				)
				( attribute "RELATIVE_PROPAGATION_DELAY" "0.00 MIL,300.00 MIL"
					( Parent
						( matchGroupRef "@crescent_city_bb_fab1_lib.crescent_city_bb_fab1(sch_1):\MG_DDR_FAR_DIMM-CLK0_CLS_DDR_A_CAC-CLKS\" )
					)
					( Units "uMatchProp" "ns" 1.000000)
					( Status sCSetFlattened )
					( Origin gBackEnd )
				)
				( attribute "RELATIVE_PROPAGATION_DELAY_SCOPE" "G"
					( Parent
						( matchGroupRef "@baseboard_fab2_lib.baseboard_fab2(sch_1):\MG_DDR_CTRL_NG_DDR_A_DLL_16\" )
					)
					( Status sCSetFlattened )
					( Origin gBackEnd )
				)
				( attribute "RELATIVE_PROPAGATION_DELAY" "0.00 MIL,25.00 MIL"
					( Parent
						( matchGroupRef "@baseboard_fab2_lib.baseboard_fab2(sch_1):\MG_DDR_CTRL_NG_DDR_A_DLL_16\" )
					)
					( Units "uMatchProp" "ns" 1.000000)
					( Status sCSetFlattened )
					( Origin gBackEnd )
				)
			)
			( pinPair "@baseboard_fab2_lib.baseboard_fab2(sch_1):\PP4004\"
				( pinRef "@baseboard_fab2_lib.baseboard_fab2(sch_1):page43_i1:S3_N_C(1)" )
				( pinRef "@baseboard_fab2_lib.baseboard_fab2(sch_1):page23_i172:DDR0_CS_N(3)" )
				( attribute "RELATIVE_PROPAGATION_DELAY_SCOPE" "G"
					( Parent
						( matchGroupRef "@crescent_city_bb_fab1_lib.crescent_city_bb_fab1(sch_1):\MG_DDR_FAR_DIMM-CLK0_CLS_DDR_A_CAC-CLKS\" )
					)
					( Status sCSetFlattened )
					( Origin gBackEnd )
				)
				( attribute "RELATIVE_PROPAGATION_DELAY" "0.00 MIL,300.00 MIL"
					( Parent
						( matchGroupRef "@crescent_city_bb_fab1_lib.crescent_city_bb_fab1(sch_1):\MG_DDR_FAR_DIMM-CLK0_CLS_DDR_A_CAC-CLKS\" )
					)
					( Units "uMatchProp" "ns" 1.000000)
					( Status sCSetFlattened )
					( Origin gBackEnd )
				)
				( attribute "RELATIVE_PROPAGATION_DELAY_SCOPE" "G"
					( Parent
						( matchGroupRef "@baseboard_fab2_lib.baseboard_fab2(sch_1):\MG_DDR_CTRL_NG_DDR_A_DLL_17\" )
					)
					( Status sCSetFlattened )
					( Origin gBackEnd )
				)
				( attribute "RELATIVE_PROPAGATION_DELAY" "0.00 MIL,25.00 MIL"
					( Parent
						( matchGroupRef "@baseboard_fab2_lib.baseboard_fab2(sch_1):\MG_DDR_CTRL_NG_DDR_A_DLL_17\" )
					)
					( Units "uMatchProp" "ns" 1.000000)
					( Status sCSetFlattened )
					( Origin gBackEnd )
				)
			)
			( pinPair "@baseboard_fab2_lib.baseboard_fab2(sch_1):\PP4002\"
				( pinRef "@baseboard_fab2_lib.baseboard_fab2(sch_1):page43_i1:S1_N" )
				( pinRef "@baseboard_fab2_lib.baseboard_fab2(sch_1):page23_i172:DDR0_CS_N(1)" )
				( attribute "RELATIVE_PROPAGATION_DELAY_SCOPE" "G"
					( Parent
						( matchGroupRef "@crescent_city_bb_fab1_lib.crescent_city_bb_fab1(sch_1):\MG_DDR_FAR_DIMM-CLK0_CLS_DDR_A_CAC-CLKS\" )
					)
					( Status sCSetFlattened )
					( Origin gBackEnd )
				)
				( attribute "RELATIVE_PROPAGATION_DELAY" "0.00 MIL,300.00 MIL"
					( Parent
						( matchGroupRef "@crescent_city_bb_fab1_lib.crescent_city_bb_fab1(sch_1):\MG_DDR_FAR_DIMM-CLK0_CLS_DDR_A_CAC-CLKS\" )
					)
					( Units "uMatchProp" "ns" 1.000000)
					( Status sCSetFlattened )
					( Origin gBackEnd )
				)
				( attribute "RELATIVE_PROPAGATION_DELAY_SCOPE" "G"
					( Parent
						( matchGroupRef "@baseboard_fab2_lib.baseboard_fab2(sch_1):\MG_DDR_CTRL_NG_DDR_A_DLL_18\" )
					)
					( Status sCSetFlattened )
					( Origin gBackEnd )
				)
				( attribute "RELATIVE_PROPAGATION_DELAY" "0.00 MIL,25.00 MIL"
					( Parent
						( matchGroupRef "@baseboard_fab2_lib.baseboard_fab2(sch_1):\MG_DDR_CTRL_NG_DDR_A_DLL_18\" )
					)
					( Units "uMatchProp" "ns" 1.000000)
					( Status sCSetFlattened )
					( Origin gBackEnd )
				)
			)
			( pinPair "@baseboard_fab2_lib.baseboard_fab2(sch_1):\PP4003\"
				( pinRef "@baseboard_fab2_lib.baseboard_fab2(sch_1):page43_i1:ODT(1)" )
				( pinRef "@baseboard_fab2_lib.baseboard_fab2(sch_1):page23_i172:DDR0_ODT(1)" )
				( attribute "RELATIVE_PROPAGATION_DELAY_SCOPE" "G"
					( Parent
						( matchGroupRef "@crescent_city_bb_fab1_lib.crescent_city_bb_fab1(sch_1):\MG_DDR_FAR_DIMM-CLK0_CLS_DDR_A_CAC-CLKS\" )
					)
					( Status sCSetFlattened )
					( Origin gBackEnd )
				)
				( attribute "RELATIVE_PROPAGATION_DELAY" "0.00 MIL,300.00 MIL"
					( Parent
						( matchGroupRef "@crescent_city_bb_fab1_lib.crescent_city_bb_fab1(sch_1):\MG_DDR_FAR_DIMM-CLK0_CLS_DDR_A_CAC-CLKS\" )
					)
					( Units "uMatchProp" "ns" 1.000000)
					( Status sCSetFlattened )
					( Origin gBackEnd )
				)
				( attribute "RELATIVE_PROPAGATION_DELAY_SCOPE" "G"
					( Parent
						( matchGroupRef "@baseboard_fab2_lib.baseboard_fab2(sch_1):\MG_DDR_CTRL_NG_DDR_A_DLL_18\" )
					)
					( Status sCSetFlattened )
					( Origin gBackEnd )
				)
				( attribute "RELATIVE_PROPAGATION_DELAY" "0.00 MIL,25.00 MIL"
					( Parent
						( matchGroupRef "@baseboard_fab2_lib.baseboard_fab2(sch_1):\MG_DDR_CTRL_NG_DDR_A_DLL_18\" )
					)
					( Units "uMatchProp" "ns" 1.000000)
					( Status sCSetFlattened )
					( Origin gBackEnd )
				)
			)
			( pinPair "@baseboard_fab2_lib.baseboard_fab2(sch_1):\PP4001\"
				( pinRef "@baseboard_fab2_lib.baseboard_fab2(sch_1):page23_i172:DDR0_CKE(1)" )
				( pinRef "@baseboard_fab2_lib.baseboard_fab2(sch_1):page43_i1:CKE(1)" )
				( attribute "RELATIVE_PROPAGATION_DELAY_SCOPE" "G"
					( Parent
						( matchGroupRef "@crescent_city_bb_fab1_lib.crescent_city_bb_fab1(sch_1):\MG_DDR_FAR_DIMM-CLK0_CLS_DDR_A_CAC-CLKS\" )
					)
					( Status sCSetFlattened )
					( Origin gBackEnd )
				)
				( attribute "RELATIVE_PROPAGATION_DELAY" "0.00 MIL,300.00 MIL"
					( Parent
						( matchGroupRef "@crescent_city_bb_fab1_lib.crescent_city_bb_fab1(sch_1):\MG_DDR_FAR_DIMM-CLK0_CLS_DDR_A_CAC-CLKS\" )
					)
					( Units "uMatchProp" "ns" 1.000000)
					( Status sCSetFlattened )
					( Origin gBackEnd )
				)
				( attribute "RELATIVE_PROPAGATION_DELAY_SCOPE" "G"
					( Parent
						( matchGroupRef "@baseboard_fab2_lib.baseboard_fab2(sch_1):\MG_DDR_CTRL_NG_DDR_A_DLL_19\" )
					)
					( Status sCSetFlattened )
					( Origin gBackEnd )
				)
				( attribute "RELATIVE_PROPAGATION_DELAY" "0.00 MIL,25.00 MIL"
					( Parent
						( matchGroupRef "@baseboard_fab2_lib.baseboard_fab2(sch_1):\MG_DDR_CTRL_NG_DDR_A_DLL_19\" )
					)
					( Units "uMatchProp" "ns" 1.000000)
					( Status sCSetFlattened )
					( Origin gBackEnd )
				)
			)
			( pinPair "@baseboard_fab2_lib.baseboard_fab2(sch_1):\PP3999\"
				( pinRef "@baseboard_fab2_lib.baseboard_fab2(sch_1):page23_i172:DDR0_CS_N(4)" )
				( pinRef "@baseboard_fab2_lib.baseboard_fab2(sch_1):page44_i13:S0_N" )
				( attribute "RELATIVE_PROPAGATION_DELAY_SCOPE" "G"
					( Parent
						( matchGroupRef "@crescent_city_bb_fab1_lib.crescent_city_bb_fab1(sch_1):\MG_DDR_NEAR_DIMM-CLK1_CLS_DDR_A_CAC-CLKS\" )
					)
					( Status sCSetFlattened )
					( Origin gBackEnd )
				)
				( attribute "RELATIVE_PROPAGATION_DELAY" "0.00 MIL,300.00 MIL"
					( Parent
						( matchGroupRef "@crescent_city_bb_fab1_lib.crescent_city_bb_fab1(sch_1):\MG_DDR_NEAR_DIMM-CLK1_CLS_DDR_A_CAC-CLKS\" )
					)
					( Units "uMatchProp" "ns" 1.000000)
					( Status sCSetFlattened )
					( Origin gBackEnd )
				)
				( attribute "RELATIVE_PROPAGATION_DELAY_SCOPE" "G"
					( Parent
						( matchGroupRef "@baseboard_fab2_lib.baseboard_fab2(sch_1):\MG_DDR_CTRL_NG_DDR_A_DLL_20\" )
					)
					( Status sCSetFlattened )
					( Origin gBackEnd )
				)
				( attribute "RELATIVE_PROPAGATION_DELAY" "0.00 MIL,25.00 MIL"
					( Parent
						( matchGroupRef "@baseboard_fab2_lib.baseboard_fab2(sch_1):\MG_DDR_CTRL_NG_DDR_A_DLL_20\" )
					)
					( Units "uMatchProp" "ns" 1.000000)
					( Status sCSetFlattened )
					( Origin gBackEnd )
				)
			)
			( pinPair "@baseboard_fab2_lib.baseboard_fab2(sch_1):\PP4000\"
				( pinRef "@baseboard_fab2_lib.baseboard_fab2(sch_1):page23_i172:DDR0_ODT(2)" )
				( pinRef "@baseboard_fab2_lib.baseboard_fab2(sch_1):page44_i13:ODT(0)" )
				( attribute "RELATIVE_PROPAGATION_DELAY_SCOPE" "G"
					( Parent
						( matchGroupRef "@crescent_city_bb_fab1_lib.crescent_city_bb_fab1(sch_1):\MG_DDR_NEAR_DIMM-CLK1_CLS_DDR_A_CAC-CLKS\" )
					)
					( Status sCSetFlattened )
					( Origin gBackEnd )
				)
				( attribute "RELATIVE_PROPAGATION_DELAY" "0.00 MIL,300.00 MIL"
					( Parent
						( matchGroupRef "@crescent_city_bb_fab1_lib.crescent_city_bb_fab1(sch_1):\MG_DDR_NEAR_DIMM-CLK1_CLS_DDR_A_CAC-CLKS\" )
					)
					( Units "uMatchProp" "ns" 1.000000)
					( Status sCSetFlattened )
					( Origin gBackEnd )
				)
				( attribute "RELATIVE_PROPAGATION_DELAY_SCOPE" "G"
					( Parent
						( matchGroupRef "@baseboard_fab2_lib.baseboard_fab2(sch_1):\MG_DDR_CTRL_NG_DDR_A_DLL_20\" )
					)
					( Status sCSetFlattened )
					( Origin gBackEnd )
				)
				( attribute "RELATIVE_PROPAGATION_DELAY" "0.00 MIL,25.00 MIL"
					( Parent
						( matchGroupRef "@baseboard_fab2_lib.baseboard_fab2(sch_1):\MG_DDR_CTRL_NG_DDR_A_DLL_20\" )
					)
					( Units "uMatchProp" "ns" 1.000000)
					( Status sCSetFlattened )
					( Origin gBackEnd )
				)
			)
			( pinPair "@baseboard_fab2_lib.baseboard_fab2(sch_1):\PP3998\"
				( pinRef "@baseboard_fab2_lib.baseboard_fab2(sch_1):page23_i172:DDR0_CKE(2)" )
				( pinRef "@baseboard_fab2_lib.baseboard_fab2(sch_1):page44_i13:CKE(0)" )
				( attribute "RELATIVE_PROPAGATION_DELAY_SCOPE" "G"
					( Parent
						( matchGroupRef "@crescent_city_bb_fab1_lib.crescent_city_bb_fab1(sch_1):\MG_DDR_NEAR_DIMM-CLK1_CLS_DDR_A_CAC-CLKS\" )
					)
					( Status sCSetFlattened )
					( Origin gBackEnd )
				)
				( attribute "RELATIVE_PROPAGATION_DELAY" "0.00 MIL,300.00 MIL"
					( Parent
						( matchGroupRef "@crescent_city_bb_fab1_lib.crescent_city_bb_fab1(sch_1):\MG_DDR_NEAR_DIMM-CLK1_CLS_DDR_A_CAC-CLKS\" )
					)
					( Units "uMatchProp" "ns" 1.000000)
					( Status sCSetFlattened )
					( Origin gBackEnd )
				)
				( attribute "RELATIVE_PROPAGATION_DELAY_SCOPE" "G"
					( Parent
						( matchGroupRef "@baseboard_fab2_lib.baseboard_fab2(sch_1):\MG_DDR_CTRL_NG_DDR_A_DLL_21\" )
					)
					( Status sCSetFlattened )
					( Origin gBackEnd )
				)
				( attribute "RELATIVE_PROPAGATION_DELAY" "0.00 MIL,25.00 MIL"
					( Parent
						( matchGroupRef "@baseboard_fab2_lib.baseboard_fab2(sch_1):\MG_DDR_CTRL_NG_DDR_A_DLL_21\" )
					)
					( Units "uMatchProp" "ns" 1.000000)
					( Status sCSetFlattened )
					( Origin gBackEnd )
				)
			)
			( pinPair "@baseboard_fab2_lib.baseboard_fab2(sch_1):\PP3996\"
				( pinRef "@baseboard_fab2_lib.baseboard_fab2(sch_1):page23_i172:DDR0_CS_N(6)" )
				( pinRef "@baseboard_fab2_lib.baseboard_fab2(sch_1):page44_i13:S2_N_C(0)" )
				( attribute "RELATIVE_PROPAGATION_DELAY_SCOPE" "G"
					( Parent
						( matchGroupRef "@crescent_city_bb_fab1_lib.crescent_city_bb_fab1(sch_1):\MG_DDR_NEAR_DIMM-CLK1_CLS_DDR_A_CAC-CLKS\" )
					)
					( Status sCSetFlattened )
					( Origin gBackEnd )
				)
				( attribute "RELATIVE_PROPAGATION_DELAY" "0.00 MIL,300.00 MIL"
					( Parent
						( matchGroupRef "@crescent_city_bb_fab1_lib.crescent_city_bb_fab1(sch_1):\MG_DDR_NEAR_DIMM-CLK1_CLS_DDR_A_CAC-CLKS\" )
					)
					( Units "uMatchProp" "ns" 1.000000)
					( Status sCSetFlattened )
					( Origin gBackEnd )
				)
				( attribute "RELATIVE_PROPAGATION_DELAY_SCOPE" "G"
					( Parent
						( matchGroupRef "@baseboard_fab2_lib.baseboard_fab2(sch_1):\MG_DDR_CTRL_NG_DDR_A_DLL_22\" )
					)
					( Status sCSetFlattened )
					( Origin gBackEnd )
				)
				( attribute "RELATIVE_PROPAGATION_DELAY" "0.00 MIL,25.00 MIL"
					( Parent
						( matchGroupRef "@baseboard_fab2_lib.baseboard_fab2(sch_1):\MG_DDR_CTRL_NG_DDR_A_DLL_22\" )
					)
					( Units "uMatchProp" "ns" 1.000000)
					( Status sCSetFlattened )
					( Origin gBackEnd )
				)
			)
			( pinPair "@baseboard_fab2_lib.baseboard_fab2(sch_1):\PP3997\"
				( pinRef "@baseboard_fab2_lib.baseboard_fab2(sch_1):page23_i172:DDR0_CS_N(7)" )
				( pinRef "@baseboard_fab2_lib.baseboard_fab2(sch_1):page44_i13:S3_N_C(1)" )
				( attribute "RELATIVE_PROPAGATION_DELAY_SCOPE" "G"
					( Parent
						( matchGroupRef "@crescent_city_bb_fab1_lib.crescent_city_bb_fab1(sch_1):\MG_DDR_NEAR_DIMM-CLK1_CLS_DDR_A_CAC-CLKS\" )
					)
					( Status sCSetFlattened )
					( Origin gBackEnd )
				)
				( attribute "RELATIVE_PROPAGATION_DELAY" "0.00 MIL,300.00 MIL"
					( Parent
						( matchGroupRef "@crescent_city_bb_fab1_lib.crescent_city_bb_fab1(sch_1):\MG_DDR_NEAR_DIMM-CLK1_CLS_DDR_A_CAC-CLKS\" )
					)
					( Units "uMatchProp" "ns" 1.000000)
					( Status sCSetFlattened )
					( Origin gBackEnd )
				)
				( attribute "RELATIVE_PROPAGATION_DELAY_SCOPE" "G"
					( Parent
						( matchGroupRef "@baseboard_fab2_lib.baseboard_fab2(sch_1):\MG_DDR_CTRL_NG_DDR_A_DLL_22\" )
					)
					( Status sCSetFlattened )
					( Origin gBackEnd )
				)
				( attribute "RELATIVE_PROPAGATION_DELAY" "0.00 MIL,25.00 MIL"
					( Parent
						( matchGroupRef "@baseboard_fab2_lib.baseboard_fab2(sch_1):\MG_DDR_CTRL_NG_DDR_A_DLL_22\" )
					)
					( Units "uMatchProp" "ns" 1.000000)
					( Status sCSetFlattened )
					( Origin gBackEnd )
				)
			)
			( pinPair "@baseboard_fab2_lib.baseboard_fab2(sch_1):\PP3994\"
				( pinRef "@baseboard_fab2_lib.baseboard_fab2(sch_1):page23_i172:DDR0_CS_N(5)" )
				( pinRef "@baseboard_fab2_lib.baseboard_fab2(sch_1):page44_i13:S1_N" )
				( attribute "RELATIVE_PROPAGATION_DELAY_SCOPE" "G"
					( Parent
						( matchGroupRef "@crescent_city_bb_fab1_lib.crescent_city_bb_fab1(sch_1):\MG_DDR_NEAR_DIMM-CLK1_CLS_DDR_A_CAC-CLKS\" )
					)
					( Status sCSetFlattened )
					( Origin gBackEnd )
				)
				( attribute "RELATIVE_PROPAGATION_DELAY" "0.00 MIL,300.00 MIL"
					( Parent
						( matchGroupRef "@crescent_city_bb_fab1_lib.crescent_city_bb_fab1(sch_1):\MG_DDR_NEAR_DIMM-CLK1_CLS_DDR_A_CAC-CLKS\" )
					)
					( Units "uMatchProp" "ns" 1.000000)
					( Status sCSetFlattened )
					( Origin gBackEnd )
				)
				( attribute "RELATIVE_PROPAGATION_DELAY_SCOPE" "G"
					( Parent
						( matchGroupRef "@baseboard_fab2_lib.baseboard_fab2(sch_1):\MG_DDR_CTRL_NG_DDR_A_DLL_23\" )
					)
					( Status sCSetFlattened )
					( Origin gBackEnd )
				)
				( attribute "RELATIVE_PROPAGATION_DELAY" "0.00 MIL,25.00 MIL"
					( Parent
						( matchGroupRef "@baseboard_fab2_lib.baseboard_fab2(sch_1):\MG_DDR_CTRL_NG_DDR_A_DLL_23\" )
					)
					( Units "uMatchProp" "ns" 1.000000)
					( Status sCSetFlattened )
					( Origin gBackEnd )
				)
			)
			( pinPair "@baseboard_fab2_lib.baseboard_fab2(sch_1):\PP3995\"
				( pinRef "@baseboard_fab2_lib.baseboard_fab2(sch_1):page23_i172:DDR0_ODT(3)" )
				( pinRef "@baseboard_fab2_lib.baseboard_fab2(sch_1):page44_i13:ODT(1)" )
				( attribute "RELATIVE_PROPAGATION_DELAY_SCOPE" "G"
					( Parent
						( matchGroupRef "@crescent_city_bb_fab1_lib.crescent_city_bb_fab1(sch_1):\MG_DDR_NEAR_DIMM-CLK1_CLS_DDR_A_CAC-CLKS\" )
					)
					( Status sCSetFlattened )
					( Origin gBackEnd )
				)
				( attribute "RELATIVE_PROPAGATION_DELAY" "0.00 MIL,300.00 MIL"
					( Parent
						( matchGroupRef "@crescent_city_bb_fab1_lib.crescent_city_bb_fab1(sch_1):\MG_DDR_NEAR_DIMM-CLK1_CLS_DDR_A_CAC-CLKS\" )
					)
					( Units "uMatchProp" "ns" 1.000000)
					( Status sCSetFlattened )
					( Origin gBackEnd )
				)
				( attribute "RELATIVE_PROPAGATION_DELAY_SCOPE" "G"
					( Parent
						( matchGroupRef "@baseboard_fab2_lib.baseboard_fab2(sch_1):\MG_DDR_CTRL_NG_DDR_A_DLL_23\" )
					)
					( Status sCSetFlattened )
					( Origin gBackEnd )
				)
				( attribute "RELATIVE_PROPAGATION_DELAY" "0.00 MIL,25.00 MIL"
					( Parent
						( matchGroupRef "@baseboard_fab2_lib.baseboard_fab2(sch_1):\MG_DDR_CTRL_NG_DDR_A_DLL_23\" )
					)
					( Units "uMatchProp" "ns" 1.000000)
					( Status sCSetFlattened )
					( Origin gBackEnd )
				)
			)
			( pinPair "@baseboard_fab2_lib.baseboard_fab2(sch_1):\PP3993\"
				( pinRef "@baseboard_fab2_lib.baseboard_fab2(sch_1):page23_i172:DDR0_CKE(3)" )
				( pinRef "@baseboard_fab2_lib.baseboard_fab2(sch_1):page44_i13:CKE(1)" )
				( attribute "RELATIVE_PROPAGATION_DELAY_SCOPE" "G"
					( Parent
						( matchGroupRef "@crescent_city_bb_fab1_lib.crescent_city_bb_fab1(sch_1):\MG_DDR_NEAR_DIMM-CLK1_CLS_DDR_A_CAC-CLKS\" )
					)
					( Status sCSetFlattened )
					( Origin gBackEnd )
				)
				( attribute "RELATIVE_PROPAGATION_DELAY" "0.00 MIL,300.00 MIL"
					( Parent
						( matchGroupRef "@crescent_city_bb_fab1_lib.crescent_city_bb_fab1(sch_1):\MG_DDR_NEAR_DIMM-CLK1_CLS_DDR_A_CAC-CLKS\" )
					)
					( Units "uMatchProp" "ns" 1.000000)
					( Status sCSetFlattened )
					( Origin gBackEnd )
				)
				( attribute "RELATIVE_PROPAGATION_DELAY_SCOPE" "G"
					( Parent
						( matchGroupRef "@baseboard_fab2_lib.baseboard_fab2(sch_1):\MG_DDR_CTRL_NG_DDR_A_DLL_24\" )
					)
					( Status sCSetFlattened )
					( Origin gBackEnd )
				)
				( attribute "RELATIVE_PROPAGATION_DELAY" "0.00 MIL,25.00 MIL"
					( Parent
						( matchGroupRef "@baseboard_fab2_lib.baseboard_fab2(sch_1):\MG_DDR_CTRL_NG_DDR_A_DLL_24\" )
					)
					( Units "uMatchProp" "ns" 1.000000)
					( Status sCSetFlattened )
					( Origin gBackEnd )
				)
			)
			( pinPair "@baseboard_fab2_lib.baseboard_fab2(sch_1):\PP4059\"
				( pinRef "@baseboard_fab2_lib.baseboard_fab2(sch_1):page28_i172:DDR5_ECC(0)" )
				( pinRef "@baseboard_fab2_lib.baseboard_fab2(sch_1):page53_i111:CB(1)" )
				( attribute "RELATIVE_PROPAGATION_DELAY_SCOPE" "G"
					( Parent
						( matchGroupRef "@baseboard_fab2_lib.baseboard_fab2(sch_1):\MG_DQ-DQS_FAR_DIMM_NG_M_F_BYTE-ECC\" )
					)
					( Status sCSetFlattened )
					( Origin gBackEnd )
				)
				( attribute "RELATIVE_PROPAGATION_DELAY" "0.00 MIL,195.00 MIL"
					( Parent
						( matchGroupRef "@baseboard_fab2_lib.baseboard_fab2(sch_1):\MG_DQ-DQS_FAR_DIMM_NG_M_F_BYTE-ECC\" )
					)
					( Units "uMatchProp" "ns" 1.000000)
					( Status sCSetFlattened )
					( Origin gBackEnd )
				)
				( attribute "RELATIVE_PROPAGATION_DELAY_SCOPE" "G"
					( Parent
						( matchGroupRef "@baseboard_fab2_lib.baseboard_fab2(sch_1):\MG_DQ_FAR_DIMM_NG_M_F_BYTE-ECC\" )
					)
					( Status sCSetFlattened )
					( Origin gBackEnd )
				)
				( attribute "RELATIVE_PROPAGATION_DELAY" "-50.00 MIL,50.00 MIL"
					( Parent
						( matchGroupRef "@baseboard_fab2_lib.baseboard_fab2(sch_1):\MG_DQ_FAR_DIMM_NG_M_F_BYTE-ECC\" )
					)
					( Units "uMatchProp" "ns" 1.000000)
					( Status sCSetFlattened )
					( Origin gBackEnd )
				)
			)
			( pinPair "@baseboard_fab2_lib.baseboard_fab2(sch_1):\PP4061\"
				( pinRef "@baseboard_fab2_lib.baseboard_fab2(sch_1):page28_i172:DDR5_ECC(0)" )
				( pinRef "@baseboard_fab2_lib.baseboard_fab2(sch_1):page54_i111:CB(0)" )
				( attribute "RELATIVE_PROPAGATION_DELAY_SCOPE" "G"
					( Parent
						( matchGroupRef "@baseboard_fab2_lib.baseboard_fab2(sch_1):\MG_DQ-DQS_NEAR_DIMM_NG_M_F_BYTE-ECC\" )
					)
					( Status sCSetFlattened )
					( Origin gBackEnd )
				)
				( attribute "RELATIVE_PROPAGATION_DELAY" "0.00 MIL,195.00 MIL"
					( Parent
						( matchGroupRef "@baseboard_fab2_lib.baseboard_fab2(sch_1):\MG_DQ-DQS_NEAR_DIMM_NG_M_F_BYTE-ECC\" )
					)
					( Units "uMatchProp" "ns" 1.000000)
					( Status sCSetFlattened )
					( Origin gBackEnd )
				)
				( attribute "RELATIVE_PROPAGATION_DELAY_SCOPE" "G"
					( Parent
						( matchGroupRef "@crescent_city_bb_fab1_lib.crescent_city_bb_fab1(sch_1):\MG_DQ_NEAR_DIMM_NG_M_F_BYTE-ECC\" )
					)
					( Status sCSetFlattened )
					( Origin gBackEnd )
				)
				( attribute "RELATIVE_PROPAGATION_DELAY" "-50.00 MIL,50.00 MIL"
					( Parent
						( matchGroupRef "@crescent_city_bb_fab1_lib.crescent_city_bb_fab1(sch_1):\MG_DQ_NEAR_DIMM_NG_M_F_BYTE-ECC\" )
					)
					( Units "uMatchProp" "ns" 1.000000)
					( Status sCSetFlattened )
					( Origin gBackEnd )
				)
			)
			( pinPair "@baseboard_fab2_lib.baseboard_fab2(sch_1):\PP4062\"
				( pinRef "@baseboard_fab2_lib.baseboard_fab2(sch_1):page28_i172:DDR5_ECC(1)" )
				( pinRef "@baseboard_fab2_lib.baseboard_fab2(sch_1):page53_i111:CB(0)" )
				( attribute "RELATIVE_PROPAGATION_DELAY_SCOPE" "G"
					( Parent
						( matchGroupRef "@baseboard_fab2_lib.baseboard_fab2(sch_1):\MG_DQ-DQS_FAR_DIMM_NG_M_F_BYTE-ECC\" )
					)
					( Status sCSetFlattened )
					( Origin gBackEnd )
				)
				( attribute "RELATIVE_PROPAGATION_DELAY" "0.00 MIL,195.00 MIL"
					( Parent
						( matchGroupRef "@baseboard_fab2_lib.baseboard_fab2(sch_1):\MG_DQ-DQS_FAR_DIMM_NG_M_F_BYTE-ECC\" )
					)
					( Units "uMatchProp" "ns" 1.000000)
					( Status sCSetFlattened )
					( Origin gBackEnd )
				)
				( attribute "RELATIVE_PROPAGATION_DELAY_SCOPE" "G"
					( Parent
						( matchGroupRef "@baseboard_fab2_lib.baseboard_fab2(sch_1):\MG_DQ_FAR_DIMM_NG_M_F_BYTE-ECC\" )
					)
					( Status sCSetFlattened )
					( Origin gBackEnd )
				)
				( attribute "RELATIVE_PROPAGATION_DELAY" "-50.00 MIL,50.00 MIL"
					( Parent
						( matchGroupRef "@baseboard_fab2_lib.baseboard_fab2(sch_1):\MG_DQ_FAR_DIMM_NG_M_F_BYTE-ECC\" )
					)
					( Units "uMatchProp" "ns" 1.000000)
					( Status sCSetFlattened )
					( Origin gBackEnd )
				)
			)
			( pinPair "@baseboard_fab2_lib.baseboard_fab2(sch_1):\PP4064\"
				( pinRef "@baseboard_fab2_lib.baseboard_fab2(sch_1):page28_i172:DDR5_ECC(1)" )
				( pinRef "@baseboard_fab2_lib.baseboard_fab2(sch_1):page54_i111:CB(1)" )
				( attribute "RELATIVE_PROPAGATION_DELAY_SCOPE" "G"
					( Parent
						( matchGroupRef "@baseboard_fab2_lib.baseboard_fab2(sch_1):\MG_DQ-DQS_NEAR_DIMM_NG_M_F_BYTE-ECC\" )
					)
					( Status sCSetFlattened )
					( Origin gBackEnd )
				)
				( attribute "RELATIVE_PROPAGATION_DELAY" "0.00 MIL,195.00 MIL"
					( Parent
						( matchGroupRef "@baseboard_fab2_lib.baseboard_fab2(sch_1):\MG_DQ-DQS_NEAR_DIMM_NG_M_F_BYTE-ECC\" )
					)
					( Units "uMatchProp" "ns" 1.000000)
					( Status sCSetFlattened )
					( Origin gBackEnd )
				)
				( attribute "RELATIVE_PROPAGATION_DELAY_SCOPE" "G"
					( Parent
						( matchGroupRef "@crescent_city_bb_fab1_lib.crescent_city_bb_fab1(sch_1):\MG_DQ_NEAR_DIMM_NG_M_F_BYTE-ECC\" )
					)
					( Status sCSetFlattened )
					( Origin gBackEnd )
				)
				( attribute "RELATIVE_PROPAGATION_DELAY" "-50.00 MIL,50.00 MIL"
					( Parent
						( matchGroupRef "@crescent_city_bb_fab1_lib.crescent_city_bb_fab1(sch_1):\MG_DQ_NEAR_DIMM_NG_M_F_BYTE-ECC\" )
					)
					( Units "uMatchProp" "ns" 1.000000)
					( Status sCSetFlattened )
					( Origin gBackEnd )
				)
			)
			( pinPair "@baseboard_fab2_lib.baseboard_fab2(sch_1):\PP4065\"
				( pinRef "@baseboard_fab2_lib.baseboard_fab2(sch_1):page28_i172:DDR5_ECC(2)" )
				( pinRef "@baseboard_fab2_lib.baseboard_fab2(sch_1):page53_i111:CB(3)" )
				( attribute "RELATIVE_PROPAGATION_DELAY_SCOPE" "G"
					( Parent
						( matchGroupRef "@baseboard_fab2_lib.baseboard_fab2(sch_1):\MG_DQ-DQS_FAR_DIMM_NG_M_F_BYTE-ECC\" )
					)
					( Status sCSetFlattened )
					( Origin gBackEnd )
				)
				( attribute "RELATIVE_PROPAGATION_DELAY" "0.00 MIL,195.00 MIL"
					( Parent
						( matchGroupRef "@baseboard_fab2_lib.baseboard_fab2(sch_1):\MG_DQ-DQS_FAR_DIMM_NG_M_F_BYTE-ECC\" )
					)
					( Units "uMatchProp" "ns" 1.000000)
					( Status sCSetFlattened )
					( Origin gBackEnd )
				)
				( attribute "RELATIVE_PROPAGATION_DELAY_SCOPE" "G"
					( Parent
						( matchGroupRef "@baseboard_fab2_lib.baseboard_fab2(sch_1):\MG_DQ_FAR_DIMM_NG_M_F_BYTE-ECC\" )
					)
					( Status sCSetFlattened )
					( Origin gBackEnd )
				)
				( attribute "RELATIVE_PROPAGATION_DELAY" "-50.00 MIL,50.00 MIL"
					( Parent
						( matchGroupRef "@baseboard_fab2_lib.baseboard_fab2(sch_1):\MG_DQ_FAR_DIMM_NG_M_F_BYTE-ECC\" )
					)
					( Units "uMatchProp" "ns" 1.000000)
					( Status sCSetFlattened )
					( Origin gBackEnd )
				)
			)
			( pinPair "@baseboard_fab2_lib.baseboard_fab2(sch_1):\PP4067\"
				( pinRef "@baseboard_fab2_lib.baseboard_fab2(sch_1):page54_i111:CB(2)" )
				( pinRef "@baseboard_fab2_lib.baseboard_fab2(sch_1):page28_i172:DDR5_ECC(2)" )
				( attribute "RELATIVE_PROPAGATION_DELAY_SCOPE" "G"
					( Parent
						( matchGroupRef "@baseboard_fab2_lib.baseboard_fab2(sch_1):\MG_DQ-DQS_NEAR_DIMM_NG_M_F_BYTE-ECC\" )
					)
					( Status sCSetFlattened )
					( Origin gBackEnd )
				)
				( attribute "RELATIVE_PROPAGATION_DELAY" "0.00 MIL,195.00 MIL"
					( Parent
						( matchGroupRef "@baseboard_fab2_lib.baseboard_fab2(sch_1):\MG_DQ-DQS_NEAR_DIMM_NG_M_F_BYTE-ECC\" )
					)
					( Units "uMatchProp" "ns" 1.000000)
					( Status sCSetFlattened )
					( Origin gBackEnd )
				)
				( attribute "RELATIVE_PROPAGATION_DELAY_SCOPE" "G"
					( Parent
						( matchGroupRef "@crescent_city_bb_fab1_lib.crescent_city_bb_fab1(sch_1):\MG_DQ_NEAR_DIMM_NG_M_F_BYTE-ECC\" )
					)
					( Status sCSetFlattened )
					( Origin gBackEnd )
				)
				( attribute "RELATIVE_PROPAGATION_DELAY" "-50.00 MIL,50.00 MIL"
					( Parent
						( matchGroupRef "@crescent_city_bb_fab1_lib.crescent_city_bb_fab1(sch_1):\MG_DQ_NEAR_DIMM_NG_M_F_BYTE-ECC\" )
					)
					( Units "uMatchProp" "ns" 1.000000)
					( Status sCSetFlattened )
					( Origin gBackEnd )
				)
			)
			( pinPair "@baseboard_fab2_lib.baseboard_fab2(sch_1):\PP4068\"
				( pinRef "@baseboard_fab2_lib.baseboard_fab2(sch_1):page28_i172:DDR5_ECC(3)" )
				( pinRef "@baseboard_fab2_lib.baseboard_fab2(sch_1):page53_i111:CB(2)" )
				( attribute "RELATIVE_PROPAGATION_DELAY_SCOPE" "G"
					( Parent
						( matchGroupRef "@baseboard_fab2_lib.baseboard_fab2(sch_1):\MG_DQ-DQS_FAR_DIMM_NG_M_F_BYTE-ECC\" )
					)
					( Status sCSetFlattened )
					( Origin gBackEnd )
				)
				( attribute "RELATIVE_PROPAGATION_DELAY" "0.00 MIL,195.00 MIL"
					( Parent
						( matchGroupRef "@baseboard_fab2_lib.baseboard_fab2(sch_1):\MG_DQ-DQS_FAR_DIMM_NG_M_F_BYTE-ECC\" )
					)
					( Units "uMatchProp" "ns" 1.000000)
					( Status sCSetFlattened )
					( Origin gBackEnd )
				)
				( attribute "RELATIVE_PROPAGATION_DELAY_SCOPE" "G"
					( Parent
						( matchGroupRef "@baseboard_fab2_lib.baseboard_fab2(sch_1):\MG_DQ_FAR_DIMM_NG_M_F_BYTE-ECC\" )
					)
					( Status sCSetFlattened )
					( Origin gBackEnd )
				)
				( attribute "RELATIVE_PROPAGATION_DELAY" "-50.00 MIL,50.00 MIL"
					( Parent
						( matchGroupRef "@baseboard_fab2_lib.baseboard_fab2(sch_1):\MG_DQ_FAR_DIMM_NG_M_F_BYTE-ECC\" )
					)
					( Units "uMatchProp" "ns" 1.000000)
					( Status sCSetFlattened )
					( Origin gBackEnd )
				)
			)
			( pinPair "@baseboard_fab2_lib.baseboard_fab2(sch_1):\PP4070\"
				( pinRef "@baseboard_fab2_lib.baseboard_fab2(sch_1):page54_i111:CB(3)" )
				( pinRef "@baseboard_fab2_lib.baseboard_fab2(sch_1):page28_i172:DDR5_ECC(3)" )
				( attribute "RELATIVE_PROPAGATION_DELAY_SCOPE" "G"
					( Parent
						( matchGroupRef "@baseboard_fab2_lib.baseboard_fab2(sch_1):\MG_DQ-DQS_NEAR_DIMM_NG_M_F_BYTE-ECC\" )
					)
					( Status sCSetFlattened )
					( Origin gBackEnd )
				)
				( attribute "RELATIVE_PROPAGATION_DELAY" "0.00 MIL,195.00 MIL"
					( Parent
						( matchGroupRef "@baseboard_fab2_lib.baseboard_fab2(sch_1):\MG_DQ-DQS_NEAR_DIMM_NG_M_F_BYTE-ECC\" )
					)
					( Units "uMatchProp" "ns" 1.000000)
					( Status sCSetFlattened )
					( Origin gBackEnd )
				)
				( attribute "RELATIVE_PROPAGATION_DELAY_SCOPE" "G"
					( Parent
						( matchGroupRef "@crescent_city_bb_fab1_lib.crescent_city_bb_fab1(sch_1):\MG_DQ_NEAR_DIMM_NG_M_F_BYTE-ECC\" )
					)
					( Status sCSetFlattened )
					( Origin gBackEnd )
				)
				( attribute "RELATIVE_PROPAGATION_DELAY" "-50.00 MIL,50.00 MIL"
					( Parent
						( matchGroupRef "@crescent_city_bb_fab1_lib.crescent_city_bb_fab1(sch_1):\MG_DQ_NEAR_DIMM_NG_M_F_BYTE-ECC\" )
					)
					( Units "uMatchProp" "ns" 1.000000)
					( Status sCSetFlattened )
					( Origin gBackEnd )
				)
			)
			( pinPair "@baseboard_fab2_lib.baseboard_fab2(sch_1):\PP4071\"
				( pinRef "@baseboard_fab2_lib.baseboard_fab2(sch_1):page28_i172:DDR5_ECC(4)" )
				( pinRef "@baseboard_fab2_lib.baseboard_fab2(sch_1):page53_i111:CB(5)" )
				( attribute "RELATIVE_PROPAGATION_DELAY_SCOPE" "G"
					( Parent
						( matchGroupRef "@baseboard_fab2_lib.baseboard_fab2(sch_1):\MG_DQ-DQS_FAR_DIMM_NG_M_F_BYTE-ECC\" )
					)
					( Status sCSetFlattened )
					( Origin gBackEnd )
				)
				( attribute "RELATIVE_PROPAGATION_DELAY" "0.00 MIL,195.00 MIL"
					( Parent
						( matchGroupRef "@baseboard_fab2_lib.baseboard_fab2(sch_1):\MG_DQ-DQS_FAR_DIMM_NG_M_F_BYTE-ECC\" )
					)
					( Units "uMatchProp" "ns" 1.000000)
					( Status sCSetFlattened )
					( Origin gBackEnd )
				)
				( attribute "RELATIVE_PROPAGATION_DELAY_SCOPE" "G"
					( Parent
						( matchGroupRef "@baseboard_fab2_lib.baseboard_fab2(sch_1):\MG_DQ_FAR_DIMM_NG_M_F_BYTE-ECC\" )
					)
					( Status sCSetFlattened )
					( Origin gBackEnd )
				)
				( attribute "RELATIVE_PROPAGATION_DELAY" "-50.00 MIL,50.00 MIL"
					( Parent
						( matchGroupRef "@baseboard_fab2_lib.baseboard_fab2(sch_1):\MG_DQ_FAR_DIMM_NG_M_F_BYTE-ECC\" )
					)
					( Units "uMatchProp" "ns" 1.000000)
					( Status sCSetFlattened )
					( Origin gBackEnd )
				)
			)
			( pinPair "@baseboard_fab2_lib.baseboard_fab2(sch_1):\PP4073\"
				( pinRef "@baseboard_fab2_lib.baseboard_fab2(sch_1):page28_i172:DDR5_ECC(4)" )
				( pinRef "@baseboard_fab2_lib.baseboard_fab2(sch_1):page54_i111:CB(4)" )
				( attribute "RELATIVE_PROPAGATION_DELAY_SCOPE" "G"
					( Parent
						( matchGroupRef "@baseboard_fab2_lib.baseboard_fab2(sch_1):\MG_DQ-DQS_NEAR_DIMM_NG_M_F_BYTE-ECC\" )
					)
					( Status sCSetFlattened )
					( Origin gBackEnd )
				)
				( attribute "RELATIVE_PROPAGATION_DELAY" "0.00 MIL,195.00 MIL"
					( Parent
						( matchGroupRef "@baseboard_fab2_lib.baseboard_fab2(sch_1):\MG_DQ-DQS_NEAR_DIMM_NG_M_F_BYTE-ECC\" )
					)
					( Units "uMatchProp" "ns" 1.000000)
					( Status sCSetFlattened )
					( Origin gBackEnd )
				)
				( attribute "RELATIVE_PROPAGATION_DELAY_SCOPE" "G"
					( Parent
						( matchGroupRef "@crescent_city_bb_fab1_lib.crescent_city_bb_fab1(sch_1):\MG_DQ_NEAR_DIMM_NG_M_F_BYTE-ECC\" )
					)
					( Status sCSetFlattened )
					( Origin gBackEnd )
				)
				( attribute "RELATIVE_PROPAGATION_DELAY" "-50.00 MIL,50.00 MIL"
					( Parent
						( matchGroupRef "@crescent_city_bb_fab1_lib.crescent_city_bb_fab1(sch_1):\MG_DQ_NEAR_DIMM_NG_M_F_BYTE-ECC\" )
					)
					( Units "uMatchProp" "ns" 1.000000)
					( Status sCSetFlattened )
					( Origin gBackEnd )
				)
			)
			( pinPair "@baseboard_fab2_lib.baseboard_fab2(sch_1):\PP4074\"
				( pinRef "@baseboard_fab2_lib.baseboard_fab2(sch_1):page28_i172:DDR5_ECC(5)" )
				( pinRef "@baseboard_fab2_lib.baseboard_fab2(sch_1):page53_i111:CB(4)" )
				( attribute "RELATIVE_PROPAGATION_DELAY_SCOPE" "G"
					( Parent
						( matchGroupRef "@baseboard_fab2_lib.baseboard_fab2(sch_1):\MG_DQ-DQS_FAR_DIMM_NG_M_F_BYTE-ECC\" )
					)
					( Status sCSetFlattened )
					( Origin gBackEnd )
				)
				( attribute "RELATIVE_PROPAGATION_DELAY" "0.00 MIL,195.00 MIL"
					( Parent
						( matchGroupRef "@baseboard_fab2_lib.baseboard_fab2(sch_1):\MG_DQ-DQS_FAR_DIMM_NG_M_F_BYTE-ECC\" )
					)
					( Units "uMatchProp" "ns" 1.000000)
					( Status sCSetFlattened )
					( Origin gBackEnd )
				)
				( attribute "RELATIVE_PROPAGATION_DELAY_SCOPE" "G"
					( Parent
						( matchGroupRef "@baseboard_fab2_lib.baseboard_fab2(sch_1):\MG_DQ_FAR_DIMM_NG_M_F_BYTE-ECC\" )
					)
					( Status sCSetFlattened )
					( Origin gBackEnd )
				)
				( attribute "RELATIVE_PROPAGATION_DELAY" "-50.00 MIL,50.00 MIL"
					( Parent
						( matchGroupRef "@baseboard_fab2_lib.baseboard_fab2(sch_1):\MG_DQ_FAR_DIMM_NG_M_F_BYTE-ECC\" )
					)
					( Units "uMatchProp" "ns" 1.000000)
					( Status sCSetFlattened )
					( Origin gBackEnd )
				)
			)
			( pinPair "@baseboard_fab2_lib.baseboard_fab2(sch_1):\PP4076\"
				( pinRef "@baseboard_fab2_lib.baseboard_fab2(sch_1):page28_i172:DDR5_ECC(5)" )
				( pinRef "@baseboard_fab2_lib.baseboard_fab2(sch_1):page54_i111:CB(5)" )
				( attribute "RELATIVE_PROPAGATION_DELAY_SCOPE" "G"
					( Parent
						( matchGroupRef "@baseboard_fab2_lib.baseboard_fab2(sch_1):\MG_DQ-DQS_NEAR_DIMM_NG_M_F_BYTE-ECC\" )
					)
					( Status sCSetFlattened )
					( Origin gBackEnd )
				)
				( attribute "RELATIVE_PROPAGATION_DELAY" "0.00 MIL,195.00 MIL"
					( Parent
						( matchGroupRef "@baseboard_fab2_lib.baseboard_fab2(sch_1):\MG_DQ-DQS_NEAR_DIMM_NG_M_F_BYTE-ECC\" )
					)
					( Units "uMatchProp" "ns" 1.000000)
					( Status sCSetFlattened )
					( Origin gBackEnd )
				)
				( attribute "RELATIVE_PROPAGATION_DELAY_SCOPE" "G"
					( Parent
						( matchGroupRef "@crescent_city_bb_fab1_lib.crescent_city_bb_fab1(sch_1):\MG_DQ_NEAR_DIMM_NG_M_F_BYTE-ECC\" )
					)
					( Status sCSetFlattened )
					( Origin gBackEnd )
				)
				( attribute "RELATIVE_PROPAGATION_DELAY" "-50.00 MIL,50.00 MIL"
					( Parent
						( matchGroupRef "@crescent_city_bb_fab1_lib.crescent_city_bb_fab1(sch_1):\MG_DQ_NEAR_DIMM_NG_M_F_BYTE-ECC\" )
					)
					( Units "uMatchProp" "ns" 1.000000)
					( Status sCSetFlattened )
					( Origin gBackEnd )
				)
			)
			( pinPair "@baseboard_fab2_lib.baseboard_fab2(sch_1):\PP4077\"
				( pinRef "@baseboard_fab2_lib.baseboard_fab2(sch_1):page28_i172:DDR5_ECC(6)" )
				( pinRef "@baseboard_fab2_lib.baseboard_fab2(sch_1):page53_i111:CB(7)" )
				( attribute "RELATIVE_PROPAGATION_DELAY_SCOPE" "G"
					( Parent
						( matchGroupRef "@baseboard_fab2_lib.baseboard_fab2(sch_1):\MG_DQ-DQS_FAR_DIMM_NG_M_F_BYTE-ECC\" )
					)
					( Status sCSetFlattened )
					( Origin gBackEnd )
				)
				( attribute "RELATIVE_PROPAGATION_DELAY" "0.00 MIL,195.00 MIL"
					( Parent
						( matchGroupRef "@baseboard_fab2_lib.baseboard_fab2(sch_1):\MG_DQ-DQS_FAR_DIMM_NG_M_F_BYTE-ECC\" )
					)
					( Units "uMatchProp" "ns" 1.000000)
					( Status sCSetFlattened )
					( Origin gBackEnd )
				)
				( attribute "RELATIVE_PROPAGATION_DELAY_SCOPE" "G"
					( Parent
						( matchGroupRef "@baseboard_fab2_lib.baseboard_fab2(sch_1):\MG_DQ_FAR_DIMM_NG_M_F_BYTE-ECC\" )
					)
					( Status sCSetFlattened )
					( Origin gBackEnd )
				)
				( attribute "RELATIVE_PROPAGATION_DELAY" "-50.00 MIL,50.00 MIL"
					( Parent
						( matchGroupRef "@baseboard_fab2_lib.baseboard_fab2(sch_1):\MG_DQ_FAR_DIMM_NG_M_F_BYTE-ECC\" )
					)
					( Units "uMatchProp" "ns" 1.000000)
					( Status sCSetFlattened )
					( Origin gBackEnd )
				)
			)
			( pinPair "@baseboard_fab2_lib.baseboard_fab2(sch_1):\PP4079\"
				( pinRef "@baseboard_fab2_lib.baseboard_fab2(sch_1):page54_i111:CB(6)" )
				( pinRef "@baseboard_fab2_lib.baseboard_fab2(sch_1):page28_i172:DDR5_ECC(6)" )
				( attribute "RELATIVE_PROPAGATION_DELAY_SCOPE" "G"
					( Parent
						( matchGroupRef "@baseboard_fab2_lib.baseboard_fab2(sch_1):\MG_DQ-DQS_NEAR_DIMM_NG_M_F_BYTE-ECC\" )
					)
					( Status sCSetFlattened )
					( Origin gBackEnd )
				)
				( attribute "RELATIVE_PROPAGATION_DELAY" "0.00 MIL,195.00 MIL"
					( Parent
						( matchGroupRef "@baseboard_fab2_lib.baseboard_fab2(sch_1):\MG_DQ-DQS_NEAR_DIMM_NG_M_F_BYTE-ECC\" )
					)
					( Units "uMatchProp" "ns" 1.000000)
					( Status sCSetFlattened )
					( Origin gBackEnd )
				)
				( attribute "RELATIVE_PROPAGATION_DELAY_SCOPE" "G"
					( Parent
						( matchGroupRef "@crescent_city_bb_fab1_lib.crescent_city_bb_fab1(sch_1):\MG_DQ_NEAR_DIMM_NG_M_F_BYTE-ECC\" )
					)
					( Status sCSetFlattened )
					( Origin gBackEnd )
				)
				( attribute "RELATIVE_PROPAGATION_DELAY" "-50.00 MIL,50.00 MIL"
					( Parent
						( matchGroupRef "@crescent_city_bb_fab1_lib.crescent_city_bb_fab1(sch_1):\MG_DQ_NEAR_DIMM_NG_M_F_BYTE-ECC\" )
					)
					( Units "uMatchProp" "ns" 1.000000)
					( Status sCSetFlattened )
					( Origin gBackEnd )
				)
			)
			( pinPair "@baseboard_fab2_lib.baseboard_fab2(sch_1):\PP4080\"
				( pinRef "@baseboard_fab2_lib.baseboard_fab2(sch_1):page28_i172:DDR5_ECC(7)" )
				( pinRef "@baseboard_fab2_lib.baseboard_fab2(sch_1):page53_i111:CB(6)" )
				( attribute "RELATIVE_PROPAGATION_DELAY_SCOPE" "G"
					( Parent
						( matchGroupRef "@baseboard_fab2_lib.baseboard_fab2(sch_1):\MG_DQ-DQS_FAR_DIMM_NG_M_F_BYTE-ECC\" )
					)
					( Status sCSetFlattened )
					( Origin gBackEnd )
				)
				( attribute "RELATIVE_PROPAGATION_DELAY" "0.00 MIL,195.00 MIL"
					( Parent
						( matchGroupRef "@baseboard_fab2_lib.baseboard_fab2(sch_1):\MG_DQ-DQS_FAR_DIMM_NG_M_F_BYTE-ECC\" )
					)
					( Units "uMatchProp" "ns" 1.000000)
					( Status sCSetFlattened )
					( Origin gBackEnd )
				)
				( attribute "RELATIVE_PROPAGATION_DELAY_SCOPE" "G"
					( Parent
						( matchGroupRef "@baseboard_fab2_lib.baseboard_fab2(sch_1):\MG_DQ_FAR_DIMM_NG_M_F_BYTE-ECC\" )
					)
					( Status sCSetFlattened )
					( Origin gBackEnd )
				)
				( attribute "RELATIVE_PROPAGATION_DELAY" "-50.00 MIL,50.00 MIL"
					( Parent
						( matchGroupRef "@baseboard_fab2_lib.baseboard_fab2(sch_1):\MG_DQ_FAR_DIMM_NG_M_F_BYTE-ECC\" )
					)
					( Units "uMatchProp" "ns" 1.000000)
					( Status sCSetFlattened )
					( Origin gBackEnd )
				)
			)
			( pinPair "@baseboard_fab2_lib.baseboard_fab2(sch_1):\PP4082\"
				( pinRef "@baseboard_fab2_lib.baseboard_fab2(sch_1):page54_i111:CB(7)" )
				( pinRef "@baseboard_fab2_lib.baseboard_fab2(sch_1):page28_i172:DDR5_ECC(7)" )
				( attribute "RELATIVE_PROPAGATION_DELAY_SCOPE" "G"
					( Parent
						( matchGroupRef "@baseboard_fab2_lib.baseboard_fab2(sch_1):\MG_DQ-DQS_NEAR_DIMM_NG_M_F_BYTE-ECC\" )
					)
					( Status sCSetFlattened )
					( Origin gBackEnd )
				)
				( attribute "RELATIVE_PROPAGATION_DELAY" "0.00 MIL,195.00 MIL"
					( Parent
						( matchGroupRef "@baseboard_fab2_lib.baseboard_fab2(sch_1):\MG_DQ-DQS_NEAR_DIMM_NG_M_F_BYTE-ECC\" )
					)
					( Units "uMatchProp" "ns" 1.000000)
					( Status sCSetFlattened )
					( Origin gBackEnd )
				)
				( attribute "RELATIVE_PROPAGATION_DELAY_SCOPE" "G"
					( Parent
						( matchGroupRef "@crescent_city_bb_fab1_lib.crescent_city_bb_fab1(sch_1):\MG_DQ_NEAR_DIMM_NG_M_F_BYTE-ECC\" )
					)
					( Origin gBackEnd )
				)
				( attribute "RELATIVE_PROPAGATION_DELAY" "TARGET,TARGET"
					( Parent
						( matchGroupRef "@crescent_city_bb_fab1_lib.crescent_city_bb_fab1(sch_1):\MG_DQ_NEAR_DIMM_NG_M_F_BYTE-ECC\" )
					)
					( Units "uMatchProp" "ns" 1.000000)
					( Origin gBackEnd )
				)
			)
			( pinPair "@baseboard_fab2_lib.baseboard_fab2(sch_1):\PP2947\"
				( pinRef "@baseboard_fab2_lib.baseboard_fab2(sch_1):page57_i172:DDR0_ECC(0)" )
				( pinRef "@baseboard_fab2_lib.baseboard_fab2(sch_1):page77_i111:CB(1)" )
				( attribute "RELATIVE_PROPAGATION_DELAY_SCOPE" "G"
					( Parent
						( matchGroupRef "@baseboard_fab2_lib.baseboard_fab2(sch_1):\MG_DQ-DQS_FAR_DIMM_NG_M_G_BYTE-ECC\" )
					)
					( Status sCSetFlattened )
					( Origin gBackEnd )
				)
				( attribute "RELATIVE_PROPAGATION_DELAY" "0.00 MIL,195.00 MIL"
					( Parent
						( matchGroupRef "@baseboard_fab2_lib.baseboard_fab2(sch_1):\MG_DQ-DQS_FAR_DIMM_NG_M_G_BYTE-ECC\" )
					)
					( Units "uMatchProp" "ns" 1.000000)
					( Status sCSetFlattened )
					( Origin gBackEnd )
				)
				( attribute "RELATIVE_PROPAGATION_DELAY_SCOPE" "G"
					( Parent
						( matchGroupRef "@crescent_city_bb_fab1_lib.crescent_city_bb_fab1(sch_1):\MG_DQ_FAR_DIMM_NG_M_G_BYTE-ECC\" )
					)
					( Status sCSetFlattened )
					( Origin gBackEnd )
				)
				( attribute "RELATIVE_PROPAGATION_DELAY" "-50.00 MIL,50.00 MIL"
					( Parent
						( matchGroupRef "@crescent_city_bb_fab1_lib.crescent_city_bb_fab1(sch_1):\MG_DQ_FAR_DIMM_NG_M_G_BYTE-ECC\" )
					)
					( Units "uMatchProp" "ns" 1.000000)
					( Status sCSetFlattened )
					( Origin gBackEnd )
				)
			)
			( pinPair "@baseboard_fab2_lib.baseboard_fab2(sch_1):\PP2948\"
				( pinRef "@baseboard_fab2_lib.baseboard_fab2(sch_1):page78_i13:CB(0)" )
				( pinRef "@baseboard_fab2_lib.baseboard_fab2(sch_1):page57_i172:DDR0_ECC(0)" )
				( attribute "RELATIVE_PROPAGATION_DELAY_SCOPE" "G"
					( Parent
						( matchGroupRef "@baseboard_fab2_lib.baseboard_fab2(sch_1):\MG_DQ-DQS_NEAR_DIMM_NG_M_G_BYTE-ECC\" )
					)
					( Status sCSetFlattened )
					( Origin gBackEnd )
				)
				( attribute "RELATIVE_PROPAGATION_DELAY" "0.00 MIL,195.00 MIL"
					( Parent
						( matchGroupRef "@baseboard_fab2_lib.baseboard_fab2(sch_1):\MG_DQ-DQS_NEAR_DIMM_NG_M_G_BYTE-ECC\" )
					)
					( Units "uMatchProp" "ns" 1.000000)
					( Status sCSetFlattened )
					( Origin gBackEnd )
				)
				( attribute "RELATIVE_PROPAGATION_DELAY_SCOPE" "G"
					( Parent
						( matchGroupRef "@crescent_city_bb_fab1_lib.crescent_city_bb_fab1(sch_1):\MG_DQ_NEAR_DIMM_NG_M_G_BYTE-ECC\" )
					)
					( Status sCSetFlattened )
					( Origin gBackEnd )
				)
				( attribute "RELATIVE_PROPAGATION_DELAY" "-50.00 MIL,50.00 MIL"
					( Parent
						( matchGroupRef "@crescent_city_bb_fab1_lib.crescent_city_bb_fab1(sch_1):\MG_DQ_NEAR_DIMM_NG_M_G_BYTE-ECC\" )
					)
					( Units "uMatchProp" "ns" 1.000000)
					( Status sCSetFlattened )
					( Origin gBackEnd )
				)
			)
			( pinPair "@baseboard_fab2_lib.baseboard_fab2(sch_1):\PP2950\"
				( pinRef "@baseboard_fab2_lib.baseboard_fab2(sch_1):page57_i172:DDR0_ECC(1)" )
				( pinRef "@baseboard_fab2_lib.baseboard_fab2(sch_1):page77_i111:CB(0)" )
				( attribute "RELATIVE_PROPAGATION_DELAY_SCOPE" "G"
					( Parent
						( matchGroupRef "@baseboard_fab2_lib.baseboard_fab2(sch_1):\MG_DQ-DQS_FAR_DIMM_NG_M_G_BYTE-ECC\" )
					)
					( Status sCSetFlattened )
					( Origin gBackEnd )
				)
				( attribute "RELATIVE_PROPAGATION_DELAY" "0.00 MIL,195.00 MIL"
					( Parent
						( matchGroupRef "@baseboard_fab2_lib.baseboard_fab2(sch_1):\MG_DQ-DQS_FAR_DIMM_NG_M_G_BYTE-ECC\" )
					)
					( Units "uMatchProp" "ns" 1.000000)
					( Status sCSetFlattened )
					( Origin gBackEnd )
				)
				( attribute "RELATIVE_PROPAGATION_DELAY_SCOPE" "G"
					( Parent
						( matchGroupRef "@crescent_city_bb_fab1_lib.crescent_city_bb_fab1(sch_1):\MG_DQ_FAR_DIMM_NG_M_G_BYTE-ECC\" )
					)
					( Origin gBackEnd )
				)
				( attribute "RELATIVE_PROPAGATION_DELAY" "TARGET,TARGET"
					( Parent
						( matchGroupRef "@crescent_city_bb_fab1_lib.crescent_city_bb_fab1(sch_1):\MG_DQ_FAR_DIMM_NG_M_G_BYTE-ECC\" )
					)
					( Units "uMatchProp" "ns" 1.000000)
					( Origin gBackEnd )
				)
			)
			( pinPair "@baseboard_fab2_lib.baseboard_fab2(sch_1):\PP2951\"
				( pinRef "@baseboard_fab2_lib.baseboard_fab2(sch_1):page78_i13:CB(1)" )
				( pinRef "@baseboard_fab2_lib.baseboard_fab2(sch_1):page57_i172:DDR0_ECC(1)" )
				( attribute "RELATIVE_PROPAGATION_DELAY_SCOPE" "G"
					( Parent
						( matchGroupRef "@baseboard_fab2_lib.baseboard_fab2(sch_1):\MG_DQ-DQS_NEAR_DIMM_NG_M_G_BYTE-ECC\" )
					)
					( Status sCSetFlattened )
					( Origin gBackEnd )
				)
				( attribute "RELATIVE_PROPAGATION_DELAY" "0.00 MIL,195.00 MIL"
					( Parent
						( matchGroupRef "@baseboard_fab2_lib.baseboard_fab2(sch_1):\MG_DQ-DQS_NEAR_DIMM_NG_M_G_BYTE-ECC\" )
					)
					( Units "uMatchProp" "ns" 1.000000)
					( Status sCSetFlattened )
					( Origin gBackEnd )
				)
				( attribute "RELATIVE_PROPAGATION_DELAY_SCOPE" "G"
					( Parent
						( matchGroupRef "@crescent_city_bb_fab1_lib.crescent_city_bb_fab1(sch_1):\MG_DQ_NEAR_DIMM_NG_M_G_BYTE-ECC\" )
					)
					( Origin gBackEnd )
				)
				( attribute "RELATIVE_PROPAGATION_DELAY" "TARGET,TARGET"
					( Parent
						( matchGroupRef "@crescent_city_bb_fab1_lib.crescent_city_bb_fab1(sch_1):\MG_DQ_NEAR_DIMM_NG_M_G_BYTE-ECC\" )
					)
					( Units "uMatchProp" "ns" 1.000000)
					( Origin gBackEnd )
				)
			)
			( pinPair "@baseboard_fab2_lib.baseboard_fab2(sch_1):\PP2953\"
				( pinRef "@baseboard_fab2_lib.baseboard_fab2(sch_1):page57_i172:DDR0_ECC(2)" )
				( pinRef "@baseboard_fab2_lib.baseboard_fab2(sch_1):page77_i111:CB(3)" )
				( attribute "RELATIVE_PROPAGATION_DELAY_SCOPE" "G"
					( Parent
						( matchGroupRef "@baseboard_fab2_lib.baseboard_fab2(sch_1):\MG_DQ-DQS_FAR_DIMM_NG_M_G_BYTE-ECC\" )
					)
					( Status sCSetFlattened )
					( Origin gBackEnd )
				)
				( attribute "RELATIVE_PROPAGATION_DELAY" "0.00 MIL,195.00 MIL"
					( Parent
						( matchGroupRef "@baseboard_fab2_lib.baseboard_fab2(sch_1):\MG_DQ-DQS_FAR_DIMM_NG_M_G_BYTE-ECC\" )
					)
					( Units "uMatchProp" "ns" 1.000000)
					( Status sCSetFlattened )
					( Origin gBackEnd )
				)
				( attribute "RELATIVE_PROPAGATION_DELAY_SCOPE" "G"
					( Parent
						( matchGroupRef "@crescent_city_bb_fab1_lib.crescent_city_bb_fab1(sch_1):\MG_DQ_FAR_DIMM_NG_M_G_BYTE-ECC\" )
					)
					( Status sCSetFlattened )
					( Origin gBackEnd )
				)
				( attribute "RELATIVE_PROPAGATION_DELAY" "-50.00 MIL,50.00 MIL"
					( Parent
						( matchGroupRef "@crescent_city_bb_fab1_lib.crescent_city_bb_fab1(sch_1):\MG_DQ_FAR_DIMM_NG_M_G_BYTE-ECC\" )
					)
					( Units "uMatchProp" "ns" 1.000000)
					( Status sCSetFlattened )
					( Origin gBackEnd )
				)
			)
			( pinPair "@baseboard_fab2_lib.baseboard_fab2(sch_1):\PP2954\"
				( pinRef "@baseboard_fab2_lib.baseboard_fab2(sch_1):page57_i172:DDR0_ECC(2)" )
				( pinRef "@baseboard_fab2_lib.baseboard_fab2(sch_1):page78_i13:CB(2)" )
				( attribute "RELATIVE_PROPAGATION_DELAY_SCOPE" "G"
					( Parent
						( matchGroupRef "@baseboard_fab2_lib.baseboard_fab2(sch_1):\MG_DQ-DQS_NEAR_DIMM_NG_M_G_BYTE-ECC\" )
					)
					( Status sCSetFlattened )
					( Origin gBackEnd )
				)
				( attribute "RELATIVE_PROPAGATION_DELAY" "0.00 MIL,195.00 MIL"
					( Parent
						( matchGroupRef "@baseboard_fab2_lib.baseboard_fab2(sch_1):\MG_DQ-DQS_NEAR_DIMM_NG_M_G_BYTE-ECC\" )
					)
					( Units "uMatchProp" "ns" 1.000000)
					( Status sCSetFlattened )
					( Origin gBackEnd )
				)
				( attribute "RELATIVE_PROPAGATION_DELAY_SCOPE" "G"
					( Parent
						( matchGroupRef "@crescent_city_bb_fab1_lib.crescent_city_bb_fab1(sch_1):\MG_DQ_NEAR_DIMM_NG_M_G_BYTE-ECC\" )
					)
					( Status sCSetFlattened )
					( Origin gBackEnd )
				)
				( attribute "RELATIVE_PROPAGATION_DELAY" "-50.00 MIL,50.00 MIL"
					( Parent
						( matchGroupRef "@crescent_city_bb_fab1_lib.crescent_city_bb_fab1(sch_1):\MG_DQ_NEAR_DIMM_NG_M_G_BYTE-ECC\" )
					)
					( Units "uMatchProp" "ns" 1.000000)
					( Status sCSetFlattened )
					( Origin gBackEnd )
				)
			)
			( pinPair "@baseboard_fab2_lib.baseboard_fab2(sch_1):\PP2956\"
				( pinRef "@baseboard_fab2_lib.baseboard_fab2(sch_1):page57_i172:DDR0_ECC(3)" )
				( pinRef "@baseboard_fab2_lib.baseboard_fab2(sch_1):page77_i111:CB(2)" )
				( attribute "RELATIVE_PROPAGATION_DELAY_SCOPE" "G"
					( Parent
						( matchGroupRef "@baseboard_fab2_lib.baseboard_fab2(sch_1):\MG_DQ-DQS_FAR_DIMM_NG_M_G_BYTE-ECC\" )
					)
					( Status sCSetFlattened )
					( Origin gBackEnd )
				)
				( attribute "RELATIVE_PROPAGATION_DELAY" "0.00 MIL,195.00 MIL"
					( Parent
						( matchGroupRef "@baseboard_fab2_lib.baseboard_fab2(sch_1):\MG_DQ-DQS_FAR_DIMM_NG_M_G_BYTE-ECC\" )
					)
					( Units "uMatchProp" "ns" 1.000000)
					( Status sCSetFlattened )
					( Origin gBackEnd )
				)
				( attribute "RELATIVE_PROPAGATION_DELAY_SCOPE" "G"
					( Parent
						( matchGroupRef "@crescent_city_bb_fab1_lib.crescent_city_bb_fab1(sch_1):\MG_DQ_FAR_DIMM_NG_M_G_BYTE-ECC\" )
					)
					( Status sCSetFlattened )
					( Origin gBackEnd )
				)
				( attribute "RELATIVE_PROPAGATION_DELAY" "-50.00 MIL,50.00 MIL"
					( Parent
						( matchGroupRef "@crescent_city_bb_fab1_lib.crescent_city_bb_fab1(sch_1):\MG_DQ_FAR_DIMM_NG_M_G_BYTE-ECC\" )
					)
					( Units "uMatchProp" "ns" 1.000000)
					( Status sCSetFlattened )
					( Origin gBackEnd )
				)
			)
			( pinPair "@baseboard_fab2_lib.baseboard_fab2(sch_1):\PP2957\"
				( pinRef "@baseboard_fab2_lib.baseboard_fab2(sch_1):page78_i13:CB(3)" )
				( pinRef "@baseboard_fab2_lib.baseboard_fab2(sch_1):page57_i172:DDR0_ECC(3)" )
				( attribute "RELATIVE_PROPAGATION_DELAY_SCOPE" "G"
					( Parent
						( matchGroupRef "@baseboard_fab2_lib.baseboard_fab2(sch_1):\MG_DQ-DQS_NEAR_DIMM_NG_M_G_BYTE-ECC\" )
					)
					( Status sCSetFlattened )
					( Origin gBackEnd )
				)
				( attribute "RELATIVE_PROPAGATION_DELAY" "0.00 MIL,195.00 MIL"
					( Parent
						( matchGroupRef "@baseboard_fab2_lib.baseboard_fab2(sch_1):\MG_DQ-DQS_NEAR_DIMM_NG_M_G_BYTE-ECC\" )
					)
					( Units "uMatchProp" "ns" 1.000000)
					( Status sCSetFlattened )
					( Origin gBackEnd )
				)
				( attribute "RELATIVE_PROPAGATION_DELAY_SCOPE" "G"
					( Parent
						( matchGroupRef "@crescent_city_bb_fab1_lib.crescent_city_bb_fab1(sch_1):\MG_DQ_NEAR_DIMM_NG_M_G_BYTE-ECC\" )
					)
					( Status sCSetFlattened )
					( Origin gBackEnd )
				)
				( attribute "RELATIVE_PROPAGATION_DELAY" "-50.00 MIL,50.00 MIL"
					( Parent
						( matchGroupRef "@crescent_city_bb_fab1_lib.crescent_city_bb_fab1(sch_1):\MG_DQ_NEAR_DIMM_NG_M_G_BYTE-ECC\" )
					)
					( Units "uMatchProp" "ns" 1.000000)
					( Status sCSetFlattened )
					( Origin gBackEnd )
				)
			)
			( pinPair "@baseboard_fab2_lib.baseboard_fab2(sch_1):\PP2959\"
				( pinRef "@baseboard_fab2_lib.baseboard_fab2(sch_1):page57_i172:DDR0_ECC(4)" )
				( pinRef "@baseboard_fab2_lib.baseboard_fab2(sch_1):page77_i111:CB(5)" )
				( attribute "RELATIVE_PROPAGATION_DELAY_SCOPE" "G"
					( Parent
						( matchGroupRef "@baseboard_fab2_lib.baseboard_fab2(sch_1):\MG_DQ-DQS_FAR_DIMM_NG_M_G_BYTE-ECC\" )
					)
					( Status sCSetFlattened )
					( Origin gBackEnd )
				)
				( attribute "RELATIVE_PROPAGATION_DELAY" "0.00 MIL,195.00 MIL"
					( Parent
						( matchGroupRef "@baseboard_fab2_lib.baseboard_fab2(sch_1):\MG_DQ-DQS_FAR_DIMM_NG_M_G_BYTE-ECC\" )
					)
					( Units "uMatchProp" "ns" 1.000000)
					( Status sCSetFlattened )
					( Origin gBackEnd )
				)
				( attribute "RELATIVE_PROPAGATION_DELAY_SCOPE" "G"
					( Parent
						( matchGroupRef "@crescent_city_bb_fab1_lib.crescent_city_bb_fab1(sch_1):\MG_DQ_FAR_DIMM_NG_M_G_BYTE-ECC\" )
					)
					( Status sCSetFlattened )
					( Origin gBackEnd )
				)
				( attribute "RELATIVE_PROPAGATION_DELAY" "-50.00 MIL,50.00 MIL"
					( Parent
						( matchGroupRef "@crescent_city_bb_fab1_lib.crescent_city_bb_fab1(sch_1):\MG_DQ_FAR_DIMM_NG_M_G_BYTE-ECC\" )
					)
					( Units "uMatchProp" "ns" 1.000000)
					( Status sCSetFlattened )
					( Origin gBackEnd )
				)
			)
			( pinPair "@baseboard_fab2_lib.baseboard_fab2(sch_1):\PP2960\"
				( pinRef "@baseboard_fab2_lib.baseboard_fab2(sch_1):page78_i13:CB(4)" )
				( pinRef "@baseboard_fab2_lib.baseboard_fab2(sch_1):page57_i172:DDR0_ECC(4)" )
				( attribute "RELATIVE_PROPAGATION_DELAY_SCOPE" "G"
					( Parent
						( matchGroupRef "@baseboard_fab2_lib.baseboard_fab2(sch_1):\MG_DQ-DQS_NEAR_DIMM_NG_M_G_BYTE-ECC\" )
					)
					( Status sCSetFlattened )
					( Origin gBackEnd )
				)
				( attribute "RELATIVE_PROPAGATION_DELAY" "0.00 MIL,195.00 MIL"
					( Parent
						( matchGroupRef "@baseboard_fab2_lib.baseboard_fab2(sch_1):\MG_DQ-DQS_NEAR_DIMM_NG_M_G_BYTE-ECC\" )
					)
					( Units "uMatchProp" "ns" 1.000000)
					( Status sCSetFlattened )
					( Origin gBackEnd )
				)
				( attribute "RELATIVE_PROPAGATION_DELAY_SCOPE" "G"
					( Parent
						( matchGroupRef "@crescent_city_bb_fab1_lib.crescent_city_bb_fab1(sch_1):\MG_DQ_NEAR_DIMM_NG_M_G_BYTE-ECC\" )
					)
					( Status sCSetFlattened )
					( Origin gBackEnd )
				)
				( attribute "RELATIVE_PROPAGATION_DELAY" "-50.00 MIL,50.00 MIL"
					( Parent
						( matchGroupRef "@crescent_city_bb_fab1_lib.crescent_city_bb_fab1(sch_1):\MG_DQ_NEAR_DIMM_NG_M_G_BYTE-ECC\" )
					)
					( Units "uMatchProp" "ns" 1.000000)
					( Status sCSetFlattened )
					( Origin gBackEnd )
				)
			)
			( pinPair "@baseboard_fab2_lib.baseboard_fab2(sch_1):\PP2962\"
				( pinRef "@baseboard_fab2_lib.baseboard_fab2(sch_1):page57_i172:DDR0_ECC(5)" )
				( pinRef "@baseboard_fab2_lib.baseboard_fab2(sch_1):page77_i111:CB(4)" )
				( attribute "RELATIVE_PROPAGATION_DELAY_SCOPE" "G"
					( Parent
						( matchGroupRef "@baseboard_fab2_lib.baseboard_fab2(sch_1):\MG_DQ-DQS_FAR_DIMM_NG_M_G_BYTE-ECC\" )
					)
					( Status sCSetFlattened )
					( Origin gBackEnd )
				)
				( attribute "RELATIVE_PROPAGATION_DELAY" "0.00 MIL,195.00 MIL"
					( Parent
						( matchGroupRef "@baseboard_fab2_lib.baseboard_fab2(sch_1):\MG_DQ-DQS_FAR_DIMM_NG_M_G_BYTE-ECC\" )
					)
					( Units "uMatchProp" "ns" 1.000000)
					( Status sCSetFlattened )
					( Origin gBackEnd )
				)
				( attribute "RELATIVE_PROPAGATION_DELAY_SCOPE" "G"
					( Parent
						( matchGroupRef "@crescent_city_bb_fab1_lib.crescent_city_bb_fab1(sch_1):\MG_DQ_FAR_DIMM_NG_M_G_BYTE-ECC\" )
					)
					( Status sCSetFlattened )
					( Origin gBackEnd )
				)
				( attribute "RELATIVE_PROPAGATION_DELAY" "-50.00 MIL,50.00 MIL"
					( Parent
						( matchGroupRef "@crescent_city_bb_fab1_lib.crescent_city_bb_fab1(sch_1):\MG_DQ_FAR_DIMM_NG_M_G_BYTE-ECC\" )
					)
					( Units "uMatchProp" "ns" 1.000000)
					( Status sCSetFlattened )
					( Origin gBackEnd )
				)
			)
			( pinPair "@baseboard_fab2_lib.baseboard_fab2(sch_1):\PP2963\"
				( pinRef "@baseboard_fab2_lib.baseboard_fab2(sch_1):page78_i13:CB(5)" )
				( pinRef "@baseboard_fab2_lib.baseboard_fab2(sch_1):page57_i172:DDR0_ECC(5)" )
				( attribute "RELATIVE_PROPAGATION_DELAY_SCOPE" "G"
					( Parent
						( matchGroupRef "@baseboard_fab2_lib.baseboard_fab2(sch_1):\MG_DQ-DQS_NEAR_DIMM_NG_M_G_BYTE-ECC\" )
					)
					( Status sCSetFlattened )
					( Origin gBackEnd )
				)
				( attribute "RELATIVE_PROPAGATION_DELAY" "0.00 MIL,195.00 MIL"
					( Parent
						( matchGroupRef "@baseboard_fab2_lib.baseboard_fab2(sch_1):\MG_DQ-DQS_NEAR_DIMM_NG_M_G_BYTE-ECC\" )
					)
					( Units "uMatchProp" "ns" 1.000000)
					( Status sCSetFlattened )
					( Origin gBackEnd )
				)
				( attribute "RELATIVE_PROPAGATION_DELAY_SCOPE" "G"
					( Parent
						( matchGroupRef "@crescent_city_bb_fab1_lib.crescent_city_bb_fab1(sch_1):\MG_DQ_NEAR_DIMM_NG_M_G_BYTE-ECC\" )
					)
					( Status sCSetFlattened )
					( Origin gBackEnd )
				)
				( attribute "RELATIVE_PROPAGATION_DELAY" "-50.00 MIL,50.00 MIL"
					( Parent
						( matchGroupRef "@crescent_city_bb_fab1_lib.crescent_city_bb_fab1(sch_1):\MG_DQ_NEAR_DIMM_NG_M_G_BYTE-ECC\" )
					)
					( Units "uMatchProp" "ns" 1.000000)
					( Status sCSetFlattened )
					( Origin gBackEnd )
				)
			)
			( pinPair "@baseboard_fab2_lib.baseboard_fab2(sch_1):\PP2965\"
				( pinRef "@baseboard_fab2_lib.baseboard_fab2(sch_1):page57_i172:DDR0_ECC(6)" )
				( pinRef "@baseboard_fab2_lib.baseboard_fab2(sch_1):page77_i111:CB(7)" )
				( attribute "RELATIVE_PROPAGATION_DELAY_SCOPE" "G"
					( Parent
						( matchGroupRef "@baseboard_fab2_lib.baseboard_fab2(sch_1):\MG_DQ-DQS_FAR_DIMM_NG_M_G_BYTE-ECC\" )
					)
					( Status sCSetFlattened )
					( Origin gBackEnd )
				)
				( attribute "RELATIVE_PROPAGATION_DELAY" "0.00 MIL,195.00 MIL"
					( Parent
						( matchGroupRef "@baseboard_fab2_lib.baseboard_fab2(sch_1):\MG_DQ-DQS_FAR_DIMM_NG_M_G_BYTE-ECC\" )
					)
					( Units "uMatchProp" "ns" 1.000000)
					( Status sCSetFlattened )
					( Origin gBackEnd )
				)
				( attribute "RELATIVE_PROPAGATION_DELAY_SCOPE" "G"
					( Parent
						( matchGroupRef "@crescent_city_bb_fab1_lib.crescent_city_bb_fab1(sch_1):\MG_DQ_FAR_DIMM_NG_M_G_BYTE-ECC\" )
					)
					( Status sCSetFlattened )
					( Origin gBackEnd )
				)
				( attribute "RELATIVE_PROPAGATION_DELAY" "-50.00 MIL,50.00 MIL"
					( Parent
						( matchGroupRef "@crescent_city_bb_fab1_lib.crescent_city_bb_fab1(sch_1):\MG_DQ_FAR_DIMM_NG_M_G_BYTE-ECC\" )
					)
					( Units "uMatchProp" "ns" 1.000000)
					( Status sCSetFlattened )
					( Origin gBackEnd )
				)
			)
			( pinPair "@baseboard_fab2_lib.baseboard_fab2(sch_1):\PP2966\"
				( pinRef "@baseboard_fab2_lib.baseboard_fab2(sch_1):page78_i13:CB(6)" )
				( pinRef "@baseboard_fab2_lib.baseboard_fab2(sch_1):page57_i172:DDR0_ECC(6)" )
				( attribute "RELATIVE_PROPAGATION_DELAY_SCOPE" "G"
					( Parent
						( matchGroupRef "@baseboard_fab2_lib.baseboard_fab2(sch_1):\MG_DQ-DQS_NEAR_DIMM_NG_M_G_BYTE-ECC\" )
					)
					( Status sCSetFlattened )
					( Origin gBackEnd )
				)
				( attribute "RELATIVE_PROPAGATION_DELAY" "0.00 MIL,195.00 MIL"
					( Parent
						( matchGroupRef "@baseboard_fab2_lib.baseboard_fab2(sch_1):\MG_DQ-DQS_NEAR_DIMM_NG_M_G_BYTE-ECC\" )
					)
					( Units "uMatchProp" "ns" 1.000000)
					( Status sCSetFlattened )
					( Origin gBackEnd )
				)
				( attribute "RELATIVE_PROPAGATION_DELAY_SCOPE" "G"
					( Parent
						( matchGroupRef "@crescent_city_bb_fab1_lib.crescent_city_bb_fab1(sch_1):\MG_DQ_NEAR_DIMM_NG_M_G_BYTE-ECC\" )
					)
					( Status sCSetFlattened )
					( Origin gBackEnd )
				)
				( attribute "RELATIVE_PROPAGATION_DELAY" "-50.00 MIL,50.00 MIL"
					( Parent
						( matchGroupRef "@crescent_city_bb_fab1_lib.crescent_city_bb_fab1(sch_1):\MG_DQ_NEAR_DIMM_NG_M_G_BYTE-ECC\" )
					)
					( Units "uMatchProp" "ns" 1.000000)
					( Status sCSetFlattened )
					( Origin gBackEnd )
				)
			)
			( pinPair "@baseboard_fab2_lib.baseboard_fab2(sch_1):\PP2968\"
				( pinRef "@baseboard_fab2_lib.baseboard_fab2(sch_1):page57_i172:DDR0_ECC(7)" )
				( pinRef "@baseboard_fab2_lib.baseboard_fab2(sch_1):page77_i111:CB(6)" )
				( attribute "RELATIVE_PROPAGATION_DELAY_SCOPE" "G"
					( Parent
						( matchGroupRef "@baseboard_fab2_lib.baseboard_fab2(sch_1):\MG_DQ-DQS_FAR_DIMM_NG_M_G_BYTE-ECC\" )
					)
					( Status sCSetFlattened )
					( Origin gBackEnd )
				)
				( attribute "RELATIVE_PROPAGATION_DELAY" "0.00 MIL,195.00 MIL"
					( Parent
						( matchGroupRef "@baseboard_fab2_lib.baseboard_fab2(sch_1):\MG_DQ-DQS_FAR_DIMM_NG_M_G_BYTE-ECC\" )
					)
					( Units "uMatchProp" "ns" 1.000000)
					( Status sCSetFlattened )
					( Origin gBackEnd )
				)
				( attribute "RELATIVE_PROPAGATION_DELAY_SCOPE" "G"
					( Parent
						( matchGroupRef "@crescent_city_bb_fab1_lib.crescent_city_bb_fab1(sch_1):\MG_DQ_FAR_DIMM_NG_M_G_BYTE-ECC\" )
					)
					( Status sCSetFlattened )
					( Origin gBackEnd )
				)
				( attribute "RELATIVE_PROPAGATION_DELAY" "-50.00 MIL,50.00 MIL"
					( Parent
						( matchGroupRef "@crescent_city_bb_fab1_lib.crescent_city_bb_fab1(sch_1):\MG_DQ_FAR_DIMM_NG_M_G_BYTE-ECC\" )
					)
					( Units "uMatchProp" "ns" 1.000000)
					( Status sCSetFlattened )
					( Origin gBackEnd )
				)
			)
			( pinPair "@baseboard_fab2_lib.baseboard_fab2(sch_1):\PP2969\"
				( pinRef "@baseboard_fab2_lib.baseboard_fab2(sch_1):page78_i13:CB(7)" )
				( pinRef "@baseboard_fab2_lib.baseboard_fab2(sch_1):page57_i172:DDR0_ECC(7)" )
				( attribute "RELATIVE_PROPAGATION_DELAY_SCOPE" "G"
					( Parent
						( matchGroupRef "@baseboard_fab2_lib.baseboard_fab2(sch_1):\MG_DQ-DQS_NEAR_DIMM_NG_M_G_BYTE-ECC\" )
					)
					( Status sCSetFlattened )
					( Origin gBackEnd )
				)
				( attribute "RELATIVE_PROPAGATION_DELAY" "0.00 MIL,195.00 MIL"
					( Parent
						( matchGroupRef "@baseboard_fab2_lib.baseboard_fab2(sch_1):\MG_DQ-DQS_NEAR_DIMM_NG_M_G_BYTE-ECC\" )
					)
					( Units "uMatchProp" "ns" 1.000000)
					( Status sCSetFlattened )
					( Origin gBackEnd )
				)
				( attribute "RELATIVE_PROPAGATION_DELAY_SCOPE" "G"
					( Parent
						( matchGroupRef "@crescent_city_bb_fab1_lib.crescent_city_bb_fab1(sch_1):\MG_DQ_NEAR_DIMM_NG_M_G_BYTE-ECC\" )
					)
					( Status sCSetFlattened )
					( Origin gBackEnd )
				)
				( attribute "RELATIVE_PROPAGATION_DELAY" "-50.00 MIL,50.00 MIL"
					( Parent
						( matchGroupRef "@crescent_city_bb_fab1_lib.crescent_city_bb_fab1(sch_1):\MG_DQ_NEAR_DIMM_NG_M_G_BYTE-ECC\" )
					)
					( Units "uMatchProp" "ns" 1.000000)
					( Status sCSetFlattened )
					( Origin gBackEnd )
				)
			)
			( pinPair "@baseboard_fab2_lib.baseboard_fab2(sch_1):\PP2731\"
				( pinRef "@baseboard_fab2_lib.baseboard_fab2(sch_1):page58_i172:DDR1_ECC(0)" )
				( pinRef "@baseboard_fab2_lib.baseboard_fab2(sch_1):page79_i111:CB(1)" )
				( attribute "RELATIVE_PROPAGATION_DELAY_SCOPE" "G"
					( Parent
						( matchGroupRef "@baseboard_fab2_lib.baseboard_fab2(sch_1):\MG_DQ-DQS_FAR_DIMM_NG_M_H_BYTE-ECC\" )
					)
					( Status sCSetFlattened )
					( Origin gBackEnd )
				)
				( attribute "RELATIVE_PROPAGATION_DELAY" "0.00 MIL,195.00 MIL"
					( Parent
						( matchGroupRef "@baseboard_fab2_lib.baseboard_fab2(sch_1):\MG_DQ-DQS_FAR_DIMM_NG_M_H_BYTE-ECC\" )
					)
					( Units "uMatchProp" "ns" 1.000000)
					( Status sCSetFlattened )
					( Origin gBackEnd )
				)
				( attribute "RELATIVE_PROPAGATION_DELAY_SCOPE" "G"
					( Parent
						( matchGroupRef "@crescent_city_bb_fab1_lib.crescent_city_bb_fab1(sch_1):\MG_DQ_FAR_DIMM_NG_M_H_BYTE-ECC\" )
					)
					( Origin gBackEnd )
				)
				( attribute "RELATIVE_PROPAGATION_DELAY" "-48.18 MIL,50.00 MIL"
					( Parent
						( matchGroupRef "@crescent_city_bb_fab1_lib.crescent_city_bb_fab1(sch_1):\MG_DQ_FAR_DIMM_NG_M_H_BYTE-ECC\" )
					)
					( Units "uMatchProp" "ns" 1.000000)
					( Origin gBackEnd )
				)
			)
			( pinPair "@baseboard_fab2_lib.baseboard_fab2(sch_1):\PP2732\"
				( pinRef "@baseboard_fab2_lib.baseboard_fab2(sch_1):page58_i172:DDR1_ECC(0)" )
				( pinRef "@baseboard_fab2_lib.baseboard_fab2(sch_1):page80_i24:CB(0)" )
				( attribute "RELATIVE_PROPAGATION_DELAY_SCOPE" "G"
					( Parent
						( matchGroupRef "@baseboard_fab2_lib.baseboard_fab2(sch_1):\MG_DQ-DQS_NEAR_DIMM_NG_M_H_BYTE-ECC\" )
					)
					( Status sCSetFlattened )
					( Origin gBackEnd )
				)
				( attribute "RELATIVE_PROPAGATION_DELAY" "0.00 MIL,195.00 MIL"
					( Parent
						( matchGroupRef "@baseboard_fab2_lib.baseboard_fab2(sch_1):\MG_DQ-DQS_NEAR_DIMM_NG_M_H_BYTE-ECC\" )
					)
					( Units "uMatchProp" "ns" 1.000000)
					( Status sCSetFlattened )
					( Origin gBackEnd )
				)
				( attribute "RELATIVE_PROPAGATION_DELAY_SCOPE" "G"
					( Parent
						( matchGroupRef "@crescent_city_bb_fab1_lib.crescent_city_bb_fab1(sch_1):\MG_DQ_NEAR_DIMM_NG_M_H_BYTE-ECC\" )
					)
					( Origin gBackEnd )
				)
				( attribute "RELATIVE_PROPAGATION_DELAY" "-48.18 MIL,50.00 MIL"
					( Parent
						( matchGroupRef "@crescent_city_bb_fab1_lib.crescent_city_bb_fab1(sch_1):\MG_DQ_NEAR_DIMM_NG_M_H_BYTE-ECC\" )
					)
					( Units "uMatchProp" "ns" 1.000000)
					( Origin gBackEnd )
				)
			)
			( pinPair "@baseboard_fab2_lib.baseboard_fab2(sch_1):\PP2734\"
				( pinRef "@baseboard_fab2_lib.baseboard_fab2(sch_1):page58_i172:DDR1_ECC(1)" )
				( pinRef "@baseboard_fab2_lib.baseboard_fab2(sch_1):page79_i111:CB(0)" )
				( attribute "RELATIVE_PROPAGATION_DELAY_SCOPE" "G"
					( Parent
						( matchGroupRef "@baseboard_fab2_lib.baseboard_fab2(sch_1):\MG_DQ-DQS_FAR_DIMM_NG_M_H_BYTE-ECC\" )
					)
					( Status sCSetFlattened )
					( Origin gBackEnd )
				)
				( attribute "RELATIVE_PROPAGATION_DELAY" "0.00 MIL,195.00 MIL"
					( Parent
						( matchGroupRef "@baseboard_fab2_lib.baseboard_fab2(sch_1):\MG_DQ-DQS_FAR_DIMM_NG_M_H_BYTE-ECC\" )
					)
					( Units "uMatchProp" "ns" 1.000000)
					( Status sCSetFlattened )
					( Origin gBackEnd )
				)
				( attribute "RELATIVE_PROPAGATION_DELAY_SCOPE" "G"
					( Parent
						( matchGroupRef "@crescent_city_bb_fab1_lib.crescent_city_bb_fab1(sch_1):\MG_DQ_FAR_DIMM_NG_M_H_BYTE-ECC\" )
					)
					( Origin gBackEnd )
				)
				( attribute "RELATIVE_PROPAGATION_DELAY" "-49.62 MIL,50.00 MIL"
					( Parent
						( matchGroupRef "@crescent_city_bb_fab1_lib.crescent_city_bb_fab1(sch_1):\MG_DQ_FAR_DIMM_NG_M_H_BYTE-ECC\" )
					)
					( Units "uMatchProp" "ns" 1.000000)
					( Origin gBackEnd )
				)
			)
			( pinPair "@baseboard_fab2_lib.baseboard_fab2(sch_1):\PP2735\"
				( pinRef "@baseboard_fab2_lib.baseboard_fab2(sch_1):page58_i172:DDR1_ECC(1)" )
				( pinRef "@baseboard_fab2_lib.baseboard_fab2(sch_1):page80_i24:CB(1)" )
				( attribute "RELATIVE_PROPAGATION_DELAY_SCOPE" "G"
					( Parent
						( matchGroupRef "@baseboard_fab2_lib.baseboard_fab2(sch_1):\MG_DQ-DQS_NEAR_DIMM_NG_M_H_BYTE-ECC\" )
					)
					( Status sCSetFlattened )
					( Origin gBackEnd )
				)
				( attribute "RELATIVE_PROPAGATION_DELAY" "0.00 MIL,195.00 MIL"
					( Parent
						( matchGroupRef "@baseboard_fab2_lib.baseboard_fab2(sch_1):\MG_DQ-DQS_NEAR_DIMM_NG_M_H_BYTE-ECC\" )
					)
					( Units "uMatchProp" "ns" 1.000000)
					( Status sCSetFlattened )
					( Origin gBackEnd )
				)
				( attribute "RELATIVE_PROPAGATION_DELAY_SCOPE" "G"
					( Parent
						( matchGroupRef "@crescent_city_bb_fab1_lib.crescent_city_bb_fab1(sch_1):\MG_DQ_NEAR_DIMM_NG_M_H_BYTE-ECC\" )
					)
					( Origin gBackEnd )
				)
				( attribute "RELATIVE_PROPAGATION_DELAY" "-49.26 MIL,50.00 MIL"
					( Parent
						( matchGroupRef "@crescent_city_bb_fab1_lib.crescent_city_bb_fab1(sch_1):\MG_DQ_NEAR_DIMM_NG_M_H_BYTE-ECC\" )
					)
					( Units "uMatchProp" "ns" 1.000000)
					( Origin gBackEnd )
				)
			)
			( pinPair "@baseboard_fab2_lib.baseboard_fab2(sch_1):\PP2737\"
				( pinRef "@baseboard_fab2_lib.baseboard_fab2(sch_1):page58_i172:DDR1_ECC(2)" )
				( pinRef "@baseboard_fab2_lib.baseboard_fab2(sch_1):page79_i111:CB(3)" )
				( attribute "RELATIVE_PROPAGATION_DELAY_SCOPE" "G"
					( Parent
						( matchGroupRef "@baseboard_fab2_lib.baseboard_fab2(sch_1):\MG_DQ-DQS_FAR_DIMM_NG_M_H_BYTE-ECC\" )
					)
					( Status sCSetFlattened )
					( Origin gBackEnd )
				)
				( attribute "RELATIVE_PROPAGATION_DELAY" "0.00 MIL,195.00 MIL"
					( Parent
						( matchGroupRef "@baseboard_fab2_lib.baseboard_fab2(sch_1):\MG_DQ-DQS_FAR_DIMM_NG_M_H_BYTE-ECC\" )
					)
					( Units "uMatchProp" "ns" 1.000000)
					( Status sCSetFlattened )
					( Origin gBackEnd )
				)
				( attribute "RELATIVE_PROPAGATION_DELAY_SCOPE" "G"
					( Parent
						( matchGroupRef "@crescent_city_bb_fab1_lib.crescent_city_bb_fab1(sch_1):\MG_DQ_FAR_DIMM_NG_M_H_BYTE-ECC\" )
					)
					( Origin gBackEnd )
				)
				( attribute "RELATIVE_PROPAGATION_DELAY" "-48.50 MIL,50.00 MIL"
					( Parent
						( matchGroupRef "@crescent_city_bb_fab1_lib.crescent_city_bb_fab1(sch_1):\MG_DQ_FAR_DIMM_NG_M_H_BYTE-ECC\" )
					)
					( Units "uMatchProp" "ns" 1.000000)
					( Origin gBackEnd )
				)
			)
			( pinPair "@baseboard_fab2_lib.baseboard_fab2(sch_1):\PP2738\"
				( pinRef "@baseboard_fab2_lib.baseboard_fab2(sch_1):page58_i172:DDR1_ECC(2)" )
				( pinRef "@baseboard_fab2_lib.baseboard_fab2(sch_1):page80_i24:CB(2)" )
				( attribute "RELATIVE_PROPAGATION_DELAY_SCOPE" "G"
					( Parent
						( matchGroupRef "@baseboard_fab2_lib.baseboard_fab2(sch_1):\MG_DQ-DQS_NEAR_DIMM_NG_M_H_BYTE-ECC\" )
					)
					( Status sCSetFlattened )
					( Origin gBackEnd )
				)
				( attribute "RELATIVE_PROPAGATION_DELAY" "0.00 MIL,195.00 MIL"
					( Parent
						( matchGroupRef "@baseboard_fab2_lib.baseboard_fab2(sch_1):\MG_DQ-DQS_NEAR_DIMM_NG_M_H_BYTE-ECC\" )
					)
					( Units "uMatchProp" "ns" 1.000000)
					( Status sCSetFlattened )
					( Origin gBackEnd )
				)
				( attribute "RELATIVE_PROPAGATION_DELAY_SCOPE" "G"
					( Parent
						( matchGroupRef "@crescent_city_bb_fab1_lib.crescent_city_bb_fab1(sch_1):\MG_DQ_NEAR_DIMM_NG_M_H_BYTE-ECC\" )
					)
					( Origin gBackEnd )
				)
				( attribute "RELATIVE_PROPAGATION_DELAY" "-48.50 MIL,50.00 MIL"
					( Parent
						( matchGroupRef "@crescent_city_bb_fab1_lib.crescent_city_bb_fab1(sch_1):\MG_DQ_NEAR_DIMM_NG_M_H_BYTE-ECC\" )
					)
					( Units "uMatchProp" "ns" 1.000000)
					( Origin gBackEnd )
				)
			)
			( pinPair "@baseboard_fab2_lib.baseboard_fab2(sch_1):\PP2740\"
				( pinRef "@baseboard_fab2_lib.baseboard_fab2(sch_1):page58_i172:DDR1_ECC(3)" )
				( pinRef "@baseboard_fab2_lib.baseboard_fab2(sch_1):page79_i111:CB(2)" )
				( attribute "RELATIVE_PROPAGATION_DELAY_SCOPE" "G"
					( Parent
						( matchGroupRef "@baseboard_fab2_lib.baseboard_fab2(sch_1):\MG_DQ-DQS_FAR_DIMM_NG_M_H_BYTE-ECC\" )
					)
					( Status sCSetFlattened )
					( Origin gBackEnd )
				)
				( attribute "RELATIVE_PROPAGATION_DELAY" "0.00 MIL,195.00 MIL"
					( Parent
						( matchGroupRef "@baseboard_fab2_lib.baseboard_fab2(sch_1):\MG_DQ-DQS_FAR_DIMM_NG_M_H_BYTE-ECC\" )
					)
					( Units "uMatchProp" "ns" 1.000000)
					( Status sCSetFlattened )
					( Origin gBackEnd )
				)
				( attribute "RELATIVE_PROPAGATION_DELAY_SCOPE" "G"
					( Parent
						( matchGroupRef "@crescent_city_bb_fab1_lib.crescent_city_bb_fab1(sch_1):\MG_DQ_FAR_DIMM_NG_M_H_BYTE-ECC\" )
					)
					( Origin gBackEnd )
				)
				( attribute "RELATIVE_PROPAGATION_DELAY" "-24.41 MIL,50.00 MIL"
					( Parent
						( matchGroupRef "@crescent_city_bb_fab1_lib.crescent_city_bb_fab1(sch_1):\MG_DQ_FAR_DIMM_NG_M_H_BYTE-ECC\" )
					)
					( Units "uMatchProp" "ns" 1.000000)
					( Origin gBackEnd )
				)
			)
			( pinPair "@baseboard_fab2_lib.baseboard_fab2(sch_1):\PP2741\"
				( pinRef "@baseboard_fab2_lib.baseboard_fab2(sch_1):page58_i172:DDR1_ECC(3)" )
				( pinRef "@baseboard_fab2_lib.baseboard_fab2(sch_1):page80_i24:CB(3)" )
				( attribute "RELATIVE_PROPAGATION_DELAY_SCOPE" "G"
					( Parent
						( matchGroupRef "@baseboard_fab2_lib.baseboard_fab2(sch_1):\MG_DQ-DQS_NEAR_DIMM_NG_M_H_BYTE-ECC\" )
					)
					( Status sCSetFlattened )
					( Origin gBackEnd )
				)
				( attribute "RELATIVE_PROPAGATION_DELAY" "0.00 MIL,195.00 MIL"
					( Parent
						( matchGroupRef "@baseboard_fab2_lib.baseboard_fab2(sch_1):\MG_DQ-DQS_NEAR_DIMM_NG_M_H_BYTE-ECC\" )
					)
					( Units "uMatchProp" "ns" 1.000000)
					( Status sCSetFlattened )
					( Origin gBackEnd )
				)
				( attribute "RELATIVE_PROPAGATION_DELAY_SCOPE" "G"
					( Parent
						( matchGroupRef "@crescent_city_bb_fab1_lib.crescent_city_bb_fab1(sch_1):\MG_DQ_NEAR_DIMM_NG_M_H_BYTE-ECC\" )
					)
					( Origin gBackEnd )
				)
				( attribute "RELATIVE_PROPAGATION_DELAY" "-24.41 MIL,50.00 MIL"
					( Parent
						( matchGroupRef "@crescent_city_bb_fab1_lib.crescent_city_bb_fab1(sch_1):\MG_DQ_NEAR_DIMM_NG_M_H_BYTE-ECC\" )
					)
					( Units "uMatchProp" "ns" 1.000000)
					( Origin gBackEnd )
				)
			)
			( pinPair "@baseboard_fab2_lib.baseboard_fab2(sch_1):\PP2743\"
				( pinRef "@baseboard_fab2_lib.baseboard_fab2(sch_1):page58_i172:DDR1_ECC(4)" )
				( pinRef "@baseboard_fab2_lib.baseboard_fab2(sch_1):page79_i111:CB(5)" )
				( attribute "RELATIVE_PROPAGATION_DELAY_SCOPE" "G"
					( Parent
						( matchGroupRef "@baseboard_fab2_lib.baseboard_fab2(sch_1):\MG_DQ-DQS_FAR_DIMM_NG_M_H_BYTE-ECC\" )
					)
					( Status sCSetFlattened )
					( Origin gBackEnd )
				)
				( attribute "RELATIVE_PROPAGATION_DELAY" "0.00 MIL,195.00 MIL"
					( Parent
						( matchGroupRef "@baseboard_fab2_lib.baseboard_fab2(sch_1):\MG_DQ-DQS_FAR_DIMM_NG_M_H_BYTE-ECC\" )
					)
					( Units "uMatchProp" "ns" 1.000000)
					( Status sCSetFlattened )
					( Origin gBackEnd )
				)
				( attribute "RELATIVE_PROPAGATION_DELAY_SCOPE" "G"
					( Parent
						( matchGroupRef "@crescent_city_bb_fab1_lib.crescent_city_bb_fab1(sch_1):\MG_DQ_FAR_DIMM_NG_M_H_BYTE-ECC\" )
					)
					( Origin gBackEnd )
				)
				( attribute "RELATIVE_PROPAGATION_DELAY" "-23.54 MIL,50.00 MIL"
					( Parent
						( matchGroupRef "@crescent_city_bb_fab1_lib.crescent_city_bb_fab1(sch_1):\MG_DQ_FAR_DIMM_NG_M_H_BYTE-ECC\" )
					)
					( Units "uMatchProp" "ns" 1.000000)
					( Origin gBackEnd )
				)
			)
			( pinPair "@baseboard_fab2_lib.baseboard_fab2(sch_1):\PP2744\"
				( pinRef "@baseboard_fab2_lib.baseboard_fab2(sch_1):page58_i172:DDR1_ECC(4)" )
				( pinRef "@baseboard_fab2_lib.baseboard_fab2(sch_1):page80_i24:CB(4)" )
				( attribute "RELATIVE_PROPAGATION_DELAY_SCOPE" "G"
					( Parent
						( matchGroupRef "@baseboard_fab2_lib.baseboard_fab2(sch_1):\MG_DQ-DQS_NEAR_DIMM_NG_M_H_BYTE-ECC\" )
					)
					( Status sCSetFlattened )
					( Origin gBackEnd )
				)
				( attribute "RELATIVE_PROPAGATION_DELAY" "0.00 MIL,195.00 MIL"
					( Parent
						( matchGroupRef "@baseboard_fab2_lib.baseboard_fab2(sch_1):\MG_DQ-DQS_NEAR_DIMM_NG_M_H_BYTE-ECC\" )
					)
					( Units "uMatchProp" "ns" 1.000000)
					( Status sCSetFlattened )
					( Origin gBackEnd )
				)
				( attribute "RELATIVE_PROPAGATION_DELAY_SCOPE" "G"
					( Parent
						( matchGroupRef "@crescent_city_bb_fab1_lib.crescent_city_bb_fab1(sch_1):\MG_DQ_NEAR_DIMM_NG_M_H_BYTE-ECC\" )
					)
					( Origin gBackEnd )
				)
				( attribute "RELATIVE_PROPAGATION_DELAY" "-23.54 MIL,50.00 MIL"
					( Parent
						( matchGroupRef "@crescent_city_bb_fab1_lib.crescent_city_bb_fab1(sch_1):\MG_DQ_NEAR_DIMM_NG_M_H_BYTE-ECC\" )
					)
					( Units "uMatchProp" "ns" 1.000000)
					( Origin gBackEnd )
				)
			)
			( pinPair "@baseboard_fab2_lib.baseboard_fab2(sch_1):\PP2746\"
				( pinRef "@baseboard_fab2_lib.baseboard_fab2(sch_1):page58_i172:DDR1_ECC(5)" )
				( pinRef "@baseboard_fab2_lib.baseboard_fab2(sch_1):page79_i111:CB(4)" )
				( attribute "RELATIVE_PROPAGATION_DELAY_SCOPE" "G"
					( Parent
						( matchGroupRef "@baseboard_fab2_lib.baseboard_fab2(sch_1):\MG_DQ-DQS_FAR_DIMM_NG_M_H_BYTE-ECC\" )
					)
					( Status sCSetFlattened )
					( Origin gBackEnd )
				)
				( attribute "RELATIVE_PROPAGATION_DELAY" "0.00 MIL,195.00 MIL"
					( Parent
						( matchGroupRef "@baseboard_fab2_lib.baseboard_fab2(sch_1):\MG_DQ-DQS_FAR_DIMM_NG_M_H_BYTE-ECC\" )
					)
					( Units "uMatchProp" "ns" 1.000000)
					( Status sCSetFlattened )
					( Origin gBackEnd )
				)
				( attribute "RELATIVE_PROPAGATION_DELAY_SCOPE" "G"
					( Parent
						( matchGroupRef "@crescent_city_bb_fab1_lib.crescent_city_bb_fab1(sch_1):\MG_DQ_FAR_DIMM_NG_M_H_BYTE-ECC\" )
					)
					( Origin gBackEnd )
				)
				( attribute "RELATIVE_PROPAGATION_DELAY" "TARGET,TARGET"
					( Parent
						( matchGroupRef "@crescent_city_bb_fab1_lib.crescent_city_bb_fab1(sch_1):\MG_DQ_FAR_DIMM_NG_M_H_BYTE-ECC\" )
					)
					( Units "uMatchProp" "ns" 1.000000)
					( Origin gBackEnd )
				)
			)
			( pinPair "@baseboard_fab2_lib.baseboard_fab2(sch_1):\PP2747\"
				( pinRef "@baseboard_fab2_lib.baseboard_fab2(sch_1):page58_i172:DDR1_ECC(5)" )
				( pinRef "@baseboard_fab2_lib.baseboard_fab2(sch_1):page80_i24:CB(5)" )
				( attribute "RELATIVE_PROPAGATION_DELAY_SCOPE" "G"
					( Parent
						( matchGroupRef "@baseboard_fab2_lib.baseboard_fab2(sch_1):\MG_DQ-DQS_NEAR_DIMM_NG_M_H_BYTE-ECC\" )
					)
					( Status sCSetFlattened )
					( Origin gBackEnd )
				)
				( attribute "RELATIVE_PROPAGATION_DELAY" "0.00 MIL,195.00 MIL"
					( Parent
						( matchGroupRef "@baseboard_fab2_lib.baseboard_fab2(sch_1):\MG_DQ-DQS_NEAR_DIMM_NG_M_H_BYTE-ECC\" )
					)
					( Units "uMatchProp" "ns" 1.000000)
					( Status sCSetFlattened )
					( Origin gBackEnd )
				)
				( attribute "RELATIVE_PROPAGATION_DELAY_SCOPE" "G"
					( Parent
						( matchGroupRef "@crescent_city_bb_fab1_lib.crescent_city_bb_fab1(sch_1):\MG_DQ_NEAR_DIMM_NG_M_H_BYTE-ECC\" )
					)
					( Origin gBackEnd )
				)
				( attribute "RELATIVE_PROPAGATION_DELAY" "TARGET,TARGET"
					( Parent
						( matchGroupRef "@crescent_city_bb_fab1_lib.crescent_city_bb_fab1(sch_1):\MG_DQ_NEAR_DIMM_NG_M_H_BYTE-ECC\" )
					)
					( Units "uMatchProp" "ns" 1.000000)
					( Origin gBackEnd )
				)
			)
			( pinPair "@baseboard_fab2_lib.baseboard_fab2(sch_1):\PP2749\"
				( pinRef "@baseboard_fab2_lib.baseboard_fab2(sch_1):page58_i172:DDR1_ECC(6)" )
				( pinRef "@baseboard_fab2_lib.baseboard_fab2(sch_1):page79_i111:CB(7)" )
				( attribute "RELATIVE_PROPAGATION_DELAY_SCOPE" "G"
					( Parent
						( matchGroupRef "@baseboard_fab2_lib.baseboard_fab2(sch_1):\MG_DQ-DQS_FAR_DIMM_NG_M_H_BYTE-ECC\" )
					)
					( Status sCSetFlattened )
					( Origin gBackEnd )
				)
				( attribute "RELATIVE_PROPAGATION_DELAY" "0.00 MIL,195.00 MIL"
					( Parent
						( matchGroupRef "@baseboard_fab2_lib.baseboard_fab2(sch_1):\MG_DQ-DQS_FAR_DIMM_NG_M_H_BYTE-ECC\" )
					)
					( Units "uMatchProp" "ns" 1.000000)
					( Status sCSetFlattened )
					( Origin gBackEnd )
				)
				( attribute "RELATIVE_PROPAGATION_DELAY_SCOPE" "G"
					( Parent
						( matchGroupRef "@crescent_city_bb_fab1_lib.crescent_city_bb_fab1(sch_1):\MG_DQ_FAR_DIMM_NG_M_H_BYTE-ECC\" )
					)
					( Origin gBackEnd )
				)
				( attribute "RELATIVE_PROPAGATION_DELAY" "-51.75 MIL,50.00 MIL"
					( Parent
						( matchGroupRef "@crescent_city_bb_fab1_lib.crescent_city_bb_fab1(sch_1):\MG_DQ_FAR_DIMM_NG_M_H_BYTE-ECC\" )
					)
					( Units "uMatchProp" "ns" 1.000000)
					( Origin gBackEnd )
				)
			)
			( pinPair "@baseboard_fab2_lib.baseboard_fab2(sch_1):\PP2750\"
				( pinRef "@baseboard_fab2_lib.baseboard_fab2(sch_1):page58_i172:DDR1_ECC(6)" )
				( pinRef "@baseboard_fab2_lib.baseboard_fab2(sch_1):page80_i24:CB(6)" )
				( attribute "RELATIVE_PROPAGATION_DELAY_SCOPE" "G"
					( Parent
						( matchGroupRef "@baseboard_fab2_lib.baseboard_fab2(sch_1):\MG_DQ-DQS_NEAR_DIMM_NG_M_H_BYTE-ECC\" )
					)
					( Status sCSetFlattened )
					( Origin gBackEnd )
				)
				( attribute "RELATIVE_PROPAGATION_DELAY" "0.00 MIL,195.00 MIL"
					( Parent
						( matchGroupRef "@baseboard_fab2_lib.baseboard_fab2(sch_1):\MG_DQ-DQS_NEAR_DIMM_NG_M_H_BYTE-ECC\" )
					)
					( Units "uMatchProp" "ns" 1.000000)
					( Status sCSetFlattened )
					( Origin gBackEnd )
				)
				( attribute "RELATIVE_PROPAGATION_DELAY_SCOPE" "G"
					( Parent
						( matchGroupRef "@crescent_city_bb_fab1_lib.crescent_city_bb_fab1(sch_1):\MG_DQ_NEAR_DIMM_NG_M_H_BYTE-ECC\" )
					)
					( Origin gBackEnd )
				)
				( attribute "RELATIVE_PROPAGATION_DELAY" "-51.75 MIL,50.00 MIL"
					( Parent
						( matchGroupRef "@crescent_city_bb_fab1_lib.crescent_city_bb_fab1(sch_1):\MG_DQ_NEAR_DIMM_NG_M_H_BYTE-ECC\" )
					)
					( Units "uMatchProp" "ns" 1.000000)
					( Origin gBackEnd )
				)
			)
			( pinPair "@baseboard_fab2_lib.baseboard_fab2(sch_1):\PP2752\"
				( pinRef "@baseboard_fab2_lib.baseboard_fab2(sch_1):page58_i172:DDR1_ECC(7)" )
				( pinRef "@baseboard_fab2_lib.baseboard_fab2(sch_1):page79_i111:CB(6)" )
				( attribute "RELATIVE_PROPAGATION_DELAY_SCOPE" "G"
					( Parent
						( matchGroupRef "@baseboard_fab2_lib.baseboard_fab2(sch_1):\MG_DQ-DQS_FAR_DIMM_NG_M_H_BYTE-ECC\" )
					)
					( Status sCSetFlattened )
					( Origin gBackEnd )
				)
				( attribute "RELATIVE_PROPAGATION_DELAY" "0.00 MIL,195.00 MIL"
					( Parent
						( matchGroupRef "@baseboard_fab2_lib.baseboard_fab2(sch_1):\MG_DQ-DQS_FAR_DIMM_NG_M_H_BYTE-ECC\" )
					)
					( Units "uMatchProp" "ns" 1.000000)
					( Status sCSetFlattened )
					( Origin gBackEnd )
				)
				( attribute "RELATIVE_PROPAGATION_DELAY_SCOPE" "G"
					( Parent
						( matchGroupRef "@crescent_city_bb_fab1_lib.crescent_city_bb_fab1(sch_1):\MG_DQ_FAR_DIMM_NG_M_H_BYTE-ECC\" )
					)
					( Origin gBackEnd )
				)
				( attribute "RELATIVE_PROPAGATION_DELAY" "-52.28 MIL,50.00 MIL"
					( Parent
						( matchGroupRef "@crescent_city_bb_fab1_lib.crescent_city_bb_fab1(sch_1):\MG_DQ_FAR_DIMM_NG_M_H_BYTE-ECC\" )
					)
					( Units "uMatchProp" "ns" 1.000000)
					( Origin gBackEnd )
				)
			)
			( pinPair "@baseboard_fab2_lib.baseboard_fab2(sch_1):\PP2753\"
				( pinRef "@baseboard_fab2_lib.baseboard_fab2(sch_1):page58_i172:DDR1_ECC(7)" )
				( pinRef "@baseboard_fab2_lib.baseboard_fab2(sch_1):page80_i24:CB(7)" )
				( attribute "RELATIVE_PROPAGATION_DELAY_SCOPE" "G"
					( Parent
						( matchGroupRef "@baseboard_fab2_lib.baseboard_fab2(sch_1):\MG_DQ-DQS_NEAR_DIMM_NG_M_H_BYTE-ECC\" )
					)
					( Status sCSetFlattened )
					( Origin gBackEnd )
				)
				( attribute "RELATIVE_PROPAGATION_DELAY" "0.00 MIL,195.00 MIL"
					( Parent
						( matchGroupRef "@baseboard_fab2_lib.baseboard_fab2(sch_1):\MG_DQ-DQS_NEAR_DIMM_NG_M_H_BYTE-ECC\" )
					)
					( Units "uMatchProp" "ns" 1.000000)
					( Status sCSetFlattened )
					( Origin gBackEnd )
				)
				( attribute "RELATIVE_PROPAGATION_DELAY_SCOPE" "G"
					( Parent
						( matchGroupRef "@crescent_city_bb_fab1_lib.crescent_city_bb_fab1(sch_1):\MG_DQ_NEAR_DIMM_NG_M_H_BYTE-ECC\" )
					)
					( Origin gBackEnd )
				)
				( attribute "RELATIVE_PROPAGATION_DELAY" "-52.28 MIL,50.00 MIL"
					( Parent
						( matchGroupRef "@crescent_city_bb_fab1_lib.crescent_city_bb_fab1(sch_1):\MG_DQ_NEAR_DIMM_NG_M_H_BYTE-ECC\" )
					)
					( Units "uMatchProp" "ns" 1.000000)
					( Origin gBackEnd )
				)
			)
			( pinPair "@baseboard_fab2_lib.baseboard_fab2(sch_1):\PP2515\"
				( pinRef "@baseboard_fab2_lib.baseboard_fab2(sch_1):page59_i172:DDR2_ECC(0)" )
				( pinRef "@baseboard_fab2_lib.baseboard_fab2(sch_1):page81_i186:CB(1)" )
				( attribute "RELATIVE_PROPAGATION_DELAY_SCOPE" "G"
					( Parent
						( matchGroupRef "@baseboard_fab2_lib.baseboard_fab2(sch_1):\MG_DQ-DQS_FAR_DIMM_NG_M_J_BYTE-ECC\" )
					)
					( Status sCSetFlattened )
					( Origin gBackEnd )
				)
				( attribute "RELATIVE_PROPAGATION_DELAY" "0.00 MIL,195.00 MIL"
					( Parent
						( matchGroupRef "@baseboard_fab2_lib.baseboard_fab2(sch_1):\MG_DQ-DQS_FAR_DIMM_NG_M_J_BYTE-ECC\" )
					)
					( Units "uMatchProp" "ns" 1.000000)
					( Status sCSetFlattened )
					( Origin gBackEnd )
				)
				( attribute "RELATIVE_PROPAGATION_DELAY_SCOPE" "G"
					( Parent
						( matchGroupRef "@baseboard_fab2_lib.baseboard_fab2(sch_1):\MG_DQ_FAR_DIMM_NG_M_J_BYTE-ECC\" )
					)
					( Status sCSetFlattened )
					( Origin gBackEnd )
				)
				( attribute "RELATIVE_PROPAGATION_DELAY" "-50.00 MIL,50.00 MIL"
					( Parent
						( matchGroupRef "@baseboard_fab2_lib.baseboard_fab2(sch_1):\MG_DQ_FAR_DIMM_NG_M_J_BYTE-ECC\" )
					)
					( Units "uMatchProp" "ns" 1.000000)
					( Status sCSetFlattened )
					( Origin gBackEnd )
				)
			)
			( pinPair "@baseboard_fab2_lib.baseboard_fab2(sch_1):\PP2516\"
				( pinRef "@baseboard_fab2_lib.baseboard_fab2(sch_1):page82_i187:CB(0)" )
				( pinRef "@baseboard_fab2_lib.baseboard_fab2(sch_1):page59_i172:DDR2_ECC(0)" )
				( attribute "RELATIVE_PROPAGATION_DELAY_SCOPE" "G"
					( Parent
						( matchGroupRef "@baseboard_fab2_lib.baseboard_fab2(sch_1):\MG_DQ-DQS_NEAR_DIMM_NG_M_J_BYTE-ECC\" )
					)
					( Status sCSetFlattened )
					( Origin gBackEnd )
				)
				( attribute "RELATIVE_PROPAGATION_DELAY" "0.00 MIL,195.00 MIL"
					( Parent
						( matchGroupRef "@baseboard_fab2_lib.baseboard_fab2(sch_1):\MG_DQ-DQS_NEAR_DIMM_NG_M_J_BYTE-ECC\" )
					)
					( Units "uMatchProp" "ns" 1.000000)
					( Status sCSetFlattened )
					( Origin gBackEnd )
				)
				( attribute "RELATIVE_PROPAGATION_DELAY_SCOPE" "G"
					( Parent
						( matchGroupRef "@baseboard_fab2_lib.baseboard_fab2(sch_1):\MG_DQ_NEAR_DIMM_NG_M_J_BYTE-ECC\" )
					)
					( Status sCSetFlattened )
					( Origin gBackEnd )
				)
				( attribute "RELATIVE_PROPAGATION_DELAY" "-50.00 MIL,50.00 MIL"
					( Parent
						( matchGroupRef "@baseboard_fab2_lib.baseboard_fab2(sch_1):\MG_DQ_NEAR_DIMM_NG_M_J_BYTE-ECC\" )
					)
					( Units "uMatchProp" "ns" 1.000000)
					( Status sCSetFlattened )
					( Origin gBackEnd )
				)
			)
			( pinPair "@baseboard_fab2_lib.baseboard_fab2(sch_1):\PP2518\"
				( pinRef "@baseboard_fab2_lib.baseboard_fab2(sch_1):page59_i172:DDR2_ECC(1)" )
				( pinRef "@baseboard_fab2_lib.baseboard_fab2(sch_1):page81_i186:CB(0)" )
				( attribute "RELATIVE_PROPAGATION_DELAY_SCOPE" "G"
					( Parent
						( matchGroupRef "@baseboard_fab2_lib.baseboard_fab2(sch_1):\MG_DQ-DQS_FAR_DIMM_NG_M_J_BYTE-ECC\" )
					)
					( Status sCSetFlattened )
					( Origin gBackEnd )
				)
				( attribute "RELATIVE_PROPAGATION_DELAY" "0.00 MIL,195.00 MIL"
					( Parent
						( matchGroupRef "@baseboard_fab2_lib.baseboard_fab2(sch_1):\MG_DQ-DQS_FAR_DIMM_NG_M_J_BYTE-ECC\" )
					)
					( Units "uMatchProp" "ns" 1.000000)
					( Status sCSetFlattened )
					( Origin gBackEnd )
				)
				( attribute "RELATIVE_PROPAGATION_DELAY_SCOPE" "G"
					( Parent
						( matchGroupRef "@baseboard_fab2_lib.baseboard_fab2(sch_1):\MG_DQ_FAR_DIMM_NG_M_J_BYTE-ECC\" )
					)
					( Status sCSetFlattened )
					( Origin gBackEnd )
				)
				( attribute "RELATIVE_PROPAGATION_DELAY" "-50.00 MIL,50.00 MIL"
					( Parent
						( matchGroupRef "@baseboard_fab2_lib.baseboard_fab2(sch_1):\MG_DQ_FAR_DIMM_NG_M_J_BYTE-ECC\" )
					)
					( Units "uMatchProp" "ns" 1.000000)
					( Status sCSetFlattened )
					( Origin gBackEnd )
				)
			)
			( pinPair "@baseboard_fab2_lib.baseboard_fab2(sch_1):\PP2519\"
				( pinRef "@baseboard_fab2_lib.baseboard_fab2(sch_1):page82_i187:CB(1)" )
				( pinRef "@baseboard_fab2_lib.baseboard_fab2(sch_1):page59_i172:DDR2_ECC(1)" )
				( attribute "RELATIVE_PROPAGATION_DELAY_SCOPE" "G"
					( Parent
						( matchGroupRef "@baseboard_fab2_lib.baseboard_fab2(sch_1):\MG_DQ-DQS_NEAR_DIMM_NG_M_J_BYTE-ECC\" )
					)
					( Status sCSetFlattened )
					( Origin gBackEnd )
				)
				( attribute "RELATIVE_PROPAGATION_DELAY" "0.00 MIL,195.00 MIL"
					( Parent
						( matchGroupRef "@baseboard_fab2_lib.baseboard_fab2(sch_1):\MG_DQ-DQS_NEAR_DIMM_NG_M_J_BYTE-ECC\" )
					)
					( Units "uMatchProp" "ns" 1.000000)
					( Status sCSetFlattened )
					( Origin gBackEnd )
				)
				( attribute "RELATIVE_PROPAGATION_DELAY_SCOPE" "G"
					( Parent
						( matchGroupRef "@baseboard_fab2_lib.baseboard_fab2(sch_1):\MG_DQ_NEAR_DIMM_NG_M_J_BYTE-ECC\" )
					)
					( Status sCSetFlattened )
					( Origin gBackEnd )
				)
				( attribute "RELATIVE_PROPAGATION_DELAY" "-50.00 MIL,50.00 MIL"
					( Parent
						( matchGroupRef "@baseboard_fab2_lib.baseboard_fab2(sch_1):\MG_DQ_NEAR_DIMM_NG_M_J_BYTE-ECC\" )
					)
					( Units "uMatchProp" "ns" 1.000000)
					( Status sCSetFlattened )
					( Origin gBackEnd )
				)
			)
			( pinPair "@baseboard_fab2_lib.baseboard_fab2(sch_1):\PP2521\"
				( pinRef "@baseboard_fab2_lib.baseboard_fab2(sch_1):page59_i172:DDR2_ECC(2)" )
				( pinRef "@baseboard_fab2_lib.baseboard_fab2(sch_1):page81_i186:CB(3)" )
				( attribute "RELATIVE_PROPAGATION_DELAY_SCOPE" "G"
					( Parent
						( matchGroupRef "@baseboard_fab2_lib.baseboard_fab2(sch_1):\MG_DQ-DQS_FAR_DIMM_NG_M_J_BYTE-ECC\" )
					)
					( Status sCSetFlattened )
					( Origin gBackEnd )
				)
				( attribute "RELATIVE_PROPAGATION_DELAY" "0.00 MIL,195.00 MIL"
					( Parent
						( matchGroupRef "@baseboard_fab2_lib.baseboard_fab2(sch_1):\MG_DQ-DQS_FAR_DIMM_NG_M_J_BYTE-ECC\" )
					)
					( Units "uMatchProp" "ns" 1.000000)
					( Status sCSetFlattened )
					( Origin gBackEnd )
				)
				( attribute "RELATIVE_PROPAGATION_DELAY_SCOPE" "G"
					( Parent
						( matchGroupRef "@baseboard_fab2_lib.baseboard_fab2(sch_1):\MG_DQ_FAR_DIMM_NG_M_J_BYTE-ECC\" )
					)
					( Status sCSetFlattened )
					( Origin gBackEnd )
				)
				( attribute "RELATIVE_PROPAGATION_DELAY" "-50.00 MIL,50.00 MIL"
					( Parent
						( matchGroupRef "@baseboard_fab2_lib.baseboard_fab2(sch_1):\MG_DQ_FAR_DIMM_NG_M_J_BYTE-ECC\" )
					)
					( Units "uMatchProp" "ns" 1.000000)
					( Status sCSetFlattened )
					( Origin gBackEnd )
				)
			)
			( pinPair "@baseboard_fab2_lib.baseboard_fab2(sch_1):\PP2522\"
				( pinRef "@baseboard_fab2_lib.baseboard_fab2(sch_1):page82_i187:CB(2)" )
				( pinRef "@baseboard_fab2_lib.baseboard_fab2(sch_1):page59_i172:DDR2_ECC(2)" )
				( attribute "RELATIVE_PROPAGATION_DELAY_SCOPE" "G"
					( Parent
						( matchGroupRef "@baseboard_fab2_lib.baseboard_fab2(sch_1):\MG_DQ-DQS_NEAR_DIMM_NG_M_J_BYTE-ECC\" )
					)
					( Status sCSetFlattened )
					( Origin gBackEnd )
				)
				( attribute "RELATIVE_PROPAGATION_DELAY" "0.00 MIL,195.00 MIL"
					( Parent
						( matchGroupRef "@baseboard_fab2_lib.baseboard_fab2(sch_1):\MG_DQ-DQS_NEAR_DIMM_NG_M_J_BYTE-ECC\" )
					)
					( Units "uMatchProp" "ns" 1.000000)
					( Status sCSetFlattened )
					( Origin gBackEnd )
				)
				( attribute "RELATIVE_PROPAGATION_DELAY_SCOPE" "G"
					( Parent
						( matchGroupRef "@baseboard_fab2_lib.baseboard_fab2(sch_1):\MG_DQ_NEAR_DIMM_NG_M_J_BYTE-ECC\" )
					)
					( Status sCSetFlattened )
					( Origin gBackEnd )
				)
				( attribute "RELATIVE_PROPAGATION_DELAY" "-50.00 MIL,50.00 MIL"
					( Parent
						( matchGroupRef "@baseboard_fab2_lib.baseboard_fab2(sch_1):\MG_DQ_NEAR_DIMM_NG_M_J_BYTE-ECC\" )
					)
					( Units "uMatchProp" "ns" 1.000000)
					( Status sCSetFlattened )
					( Origin gBackEnd )
				)
			)
			( pinPair "@baseboard_fab2_lib.baseboard_fab2(sch_1):\PP2524\"
				( pinRef "@baseboard_fab2_lib.baseboard_fab2(sch_1):page59_i172:DDR2_ECC(3)" )
				( pinRef "@baseboard_fab2_lib.baseboard_fab2(sch_1):page81_i186:CB(2)" )
				( attribute "RELATIVE_PROPAGATION_DELAY_SCOPE" "G"
					( Parent
						( matchGroupRef "@baseboard_fab2_lib.baseboard_fab2(sch_1):\MG_DQ-DQS_FAR_DIMM_NG_M_J_BYTE-ECC\" )
					)
					( Status sCSetFlattened )
					( Origin gBackEnd )
				)
				( attribute "RELATIVE_PROPAGATION_DELAY" "0.00 MIL,195.00 MIL"
					( Parent
						( matchGroupRef "@baseboard_fab2_lib.baseboard_fab2(sch_1):\MG_DQ-DQS_FAR_DIMM_NG_M_J_BYTE-ECC\" )
					)
					( Units "uMatchProp" "ns" 1.000000)
					( Status sCSetFlattened )
					( Origin gBackEnd )
				)
				( attribute "RELATIVE_PROPAGATION_DELAY_SCOPE" "G"
					( Parent
						( matchGroupRef "@baseboard_fab2_lib.baseboard_fab2(sch_1):\MG_DQ_FAR_DIMM_NG_M_J_BYTE-ECC\" )
					)
					( Status sCSetFlattened )
					( Origin gBackEnd )
				)
				( attribute "RELATIVE_PROPAGATION_DELAY" "-50.00 MIL,50.00 MIL"
					( Parent
						( matchGroupRef "@baseboard_fab2_lib.baseboard_fab2(sch_1):\MG_DQ_FAR_DIMM_NG_M_J_BYTE-ECC\" )
					)
					( Units "uMatchProp" "ns" 1.000000)
					( Status sCSetFlattened )
					( Origin gBackEnd )
				)
			)
			( pinPair "@baseboard_fab2_lib.baseboard_fab2(sch_1):\PP2525\"
				( pinRef "@baseboard_fab2_lib.baseboard_fab2(sch_1):page59_i172:DDR2_ECC(3)" )
				( pinRef "@baseboard_fab2_lib.baseboard_fab2(sch_1):page82_i187:CB(3)" )
				( attribute "RELATIVE_PROPAGATION_DELAY_SCOPE" "G"
					( Parent
						( matchGroupRef "@baseboard_fab2_lib.baseboard_fab2(sch_1):\MG_DQ-DQS_NEAR_DIMM_NG_M_J_BYTE-ECC\" )
					)
					( Status sCSetFlattened )
					( Origin gBackEnd )
				)
				( attribute "RELATIVE_PROPAGATION_DELAY" "0.00 MIL,195.00 MIL"
					( Parent
						( matchGroupRef "@baseboard_fab2_lib.baseboard_fab2(sch_1):\MG_DQ-DQS_NEAR_DIMM_NG_M_J_BYTE-ECC\" )
					)
					( Units "uMatchProp" "ns" 1.000000)
					( Status sCSetFlattened )
					( Origin gBackEnd )
				)
				( attribute "RELATIVE_PROPAGATION_DELAY_SCOPE" "G"
					( Parent
						( matchGroupRef "@baseboard_fab2_lib.baseboard_fab2(sch_1):\MG_DQ_NEAR_DIMM_NG_M_J_BYTE-ECC\" )
					)
					( Status sCSetFlattened )
					( Origin gBackEnd )
				)
				( attribute "RELATIVE_PROPAGATION_DELAY" "-50.00 MIL,50.00 MIL"
					( Parent
						( matchGroupRef "@baseboard_fab2_lib.baseboard_fab2(sch_1):\MG_DQ_NEAR_DIMM_NG_M_J_BYTE-ECC\" )
					)
					( Units "uMatchProp" "ns" 1.000000)
					( Status sCSetFlattened )
					( Origin gBackEnd )
				)
			)
			( pinPair "@baseboard_fab2_lib.baseboard_fab2(sch_1):\PP2527\"
				( pinRef "@baseboard_fab2_lib.baseboard_fab2(sch_1):page59_i172:DDR2_ECC(4)" )
				( pinRef "@baseboard_fab2_lib.baseboard_fab2(sch_1):page81_i186:CB(5)" )
				( attribute "RELATIVE_PROPAGATION_DELAY_SCOPE" "G"
					( Parent
						( matchGroupRef "@baseboard_fab2_lib.baseboard_fab2(sch_1):\MG_DQ-DQS_FAR_DIMM_NG_M_J_BYTE-ECC\" )
					)
					( Status sCSetFlattened )
					( Origin gBackEnd )
				)
				( attribute "RELATIVE_PROPAGATION_DELAY" "0.00 MIL,195.00 MIL"
					( Parent
						( matchGroupRef "@baseboard_fab2_lib.baseboard_fab2(sch_1):\MG_DQ-DQS_FAR_DIMM_NG_M_J_BYTE-ECC\" )
					)
					( Units "uMatchProp" "ns" 1.000000)
					( Status sCSetFlattened )
					( Origin gBackEnd )
				)
				( attribute "RELATIVE_PROPAGATION_DELAY_SCOPE" "G"
					( Parent
						( matchGroupRef "@baseboard_fab2_lib.baseboard_fab2(sch_1):\MG_DQ_FAR_DIMM_NG_M_J_BYTE-ECC\" )
					)
					( Status sCSetFlattened )
					( Origin gBackEnd )
				)
				( attribute "RELATIVE_PROPAGATION_DELAY" "-50.00 MIL,50.00 MIL"
					( Parent
						( matchGroupRef "@baseboard_fab2_lib.baseboard_fab2(sch_1):\MG_DQ_FAR_DIMM_NG_M_J_BYTE-ECC\" )
					)
					( Units "uMatchProp" "ns" 1.000000)
					( Status sCSetFlattened )
					( Origin gBackEnd )
				)
			)
			( pinPair "@baseboard_fab2_lib.baseboard_fab2(sch_1):\PP2528\"
				( pinRef "@baseboard_fab2_lib.baseboard_fab2(sch_1):page59_i172:DDR2_ECC(4)" )
				( pinRef "@baseboard_fab2_lib.baseboard_fab2(sch_1):page82_i187:CB(4)" )
				( attribute "RELATIVE_PROPAGATION_DELAY_SCOPE" "G"
					( Parent
						( matchGroupRef "@baseboard_fab2_lib.baseboard_fab2(sch_1):\MG_DQ-DQS_NEAR_DIMM_NG_M_J_BYTE-ECC\" )
					)
					( Status sCSetFlattened )
					( Origin gBackEnd )
				)
				( attribute "RELATIVE_PROPAGATION_DELAY" "0.00 MIL,195.00 MIL"
					( Parent
						( matchGroupRef "@baseboard_fab2_lib.baseboard_fab2(sch_1):\MG_DQ-DQS_NEAR_DIMM_NG_M_J_BYTE-ECC\" )
					)
					( Units "uMatchProp" "ns" 1.000000)
					( Status sCSetFlattened )
					( Origin gBackEnd )
				)
				( attribute "RELATIVE_PROPAGATION_DELAY_SCOPE" "G"
					( Parent
						( matchGroupRef "@baseboard_fab2_lib.baseboard_fab2(sch_1):\MG_DQ_NEAR_DIMM_NG_M_J_BYTE-ECC\" )
					)
					( Status sCSetFlattened )
					( Origin gBackEnd )
				)
				( attribute "RELATIVE_PROPAGATION_DELAY" "-50.00 MIL,50.00 MIL"
					( Parent
						( matchGroupRef "@baseboard_fab2_lib.baseboard_fab2(sch_1):\MG_DQ_NEAR_DIMM_NG_M_J_BYTE-ECC\" )
					)
					( Units "uMatchProp" "ns" 1.000000)
					( Status sCSetFlattened )
					( Origin gBackEnd )
				)
			)
			( pinPair "@baseboard_fab2_lib.baseboard_fab2(sch_1):\PP2530\"
				( pinRef "@baseboard_fab2_lib.baseboard_fab2(sch_1):page59_i172:DDR2_ECC(5)" )
				( pinRef "@baseboard_fab2_lib.baseboard_fab2(sch_1):page81_i186:CB(4)" )
				( attribute "RELATIVE_PROPAGATION_DELAY_SCOPE" "G"
					( Parent
						( matchGroupRef "@baseboard_fab2_lib.baseboard_fab2(sch_1):\MG_DQ-DQS_FAR_DIMM_NG_M_J_BYTE-ECC\" )
					)
					( Status sCSetFlattened )
					( Origin gBackEnd )
				)
				( attribute "RELATIVE_PROPAGATION_DELAY" "0.00 MIL,195.00 MIL"
					( Parent
						( matchGroupRef "@baseboard_fab2_lib.baseboard_fab2(sch_1):\MG_DQ-DQS_FAR_DIMM_NG_M_J_BYTE-ECC\" )
					)
					( Units "uMatchProp" "ns" 1.000000)
					( Status sCSetFlattened )
					( Origin gBackEnd )
				)
				( attribute "RELATIVE_PROPAGATION_DELAY_SCOPE" "G"
					( Parent
						( matchGroupRef "@baseboard_fab2_lib.baseboard_fab2(sch_1):\MG_DQ_FAR_DIMM_NG_M_J_BYTE-ECC\" )
					)
					( Status sCSetFlattened )
					( Origin gBackEnd )
				)
				( attribute "RELATIVE_PROPAGATION_DELAY" "-50.00 MIL,50.00 MIL"
					( Parent
						( matchGroupRef "@baseboard_fab2_lib.baseboard_fab2(sch_1):\MG_DQ_FAR_DIMM_NG_M_J_BYTE-ECC\" )
					)
					( Units "uMatchProp" "ns" 1.000000)
					( Status sCSetFlattened )
					( Origin gBackEnd )
				)
			)
			( pinPair "@baseboard_fab2_lib.baseboard_fab2(sch_1):\PP2531\"
				( pinRef "@baseboard_fab2_lib.baseboard_fab2(sch_1):page82_i187:CB(5)" )
				( pinRef "@baseboard_fab2_lib.baseboard_fab2(sch_1):page59_i172:DDR2_ECC(5)" )
				( attribute "RELATIVE_PROPAGATION_DELAY_SCOPE" "G"
					( Parent
						( matchGroupRef "@baseboard_fab2_lib.baseboard_fab2(sch_1):\MG_DQ-DQS_NEAR_DIMM_NG_M_J_BYTE-ECC\" )
					)
					( Status sCSetFlattened )
					( Origin gBackEnd )
				)
				( attribute "RELATIVE_PROPAGATION_DELAY" "0.00 MIL,195.00 MIL"
					( Parent
						( matchGroupRef "@baseboard_fab2_lib.baseboard_fab2(sch_1):\MG_DQ-DQS_NEAR_DIMM_NG_M_J_BYTE-ECC\" )
					)
					( Units "uMatchProp" "ns" 1.000000)
					( Status sCSetFlattened )
					( Origin gBackEnd )
				)
				( attribute "RELATIVE_PROPAGATION_DELAY_SCOPE" "G"
					( Parent
						( matchGroupRef "@baseboard_fab2_lib.baseboard_fab2(sch_1):\MG_DQ_NEAR_DIMM_NG_M_J_BYTE-ECC\" )
					)
					( Status sCSetFlattened )
					( Origin gBackEnd )
				)
				( attribute "RELATIVE_PROPAGATION_DELAY" "-50.00 MIL,50.00 MIL"
					( Parent
						( matchGroupRef "@baseboard_fab2_lib.baseboard_fab2(sch_1):\MG_DQ_NEAR_DIMM_NG_M_J_BYTE-ECC\" )
					)
					( Units "uMatchProp" "ns" 1.000000)
					( Status sCSetFlattened )
					( Origin gBackEnd )
				)
			)
			( pinPair "@baseboard_fab2_lib.baseboard_fab2(sch_1):\PP2533\"
				( pinRef "@baseboard_fab2_lib.baseboard_fab2(sch_1):page59_i172:DDR2_ECC(6)" )
				( pinRef "@baseboard_fab2_lib.baseboard_fab2(sch_1):page81_i186:CB(7)" )
				( attribute "RELATIVE_PROPAGATION_DELAY_SCOPE" "G"
					( Parent
						( matchGroupRef "@baseboard_fab2_lib.baseboard_fab2(sch_1):\MG_DQ-DQS_FAR_DIMM_NG_M_J_BYTE-ECC\" )
					)
					( Status sCSetFlattened )
					( Origin gBackEnd )
				)
				( attribute "RELATIVE_PROPAGATION_DELAY" "0.00 MIL,195.00 MIL"
					( Parent
						( matchGroupRef "@baseboard_fab2_lib.baseboard_fab2(sch_1):\MG_DQ-DQS_FAR_DIMM_NG_M_J_BYTE-ECC\" )
					)
					( Units "uMatchProp" "ns" 1.000000)
					( Status sCSetFlattened )
					( Origin gBackEnd )
				)
				( attribute "RELATIVE_PROPAGATION_DELAY_SCOPE" "G"
					( Parent
						( matchGroupRef "@baseboard_fab2_lib.baseboard_fab2(sch_1):\MG_DQ_FAR_DIMM_NG_M_J_BYTE-ECC\" )
					)
					( Status sCSetFlattened )
					( Origin gBackEnd )
				)
				( attribute "RELATIVE_PROPAGATION_DELAY" "-50.00 MIL,50.00 MIL"
					( Parent
						( matchGroupRef "@baseboard_fab2_lib.baseboard_fab2(sch_1):\MG_DQ_FAR_DIMM_NG_M_J_BYTE-ECC\" )
					)
					( Units "uMatchProp" "ns" 1.000000)
					( Status sCSetFlattened )
					( Origin gBackEnd )
				)
			)
			( pinPair "@baseboard_fab2_lib.baseboard_fab2(sch_1):\PP2534\"
				( pinRef "@baseboard_fab2_lib.baseboard_fab2(sch_1):page82_i187:CB(6)" )
				( pinRef "@baseboard_fab2_lib.baseboard_fab2(sch_1):page59_i172:DDR2_ECC(6)" )
				( attribute "RELATIVE_PROPAGATION_DELAY_SCOPE" "G"
					( Parent
						( matchGroupRef "@baseboard_fab2_lib.baseboard_fab2(sch_1):\MG_DQ-DQS_NEAR_DIMM_NG_M_J_BYTE-ECC\" )
					)
					( Status sCSetFlattened )
					( Origin gBackEnd )
				)
				( attribute "RELATIVE_PROPAGATION_DELAY" "0.00 MIL,195.00 MIL"
					( Parent
						( matchGroupRef "@baseboard_fab2_lib.baseboard_fab2(sch_1):\MG_DQ-DQS_NEAR_DIMM_NG_M_J_BYTE-ECC\" )
					)
					( Units "uMatchProp" "ns" 1.000000)
					( Status sCSetFlattened )
					( Origin gBackEnd )
				)
				( attribute "RELATIVE_PROPAGATION_DELAY_SCOPE" "G"
					( Parent
						( matchGroupRef "@baseboard_fab2_lib.baseboard_fab2(sch_1):\MG_DQ_NEAR_DIMM_NG_M_J_BYTE-ECC\" )
					)
					( Status sCSetFlattened )
					( Origin gBackEnd )
				)
				( attribute "RELATIVE_PROPAGATION_DELAY" "-50.00 MIL,50.00 MIL"
					( Parent
						( matchGroupRef "@baseboard_fab2_lib.baseboard_fab2(sch_1):\MG_DQ_NEAR_DIMM_NG_M_J_BYTE-ECC\" )
					)
					( Units "uMatchProp" "ns" 1.000000)
					( Status sCSetFlattened )
					( Origin gBackEnd )
				)
			)
			( pinPair "@baseboard_fab2_lib.baseboard_fab2(sch_1):\PP2536\"
				( pinRef "@baseboard_fab2_lib.baseboard_fab2(sch_1):page59_i172:DDR2_ECC(7)" )
				( pinRef "@baseboard_fab2_lib.baseboard_fab2(sch_1):page81_i186:CB(6)" )
				( attribute "RELATIVE_PROPAGATION_DELAY_SCOPE" "G"
					( Parent
						( matchGroupRef "@baseboard_fab2_lib.baseboard_fab2(sch_1):\MG_DQ-DQS_FAR_DIMM_NG_M_J_BYTE-ECC\" )
					)
					( Status sCSetFlattened )
					( Origin gBackEnd )
				)
				( attribute "RELATIVE_PROPAGATION_DELAY" "0.00 MIL,195.00 MIL"
					( Parent
						( matchGroupRef "@baseboard_fab2_lib.baseboard_fab2(sch_1):\MG_DQ-DQS_FAR_DIMM_NG_M_J_BYTE-ECC\" )
					)
					( Units "uMatchProp" "ns" 1.000000)
					( Status sCSetFlattened )
					( Origin gBackEnd )
				)
				( attribute "RELATIVE_PROPAGATION_DELAY_SCOPE" "G"
					( Parent
						( matchGroupRef "@baseboard_fab2_lib.baseboard_fab2(sch_1):\MG_DQ_FAR_DIMM_NG_M_J_BYTE-ECC\" )
					)
					( Status sCSetFlattened )
					( Origin gBackEnd )
				)
				( attribute "RELATIVE_PROPAGATION_DELAY" "-50.00 MIL,50.00 MIL"
					( Parent
						( matchGroupRef "@baseboard_fab2_lib.baseboard_fab2(sch_1):\MG_DQ_FAR_DIMM_NG_M_J_BYTE-ECC\" )
					)
					( Units "uMatchProp" "ns" 1.000000)
					( Status sCSetFlattened )
					( Origin gBackEnd )
				)
			)
			( pinPair "@baseboard_fab2_lib.baseboard_fab2(sch_1):\PP2537\"
				( pinRef "@baseboard_fab2_lib.baseboard_fab2(sch_1):page82_i187:CB(7)" )
				( pinRef "@baseboard_fab2_lib.baseboard_fab2(sch_1):page59_i172:DDR2_ECC(7)" )
				( attribute "RELATIVE_PROPAGATION_DELAY_SCOPE" "G"
					( Parent
						( matchGroupRef "@baseboard_fab2_lib.baseboard_fab2(sch_1):\MG_DQ-DQS_NEAR_DIMM_NG_M_J_BYTE-ECC\" )
					)
					( Status sCSetFlattened )
					( Origin gBackEnd )
				)
				( attribute "RELATIVE_PROPAGATION_DELAY" "0.00 MIL,195.00 MIL"
					( Parent
						( matchGroupRef "@baseboard_fab2_lib.baseboard_fab2(sch_1):\MG_DQ-DQS_NEAR_DIMM_NG_M_J_BYTE-ECC\" )
					)
					( Units "uMatchProp" "ns" 1.000000)
					( Status sCSetFlattened )
					( Origin gBackEnd )
				)
				( attribute "RELATIVE_PROPAGATION_DELAY_SCOPE" "G"
					( Parent
						( matchGroupRef "@baseboard_fab2_lib.baseboard_fab2(sch_1):\MG_DQ_NEAR_DIMM_NG_M_J_BYTE-ECC\" )
					)
					( Status sCSetFlattened )
					( Origin gBackEnd )
				)
				( attribute "RELATIVE_PROPAGATION_DELAY" "-50.00 MIL,50.00 MIL"
					( Parent
						( matchGroupRef "@baseboard_fab2_lib.baseboard_fab2(sch_1):\MG_DQ_NEAR_DIMM_NG_M_J_BYTE-ECC\" )
					)
					( Units "uMatchProp" "ns" 1.000000)
					( Status sCSetFlattened )
					( Origin gBackEnd )
				)
			)
			( pinPair "@baseboard_fab2_lib.baseboard_fab2(sch_1):\PP2299\"
				( pinRef "@baseboard_fab2_lib.baseboard_fab2(sch_1):page60_i172:DDR3_ECC(0)" )
				( pinRef "@baseboard_fab2_lib.baseboard_fab2(sch_1):page83_i111:CB(1)" )
				( attribute "RELATIVE_PROPAGATION_DELAY_SCOPE" "G"
					( Parent
						( matchGroupRef "@baseboard_fab2_lib.baseboard_fab2(sch_1):\MG_DQ-DQS_FAR_DIMM_NG_M_K_BYTE-ECC\" )
					)
					( Status sCSetFlattened )
					( Origin gBackEnd )
				)
				( attribute "RELATIVE_PROPAGATION_DELAY" "0.00 MIL,195.00 MIL"
					( Parent
						( matchGroupRef "@baseboard_fab2_lib.baseboard_fab2(sch_1):\MG_DQ-DQS_FAR_DIMM_NG_M_K_BYTE-ECC\" )
					)
					( Units "uMatchProp" "ns" 1.000000)
					( Status sCSetFlattened )
					( Origin gBackEnd )
				)
				( attribute "RELATIVE_PROPAGATION_DELAY_SCOPE" "G"
					( Parent
						( matchGroupRef "@baseboard_fab2_lib.baseboard_fab2(sch_1):\MG_DQ_FAR_DIMM_NG_M_K_BYTE-ECC\" )
					)
					( Status sCSetFlattened )
					( Origin gBackEnd )
				)
				( attribute "RELATIVE_PROPAGATION_DELAY" "-50.00 MIL,50.00 MIL"
					( Parent
						( matchGroupRef "@baseboard_fab2_lib.baseboard_fab2(sch_1):\MG_DQ_FAR_DIMM_NG_M_K_BYTE-ECC\" )
					)
					( Units "uMatchProp" "ns" 1.000000)
					( Status sCSetFlattened )
					( Origin gBackEnd )
				)
			)
			( pinPair "@baseboard_fab2_lib.baseboard_fab2(sch_1):\PP2300\"
				( pinRef "@baseboard_fab2_lib.baseboard_fab2(sch_1):page60_i172:DDR3_ECC(0)" )
				( pinRef "@baseboard_fab2_lib.baseboard_fab2(sch_1):page84_i14:CB(0)" )
				( attribute "RELATIVE_PROPAGATION_DELAY_SCOPE" "G"
					( Parent
						( matchGroupRef "@baseboard_fab2_lib.baseboard_fab2(sch_1):\MG_DQ-DQS_NEAR_DIMM_NG_M_K_BYTE-ECC\" )
					)
					( Status sCSetFlattened )
					( Origin gBackEnd )
				)
				( attribute "RELATIVE_PROPAGATION_DELAY" "0.00 MIL,195.00 MIL"
					( Parent
						( matchGroupRef "@baseboard_fab2_lib.baseboard_fab2(sch_1):\MG_DQ-DQS_NEAR_DIMM_NG_M_K_BYTE-ECC\" )
					)
					( Units "uMatchProp" "ns" 1.000000)
					( Status sCSetFlattened )
					( Origin gBackEnd )
				)
				( attribute "RELATIVE_PROPAGATION_DELAY_SCOPE" "G"
					( Parent
						( matchGroupRef "@baseboard_fab2_lib.baseboard_fab2(sch_1):\MG_DQ_NEAR_DIMM_NG_M_K_BYTE-ECC\" )
					)
					( Status sCSetFlattened )
					( Origin gBackEnd )
				)
				( attribute "RELATIVE_PROPAGATION_DELAY" "-50.00 MIL,50.00 MIL"
					( Parent
						( matchGroupRef "@baseboard_fab2_lib.baseboard_fab2(sch_1):\MG_DQ_NEAR_DIMM_NG_M_K_BYTE-ECC\" )
					)
					( Units "uMatchProp" "ns" 1.000000)
					( Status sCSetFlattened )
					( Origin gBackEnd )
				)
			)
			( pinPair "@baseboard_fab2_lib.baseboard_fab2(sch_1):\PP2302\"
				( pinRef "@baseboard_fab2_lib.baseboard_fab2(sch_1):page60_i172:DDR3_ECC(1)" )
				( pinRef "@baseboard_fab2_lib.baseboard_fab2(sch_1):page83_i111:CB(0)" )
				( attribute "RELATIVE_PROPAGATION_DELAY_SCOPE" "G"
					( Parent
						( matchGroupRef "@baseboard_fab2_lib.baseboard_fab2(sch_1):\MG_DQ-DQS_FAR_DIMM_NG_M_K_BYTE-ECC\" )
					)
					( Status sCSetFlattened )
					( Origin gBackEnd )
				)
				( attribute "RELATIVE_PROPAGATION_DELAY" "0.00 MIL,195.00 MIL"
					( Parent
						( matchGroupRef "@baseboard_fab2_lib.baseboard_fab2(sch_1):\MG_DQ-DQS_FAR_DIMM_NG_M_K_BYTE-ECC\" )
					)
					( Units "uMatchProp" "ns" 1.000000)
					( Status sCSetFlattened )
					( Origin gBackEnd )
				)
				( attribute "RELATIVE_PROPAGATION_DELAY_SCOPE" "G"
					( Parent
						( matchGroupRef "@baseboard_fab2_lib.baseboard_fab2(sch_1):\MG_DQ_FAR_DIMM_NG_M_K_BYTE-ECC\" )
					)
					( Status sCSetFlattened )
					( Origin gBackEnd )
				)
				( attribute "RELATIVE_PROPAGATION_DELAY" "-50.00 MIL,50.00 MIL"
					( Parent
						( matchGroupRef "@baseboard_fab2_lib.baseboard_fab2(sch_1):\MG_DQ_FAR_DIMM_NG_M_K_BYTE-ECC\" )
					)
					( Units "uMatchProp" "ns" 1.000000)
					( Status sCSetFlattened )
					( Origin gBackEnd )
				)
			)
			( pinPair "@baseboard_fab2_lib.baseboard_fab2(sch_1):\PP2303\"
				( pinRef "@baseboard_fab2_lib.baseboard_fab2(sch_1):page60_i172:DDR3_ECC(1)" )
				( pinRef "@baseboard_fab2_lib.baseboard_fab2(sch_1):page84_i14:CB(1)" )
				( attribute "RELATIVE_PROPAGATION_DELAY_SCOPE" "G"
					( Parent
						( matchGroupRef "@baseboard_fab2_lib.baseboard_fab2(sch_1):\MG_DQ-DQS_NEAR_DIMM_NG_M_K_BYTE-ECC\" )
					)
					( Status sCSetFlattened )
					( Origin gBackEnd )
				)
				( attribute "RELATIVE_PROPAGATION_DELAY" "0.00 MIL,195.00 MIL"
					( Parent
						( matchGroupRef "@baseboard_fab2_lib.baseboard_fab2(sch_1):\MG_DQ-DQS_NEAR_DIMM_NG_M_K_BYTE-ECC\" )
					)
					( Units "uMatchProp" "ns" 1.000000)
					( Status sCSetFlattened )
					( Origin gBackEnd )
				)
				( attribute "RELATIVE_PROPAGATION_DELAY_SCOPE" "G"
					( Parent
						( matchGroupRef "@baseboard_fab2_lib.baseboard_fab2(sch_1):\MG_DQ_NEAR_DIMM_NG_M_K_BYTE-ECC\" )
					)
					( Status sCSetFlattened )
					( Origin gBackEnd )
				)
				( attribute "RELATIVE_PROPAGATION_DELAY" "-50.00 MIL,50.00 MIL"
					( Parent
						( matchGroupRef "@baseboard_fab2_lib.baseboard_fab2(sch_1):\MG_DQ_NEAR_DIMM_NG_M_K_BYTE-ECC\" )
					)
					( Units "uMatchProp" "ns" 1.000000)
					( Status sCSetFlattened )
					( Origin gBackEnd )
				)
			)
			( pinPair "@baseboard_fab2_lib.baseboard_fab2(sch_1):\PP2305\"
				( pinRef "@baseboard_fab2_lib.baseboard_fab2(sch_1):page60_i172:DDR3_ECC(2)" )
				( pinRef "@baseboard_fab2_lib.baseboard_fab2(sch_1):page83_i111:CB(3)" )
				( attribute "RELATIVE_PROPAGATION_DELAY_SCOPE" "G"
					( Parent
						( matchGroupRef "@baseboard_fab2_lib.baseboard_fab2(sch_1):\MG_DQ-DQS_FAR_DIMM_NG_M_K_BYTE-ECC\" )
					)
					( Status sCSetFlattened )
					( Origin gBackEnd )
				)
				( attribute "RELATIVE_PROPAGATION_DELAY" "0.00 MIL,195.00 MIL"
					( Parent
						( matchGroupRef "@baseboard_fab2_lib.baseboard_fab2(sch_1):\MG_DQ-DQS_FAR_DIMM_NG_M_K_BYTE-ECC\" )
					)
					( Units "uMatchProp" "ns" 1.000000)
					( Status sCSetFlattened )
					( Origin gBackEnd )
				)
				( attribute "RELATIVE_PROPAGATION_DELAY_SCOPE" "G"
					( Parent
						( matchGroupRef "@baseboard_fab2_lib.baseboard_fab2(sch_1):\MG_DQ_FAR_DIMM_NG_M_K_BYTE-ECC\" )
					)
					( Status sCSetFlattened )
					( Origin gBackEnd )
				)
				( attribute "RELATIVE_PROPAGATION_DELAY" "-50.00 MIL,50.00 MIL"
					( Parent
						( matchGroupRef "@baseboard_fab2_lib.baseboard_fab2(sch_1):\MG_DQ_FAR_DIMM_NG_M_K_BYTE-ECC\" )
					)
					( Units "uMatchProp" "ns" 1.000000)
					( Status sCSetFlattened )
					( Origin gBackEnd )
				)
			)
			( pinPair "@baseboard_fab2_lib.baseboard_fab2(sch_1):\PP2306\"
				( pinRef "@baseboard_fab2_lib.baseboard_fab2(sch_1):page60_i172:DDR3_ECC(2)" )
				( pinRef "@baseboard_fab2_lib.baseboard_fab2(sch_1):page84_i14:CB(2)" )
				( attribute "RELATIVE_PROPAGATION_DELAY_SCOPE" "G"
					( Parent
						( matchGroupRef "@baseboard_fab2_lib.baseboard_fab2(sch_1):\MG_DQ-DQS_NEAR_DIMM_NG_M_K_BYTE-ECC\" )
					)
					( Status sCSetFlattened )
					( Origin gBackEnd )
				)
				( attribute "RELATIVE_PROPAGATION_DELAY" "0.00 MIL,195.00 MIL"
					( Parent
						( matchGroupRef "@baseboard_fab2_lib.baseboard_fab2(sch_1):\MG_DQ-DQS_NEAR_DIMM_NG_M_K_BYTE-ECC\" )
					)
					( Units "uMatchProp" "ns" 1.000000)
					( Status sCSetFlattened )
					( Origin gBackEnd )
				)
				( attribute "RELATIVE_PROPAGATION_DELAY_SCOPE" "G"
					( Parent
						( matchGroupRef "@baseboard_fab2_lib.baseboard_fab2(sch_1):\MG_DQ_NEAR_DIMM_NG_M_K_BYTE-ECC\" )
					)
					( Status sCSetFlattened )
					( Origin gBackEnd )
				)
				( attribute "RELATIVE_PROPAGATION_DELAY" "-50.00 MIL,50.00 MIL"
					( Parent
						( matchGroupRef "@baseboard_fab2_lib.baseboard_fab2(sch_1):\MG_DQ_NEAR_DIMM_NG_M_K_BYTE-ECC\" )
					)
					( Units "uMatchProp" "ns" 1.000000)
					( Status sCSetFlattened )
					( Origin gBackEnd )
				)
			)
			( pinPair "@baseboard_fab2_lib.baseboard_fab2(sch_1):\PP2308\"
				( pinRef "@baseboard_fab2_lib.baseboard_fab2(sch_1):page60_i172:DDR3_ECC(3)" )
				( pinRef "@baseboard_fab2_lib.baseboard_fab2(sch_1):page83_i111:CB(2)" )
				( attribute "RELATIVE_PROPAGATION_DELAY_SCOPE" "G"
					( Parent
						( matchGroupRef "@baseboard_fab2_lib.baseboard_fab2(sch_1):\MG_DQ-DQS_FAR_DIMM_NG_M_K_BYTE-ECC\" )
					)
					( Status sCSetFlattened )
					( Origin gBackEnd )
				)
				( attribute "RELATIVE_PROPAGATION_DELAY" "0.00 MIL,195.00 MIL"
					( Parent
						( matchGroupRef "@baseboard_fab2_lib.baseboard_fab2(sch_1):\MG_DQ-DQS_FAR_DIMM_NG_M_K_BYTE-ECC\" )
					)
					( Units "uMatchProp" "ns" 1.000000)
					( Status sCSetFlattened )
					( Origin gBackEnd )
				)
				( attribute "RELATIVE_PROPAGATION_DELAY_SCOPE" "G"
					( Parent
						( matchGroupRef "@baseboard_fab2_lib.baseboard_fab2(sch_1):\MG_DQ_FAR_DIMM_NG_M_K_BYTE-ECC\" )
					)
					( Status sCSetFlattened )
					( Origin gBackEnd )
				)
				( attribute "RELATIVE_PROPAGATION_DELAY" "-50.00 MIL,50.00 MIL"
					( Parent
						( matchGroupRef "@baseboard_fab2_lib.baseboard_fab2(sch_1):\MG_DQ_FAR_DIMM_NG_M_K_BYTE-ECC\" )
					)
					( Units "uMatchProp" "ns" 1.000000)
					( Status sCSetFlattened )
					( Origin gBackEnd )
				)
			)
			( pinPair "@baseboard_fab2_lib.baseboard_fab2(sch_1):\PP2309\"
				( pinRef "@baseboard_fab2_lib.baseboard_fab2(sch_1):page60_i172:DDR3_ECC(3)" )
				( pinRef "@baseboard_fab2_lib.baseboard_fab2(sch_1):page84_i14:CB(3)" )
				( attribute "RELATIVE_PROPAGATION_DELAY_SCOPE" "G"
					( Parent
						( matchGroupRef "@baseboard_fab2_lib.baseboard_fab2(sch_1):\MG_DQ-DQS_NEAR_DIMM_NG_M_K_BYTE-ECC\" )
					)
					( Status sCSetFlattened )
					( Origin gBackEnd )
				)
				( attribute "RELATIVE_PROPAGATION_DELAY" "0.00 MIL,195.00 MIL"
					( Parent
						( matchGroupRef "@baseboard_fab2_lib.baseboard_fab2(sch_1):\MG_DQ-DQS_NEAR_DIMM_NG_M_K_BYTE-ECC\" )
					)
					( Units "uMatchProp" "ns" 1.000000)
					( Status sCSetFlattened )
					( Origin gBackEnd )
				)
				( attribute "RELATIVE_PROPAGATION_DELAY_SCOPE" "G"
					( Parent
						( matchGroupRef "@baseboard_fab2_lib.baseboard_fab2(sch_1):\MG_DQ_NEAR_DIMM_NG_M_K_BYTE-ECC\" )
					)
					( Status sCSetFlattened )
					( Origin gBackEnd )
				)
				( attribute "RELATIVE_PROPAGATION_DELAY" "-50.00 MIL,50.00 MIL"
					( Parent
						( matchGroupRef "@baseboard_fab2_lib.baseboard_fab2(sch_1):\MG_DQ_NEAR_DIMM_NG_M_K_BYTE-ECC\" )
					)
					( Units "uMatchProp" "ns" 1.000000)
					( Status sCSetFlattened )
					( Origin gBackEnd )
				)
			)
			( pinPair "@baseboard_fab2_lib.baseboard_fab2(sch_1):\PP2311\"
				( pinRef "@baseboard_fab2_lib.baseboard_fab2(sch_1):page60_i172:DDR3_ECC(4)" )
				( pinRef "@baseboard_fab2_lib.baseboard_fab2(sch_1):page83_i111:CB(5)" )
				( attribute "RELATIVE_PROPAGATION_DELAY_SCOPE" "G"
					( Parent
						( matchGroupRef "@baseboard_fab2_lib.baseboard_fab2(sch_1):\MG_DQ-DQS_FAR_DIMM_NG_M_K_BYTE-ECC\" )
					)
					( Status sCSetFlattened )
					( Origin gBackEnd )
				)
				( attribute "RELATIVE_PROPAGATION_DELAY" "0.00 MIL,195.00 MIL"
					( Parent
						( matchGroupRef "@baseboard_fab2_lib.baseboard_fab2(sch_1):\MG_DQ-DQS_FAR_DIMM_NG_M_K_BYTE-ECC\" )
					)
					( Units "uMatchProp" "ns" 1.000000)
					( Status sCSetFlattened )
					( Origin gBackEnd )
				)
				( attribute "RELATIVE_PROPAGATION_DELAY_SCOPE" "G"
					( Parent
						( matchGroupRef "@baseboard_fab2_lib.baseboard_fab2(sch_1):\MG_DQ_FAR_DIMM_NG_M_K_BYTE-ECC\" )
					)
					( Status sCSetFlattened )
					( Origin gBackEnd )
				)
				( attribute "RELATIVE_PROPAGATION_DELAY" "-50.00 MIL,50.00 MIL"
					( Parent
						( matchGroupRef "@baseboard_fab2_lib.baseboard_fab2(sch_1):\MG_DQ_FAR_DIMM_NG_M_K_BYTE-ECC\" )
					)
					( Units "uMatchProp" "ns" 1.000000)
					( Status sCSetFlattened )
					( Origin gBackEnd )
				)
			)
			( pinPair "@baseboard_fab2_lib.baseboard_fab2(sch_1):\PP2312\"
				( pinRef "@baseboard_fab2_lib.baseboard_fab2(sch_1):page60_i172:DDR3_ECC(4)" )
				( pinRef "@baseboard_fab2_lib.baseboard_fab2(sch_1):page84_i14:CB(4)" )
				( attribute "RELATIVE_PROPAGATION_DELAY_SCOPE" "G"
					( Parent
						( matchGroupRef "@baseboard_fab2_lib.baseboard_fab2(sch_1):\MG_DQ-DQS_NEAR_DIMM_NG_M_K_BYTE-ECC\" )
					)
					( Status sCSetFlattened )
					( Origin gBackEnd )
				)
				( attribute "RELATIVE_PROPAGATION_DELAY" "0.00 MIL,195.00 MIL"
					( Parent
						( matchGroupRef "@baseboard_fab2_lib.baseboard_fab2(sch_1):\MG_DQ-DQS_NEAR_DIMM_NG_M_K_BYTE-ECC\" )
					)
					( Units "uMatchProp" "ns" 1.000000)
					( Status sCSetFlattened )
					( Origin gBackEnd )
				)
				( attribute "RELATIVE_PROPAGATION_DELAY_SCOPE" "G"
					( Parent
						( matchGroupRef "@baseboard_fab2_lib.baseboard_fab2(sch_1):\MG_DQ_NEAR_DIMM_NG_M_K_BYTE-ECC\" )
					)
					( Status sCSetFlattened )
					( Origin gBackEnd )
				)
				( attribute "RELATIVE_PROPAGATION_DELAY" "-50.00 MIL,50.00 MIL"
					( Parent
						( matchGroupRef "@baseboard_fab2_lib.baseboard_fab2(sch_1):\MG_DQ_NEAR_DIMM_NG_M_K_BYTE-ECC\" )
					)
					( Units "uMatchProp" "ns" 1.000000)
					( Status sCSetFlattened )
					( Origin gBackEnd )
				)
			)
			( pinPair "@baseboard_fab2_lib.baseboard_fab2(sch_1):\PP2314\"
				( pinRef "@baseboard_fab2_lib.baseboard_fab2(sch_1):page60_i172:DDR3_ECC(5)" )
				( pinRef "@baseboard_fab2_lib.baseboard_fab2(sch_1):page83_i111:CB(4)" )
				( attribute "RELATIVE_PROPAGATION_DELAY_SCOPE" "G"
					( Parent
						( matchGroupRef "@baseboard_fab2_lib.baseboard_fab2(sch_1):\MG_DQ-DQS_FAR_DIMM_NG_M_K_BYTE-ECC\" )
					)
					( Status sCSetFlattened )
					( Origin gBackEnd )
				)
				( attribute "RELATIVE_PROPAGATION_DELAY" "0.00 MIL,195.00 MIL"
					( Parent
						( matchGroupRef "@baseboard_fab2_lib.baseboard_fab2(sch_1):\MG_DQ-DQS_FAR_DIMM_NG_M_K_BYTE-ECC\" )
					)
					( Units "uMatchProp" "ns" 1.000000)
					( Status sCSetFlattened )
					( Origin gBackEnd )
				)
				( attribute "RELATIVE_PROPAGATION_DELAY_SCOPE" "G"
					( Parent
						( matchGroupRef "@baseboard_fab2_lib.baseboard_fab2(sch_1):\MG_DQ_FAR_DIMM_NG_M_K_BYTE-ECC\" )
					)
					( Status sCSetFlattened )
					( Origin gBackEnd )
				)
				( attribute "RELATIVE_PROPAGATION_DELAY" "-50.00 MIL,50.00 MIL"
					( Parent
						( matchGroupRef "@baseboard_fab2_lib.baseboard_fab2(sch_1):\MG_DQ_FAR_DIMM_NG_M_K_BYTE-ECC\" )
					)
					( Units "uMatchProp" "ns" 1.000000)
					( Status sCSetFlattened )
					( Origin gBackEnd )
				)
			)
			( pinPair "@baseboard_fab2_lib.baseboard_fab2(sch_1):\PP2315\"
				( pinRef "@baseboard_fab2_lib.baseboard_fab2(sch_1):page60_i172:DDR3_ECC(5)" )
				( pinRef "@baseboard_fab2_lib.baseboard_fab2(sch_1):page84_i14:CB(5)" )
				( attribute "RELATIVE_PROPAGATION_DELAY_SCOPE" "G"
					( Parent
						( matchGroupRef "@baseboard_fab2_lib.baseboard_fab2(sch_1):\MG_DQ-DQS_NEAR_DIMM_NG_M_K_BYTE-ECC\" )
					)
					( Status sCSetFlattened )
					( Origin gBackEnd )
				)
				( attribute "RELATIVE_PROPAGATION_DELAY" "0.00 MIL,195.00 MIL"
					( Parent
						( matchGroupRef "@baseboard_fab2_lib.baseboard_fab2(sch_1):\MG_DQ-DQS_NEAR_DIMM_NG_M_K_BYTE-ECC\" )
					)
					( Units "uMatchProp" "ns" 1.000000)
					( Status sCSetFlattened )
					( Origin gBackEnd )
				)
				( attribute "RELATIVE_PROPAGATION_DELAY_SCOPE" "G"
					( Parent
						( matchGroupRef "@baseboard_fab2_lib.baseboard_fab2(sch_1):\MG_DQ_NEAR_DIMM_NG_M_K_BYTE-ECC\" )
					)
					( Status sCSetFlattened )
					( Origin gBackEnd )
				)
				( attribute "RELATIVE_PROPAGATION_DELAY" "-50.00 MIL,50.00 MIL"
					( Parent
						( matchGroupRef "@baseboard_fab2_lib.baseboard_fab2(sch_1):\MG_DQ_NEAR_DIMM_NG_M_K_BYTE-ECC\" )
					)
					( Units "uMatchProp" "ns" 1.000000)
					( Status sCSetFlattened )
					( Origin gBackEnd )
				)
			)
			( pinPair "@baseboard_fab2_lib.baseboard_fab2(sch_1):\PP2317\"
				( pinRef "@baseboard_fab2_lib.baseboard_fab2(sch_1):page60_i172:DDR3_ECC(6)" )
				( pinRef "@baseboard_fab2_lib.baseboard_fab2(sch_1):page83_i111:CB(7)" )
				( attribute "RELATIVE_PROPAGATION_DELAY_SCOPE" "G"
					( Parent
						( matchGroupRef "@baseboard_fab2_lib.baseboard_fab2(sch_1):\MG_DQ-DQS_FAR_DIMM_NG_M_K_BYTE-ECC\" )
					)
					( Status sCSetFlattened )
					( Origin gBackEnd )
				)
				( attribute "RELATIVE_PROPAGATION_DELAY" "0.00 MIL,195.00 MIL"
					( Parent
						( matchGroupRef "@baseboard_fab2_lib.baseboard_fab2(sch_1):\MG_DQ-DQS_FAR_DIMM_NG_M_K_BYTE-ECC\" )
					)
					( Units "uMatchProp" "ns" 1.000000)
					( Status sCSetFlattened )
					( Origin gBackEnd )
				)
				( attribute "RELATIVE_PROPAGATION_DELAY_SCOPE" "G"
					( Parent
						( matchGroupRef "@baseboard_fab2_lib.baseboard_fab2(sch_1):\MG_DQ_FAR_DIMM_NG_M_K_BYTE-ECC\" )
					)
					( Status sCSetFlattened )
					( Origin gBackEnd )
				)
				( attribute "RELATIVE_PROPAGATION_DELAY" "-50.00 MIL,50.00 MIL"
					( Parent
						( matchGroupRef "@baseboard_fab2_lib.baseboard_fab2(sch_1):\MG_DQ_FAR_DIMM_NG_M_K_BYTE-ECC\" )
					)
					( Units "uMatchProp" "ns" 1.000000)
					( Status sCSetFlattened )
					( Origin gBackEnd )
				)
			)
			( pinPair "@baseboard_fab2_lib.baseboard_fab2(sch_1):\PP2318\"
				( pinRef "@baseboard_fab2_lib.baseboard_fab2(sch_1):page60_i172:DDR3_ECC(6)" )
				( pinRef "@baseboard_fab2_lib.baseboard_fab2(sch_1):page84_i14:CB(6)" )
				( attribute "RELATIVE_PROPAGATION_DELAY_SCOPE" "G"
					( Parent
						( matchGroupRef "@baseboard_fab2_lib.baseboard_fab2(sch_1):\MG_DQ-DQS_NEAR_DIMM_NG_M_K_BYTE-ECC\" )
					)
					( Status sCSetFlattened )
					( Origin gBackEnd )
				)
				( attribute "RELATIVE_PROPAGATION_DELAY" "0.00 MIL,195.00 MIL"
					( Parent
						( matchGroupRef "@baseboard_fab2_lib.baseboard_fab2(sch_1):\MG_DQ-DQS_NEAR_DIMM_NG_M_K_BYTE-ECC\" )
					)
					( Units "uMatchProp" "ns" 1.000000)
					( Status sCSetFlattened )
					( Origin gBackEnd )
				)
				( attribute "RELATIVE_PROPAGATION_DELAY_SCOPE" "G"
					( Parent
						( matchGroupRef "@baseboard_fab2_lib.baseboard_fab2(sch_1):\MG_DQ_NEAR_DIMM_NG_M_K_BYTE-ECC\" )
					)
					( Status sCSetFlattened )
					( Origin gBackEnd )
				)
				( attribute "RELATIVE_PROPAGATION_DELAY" "-50.00 MIL,50.00 MIL"
					( Parent
						( matchGroupRef "@baseboard_fab2_lib.baseboard_fab2(sch_1):\MG_DQ_NEAR_DIMM_NG_M_K_BYTE-ECC\" )
					)
					( Units "uMatchProp" "ns" 1.000000)
					( Status sCSetFlattened )
					( Origin gBackEnd )
				)
			)
			( pinPair "@baseboard_fab2_lib.baseboard_fab2(sch_1):\PP2320\"
				( pinRef "@baseboard_fab2_lib.baseboard_fab2(sch_1):page60_i172:DDR3_ECC(7)" )
				( pinRef "@baseboard_fab2_lib.baseboard_fab2(sch_1):page83_i111:CB(6)" )
				( attribute "RELATIVE_PROPAGATION_DELAY_SCOPE" "G"
					( Parent
						( matchGroupRef "@baseboard_fab2_lib.baseboard_fab2(sch_1):\MG_DQ-DQS_FAR_DIMM_NG_M_K_BYTE-ECC\" )
					)
					( Status sCSetFlattened )
					( Origin gBackEnd )
				)
				( attribute "RELATIVE_PROPAGATION_DELAY" "0.00 MIL,195.00 MIL"
					( Parent
						( matchGroupRef "@baseboard_fab2_lib.baseboard_fab2(sch_1):\MG_DQ-DQS_FAR_DIMM_NG_M_K_BYTE-ECC\" )
					)
					( Units "uMatchProp" "ns" 1.000000)
					( Status sCSetFlattened )
					( Origin gBackEnd )
				)
				( attribute "RELATIVE_PROPAGATION_DELAY_SCOPE" "G"
					( Parent
						( matchGroupRef "@baseboard_fab2_lib.baseboard_fab2(sch_1):\MG_DQ_FAR_DIMM_NG_M_K_BYTE-ECC\" )
					)
					( Status sCSetFlattened )
					( Origin gBackEnd )
				)
				( attribute "RELATIVE_PROPAGATION_DELAY" "-50.00 MIL,50.00 MIL"
					( Parent
						( matchGroupRef "@baseboard_fab2_lib.baseboard_fab2(sch_1):\MG_DQ_FAR_DIMM_NG_M_K_BYTE-ECC\" )
					)
					( Units "uMatchProp" "ns" 1.000000)
					( Status sCSetFlattened )
					( Origin gBackEnd )
				)
			)
			( pinPair "@baseboard_fab2_lib.baseboard_fab2(sch_1):\PP2321\"
				( pinRef "@baseboard_fab2_lib.baseboard_fab2(sch_1):page60_i172:DDR3_ECC(7)" )
				( pinRef "@baseboard_fab2_lib.baseboard_fab2(sch_1):page84_i14:CB(7)" )
				( attribute "RELATIVE_PROPAGATION_DELAY_SCOPE" "G"
					( Parent
						( matchGroupRef "@baseboard_fab2_lib.baseboard_fab2(sch_1):\MG_DQ-DQS_NEAR_DIMM_NG_M_K_BYTE-ECC\" )
					)
					( Status sCSetFlattened )
					( Origin gBackEnd )
				)
				( attribute "RELATIVE_PROPAGATION_DELAY" "0.00 MIL,195.00 MIL"
					( Parent
						( matchGroupRef "@baseboard_fab2_lib.baseboard_fab2(sch_1):\MG_DQ-DQS_NEAR_DIMM_NG_M_K_BYTE-ECC\" )
					)
					( Units "uMatchProp" "ns" 1.000000)
					( Status sCSetFlattened )
					( Origin gBackEnd )
				)
				( attribute "RELATIVE_PROPAGATION_DELAY_SCOPE" "G"
					( Parent
						( matchGroupRef "@baseboard_fab2_lib.baseboard_fab2(sch_1):\MG_DQ_NEAR_DIMM_NG_M_K_BYTE-ECC\" )
					)
					( Status sCSetFlattened )
					( Origin gBackEnd )
				)
				( attribute "RELATIVE_PROPAGATION_DELAY" "-50.00 MIL,50.00 MIL"
					( Parent
						( matchGroupRef "@baseboard_fab2_lib.baseboard_fab2(sch_1):\MG_DQ_NEAR_DIMM_NG_M_K_BYTE-ECC\" )
					)
					( Units "uMatchProp" "ns" 1.000000)
					( Status sCSetFlattened )
					( Origin gBackEnd )
				)
			)
			( pinPair "@baseboard_fab2_lib.baseboard_fab2(sch_1):\PP2083\"
				( pinRef "@baseboard_fab2_lib.baseboard_fab2(sch_1):page61_i172:DDR4_ECC(0)" )
				( pinRef "@baseboard_fab2_lib.baseboard_fab2(sch_1):page85_i111:CB(1)" )
				( attribute "RELATIVE_PROPAGATION_DELAY_SCOPE" "G"
					( Parent
						( matchGroupRef "@baseboard_fab2_lib.baseboard_fab2(sch_1):\MG_DQ-DQS_FAR_DIMM_NG_M_L_BYTE-ECC\" )
					)
					( Status sCSetFlattened )
					( Origin gBackEnd )
				)
				( attribute "RELATIVE_PROPAGATION_DELAY" "0.00 MIL,195.00 MIL"
					( Parent
						( matchGroupRef "@baseboard_fab2_lib.baseboard_fab2(sch_1):\MG_DQ-DQS_FAR_DIMM_NG_M_L_BYTE-ECC\" )
					)
					( Units "uMatchProp" "ns" 1.000000)
					( Status sCSetFlattened )
					( Origin gBackEnd )
				)
				( attribute "RELATIVE_PROPAGATION_DELAY_SCOPE" "G"
					( Parent
						( matchGroupRef "@crescent_city_bb_fab1_lib.crescent_city_bb_fab1(sch_1):\MG_DQ_FAR_DIMM_NG_M_L_BYTE-ECC\" )
					)
					( Origin gBackEnd )
				)
				( attribute "RELATIVE_PROPAGATION_DELAY" "-83.78 MIL,50.00 MIL"
					( Parent
						( matchGroupRef "@crescent_city_bb_fab1_lib.crescent_city_bb_fab1(sch_1):\MG_DQ_FAR_DIMM_NG_M_L_BYTE-ECC\" )
					)
					( Units "uMatchProp" "ns" 1.000000)
					( Origin gBackEnd )
				)
			)
			( pinPair "@baseboard_fab2_lib.baseboard_fab2(sch_1):\PP2084\"
				( pinRef "@baseboard_fab2_lib.baseboard_fab2(sch_1):page61_i172:DDR4_ECC(0)" )
				( pinRef "@baseboard_fab2_lib.baseboard_fab2(sch_1):page86_i12:CB(0)" )
				( attribute "RELATIVE_PROPAGATION_DELAY_SCOPE" "G"
					( Parent
						( matchGroupRef "@baseboard_fab2_lib.baseboard_fab2(sch_1):\MG_DQ-DQS_NEAR_DIMM_NG_M_L_BYTE-ECC\" )
					)
					( Status sCSetFlattened )
					( Origin gBackEnd )
				)
				( attribute "RELATIVE_PROPAGATION_DELAY" "0.00 MIL,195.00 MIL"
					( Parent
						( matchGroupRef "@baseboard_fab2_lib.baseboard_fab2(sch_1):\MG_DQ-DQS_NEAR_DIMM_NG_M_L_BYTE-ECC\" )
					)
					( Units "uMatchProp" "ns" 1.000000)
					( Status sCSetFlattened )
					( Origin gBackEnd )
				)
				( attribute "RELATIVE_PROPAGATION_DELAY_SCOPE" "G"
					( Parent
						( matchGroupRef "@crescent_city_bb_fab1_lib.crescent_city_bb_fab1(sch_1):\MG_DQ_NEAR_DIMM_NG_M_L_BYTE-ECC\" )
					)
					( Origin gBackEnd )
				)
				( attribute "RELATIVE_PROPAGATION_DELAY" "-83.78 MIL,50.00 MIL"
					( Parent
						( matchGroupRef "@crescent_city_bb_fab1_lib.crescent_city_bb_fab1(sch_1):\MG_DQ_NEAR_DIMM_NG_M_L_BYTE-ECC\" )
					)
					( Units "uMatchProp" "ns" 1.000000)
					( Origin gBackEnd )
				)
			)
			( pinPair "@baseboard_fab2_lib.baseboard_fab2(sch_1):\PP2086\"
				( pinRef "@baseboard_fab2_lib.baseboard_fab2(sch_1):page61_i172:DDR4_ECC(1)" )
				( pinRef "@baseboard_fab2_lib.baseboard_fab2(sch_1):page85_i111:CB(0)" )
				( attribute "RELATIVE_PROPAGATION_DELAY_SCOPE" "G"
					( Parent
						( matchGroupRef "@baseboard_fab2_lib.baseboard_fab2(sch_1):\MG_DQ-DQS_FAR_DIMM_NG_M_L_BYTE-ECC\" )
					)
					( Status sCSetFlattened )
					( Origin gBackEnd )
				)
				( attribute "RELATIVE_PROPAGATION_DELAY" "0.00 MIL,195.00 MIL"
					( Parent
						( matchGroupRef "@baseboard_fab2_lib.baseboard_fab2(sch_1):\MG_DQ-DQS_FAR_DIMM_NG_M_L_BYTE-ECC\" )
					)
					( Units "uMatchProp" "ns" 1.000000)
					( Status sCSetFlattened )
					( Origin gBackEnd )
				)
				( attribute "RELATIVE_PROPAGATION_DELAY_SCOPE" "G"
					( Parent
						( matchGroupRef "@crescent_city_bb_fab1_lib.crescent_city_bb_fab1(sch_1):\MG_DQ_FAR_DIMM_NG_M_L_BYTE-ECC\" )
					)
					( Origin gBackEnd )
				)
				( attribute "RELATIVE_PROPAGATION_DELAY" "-82.30 MIL,50.00 MIL"
					( Parent
						( matchGroupRef "@crescent_city_bb_fab1_lib.crescent_city_bb_fab1(sch_1):\MG_DQ_FAR_DIMM_NG_M_L_BYTE-ECC\" )
					)
					( Units "uMatchProp" "ns" 1.000000)
					( Origin gBackEnd )
				)
			)
			( pinPair "@baseboard_fab2_lib.baseboard_fab2(sch_1):\PP2087\"
				( pinRef "@baseboard_fab2_lib.baseboard_fab2(sch_1):page61_i172:DDR4_ECC(1)" )
				( pinRef "@baseboard_fab2_lib.baseboard_fab2(sch_1):page86_i12:CB(1)" )
				( attribute "RELATIVE_PROPAGATION_DELAY_SCOPE" "G"
					( Parent
						( matchGroupRef "@baseboard_fab2_lib.baseboard_fab2(sch_1):\MG_DQ-DQS_NEAR_DIMM_NG_M_L_BYTE-ECC\" )
					)
					( Status sCSetFlattened )
					( Origin gBackEnd )
				)
				( attribute "RELATIVE_PROPAGATION_DELAY" "0.00 MIL,195.00 MIL"
					( Parent
						( matchGroupRef "@baseboard_fab2_lib.baseboard_fab2(sch_1):\MG_DQ-DQS_NEAR_DIMM_NG_M_L_BYTE-ECC\" )
					)
					( Units "uMatchProp" "ns" 1.000000)
					( Status sCSetFlattened )
					( Origin gBackEnd )
				)
				( attribute "RELATIVE_PROPAGATION_DELAY_SCOPE" "G"
					( Parent
						( matchGroupRef "@crescent_city_bb_fab1_lib.crescent_city_bb_fab1(sch_1):\MG_DQ_NEAR_DIMM_NG_M_L_BYTE-ECC\" )
					)
					( Origin gBackEnd )
				)
				( attribute "RELATIVE_PROPAGATION_DELAY" "-82.30 MIL,50.00 MIL"
					( Parent
						( matchGroupRef "@crescent_city_bb_fab1_lib.crescent_city_bb_fab1(sch_1):\MG_DQ_NEAR_DIMM_NG_M_L_BYTE-ECC\" )
					)
					( Units "uMatchProp" "ns" 1.000000)
					( Origin gBackEnd )
				)
			)
			( pinPair "@baseboard_fab2_lib.baseboard_fab2(sch_1):\PP2089\"
				( pinRef "@baseboard_fab2_lib.baseboard_fab2(sch_1):page61_i172:DDR4_ECC(2)" )
				( pinRef "@baseboard_fab2_lib.baseboard_fab2(sch_1):page85_i111:CB(3)" )
				( attribute "RELATIVE_PROPAGATION_DELAY_SCOPE" "G"
					( Parent
						( matchGroupRef "@baseboard_fab2_lib.baseboard_fab2(sch_1):\MG_DQ-DQS_FAR_DIMM_NG_M_L_BYTE-ECC\" )
					)
					( Status sCSetFlattened )
					( Origin gBackEnd )
				)
				( attribute "RELATIVE_PROPAGATION_DELAY" "0.00 MIL,195.00 MIL"
					( Parent
						( matchGroupRef "@baseboard_fab2_lib.baseboard_fab2(sch_1):\MG_DQ-DQS_FAR_DIMM_NG_M_L_BYTE-ECC\" )
					)
					( Units "uMatchProp" "ns" 1.000000)
					( Status sCSetFlattened )
					( Origin gBackEnd )
				)
				( attribute "RELATIVE_PROPAGATION_DELAY_SCOPE" "G"
					( Parent
						( matchGroupRef "@crescent_city_bb_fab1_lib.crescent_city_bb_fab1(sch_1):\MG_DQ_FAR_DIMM_NG_M_L_BYTE-ECC\" )
					)
					( Origin gBackEnd )
				)
				( attribute "RELATIVE_PROPAGATION_DELAY" "-88.70 MIL,50.00 MIL"
					( Parent
						( matchGroupRef "@crescent_city_bb_fab1_lib.crescent_city_bb_fab1(sch_1):\MG_DQ_FAR_DIMM_NG_M_L_BYTE-ECC\" )
					)
					( Units "uMatchProp" "ns" 1.000000)
					( Origin gBackEnd )
				)
			)
			( pinPair "@baseboard_fab2_lib.baseboard_fab2(sch_1):\PP2090\"
				( pinRef "@baseboard_fab2_lib.baseboard_fab2(sch_1):page61_i172:DDR4_ECC(2)" )
				( pinRef "@baseboard_fab2_lib.baseboard_fab2(sch_1):page86_i12:CB(2)" )
				( attribute "RELATIVE_PROPAGATION_DELAY_SCOPE" "G"
					( Parent
						( matchGroupRef "@baseboard_fab2_lib.baseboard_fab2(sch_1):\MG_DQ-DQS_NEAR_DIMM_NG_M_L_BYTE-ECC\" )
					)
					( Status sCSetFlattened )
					( Origin gBackEnd )
				)
				( attribute "RELATIVE_PROPAGATION_DELAY" "0.00 MIL,195.00 MIL"
					( Parent
						( matchGroupRef "@baseboard_fab2_lib.baseboard_fab2(sch_1):\MG_DQ-DQS_NEAR_DIMM_NG_M_L_BYTE-ECC\" )
					)
					( Units "uMatchProp" "ns" 1.000000)
					( Status sCSetFlattened )
					( Origin gBackEnd )
				)
				( attribute "RELATIVE_PROPAGATION_DELAY_SCOPE" "G"
					( Parent
						( matchGroupRef "@crescent_city_bb_fab1_lib.crescent_city_bb_fab1(sch_1):\MG_DQ_NEAR_DIMM_NG_M_L_BYTE-ECC\" )
					)
					( Origin gBackEnd )
				)
				( attribute "RELATIVE_PROPAGATION_DELAY" "-88.70 MIL,50.00 MIL"
					( Parent
						( matchGroupRef "@crescent_city_bb_fab1_lib.crescent_city_bb_fab1(sch_1):\MG_DQ_NEAR_DIMM_NG_M_L_BYTE-ECC\" )
					)
					( Units "uMatchProp" "ns" 1.000000)
					( Origin gBackEnd )
				)
			)
			( pinPair "@baseboard_fab2_lib.baseboard_fab2(sch_1):\PP2092\"
				( pinRef "@baseboard_fab2_lib.baseboard_fab2(sch_1):page61_i172:DDR4_ECC(3)" )
				( pinRef "@baseboard_fab2_lib.baseboard_fab2(sch_1):page85_i111:CB(2)" )
				( attribute "RELATIVE_PROPAGATION_DELAY_SCOPE" "G"
					( Parent
						( matchGroupRef "@baseboard_fab2_lib.baseboard_fab2(sch_1):\MG_DQ-DQS_FAR_DIMM_NG_M_L_BYTE-ECC\" )
					)
					( Status sCSetFlattened )
					( Origin gBackEnd )
				)
				( attribute "RELATIVE_PROPAGATION_DELAY" "0.00 MIL,195.00 MIL"
					( Parent
						( matchGroupRef "@baseboard_fab2_lib.baseboard_fab2(sch_1):\MG_DQ-DQS_FAR_DIMM_NG_M_L_BYTE-ECC\" )
					)
					( Units "uMatchProp" "ns" 1.000000)
					( Status sCSetFlattened )
					( Origin gBackEnd )
				)
				( attribute "RELATIVE_PROPAGATION_DELAY_SCOPE" "G"
					( Parent
						( matchGroupRef "@crescent_city_bb_fab1_lib.crescent_city_bb_fab1(sch_1):\MG_DQ_FAR_DIMM_NG_M_L_BYTE-ECC\" )
					)
					( Origin gBackEnd )
				)
				( attribute "RELATIVE_PROPAGATION_DELAY" "-57.52 MIL,50.00 MIL"
					( Parent
						( matchGroupRef "@crescent_city_bb_fab1_lib.crescent_city_bb_fab1(sch_1):\MG_DQ_FAR_DIMM_NG_M_L_BYTE-ECC\" )
					)
					( Units "uMatchProp" "ns" 1.000000)
					( Origin gBackEnd )
				)
			)
			( pinPair "@baseboard_fab2_lib.baseboard_fab2(sch_1):\PP2093\"
				( pinRef "@baseboard_fab2_lib.baseboard_fab2(sch_1):page61_i172:DDR4_ECC(3)" )
				( pinRef "@baseboard_fab2_lib.baseboard_fab2(sch_1):page86_i12:CB(3)" )
				( attribute "RELATIVE_PROPAGATION_DELAY_SCOPE" "G"
					( Parent
						( matchGroupRef "@baseboard_fab2_lib.baseboard_fab2(sch_1):\MG_DQ-DQS_NEAR_DIMM_NG_M_L_BYTE-ECC\" )
					)
					( Status sCSetFlattened )
					( Origin gBackEnd )
				)
				( attribute "RELATIVE_PROPAGATION_DELAY" "0.00 MIL,195.00 MIL"
					( Parent
						( matchGroupRef "@baseboard_fab2_lib.baseboard_fab2(sch_1):\MG_DQ-DQS_NEAR_DIMM_NG_M_L_BYTE-ECC\" )
					)
					( Units "uMatchProp" "ns" 1.000000)
					( Status sCSetFlattened )
					( Origin gBackEnd )
				)
				( attribute "RELATIVE_PROPAGATION_DELAY_SCOPE" "G"
					( Parent
						( matchGroupRef "@crescent_city_bb_fab1_lib.crescent_city_bb_fab1(sch_1):\MG_DQ_NEAR_DIMM_NG_M_L_BYTE-ECC\" )
					)
					( Origin gBackEnd )
				)
				( attribute "RELATIVE_PROPAGATION_DELAY" "-57.52 MIL,50.00 MIL"
					( Parent
						( matchGroupRef "@crescent_city_bb_fab1_lib.crescent_city_bb_fab1(sch_1):\MG_DQ_NEAR_DIMM_NG_M_L_BYTE-ECC\" )
					)
					( Units "uMatchProp" "ns" 1.000000)
					( Origin gBackEnd )
				)
			)
			( pinPair "@baseboard_fab2_lib.baseboard_fab2(sch_1):\PP2095\"
				( pinRef "@baseboard_fab2_lib.baseboard_fab2(sch_1):page61_i172:DDR4_ECC(4)" )
				( pinRef "@baseboard_fab2_lib.baseboard_fab2(sch_1):page85_i111:CB(5)" )
				( attribute "RELATIVE_PROPAGATION_DELAY_SCOPE" "G"
					( Parent
						( matchGroupRef "@baseboard_fab2_lib.baseboard_fab2(sch_1):\MG_DQ-DQS_FAR_DIMM_NG_M_L_BYTE-ECC\" )
					)
					( Status sCSetFlattened )
					( Origin gBackEnd )
				)
				( attribute "RELATIVE_PROPAGATION_DELAY" "0.00 MIL,195.00 MIL"
					( Parent
						( matchGroupRef "@baseboard_fab2_lib.baseboard_fab2(sch_1):\MG_DQ-DQS_FAR_DIMM_NG_M_L_BYTE-ECC\" )
					)
					( Units "uMatchProp" "ns" 1.000000)
					( Status sCSetFlattened )
					( Origin gBackEnd )
				)
				( attribute "RELATIVE_PROPAGATION_DELAY_SCOPE" "G"
					( Parent
						( matchGroupRef "@crescent_city_bb_fab1_lib.crescent_city_bb_fab1(sch_1):\MG_DQ_FAR_DIMM_NG_M_L_BYTE-ECC\" )
					)
					( Status sCSetFlattened )
					( Origin gBackEnd )
				)
				( attribute "RELATIVE_PROPAGATION_DELAY" "-50.00 MIL,50.00 MIL"
					( Parent
						( matchGroupRef "@crescent_city_bb_fab1_lib.crescent_city_bb_fab1(sch_1):\MG_DQ_FAR_DIMM_NG_M_L_BYTE-ECC\" )
					)
					( Units "uMatchProp" "ns" 1.000000)
					( Status sCSetFlattened )
					( Origin gBackEnd )
				)
			)
			( pinPair "@baseboard_fab2_lib.baseboard_fab2(sch_1):\PP2096\"
				( pinRef "@baseboard_fab2_lib.baseboard_fab2(sch_1):page61_i172:DDR4_ECC(4)" )
				( pinRef "@baseboard_fab2_lib.baseboard_fab2(sch_1):page86_i12:CB(4)" )
				( attribute "RELATIVE_PROPAGATION_DELAY_SCOPE" "G"
					( Parent
						( matchGroupRef "@baseboard_fab2_lib.baseboard_fab2(sch_1):\MG_DQ-DQS_NEAR_DIMM_NG_M_L_BYTE-ECC\" )
					)
					( Status sCSetFlattened )
					( Origin gBackEnd )
				)
				( attribute "RELATIVE_PROPAGATION_DELAY" "0.00 MIL,195.00 MIL"
					( Parent
						( matchGroupRef "@baseboard_fab2_lib.baseboard_fab2(sch_1):\MG_DQ-DQS_NEAR_DIMM_NG_M_L_BYTE-ECC\" )
					)
					( Units "uMatchProp" "ns" 1.000000)
					( Status sCSetFlattened )
					( Origin gBackEnd )
				)
				( attribute "RELATIVE_PROPAGATION_DELAY_SCOPE" "G"
					( Parent
						( matchGroupRef "@crescent_city_bb_fab1_lib.crescent_city_bb_fab1(sch_1):\MG_DQ_NEAR_DIMM_NG_M_L_BYTE-ECC\" )
					)
					( Status sCSetFlattened )
					( Origin gBackEnd )
				)
				( attribute "RELATIVE_PROPAGATION_DELAY" "-50.00 MIL,50.00 MIL"
					( Parent
						( matchGroupRef "@crescent_city_bb_fab1_lib.crescent_city_bb_fab1(sch_1):\MG_DQ_NEAR_DIMM_NG_M_L_BYTE-ECC\" )
					)
					( Units "uMatchProp" "ns" 1.000000)
					( Status sCSetFlattened )
					( Origin gBackEnd )
				)
			)
			( pinPair "@baseboard_fab2_lib.baseboard_fab2(sch_1):\PP2098\"
				( pinRef "@baseboard_fab2_lib.baseboard_fab2(sch_1):page61_i172:DDR4_ECC(5)" )
				( pinRef "@baseboard_fab2_lib.baseboard_fab2(sch_1):page85_i111:CB(4)" )
				( attribute "RELATIVE_PROPAGATION_DELAY_SCOPE" "G"
					( Parent
						( matchGroupRef "@baseboard_fab2_lib.baseboard_fab2(sch_1):\MG_DQ-DQS_FAR_DIMM_NG_M_L_BYTE-ECC\" )
					)
					( Status sCSetFlattened )
					( Origin gBackEnd )
				)
				( attribute "RELATIVE_PROPAGATION_DELAY" "0.00 MIL,195.00 MIL"
					( Parent
						( matchGroupRef "@baseboard_fab2_lib.baseboard_fab2(sch_1):\MG_DQ-DQS_FAR_DIMM_NG_M_L_BYTE-ECC\" )
					)
					( Units "uMatchProp" "ns" 1.000000)
					( Status sCSetFlattened )
					( Origin gBackEnd )
				)
				( attribute "RELATIVE_PROPAGATION_DELAY_SCOPE" "G"
					( Parent
						( matchGroupRef "@crescent_city_bb_fab1_lib.crescent_city_bb_fab1(sch_1):\MG_DQ_FAR_DIMM_NG_M_L_BYTE-ECC\" )
					)
					( Origin gBackEnd )
				)
				( attribute "RELATIVE_PROPAGATION_DELAY" "-75.02 MIL,50.00 MIL"
					( Parent
						( matchGroupRef "@crescent_city_bb_fab1_lib.crescent_city_bb_fab1(sch_1):\MG_DQ_FAR_DIMM_NG_M_L_BYTE-ECC\" )
					)
					( Units "uMatchProp" "ns" 1.000000)
					( Origin gBackEnd )
				)
			)
			( pinPair "@baseboard_fab2_lib.baseboard_fab2(sch_1):\PP2099\"
				( pinRef "@baseboard_fab2_lib.baseboard_fab2(sch_1):page61_i172:DDR4_ECC(5)" )
				( pinRef "@baseboard_fab2_lib.baseboard_fab2(sch_1):page86_i12:CB(5)" )
				( attribute "RELATIVE_PROPAGATION_DELAY_SCOPE" "G"
					( Parent
						( matchGroupRef "@baseboard_fab2_lib.baseboard_fab2(sch_1):\MG_DQ-DQS_NEAR_DIMM_NG_M_L_BYTE-ECC\" )
					)
					( Status sCSetFlattened )
					( Origin gBackEnd )
				)
				( attribute "RELATIVE_PROPAGATION_DELAY" "0.00 MIL,195.00 MIL"
					( Parent
						( matchGroupRef "@baseboard_fab2_lib.baseboard_fab2(sch_1):\MG_DQ-DQS_NEAR_DIMM_NG_M_L_BYTE-ECC\" )
					)
					( Units "uMatchProp" "ns" 1.000000)
					( Status sCSetFlattened )
					( Origin gBackEnd )
				)
				( attribute "RELATIVE_PROPAGATION_DELAY_SCOPE" "G"
					( Parent
						( matchGroupRef "@crescent_city_bb_fab1_lib.crescent_city_bb_fab1(sch_1):\MG_DQ_NEAR_DIMM_NG_M_L_BYTE-ECC\" )
					)
					( Origin gBackEnd )
				)
				( attribute "RELATIVE_PROPAGATION_DELAY" "-75.02 MIL,50.00 MIL"
					( Parent
						( matchGroupRef "@crescent_city_bb_fab1_lib.crescent_city_bb_fab1(sch_1):\MG_DQ_NEAR_DIMM_NG_M_L_BYTE-ECC\" )
					)
					( Units "uMatchProp" "ns" 1.000000)
					( Origin gBackEnd )
				)
			)
			( pinPair "@baseboard_fab2_lib.baseboard_fab2(sch_1):\PP2101\"
				( pinRef "@baseboard_fab2_lib.baseboard_fab2(sch_1):page61_i172:DDR4_ECC(6)" )
				( pinRef "@baseboard_fab2_lib.baseboard_fab2(sch_1):page85_i111:CB(7)" )
				( attribute "RELATIVE_PROPAGATION_DELAY_SCOPE" "G"
					( Parent
						( matchGroupRef "@baseboard_fab2_lib.baseboard_fab2(sch_1):\MG_DQ-DQS_FAR_DIMM_NG_M_L_BYTE-ECC\" )
					)
					( Status sCSetFlattened )
					( Origin gBackEnd )
				)
				( attribute "RELATIVE_PROPAGATION_DELAY" "0.00 MIL,195.00 MIL"
					( Parent
						( matchGroupRef "@baseboard_fab2_lib.baseboard_fab2(sch_1):\MG_DQ-DQS_FAR_DIMM_NG_M_L_BYTE-ECC\" )
					)
					( Units "uMatchProp" "ns" 1.000000)
					( Status sCSetFlattened )
					( Origin gBackEnd )
				)
				( attribute "RELATIVE_PROPAGATION_DELAY_SCOPE" "G"
					( Parent
						( matchGroupRef "@crescent_city_bb_fab1_lib.crescent_city_bb_fab1(sch_1):\MG_DQ_FAR_DIMM_NG_M_L_BYTE-ECC\" )
					)
					( Origin gBackEnd )
				)
				( attribute "RELATIVE_PROPAGATION_DELAY" "-84.73 MIL,50.00 MIL"
					( Parent
						( matchGroupRef "@crescent_city_bb_fab1_lib.crescent_city_bb_fab1(sch_1):\MG_DQ_FAR_DIMM_NG_M_L_BYTE-ECC\" )
					)
					( Units "uMatchProp" "ns" 1.000000)
					( Origin gBackEnd )
				)
			)
			( pinPair "@baseboard_fab2_lib.baseboard_fab2(sch_1):\PP2102\"
				( pinRef "@baseboard_fab2_lib.baseboard_fab2(sch_1):page61_i172:DDR4_ECC(6)" )
				( pinRef "@baseboard_fab2_lib.baseboard_fab2(sch_1):page86_i12:CB(6)" )
				( attribute "RELATIVE_PROPAGATION_DELAY_SCOPE" "G"
					( Parent
						( matchGroupRef "@baseboard_fab2_lib.baseboard_fab2(sch_1):\MG_DQ-DQS_NEAR_DIMM_NG_M_L_BYTE-ECC\" )
					)
					( Status sCSetFlattened )
					( Origin gBackEnd )
				)
				( attribute "RELATIVE_PROPAGATION_DELAY" "0.00 MIL,195.00 MIL"
					( Parent
						( matchGroupRef "@baseboard_fab2_lib.baseboard_fab2(sch_1):\MG_DQ-DQS_NEAR_DIMM_NG_M_L_BYTE-ECC\" )
					)
					( Units "uMatchProp" "ns" 1.000000)
					( Status sCSetFlattened )
					( Origin gBackEnd )
				)
				( attribute "RELATIVE_PROPAGATION_DELAY_SCOPE" "G"
					( Parent
						( matchGroupRef "@crescent_city_bb_fab1_lib.crescent_city_bb_fab1(sch_1):\MG_DQ_NEAR_DIMM_NG_M_L_BYTE-ECC\" )
					)
					( Origin gBackEnd )
				)
				( attribute "RELATIVE_PROPAGATION_DELAY" "-84.73 MIL,50.00 MIL"
					( Parent
						( matchGroupRef "@crescent_city_bb_fab1_lib.crescent_city_bb_fab1(sch_1):\MG_DQ_NEAR_DIMM_NG_M_L_BYTE-ECC\" )
					)
					( Units "uMatchProp" "ns" 1.000000)
					( Origin gBackEnd )
				)
			)
			( pinPair "@baseboard_fab2_lib.baseboard_fab2(sch_1):\PP2104\"
				( pinRef "@baseboard_fab2_lib.baseboard_fab2(sch_1):page61_i172:DDR4_ECC(7)" )
				( pinRef "@baseboard_fab2_lib.baseboard_fab2(sch_1):page85_i111:CB(6)" )
				( attribute "RELATIVE_PROPAGATION_DELAY_SCOPE" "G"
					( Parent
						( matchGroupRef "@baseboard_fab2_lib.baseboard_fab2(sch_1):\MG_DQ-DQS_FAR_DIMM_NG_M_L_BYTE-ECC\" )
					)
					( Status sCSetFlattened )
					( Origin gBackEnd )
				)
				( attribute "RELATIVE_PROPAGATION_DELAY" "0.00 MIL,195.00 MIL"
					( Parent
						( matchGroupRef "@baseboard_fab2_lib.baseboard_fab2(sch_1):\MG_DQ-DQS_FAR_DIMM_NG_M_L_BYTE-ECC\" )
					)
					( Units "uMatchProp" "ns" 1.000000)
					( Status sCSetFlattened )
					( Origin gBackEnd )
				)
				( attribute "RELATIVE_PROPAGATION_DELAY_SCOPE" "G"
					( Parent
						( matchGroupRef "@crescent_city_bb_fab1_lib.crescent_city_bb_fab1(sch_1):\MG_DQ_FAR_DIMM_NG_M_L_BYTE-ECC\" )
					)
					( Origin gBackEnd )
				)
				( attribute "RELATIVE_PROPAGATION_DELAY" "-88.37 MIL,50.00 MIL"
					( Parent
						( matchGroupRef "@crescent_city_bb_fab1_lib.crescent_city_bb_fab1(sch_1):\MG_DQ_FAR_DIMM_NG_M_L_BYTE-ECC\" )
					)
					( Units "uMatchProp" "ns" 1.000000)
					( Origin gBackEnd )
				)
			)
			( pinPair "@baseboard_fab2_lib.baseboard_fab2(sch_1):\PP2105\"
				( pinRef "@baseboard_fab2_lib.baseboard_fab2(sch_1):page61_i172:DDR4_ECC(7)" )
				( pinRef "@baseboard_fab2_lib.baseboard_fab2(sch_1):page86_i12:CB(7)" )
				( attribute "RELATIVE_PROPAGATION_DELAY_SCOPE" "G"
					( Parent
						( matchGroupRef "@baseboard_fab2_lib.baseboard_fab2(sch_1):\MG_DQ-DQS_NEAR_DIMM_NG_M_L_BYTE-ECC\" )
					)
					( Status sCSetFlattened )
					( Origin gBackEnd )
				)
				( attribute "RELATIVE_PROPAGATION_DELAY" "0.00 MIL,195.00 MIL"
					( Parent
						( matchGroupRef "@baseboard_fab2_lib.baseboard_fab2(sch_1):\MG_DQ-DQS_NEAR_DIMM_NG_M_L_BYTE-ECC\" )
					)
					( Units "uMatchProp" "ns" 1.000000)
					( Status sCSetFlattened )
					( Origin gBackEnd )
				)
				( attribute "RELATIVE_PROPAGATION_DELAY_SCOPE" "G"
					( Parent
						( matchGroupRef "@crescent_city_bb_fab1_lib.crescent_city_bb_fab1(sch_1):\MG_DQ_NEAR_DIMM_NG_M_L_BYTE-ECC\" )
					)
					( Origin gBackEnd )
				)
				( attribute "RELATIVE_PROPAGATION_DELAY" "-88.37 MIL,50.00 MIL"
					( Parent
						( matchGroupRef "@crescent_city_bb_fab1_lib.crescent_city_bb_fab1(sch_1):\MG_DQ_NEAR_DIMM_NG_M_L_BYTE-ECC\" )
					)
					( Units "uMatchProp" "ns" 1.000000)
					( Origin gBackEnd )
				)
			)
			( pinPair "@baseboard_fab2_lib.baseboard_fab2(sch_1):\PP1867\"
				( pinRef "@baseboard_fab2_lib.baseboard_fab2(sch_1):page62_i172:DDR5_ECC(0)" )
				( pinRef "@baseboard_fab2_lib.baseboard_fab2(sch_1):page87_i186:CB(1)" )
				( attribute "RELATIVE_PROPAGATION_DELAY_SCOPE" "G"
					( Parent
						( matchGroupRef "@baseboard_fab2_lib.baseboard_fab2(sch_1):\MG_DQ-DQS_FAR_DIMM_NG_M_M_BYTE-ECC\" )
					)
					( Status sCSetFlattened )
					( Origin gBackEnd )
				)
				( attribute "RELATIVE_PROPAGATION_DELAY" "0.00 MIL,195.00 MIL"
					( Parent
						( matchGroupRef "@baseboard_fab2_lib.baseboard_fab2(sch_1):\MG_DQ-DQS_FAR_DIMM_NG_M_M_BYTE-ECC\" )
					)
					( Units "uMatchProp" "ns" 1.000000)
					( Status sCSetFlattened )
					( Origin gBackEnd )
				)
				( attribute "RELATIVE_PROPAGATION_DELAY_SCOPE" "G"
					( Parent
						( matchGroupRef "@baseboard_fab2_lib.baseboard_fab2(sch_1):\MG_DQ_FAR_DIMM_NG_M_M_BYTE-ECC\" )
					)
					( Status sCSetFlattened )
					( Origin gBackEnd )
				)
				( attribute "RELATIVE_PROPAGATION_DELAY" "-50.00 MIL,50.00 MIL"
					( Parent
						( matchGroupRef "@baseboard_fab2_lib.baseboard_fab2(sch_1):\MG_DQ_FAR_DIMM_NG_M_M_BYTE-ECC\" )
					)
					( Units "uMatchProp" "ns" 1.000000)
					( Status sCSetFlattened )
					( Origin gBackEnd )
				)
			)
			( pinPair "@baseboard_fab2_lib.baseboard_fab2(sch_1):\PP1868\"
				( pinRef "@baseboard_fab2_lib.baseboard_fab2(sch_1):page62_i172:DDR5_ECC(0)" )
				( pinRef "@baseboard_fab2_lib.baseboard_fab2(sch_1):page88_i111:CB(0)" )
				( attribute "RELATIVE_PROPAGATION_DELAY_SCOPE" "G"
					( Parent
						( matchGroupRef "@baseboard_fab2_lib.baseboard_fab2(sch_1):\MG_DQ-DQS_NEAR_DIMM_NG_M_M_BYTE-ECC\" )
					)
					( Status sCSetFlattened )
					( Origin gBackEnd )
				)
				( attribute "RELATIVE_PROPAGATION_DELAY" "0.00 MIL,195.00 MIL"
					( Parent
						( matchGroupRef "@baseboard_fab2_lib.baseboard_fab2(sch_1):\MG_DQ-DQS_NEAR_DIMM_NG_M_M_BYTE-ECC\" )
					)
					( Units "uMatchProp" "ns" 1.000000)
					( Status sCSetFlattened )
					( Origin gBackEnd )
				)
				( attribute "RELATIVE_PROPAGATION_DELAY_SCOPE" "G"
					( Parent
						( matchGroupRef "@crescent_city_bb_fab1_lib.crescent_city_bb_fab1(sch_1):\MG_DQ_NEAR_DIMM_NG_M_M_BYTE-ECC\" )
					)
					( Status sCSetFlattened )
					( Origin gBackEnd )
				)
				( attribute "RELATIVE_PROPAGATION_DELAY" "-50.00 MIL,50.00 MIL"
					( Parent
						( matchGroupRef "@crescent_city_bb_fab1_lib.crescent_city_bb_fab1(sch_1):\MG_DQ_NEAR_DIMM_NG_M_M_BYTE-ECC\" )
					)
					( Units "uMatchProp" "ns" 1.000000)
					( Status sCSetFlattened )
					( Origin gBackEnd )
				)
			)
			( pinPair "@baseboard_fab2_lib.baseboard_fab2(sch_1):\PP1870\"
				( pinRef "@baseboard_fab2_lib.baseboard_fab2(sch_1):page62_i172:DDR5_ECC(1)" )
				( pinRef "@baseboard_fab2_lib.baseboard_fab2(sch_1):page87_i186:CB(0)" )
				( attribute "RELATIVE_PROPAGATION_DELAY_SCOPE" "G"
					( Parent
						( matchGroupRef "@baseboard_fab2_lib.baseboard_fab2(sch_1):\MG_DQ-DQS_FAR_DIMM_NG_M_M_BYTE-ECC\" )
					)
					( Status sCSetFlattened )
					( Origin gBackEnd )
				)
				( attribute "RELATIVE_PROPAGATION_DELAY" "0.00 MIL,195.00 MIL"
					( Parent
						( matchGroupRef "@baseboard_fab2_lib.baseboard_fab2(sch_1):\MG_DQ-DQS_FAR_DIMM_NG_M_M_BYTE-ECC\" )
					)
					( Units "uMatchProp" "ns" 1.000000)
					( Status sCSetFlattened )
					( Origin gBackEnd )
				)
				( attribute "RELATIVE_PROPAGATION_DELAY_SCOPE" "G"
					( Parent
						( matchGroupRef "@baseboard_fab2_lib.baseboard_fab2(sch_1):\MG_DQ_FAR_DIMM_NG_M_M_BYTE-ECC\" )
					)
					( Status sCSetFlattened )
					( Origin gBackEnd )
				)
				( attribute "RELATIVE_PROPAGATION_DELAY" "-50.00 MIL,50.00 MIL"
					( Parent
						( matchGroupRef "@baseboard_fab2_lib.baseboard_fab2(sch_1):\MG_DQ_FAR_DIMM_NG_M_M_BYTE-ECC\" )
					)
					( Units "uMatchProp" "ns" 1.000000)
					( Status sCSetFlattened )
					( Origin gBackEnd )
				)
			)
			( pinPair "@baseboard_fab2_lib.baseboard_fab2(sch_1):\PP1871\"
				( pinRef "@baseboard_fab2_lib.baseboard_fab2(sch_1):page62_i172:DDR5_ECC(1)" )
				( pinRef "@baseboard_fab2_lib.baseboard_fab2(sch_1):page88_i111:CB(1)" )
				( attribute "RELATIVE_PROPAGATION_DELAY_SCOPE" "G"
					( Parent
						( matchGroupRef "@baseboard_fab2_lib.baseboard_fab2(sch_1):\MG_DQ-DQS_NEAR_DIMM_NG_M_M_BYTE-ECC\" )
					)
					( Status sCSetFlattened )
					( Origin gBackEnd )
				)
				( attribute "RELATIVE_PROPAGATION_DELAY" "0.00 MIL,195.00 MIL"
					( Parent
						( matchGroupRef "@baseboard_fab2_lib.baseboard_fab2(sch_1):\MG_DQ-DQS_NEAR_DIMM_NG_M_M_BYTE-ECC\" )
					)
					( Units "uMatchProp" "ns" 1.000000)
					( Status sCSetFlattened )
					( Origin gBackEnd )
				)
				( attribute "RELATIVE_PROPAGATION_DELAY_SCOPE" "G"
					( Parent
						( matchGroupRef "@crescent_city_bb_fab1_lib.crescent_city_bb_fab1(sch_1):\MG_DQ_NEAR_DIMM_NG_M_M_BYTE-ECC\" )
					)
					( Status sCSetFlattened )
					( Origin gBackEnd )
				)
				( attribute "RELATIVE_PROPAGATION_DELAY" "-50.00 MIL,50.00 MIL"
					( Parent
						( matchGroupRef "@crescent_city_bb_fab1_lib.crescent_city_bb_fab1(sch_1):\MG_DQ_NEAR_DIMM_NG_M_M_BYTE-ECC\" )
					)
					( Units "uMatchProp" "ns" 1.000000)
					( Status sCSetFlattened )
					( Origin gBackEnd )
				)
			)
			( pinPair "@baseboard_fab2_lib.baseboard_fab2(sch_1):\PP1873\"
				( pinRef "@baseboard_fab2_lib.baseboard_fab2(sch_1):page62_i172:DDR5_ECC(2)" )
				( pinRef "@baseboard_fab2_lib.baseboard_fab2(sch_1):page87_i186:CB(3)" )
				( attribute "RELATIVE_PROPAGATION_DELAY_SCOPE" "G"
					( Parent
						( matchGroupRef "@baseboard_fab2_lib.baseboard_fab2(sch_1):\MG_DQ-DQS_FAR_DIMM_NG_M_M_BYTE-ECC\" )
					)
					( Status sCSetFlattened )
					( Origin gBackEnd )
				)
				( attribute "RELATIVE_PROPAGATION_DELAY" "0.00 MIL,195.00 MIL"
					( Parent
						( matchGroupRef "@baseboard_fab2_lib.baseboard_fab2(sch_1):\MG_DQ-DQS_FAR_DIMM_NG_M_M_BYTE-ECC\" )
					)
					( Units "uMatchProp" "ns" 1.000000)
					( Status sCSetFlattened )
					( Origin gBackEnd )
				)
				( attribute "RELATIVE_PROPAGATION_DELAY_SCOPE" "G"
					( Parent
						( matchGroupRef "@baseboard_fab2_lib.baseboard_fab2(sch_1):\MG_DQ_FAR_DIMM_NG_M_M_BYTE-ECC\" )
					)
					( Status sCSetFlattened )
					( Origin gBackEnd )
				)
				( attribute "RELATIVE_PROPAGATION_DELAY" "-50.00 MIL,50.00 MIL"
					( Parent
						( matchGroupRef "@baseboard_fab2_lib.baseboard_fab2(sch_1):\MG_DQ_FAR_DIMM_NG_M_M_BYTE-ECC\" )
					)
					( Units "uMatchProp" "ns" 1.000000)
					( Status sCSetFlattened )
					( Origin gBackEnd )
				)
			)
			( pinPair "@baseboard_fab2_lib.baseboard_fab2(sch_1):\PP1874\"
				( pinRef "@baseboard_fab2_lib.baseboard_fab2(sch_1):page62_i172:DDR5_ECC(2)" )
				( pinRef "@baseboard_fab2_lib.baseboard_fab2(sch_1):page88_i111:CB(2)" )
				( attribute "RELATIVE_PROPAGATION_DELAY_SCOPE" "G"
					( Parent
						( matchGroupRef "@baseboard_fab2_lib.baseboard_fab2(sch_1):\MG_DQ-DQS_NEAR_DIMM_NG_M_M_BYTE-ECC\" )
					)
					( Status sCSetFlattened )
					( Origin gBackEnd )
				)
				( attribute "RELATIVE_PROPAGATION_DELAY" "0.00 MIL,195.00 MIL"
					( Parent
						( matchGroupRef "@baseboard_fab2_lib.baseboard_fab2(sch_1):\MG_DQ-DQS_NEAR_DIMM_NG_M_M_BYTE-ECC\" )
					)
					( Units "uMatchProp" "ns" 1.000000)
					( Status sCSetFlattened )
					( Origin gBackEnd )
				)
				( attribute "RELATIVE_PROPAGATION_DELAY_SCOPE" "G"
					( Parent
						( matchGroupRef "@crescent_city_bb_fab1_lib.crescent_city_bb_fab1(sch_1):\MG_DQ_NEAR_DIMM_NG_M_M_BYTE-ECC\" )
					)
					( Status sCSetFlattened )
					( Origin gBackEnd )
				)
				( attribute "RELATIVE_PROPAGATION_DELAY" "-50.00 MIL,50.00 MIL"
					( Parent
						( matchGroupRef "@crescent_city_bb_fab1_lib.crescent_city_bb_fab1(sch_1):\MG_DQ_NEAR_DIMM_NG_M_M_BYTE-ECC\" )
					)
					( Units "uMatchProp" "ns" 1.000000)
					( Status sCSetFlattened )
					( Origin gBackEnd )
				)
			)
			( pinPair "@baseboard_fab2_lib.baseboard_fab2(sch_1):\PP1876\"
				( pinRef "@baseboard_fab2_lib.baseboard_fab2(sch_1):page62_i172:DDR5_ECC(3)" )
				( pinRef "@baseboard_fab2_lib.baseboard_fab2(sch_1):page87_i186:CB(2)" )
				( attribute "RELATIVE_PROPAGATION_DELAY_SCOPE" "G"
					( Parent
						( matchGroupRef "@baseboard_fab2_lib.baseboard_fab2(sch_1):\MG_DQ-DQS_FAR_DIMM_NG_M_M_BYTE-ECC\" )
					)
					( Status sCSetFlattened )
					( Origin gBackEnd )
				)
				( attribute "RELATIVE_PROPAGATION_DELAY" "0.00 MIL,195.00 MIL"
					( Parent
						( matchGroupRef "@baseboard_fab2_lib.baseboard_fab2(sch_1):\MG_DQ-DQS_FAR_DIMM_NG_M_M_BYTE-ECC\" )
					)
					( Units "uMatchProp" "ns" 1.000000)
					( Status sCSetFlattened )
					( Origin gBackEnd )
				)
				( attribute "RELATIVE_PROPAGATION_DELAY_SCOPE" "G"
					( Parent
						( matchGroupRef "@baseboard_fab2_lib.baseboard_fab2(sch_1):\MG_DQ_FAR_DIMM_NG_M_M_BYTE-ECC\" )
					)
					( Status sCSetFlattened )
					( Origin gBackEnd )
				)
				( attribute "RELATIVE_PROPAGATION_DELAY" "-50.00 MIL,50.00 MIL"
					( Parent
						( matchGroupRef "@baseboard_fab2_lib.baseboard_fab2(sch_1):\MG_DQ_FAR_DIMM_NG_M_M_BYTE-ECC\" )
					)
					( Units "uMatchProp" "ns" 1.000000)
					( Status sCSetFlattened )
					( Origin gBackEnd )
				)
			)
			( pinPair "@baseboard_fab2_lib.baseboard_fab2(sch_1):\PP1877\"
				( pinRef "@baseboard_fab2_lib.baseboard_fab2(sch_1):page62_i172:DDR5_ECC(3)" )
				( pinRef "@baseboard_fab2_lib.baseboard_fab2(sch_1):page88_i111:CB(3)" )
				( attribute "RELATIVE_PROPAGATION_DELAY_SCOPE" "G"
					( Parent
						( matchGroupRef "@baseboard_fab2_lib.baseboard_fab2(sch_1):\MG_DQ-DQS_NEAR_DIMM_NG_M_M_BYTE-ECC\" )
					)
					( Status sCSetFlattened )
					( Origin gBackEnd )
				)
				( attribute "RELATIVE_PROPAGATION_DELAY" "0.00 MIL,195.00 MIL"
					( Parent
						( matchGroupRef "@baseboard_fab2_lib.baseboard_fab2(sch_1):\MG_DQ-DQS_NEAR_DIMM_NG_M_M_BYTE-ECC\" )
					)
					( Units "uMatchProp" "ns" 1.000000)
					( Status sCSetFlattened )
					( Origin gBackEnd )
				)
				( attribute "RELATIVE_PROPAGATION_DELAY_SCOPE" "G"
					( Parent
						( matchGroupRef "@crescent_city_bb_fab1_lib.crescent_city_bb_fab1(sch_1):\MG_DQ_NEAR_DIMM_NG_M_M_BYTE-ECC\" )
					)
					( Status sCSetFlattened )
					( Origin gBackEnd )
				)
				( attribute "RELATIVE_PROPAGATION_DELAY" "-50.00 MIL,50.00 MIL"
					( Parent
						( matchGroupRef "@crescent_city_bb_fab1_lib.crescent_city_bb_fab1(sch_1):\MG_DQ_NEAR_DIMM_NG_M_M_BYTE-ECC\" )
					)
					( Units "uMatchProp" "ns" 1.000000)
					( Status sCSetFlattened )
					( Origin gBackEnd )
				)
			)
			( pinPair "@baseboard_fab2_lib.baseboard_fab2(sch_1):\PP1879\"
				( pinRef "@baseboard_fab2_lib.baseboard_fab2(sch_1):page62_i172:DDR5_ECC(4)" )
				( pinRef "@baseboard_fab2_lib.baseboard_fab2(sch_1):page87_i186:CB(5)" )
				( attribute "RELATIVE_PROPAGATION_DELAY_SCOPE" "G"
					( Parent
						( matchGroupRef "@baseboard_fab2_lib.baseboard_fab2(sch_1):\MG_DQ-DQS_FAR_DIMM_NG_M_M_BYTE-ECC\" )
					)
					( Status sCSetFlattened )
					( Origin gBackEnd )
				)
				( attribute "RELATIVE_PROPAGATION_DELAY" "0.00 MIL,195.00 MIL"
					( Parent
						( matchGroupRef "@baseboard_fab2_lib.baseboard_fab2(sch_1):\MG_DQ-DQS_FAR_DIMM_NG_M_M_BYTE-ECC\" )
					)
					( Units "uMatchProp" "ns" 1.000000)
					( Status sCSetFlattened )
					( Origin gBackEnd )
				)
				( attribute "RELATIVE_PROPAGATION_DELAY_SCOPE" "G"
					( Parent
						( matchGroupRef "@baseboard_fab2_lib.baseboard_fab2(sch_1):\MG_DQ_FAR_DIMM_NG_M_M_BYTE-ECC\" )
					)
					( Status sCSetFlattened )
					( Origin gBackEnd )
				)
				( attribute "RELATIVE_PROPAGATION_DELAY" "-50.00 MIL,50.00 MIL"
					( Parent
						( matchGroupRef "@baseboard_fab2_lib.baseboard_fab2(sch_1):\MG_DQ_FAR_DIMM_NG_M_M_BYTE-ECC\" )
					)
					( Units "uMatchProp" "ns" 1.000000)
					( Status sCSetFlattened )
					( Origin gBackEnd )
				)
			)
			( pinPair "@baseboard_fab2_lib.baseboard_fab2(sch_1):\PP1880\"
				( pinRef "@baseboard_fab2_lib.baseboard_fab2(sch_1):page62_i172:DDR5_ECC(4)" )
				( pinRef "@baseboard_fab2_lib.baseboard_fab2(sch_1):page88_i111:CB(4)" )
				( attribute "RELATIVE_PROPAGATION_DELAY_SCOPE" "G"
					( Parent
						( matchGroupRef "@baseboard_fab2_lib.baseboard_fab2(sch_1):\MG_DQ-DQS_NEAR_DIMM_NG_M_M_BYTE-ECC\" )
					)
					( Status sCSetFlattened )
					( Origin gBackEnd )
				)
				( attribute "RELATIVE_PROPAGATION_DELAY" "0.00 MIL,195.00 MIL"
					( Parent
						( matchGroupRef "@baseboard_fab2_lib.baseboard_fab2(sch_1):\MG_DQ-DQS_NEAR_DIMM_NG_M_M_BYTE-ECC\" )
					)
					( Units "uMatchProp" "ns" 1.000000)
					( Status sCSetFlattened )
					( Origin gBackEnd )
				)
				( attribute "RELATIVE_PROPAGATION_DELAY_SCOPE" "G"
					( Parent
						( matchGroupRef "@crescent_city_bb_fab1_lib.crescent_city_bb_fab1(sch_1):\MG_DQ_NEAR_DIMM_NG_M_M_BYTE-ECC\" )
					)
					( Status sCSetFlattened )
					( Origin gBackEnd )
				)
				( attribute "RELATIVE_PROPAGATION_DELAY" "-50.00 MIL,50.00 MIL"
					( Parent
						( matchGroupRef "@crescent_city_bb_fab1_lib.crescent_city_bb_fab1(sch_1):\MG_DQ_NEAR_DIMM_NG_M_M_BYTE-ECC\" )
					)
					( Units "uMatchProp" "ns" 1.000000)
					( Status sCSetFlattened )
					( Origin gBackEnd )
				)
			)
			( pinPair "@baseboard_fab2_lib.baseboard_fab2(sch_1):\PP1882\"
				( pinRef "@baseboard_fab2_lib.baseboard_fab2(sch_1):page62_i172:DDR5_ECC(5)" )
				( pinRef "@baseboard_fab2_lib.baseboard_fab2(sch_1):page87_i186:CB(4)" )
				( attribute "RELATIVE_PROPAGATION_DELAY_SCOPE" "G"
					( Parent
						( matchGroupRef "@baseboard_fab2_lib.baseboard_fab2(sch_1):\MG_DQ-DQS_FAR_DIMM_NG_M_M_BYTE-ECC\" )
					)
					( Status sCSetFlattened )
					( Origin gBackEnd )
				)
				( attribute "RELATIVE_PROPAGATION_DELAY" "0.00 MIL,195.00 MIL"
					( Parent
						( matchGroupRef "@baseboard_fab2_lib.baseboard_fab2(sch_1):\MG_DQ-DQS_FAR_DIMM_NG_M_M_BYTE-ECC\" )
					)
					( Units "uMatchProp" "ns" 1.000000)
					( Status sCSetFlattened )
					( Origin gBackEnd )
				)
				( attribute "RELATIVE_PROPAGATION_DELAY_SCOPE" "G"
					( Parent
						( matchGroupRef "@baseboard_fab2_lib.baseboard_fab2(sch_1):\MG_DQ_FAR_DIMM_NG_M_M_BYTE-ECC\" )
					)
					( Status sCSetFlattened )
					( Origin gBackEnd )
				)
				( attribute "RELATIVE_PROPAGATION_DELAY" "-50.00 MIL,50.00 MIL"
					( Parent
						( matchGroupRef "@baseboard_fab2_lib.baseboard_fab2(sch_1):\MG_DQ_FAR_DIMM_NG_M_M_BYTE-ECC\" )
					)
					( Units "uMatchProp" "ns" 1.000000)
					( Status sCSetFlattened )
					( Origin gBackEnd )
				)
			)
			( pinPair "@baseboard_fab2_lib.baseboard_fab2(sch_1):\PP1883\"
				( pinRef "@baseboard_fab2_lib.baseboard_fab2(sch_1):page62_i172:DDR5_ECC(5)" )
				( pinRef "@baseboard_fab2_lib.baseboard_fab2(sch_1):page88_i111:CB(5)" )
				( attribute "RELATIVE_PROPAGATION_DELAY_SCOPE" "G"
					( Parent
						( matchGroupRef "@baseboard_fab2_lib.baseboard_fab2(sch_1):\MG_DQ-DQS_NEAR_DIMM_NG_M_M_BYTE-ECC\" )
					)
					( Status sCSetFlattened )
					( Origin gBackEnd )
				)
				( attribute "RELATIVE_PROPAGATION_DELAY" "0.00 MIL,195.00 MIL"
					( Parent
						( matchGroupRef "@baseboard_fab2_lib.baseboard_fab2(sch_1):\MG_DQ-DQS_NEAR_DIMM_NG_M_M_BYTE-ECC\" )
					)
					( Units "uMatchProp" "ns" 1.000000)
					( Status sCSetFlattened )
					( Origin gBackEnd )
				)
				( attribute "RELATIVE_PROPAGATION_DELAY_SCOPE" "G"
					( Parent
						( matchGroupRef "@crescent_city_bb_fab1_lib.crescent_city_bb_fab1(sch_1):\MG_DQ_NEAR_DIMM_NG_M_M_BYTE-ECC\" )
					)
					( Status sCSetFlattened )
					( Origin gBackEnd )
				)
				( attribute "RELATIVE_PROPAGATION_DELAY" "-50.00 MIL,50.00 MIL"
					( Parent
						( matchGroupRef "@crescent_city_bb_fab1_lib.crescent_city_bb_fab1(sch_1):\MG_DQ_NEAR_DIMM_NG_M_M_BYTE-ECC\" )
					)
					( Units "uMatchProp" "ns" 1.000000)
					( Status sCSetFlattened )
					( Origin gBackEnd )
				)
			)
			( pinPair "@baseboard_fab2_lib.baseboard_fab2(sch_1):\PP1885\"
				( pinRef "@baseboard_fab2_lib.baseboard_fab2(sch_1):page62_i172:DDR5_ECC(6)" )
				( pinRef "@baseboard_fab2_lib.baseboard_fab2(sch_1):page87_i186:CB(7)" )
				( attribute "RELATIVE_PROPAGATION_DELAY_SCOPE" "G"
					( Parent
						( matchGroupRef "@baseboard_fab2_lib.baseboard_fab2(sch_1):\MG_DQ-DQS_FAR_DIMM_NG_M_M_BYTE-ECC\" )
					)
					( Status sCSetFlattened )
					( Origin gBackEnd )
				)
				( attribute "RELATIVE_PROPAGATION_DELAY" "0.00 MIL,195.00 MIL"
					( Parent
						( matchGroupRef "@baseboard_fab2_lib.baseboard_fab2(sch_1):\MG_DQ-DQS_FAR_DIMM_NG_M_M_BYTE-ECC\" )
					)
					( Units "uMatchProp" "ns" 1.000000)
					( Status sCSetFlattened )
					( Origin gBackEnd )
				)
				( attribute "RELATIVE_PROPAGATION_DELAY_SCOPE" "G"
					( Parent
						( matchGroupRef "@baseboard_fab2_lib.baseboard_fab2(sch_1):\MG_DQ_FAR_DIMM_NG_M_M_BYTE-ECC\" )
					)
					( Status sCSetFlattened )
					( Origin gBackEnd )
				)
				( attribute "RELATIVE_PROPAGATION_DELAY" "-50.00 MIL,50.00 MIL"
					( Parent
						( matchGroupRef "@baseboard_fab2_lib.baseboard_fab2(sch_1):\MG_DQ_FAR_DIMM_NG_M_M_BYTE-ECC\" )
					)
					( Units "uMatchProp" "ns" 1.000000)
					( Status sCSetFlattened )
					( Origin gBackEnd )
				)
			)
			( pinPair "@baseboard_fab2_lib.baseboard_fab2(sch_1):\PP1886\"
				( pinRef "@baseboard_fab2_lib.baseboard_fab2(sch_1):page62_i172:DDR5_ECC(6)" )
				( pinRef "@baseboard_fab2_lib.baseboard_fab2(sch_1):page88_i111:CB(6)" )
				( attribute "RELATIVE_PROPAGATION_DELAY_SCOPE" "G"
					( Parent
						( matchGroupRef "@baseboard_fab2_lib.baseboard_fab2(sch_1):\MG_DQ-DQS_NEAR_DIMM_NG_M_M_BYTE-ECC\" )
					)
					( Status sCSetFlattened )
					( Origin gBackEnd )
				)
				( attribute "RELATIVE_PROPAGATION_DELAY" "0.00 MIL,195.00 MIL"
					( Parent
						( matchGroupRef "@baseboard_fab2_lib.baseboard_fab2(sch_1):\MG_DQ-DQS_NEAR_DIMM_NG_M_M_BYTE-ECC\" )
					)
					( Units "uMatchProp" "ns" 1.000000)
					( Status sCSetFlattened )
					( Origin gBackEnd )
				)
				( attribute "RELATIVE_PROPAGATION_DELAY_SCOPE" "G"
					( Parent
						( matchGroupRef "@crescent_city_bb_fab1_lib.crescent_city_bb_fab1(sch_1):\MG_DQ_NEAR_DIMM_NG_M_M_BYTE-ECC\" )
					)
					( Status sCSetFlattened )
					( Origin gBackEnd )
				)
				( attribute "RELATIVE_PROPAGATION_DELAY" "-50.00 MIL,50.00 MIL"
					( Parent
						( matchGroupRef "@crescent_city_bb_fab1_lib.crescent_city_bb_fab1(sch_1):\MG_DQ_NEAR_DIMM_NG_M_M_BYTE-ECC\" )
					)
					( Units "uMatchProp" "ns" 1.000000)
					( Status sCSetFlattened )
					( Origin gBackEnd )
				)
			)
			( pinPair "@baseboard_fab2_lib.baseboard_fab2(sch_1):\PP1888\"
				( pinRef "@baseboard_fab2_lib.baseboard_fab2(sch_1):page62_i172:DDR5_ECC(7)" )
				( pinRef "@baseboard_fab2_lib.baseboard_fab2(sch_1):page87_i186:CB(6)" )
				( attribute "RELATIVE_PROPAGATION_DELAY_SCOPE" "G"
					( Parent
						( matchGroupRef "@baseboard_fab2_lib.baseboard_fab2(sch_1):\MG_DQ-DQS_FAR_DIMM_NG_M_M_BYTE-ECC\" )
					)
					( Status sCSetFlattened )
					( Origin gBackEnd )
				)
				( attribute "RELATIVE_PROPAGATION_DELAY" "0.00 MIL,195.00 MIL"
					( Parent
						( matchGroupRef "@baseboard_fab2_lib.baseboard_fab2(sch_1):\MG_DQ-DQS_FAR_DIMM_NG_M_M_BYTE-ECC\" )
					)
					( Units "uMatchProp" "ns" 1.000000)
					( Status sCSetFlattened )
					( Origin gBackEnd )
				)
				( attribute "RELATIVE_PROPAGATION_DELAY_SCOPE" "G"
					( Parent
						( matchGroupRef "@baseboard_fab2_lib.baseboard_fab2(sch_1):\MG_DQ_FAR_DIMM_NG_M_M_BYTE-ECC\" )
					)
					( Status sCSetFlattened )
					( Origin gBackEnd )
				)
				( attribute "RELATIVE_PROPAGATION_DELAY" "-50.00 MIL,50.00 MIL"
					( Parent
						( matchGroupRef "@baseboard_fab2_lib.baseboard_fab2(sch_1):\MG_DQ_FAR_DIMM_NG_M_M_BYTE-ECC\" )
					)
					( Units "uMatchProp" "ns" 1.000000)
					( Status sCSetFlattened )
					( Origin gBackEnd )
				)
			)
			( pinPair "@baseboard_fab2_lib.baseboard_fab2(sch_1):\PP1889\"
				( pinRef "@baseboard_fab2_lib.baseboard_fab2(sch_1):page62_i172:DDR5_ECC(7)" )
				( pinRef "@baseboard_fab2_lib.baseboard_fab2(sch_1):page88_i111:CB(7)" )
				( attribute "RELATIVE_PROPAGATION_DELAY_SCOPE" "G"
					( Parent
						( matchGroupRef "@baseboard_fab2_lib.baseboard_fab2(sch_1):\MG_DQ-DQS_NEAR_DIMM_NG_M_M_BYTE-ECC\" )
					)
					( Status sCSetFlattened )
					( Origin gBackEnd )
				)
				( attribute "RELATIVE_PROPAGATION_DELAY" "0.00 MIL,195.00 MIL"
					( Parent
						( matchGroupRef "@baseboard_fab2_lib.baseboard_fab2(sch_1):\MG_DQ-DQS_NEAR_DIMM_NG_M_M_BYTE-ECC\" )
					)
					( Units "uMatchProp" "ns" 1.000000)
					( Status sCSetFlattened )
					( Origin gBackEnd )
				)
				( attribute "RELATIVE_PROPAGATION_DELAY_SCOPE" "G"
					( Parent
						( matchGroupRef "@crescent_city_bb_fab1_lib.crescent_city_bb_fab1(sch_1):\MG_DQ_NEAR_DIMM_NG_M_M_BYTE-ECC\" )
					)
					( Origin gBackEnd )
				)
				( attribute "RELATIVE_PROPAGATION_DELAY" "TARGET,TARGET"
					( Parent
						( matchGroupRef "@crescent_city_bb_fab1_lib.crescent_city_bb_fab1(sch_1):\MG_DQ_NEAR_DIMM_NG_M_M_BYTE-ECC\" )
					)
					( Units "uMatchProp" "ns" 1.000000)
					( Origin gBackEnd )
				)
			)
			( pinPair "@baseboard_fab2_lib.baseboard_fab2(sch_1):\PP4230\"
				( pinRef "@baseboard_fab2_lib.baseboard_fab2(sch_1):page28_i172:DDR5_DQ(9)" )
				( pinRef "@baseboard_fab2_lib.baseboard_fab2(sch_1):page53_i111:DQ(8)" )
				( attribute "RELATIVE_PROPAGATION_DELAY_SCOPE" "G"
					( Parent
						( matchGroupRef "@baseboard_fab2_lib.baseboard_fab2(sch_1):\MG_DQ-DQS_FAR_DIMM_NG_M_F_BYTE1\" )
					)
					( Status sCSetFlattened )
					( Origin gBackEnd )
				)
				( attribute "RELATIVE_PROPAGATION_DELAY" "0.00 MIL,195.00 MIL"
					( Parent
						( matchGroupRef "@baseboard_fab2_lib.baseboard_fab2(sch_1):\MG_DQ-DQS_FAR_DIMM_NG_M_F_BYTE1\" )
					)
					( Units "uMatchProp" "ns" 1.000000)
					( Status sCSetFlattened )
					( Origin gBackEnd )
				)
				( attribute "RELATIVE_PROPAGATION_DELAY_SCOPE" "G"
					( Parent
						( matchGroupRef "@crescent_city_bb_fab1_lib.crescent_city_bb_fab1(sch_1):\MG_DQ_FAR_DIMM_NG_M_F_BYTE1\" )
					)
					( Status sCSetFlattened )
					( Origin gBackEnd )
				)
				( attribute "RELATIVE_PROPAGATION_DELAY" "-50.00 MIL,50.00 MIL"
					( Parent
						( matchGroupRef "@crescent_city_bb_fab1_lib.crescent_city_bb_fab1(sch_1):\MG_DQ_FAR_DIMM_NG_M_F_BYTE1\" )
					)
					( Units "uMatchProp" "ns" 1.000000)
					( Status sCSetFlattened )
					( Origin gBackEnd )
				)
			)
			( pinPair "@baseboard_fab2_lib.baseboard_fab2(sch_1):\PP4232\"
				( pinRef "@baseboard_fab2_lib.baseboard_fab2(sch_1):page54_i111:DQ(9)" )
				( pinRef "@baseboard_fab2_lib.baseboard_fab2(sch_1):page28_i172:DDR5_DQ(9)" )
				( attribute "RELATIVE_PROPAGATION_DELAY_SCOPE" "G"
					( Parent
						( matchGroupRef "@baseboard_fab2_lib.baseboard_fab2(sch_1):\MG_DQ-DQS_NEAR_DIMM_NG_M_F_BYTE1\" )
					)
					( Status sCSetFlattened )
					( Origin gBackEnd )
				)
				( attribute "RELATIVE_PROPAGATION_DELAY" "0.00 MIL,195.00 MIL"
					( Parent
						( matchGroupRef "@baseboard_fab2_lib.baseboard_fab2(sch_1):\MG_DQ-DQS_NEAR_DIMM_NG_M_F_BYTE1\" )
					)
					( Units "uMatchProp" "ns" 1.000000)
					( Status sCSetFlattened )
					( Origin gBackEnd )
				)
				( attribute "RELATIVE_PROPAGATION_DELAY_SCOPE" "G"
					( Parent
						( matchGroupRef "@baseboard_fab2_lib.baseboard_fab2(sch_1):\MG_DQ_NEAR_DIMM_NG_M_F_BYTE1\" )
					)
					( Status sCSetFlattened )
					( Origin gBackEnd )
				)
				( attribute "RELATIVE_PROPAGATION_DELAY" "-50.00 MIL,50.00 MIL"
					( Parent
						( matchGroupRef "@baseboard_fab2_lib.baseboard_fab2(sch_1):\MG_DQ_NEAR_DIMM_NG_M_F_BYTE1\" )
					)
					( Units "uMatchProp" "ns" 1.000000)
					( Status sCSetFlattened )
					( Origin gBackEnd )
				)
			)
			( pinPair "@baseboard_fab2_lib.baseboard_fab2(sch_1):\PP4233\"
				( pinRef "@baseboard_fab2_lib.baseboard_fab2(sch_1):page28_i172:DDR5_DQ(10)" )
				( pinRef "@baseboard_fab2_lib.baseboard_fab2(sch_1):page53_i111:DQ(11)" )
				( attribute "RELATIVE_PROPAGATION_DELAY_SCOPE" "G"
					( Parent
						( matchGroupRef "@baseboard_fab2_lib.baseboard_fab2(sch_1):\MG_DQ-DQS_FAR_DIMM_NG_M_F_BYTE1\" )
					)
					( Status sCSetFlattened )
					( Origin gBackEnd )
				)
				( attribute "RELATIVE_PROPAGATION_DELAY" "0.00 MIL,195.00 MIL"
					( Parent
						( matchGroupRef "@baseboard_fab2_lib.baseboard_fab2(sch_1):\MG_DQ-DQS_FAR_DIMM_NG_M_F_BYTE1\" )
					)
					( Units "uMatchProp" "ns" 1.000000)
					( Status sCSetFlattened )
					( Origin gBackEnd )
				)
				( attribute "RELATIVE_PROPAGATION_DELAY_SCOPE" "G"
					( Parent
						( matchGroupRef "@crescent_city_bb_fab1_lib.crescent_city_bb_fab1(sch_1):\MG_DQ_FAR_DIMM_NG_M_F_BYTE1\" )
					)
					( Status sCSetFlattened )
					( Origin gBackEnd )
				)
				( attribute "RELATIVE_PROPAGATION_DELAY" "-50.00 MIL,50.00 MIL"
					( Parent
						( matchGroupRef "@crescent_city_bb_fab1_lib.crescent_city_bb_fab1(sch_1):\MG_DQ_FAR_DIMM_NG_M_F_BYTE1\" )
					)
					( Units "uMatchProp" "ns" 1.000000)
					( Status sCSetFlattened )
					( Origin gBackEnd )
				)
			)
			( pinPair "@baseboard_fab2_lib.baseboard_fab2(sch_1):\PP4235\"
				( pinRef "@baseboard_fab2_lib.baseboard_fab2(sch_1):page54_i111:DQ(10)" )
				( pinRef "@baseboard_fab2_lib.baseboard_fab2(sch_1):page28_i172:DDR5_DQ(10)" )
				( attribute "RELATIVE_PROPAGATION_DELAY_SCOPE" "G"
					( Parent
						( matchGroupRef "@baseboard_fab2_lib.baseboard_fab2(sch_1):\MG_DQ-DQS_NEAR_DIMM_NG_M_F_BYTE1\" )
					)
					( Status sCSetFlattened )
					( Origin gBackEnd )
				)
				( attribute "RELATIVE_PROPAGATION_DELAY" "0.00 MIL,195.00 MIL"
					( Parent
						( matchGroupRef "@baseboard_fab2_lib.baseboard_fab2(sch_1):\MG_DQ-DQS_NEAR_DIMM_NG_M_F_BYTE1\" )
					)
					( Units "uMatchProp" "ns" 1.000000)
					( Status sCSetFlattened )
					( Origin gBackEnd )
				)
				( attribute "RELATIVE_PROPAGATION_DELAY_SCOPE" "G"
					( Parent
						( matchGroupRef "@baseboard_fab2_lib.baseboard_fab2(sch_1):\MG_DQ_NEAR_DIMM_NG_M_F_BYTE1\" )
					)
					( Status sCSetFlattened )
					( Origin gBackEnd )
				)
				( attribute "RELATIVE_PROPAGATION_DELAY" "-50.00 MIL,50.00 MIL"
					( Parent
						( matchGroupRef "@baseboard_fab2_lib.baseboard_fab2(sch_1):\MG_DQ_NEAR_DIMM_NG_M_F_BYTE1\" )
					)
					( Units "uMatchProp" "ns" 1.000000)
					( Status sCSetFlattened )
					( Origin gBackEnd )
				)
			)
			( pinPair "@baseboard_fab2_lib.baseboard_fab2(sch_1):\PP4236\"
				( pinRef "@baseboard_fab2_lib.baseboard_fab2(sch_1):page28_i172:DDR5_DQ(11)" )
				( pinRef "@baseboard_fab2_lib.baseboard_fab2(sch_1):page53_i111:DQ(10)" )
				( attribute "RELATIVE_PROPAGATION_DELAY_SCOPE" "G"
					( Parent
						( matchGroupRef "@baseboard_fab2_lib.baseboard_fab2(sch_1):\MG_DQ-DQS_FAR_DIMM_NG_M_F_BYTE1\" )
					)
					( Status sCSetFlattened )
					( Origin gBackEnd )
				)
				( attribute "RELATIVE_PROPAGATION_DELAY" "0.00 MIL,195.00 MIL"
					( Parent
						( matchGroupRef "@baseboard_fab2_lib.baseboard_fab2(sch_1):\MG_DQ-DQS_FAR_DIMM_NG_M_F_BYTE1\" )
					)
					( Units "uMatchProp" "ns" 1.000000)
					( Status sCSetFlattened )
					( Origin gBackEnd )
				)
				( attribute "RELATIVE_PROPAGATION_DELAY_SCOPE" "G"
					( Parent
						( matchGroupRef "@crescent_city_bb_fab1_lib.crescent_city_bb_fab1(sch_1):\MG_DQ_FAR_DIMM_NG_M_F_BYTE1\" )
					)
					( Status sCSetFlattened )
					( Origin gBackEnd )
				)
				( attribute "RELATIVE_PROPAGATION_DELAY" "-50.00 MIL,50.00 MIL"
					( Parent
						( matchGroupRef "@crescent_city_bb_fab1_lib.crescent_city_bb_fab1(sch_1):\MG_DQ_FAR_DIMM_NG_M_F_BYTE1\" )
					)
					( Units "uMatchProp" "ns" 1.000000)
					( Status sCSetFlattened )
					( Origin gBackEnd )
				)
			)
			( pinPair "@baseboard_fab2_lib.baseboard_fab2(sch_1):\PP4238\"
				( pinRef "@baseboard_fab2_lib.baseboard_fab2(sch_1):page54_i111:DQ(11)" )
				( pinRef "@baseboard_fab2_lib.baseboard_fab2(sch_1):page28_i172:DDR5_DQ(11)" )
				( attribute "RELATIVE_PROPAGATION_DELAY_SCOPE" "G"
					( Parent
						( matchGroupRef "@baseboard_fab2_lib.baseboard_fab2(sch_1):\MG_DQ-DQS_NEAR_DIMM_NG_M_F_BYTE1\" )
					)
					( Status sCSetFlattened )
					( Origin gBackEnd )
				)
				( attribute "RELATIVE_PROPAGATION_DELAY" "0.00 MIL,195.00 MIL"
					( Parent
						( matchGroupRef "@baseboard_fab2_lib.baseboard_fab2(sch_1):\MG_DQ-DQS_NEAR_DIMM_NG_M_F_BYTE1\" )
					)
					( Units "uMatchProp" "ns" 1.000000)
					( Status sCSetFlattened )
					( Origin gBackEnd )
				)
				( attribute "RELATIVE_PROPAGATION_DELAY_SCOPE" "G"
					( Parent
						( matchGroupRef "@baseboard_fab2_lib.baseboard_fab2(sch_1):\MG_DQ_NEAR_DIMM_NG_M_F_BYTE1\" )
					)
					( Status sCSetFlattened )
					( Origin gBackEnd )
				)
				( attribute "RELATIVE_PROPAGATION_DELAY" "-50.00 MIL,50.00 MIL"
					( Parent
						( matchGroupRef "@baseboard_fab2_lib.baseboard_fab2(sch_1):\MG_DQ_NEAR_DIMM_NG_M_F_BYTE1\" )
					)
					( Units "uMatchProp" "ns" 1.000000)
					( Status sCSetFlattened )
					( Origin gBackEnd )
				)
			)
			( pinPair "@baseboard_fab2_lib.baseboard_fab2(sch_1):\PP4239\"
				( pinRef "@baseboard_fab2_lib.baseboard_fab2(sch_1):page28_i172:DDR5_DQ(12)" )
				( pinRef "@baseboard_fab2_lib.baseboard_fab2(sch_1):page53_i111:DQ(13)" )
				( attribute "RELATIVE_PROPAGATION_DELAY_SCOPE" "G"
					( Parent
						( matchGroupRef "@baseboard_fab2_lib.baseboard_fab2(sch_1):\MG_DQ-DQS_FAR_DIMM_NG_M_F_BYTE1\" )
					)
					( Status sCSetFlattened )
					( Origin gBackEnd )
				)
				( attribute "RELATIVE_PROPAGATION_DELAY" "0.00 MIL,195.00 MIL"
					( Parent
						( matchGroupRef "@baseboard_fab2_lib.baseboard_fab2(sch_1):\MG_DQ-DQS_FAR_DIMM_NG_M_F_BYTE1\" )
					)
					( Units "uMatchProp" "ns" 1.000000)
					( Status sCSetFlattened )
					( Origin gBackEnd )
				)
				( attribute "RELATIVE_PROPAGATION_DELAY_SCOPE" "G"
					( Parent
						( matchGroupRef "@crescent_city_bb_fab1_lib.crescent_city_bb_fab1(sch_1):\MG_DQ_FAR_DIMM_NG_M_F_BYTE1\" )
					)
					( Origin gBackEnd )
				)
				( attribute "RELATIVE_PROPAGATION_DELAY" "TARGET,TARGET"
					( Parent
						( matchGroupRef "@crescent_city_bb_fab1_lib.crescent_city_bb_fab1(sch_1):\MG_DQ_FAR_DIMM_NG_M_F_BYTE1\" )
					)
					( Units "uMatchProp" "ns" 1.000000)
					( Origin gBackEnd )
				)
			)
			( pinPair "@baseboard_fab2_lib.baseboard_fab2(sch_1):\PP4241\"
				( pinRef "@baseboard_fab2_lib.baseboard_fab2(sch_1):page54_i111:DQ(12)" )
				( pinRef "@baseboard_fab2_lib.baseboard_fab2(sch_1):page28_i172:DDR5_DQ(12)" )
				( attribute "RELATIVE_PROPAGATION_DELAY_SCOPE" "G"
					( Parent
						( matchGroupRef "@baseboard_fab2_lib.baseboard_fab2(sch_1):\MG_DQ-DQS_NEAR_DIMM_NG_M_F_BYTE1\" )
					)
					( Status sCSetFlattened )
					( Origin gBackEnd )
				)
				( attribute "RELATIVE_PROPAGATION_DELAY" "0.00 MIL,195.00 MIL"
					( Parent
						( matchGroupRef "@baseboard_fab2_lib.baseboard_fab2(sch_1):\MG_DQ-DQS_NEAR_DIMM_NG_M_F_BYTE1\" )
					)
					( Units "uMatchProp" "ns" 1.000000)
					( Status sCSetFlattened )
					( Origin gBackEnd )
				)
				( attribute "RELATIVE_PROPAGATION_DELAY_SCOPE" "G"
					( Parent
						( matchGroupRef "@baseboard_fab2_lib.baseboard_fab2(sch_1):\MG_DQ_NEAR_DIMM_NG_M_F_BYTE1\" )
					)
					( Status sCSetFlattened )
					( Origin gBackEnd )
				)
				( attribute "RELATIVE_PROPAGATION_DELAY" "-50.00 MIL,50.00 MIL"
					( Parent
						( matchGroupRef "@baseboard_fab2_lib.baseboard_fab2(sch_1):\MG_DQ_NEAR_DIMM_NG_M_F_BYTE1\" )
					)
					( Units "uMatchProp" "ns" 1.000000)
					( Status sCSetFlattened )
					( Origin gBackEnd )
				)
			)
			( pinPair "@baseboard_fab2_lib.baseboard_fab2(sch_1):\PP4242\"
				( pinRef "@baseboard_fab2_lib.baseboard_fab2(sch_1):page28_i172:DDR5_DQ(13)" )
				( pinRef "@baseboard_fab2_lib.baseboard_fab2(sch_1):page53_i111:DQ(12)" )
				( attribute "RELATIVE_PROPAGATION_DELAY_SCOPE" "G"
					( Parent
						( matchGroupRef "@baseboard_fab2_lib.baseboard_fab2(sch_1):\MG_DQ-DQS_FAR_DIMM_NG_M_F_BYTE1\" )
					)
					( Status sCSetFlattened )
					( Origin gBackEnd )
				)
				( attribute "RELATIVE_PROPAGATION_DELAY" "0.00 MIL,195.00 MIL"
					( Parent
						( matchGroupRef "@baseboard_fab2_lib.baseboard_fab2(sch_1):\MG_DQ-DQS_FAR_DIMM_NG_M_F_BYTE1\" )
					)
					( Units "uMatchProp" "ns" 1.000000)
					( Status sCSetFlattened )
					( Origin gBackEnd )
				)
				( attribute "RELATIVE_PROPAGATION_DELAY_SCOPE" "G"
					( Parent
						( matchGroupRef "@crescent_city_bb_fab1_lib.crescent_city_bb_fab1(sch_1):\MG_DQ_FAR_DIMM_NG_M_F_BYTE1\" )
					)
					( Status sCSetFlattened )
					( Origin gBackEnd )
				)
				( attribute "RELATIVE_PROPAGATION_DELAY" "-50.00 MIL,50.00 MIL"
					( Parent
						( matchGroupRef "@crescent_city_bb_fab1_lib.crescent_city_bb_fab1(sch_1):\MG_DQ_FAR_DIMM_NG_M_F_BYTE1\" )
					)
					( Units "uMatchProp" "ns" 1.000000)
					( Status sCSetFlattened )
					( Origin gBackEnd )
				)
			)
			( pinPair "@baseboard_fab2_lib.baseboard_fab2(sch_1):\PP4244\"
				( pinRef "@baseboard_fab2_lib.baseboard_fab2(sch_1):page54_i111:DQ(13)" )
				( pinRef "@baseboard_fab2_lib.baseboard_fab2(sch_1):page28_i172:DDR5_DQ(13)" )
				( attribute "RELATIVE_PROPAGATION_DELAY_SCOPE" "G"
					( Parent
						( matchGroupRef "@baseboard_fab2_lib.baseboard_fab2(sch_1):\MG_DQ-DQS_NEAR_DIMM_NG_M_F_BYTE1\" )
					)
					( Status sCSetFlattened )
					( Origin gBackEnd )
				)
				( attribute "RELATIVE_PROPAGATION_DELAY" "0.00 MIL,195.00 MIL"
					( Parent
						( matchGroupRef "@baseboard_fab2_lib.baseboard_fab2(sch_1):\MG_DQ-DQS_NEAR_DIMM_NG_M_F_BYTE1\" )
					)
					( Units "uMatchProp" "ns" 1.000000)
					( Status sCSetFlattened )
					( Origin gBackEnd )
				)
				( attribute "RELATIVE_PROPAGATION_DELAY_SCOPE" "G"
					( Parent
						( matchGroupRef "@baseboard_fab2_lib.baseboard_fab2(sch_1):\MG_DQ_NEAR_DIMM_NG_M_F_BYTE1\" )
					)
					( Status sCSetFlattened )
					( Origin gBackEnd )
				)
				( attribute "RELATIVE_PROPAGATION_DELAY" "-50.00 MIL,50.00 MIL"
					( Parent
						( matchGroupRef "@baseboard_fab2_lib.baseboard_fab2(sch_1):\MG_DQ_NEAR_DIMM_NG_M_F_BYTE1\" )
					)
					( Units "uMatchProp" "ns" 1.000000)
					( Status sCSetFlattened )
					( Origin gBackEnd )
				)
			)
			( pinPair "@baseboard_fab2_lib.baseboard_fab2(sch_1):\PP4245\"
				( pinRef "@baseboard_fab2_lib.baseboard_fab2(sch_1):page28_i172:DDR5_DQ(14)" )
				( pinRef "@baseboard_fab2_lib.baseboard_fab2(sch_1):page53_i111:DQ(15)" )
				( attribute "RELATIVE_PROPAGATION_DELAY_SCOPE" "G"
					( Parent
						( matchGroupRef "@baseboard_fab2_lib.baseboard_fab2(sch_1):\MG_DQ-DQS_FAR_DIMM_NG_M_F_BYTE1\" )
					)
					( Status sCSetFlattened )
					( Origin gBackEnd )
				)
				( attribute "RELATIVE_PROPAGATION_DELAY" "0.00 MIL,195.00 MIL"
					( Parent
						( matchGroupRef "@baseboard_fab2_lib.baseboard_fab2(sch_1):\MG_DQ-DQS_FAR_DIMM_NG_M_F_BYTE1\" )
					)
					( Units "uMatchProp" "ns" 1.000000)
					( Status sCSetFlattened )
					( Origin gBackEnd )
				)
				( attribute "RELATIVE_PROPAGATION_DELAY_SCOPE" "G"
					( Parent
						( matchGroupRef "@crescent_city_bb_fab1_lib.crescent_city_bb_fab1(sch_1):\MG_DQ_FAR_DIMM_NG_M_F_BYTE1\" )
					)
					( Status sCSetFlattened )
					( Origin gBackEnd )
				)
				( attribute "RELATIVE_PROPAGATION_DELAY" "-50.00 MIL,50.00 MIL"
					( Parent
						( matchGroupRef "@crescent_city_bb_fab1_lib.crescent_city_bb_fab1(sch_1):\MG_DQ_FAR_DIMM_NG_M_F_BYTE1\" )
					)
					( Units "uMatchProp" "ns" 1.000000)
					( Status sCSetFlattened )
					( Origin gBackEnd )
				)
			)
			( pinPair "@baseboard_fab2_lib.baseboard_fab2(sch_1):\PP4247\"
				( pinRef "@baseboard_fab2_lib.baseboard_fab2(sch_1):page54_i111:DQ(14)" )
				( pinRef "@baseboard_fab2_lib.baseboard_fab2(sch_1):page28_i172:DDR5_DQ(14)" )
				( attribute "RELATIVE_PROPAGATION_DELAY_SCOPE" "G"
					( Parent
						( matchGroupRef "@baseboard_fab2_lib.baseboard_fab2(sch_1):\MG_DQ-DQS_NEAR_DIMM_NG_M_F_BYTE1\" )
					)
					( Status sCSetFlattened )
					( Origin gBackEnd )
				)
				( attribute "RELATIVE_PROPAGATION_DELAY" "0.00 MIL,195.00 MIL"
					( Parent
						( matchGroupRef "@baseboard_fab2_lib.baseboard_fab2(sch_1):\MG_DQ-DQS_NEAR_DIMM_NG_M_F_BYTE1\" )
					)
					( Units "uMatchProp" "ns" 1.000000)
					( Status sCSetFlattened )
					( Origin gBackEnd )
				)
				( attribute "RELATIVE_PROPAGATION_DELAY_SCOPE" "G"
					( Parent
						( matchGroupRef "@baseboard_fab2_lib.baseboard_fab2(sch_1):\MG_DQ_NEAR_DIMM_NG_M_F_BYTE1\" )
					)
					( Status sCSetFlattened )
					( Origin gBackEnd )
				)
				( attribute "RELATIVE_PROPAGATION_DELAY" "-50.00 MIL,50.00 MIL"
					( Parent
						( matchGroupRef "@baseboard_fab2_lib.baseboard_fab2(sch_1):\MG_DQ_NEAR_DIMM_NG_M_F_BYTE1\" )
					)
					( Units "uMatchProp" "ns" 1.000000)
					( Status sCSetFlattened )
					( Origin gBackEnd )
				)
			)
			( pinPair "@baseboard_fab2_lib.baseboard_fab2(sch_1):\PP4248\"
				( pinRef "@baseboard_fab2_lib.baseboard_fab2(sch_1):page28_i172:DDR5_DQ(15)" )
				( pinRef "@baseboard_fab2_lib.baseboard_fab2(sch_1):page53_i111:DQ(14)" )
				( attribute "RELATIVE_PROPAGATION_DELAY_SCOPE" "G"
					( Parent
						( matchGroupRef "@baseboard_fab2_lib.baseboard_fab2(sch_1):\MG_DQ-DQS_FAR_DIMM_NG_M_F_BYTE1\" )
					)
					( Status sCSetFlattened )
					( Origin gBackEnd )
				)
				( attribute "RELATIVE_PROPAGATION_DELAY" "0.00 MIL,195.00 MIL"
					( Parent
						( matchGroupRef "@baseboard_fab2_lib.baseboard_fab2(sch_1):\MG_DQ-DQS_FAR_DIMM_NG_M_F_BYTE1\" )
					)
					( Units "uMatchProp" "ns" 1.000000)
					( Status sCSetFlattened )
					( Origin gBackEnd )
				)
				( attribute "RELATIVE_PROPAGATION_DELAY_SCOPE" "G"
					( Parent
						( matchGroupRef "@crescent_city_bb_fab1_lib.crescent_city_bb_fab1(sch_1):\MG_DQ_FAR_DIMM_NG_M_F_BYTE1\" )
					)
					( Status sCSetFlattened )
					( Origin gBackEnd )
				)
				( attribute "RELATIVE_PROPAGATION_DELAY" "-50.00 MIL,50.00 MIL"
					( Parent
						( matchGroupRef "@crescent_city_bb_fab1_lib.crescent_city_bb_fab1(sch_1):\MG_DQ_FAR_DIMM_NG_M_F_BYTE1\" )
					)
					( Units "uMatchProp" "ns" 1.000000)
					( Status sCSetFlattened )
					( Origin gBackEnd )
				)
			)
			( pinPair "@baseboard_fab2_lib.baseboard_fab2(sch_1):\PP4250\"
				( pinRef "@baseboard_fab2_lib.baseboard_fab2(sch_1):page54_i111:DQ(15)" )
				( pinRef "@baseboard_fab2_lib.baseboard_fab2(sch_1):page28_i172:DDR5_DQ(15)" )
				( attribute "RELATIVE_PROPAGATION_DELAY_SCOPE" "G"
					( Parent
						( matchGroupRef "@baseboard_fab2_lib.baseboard_fab2(sch_1):\MG_DQ-DQS_NEAR_DIMM_NG_M_F_BYTE1\" )
					)
					( Status sCSetFlattened )
					( Origin gBackEnd )
				)
				( attribute "RELATIVE_PROPAGATION_DELAY" "0.00 MIL,195.00 MIL"
					( Parent
						( matchGroupRef "@baseboard_fab2_lib.baseboard_fab2(sch_1):\MG_DQ-DQS_NEAR_DIMM_NG_M_F_BYTE1\" )
					)
					( Units "uMatchProp" "ns" 1.000000)
					( Status sCSetFlattened )
					( Origin gBackEnd )
				)
				( attribute "RELATIVE_PROPAGATION_DELAY_SCOPE" "G"
					( Parent
						( matchGroupRef "@baseboard_fab2_lib.baseboard_fab2(sch_1):\MG_DQ_NEAR_DIMM_NG_M_F_BYTE1\" )
					)
					( Status sCSetFlattened )
					( Origin gBackEnd )
				)
				( attribute "RELATIVE_PROPAGATION_DELAY" "-50.00 MIL,50.00 MIL"
					( Parent
						( matchGroupRef "@baseboard_fab2_lib.baseboard_fab2(sch_1):\MG_DQ_NEAR_DIMM_NG_M_F_BYTE1\" )
					)
					( Units "uMatchProp" "ns" 1.000000)
					( Status sCSetFlattened )
					( Origin gBackEnd )
				)
			)
			( pinPair "@baseboard_fab2_lib.baseboard_fab2(sch_1):\PP4203\"
				( pinRef "@baseboard_fab2_lib.baseboard_fab2(sch_1):page28_i172:DDR5_DQ(16)" )
				( pinRef "@baseboard_fab2_lib.baseboard_fab2(sch_1):page53_i111:DQ(17)" )
				( attribute "RELATIVE_PROPAGATION_DELAY_SCOPE" "G"
					( Parent
						( matchGroupRef "@baseboard_fab2_lib.baseboard_fab2(sch_1):\MG_DQ-DQS_FAR_DIMM_NG_M_F_BYTE2\" )
					)
					( Status sCSetFlattened )
					( Origin gBackEnd )
				)
				( attribute "RELATIVE_PROPAGATION_DELAY" "0.00 MIL,195.00 MIL"
					( Parent
						( matchGroupRef "@baseboard_fab2_lib.baseboard_fab2(sch_1):\MG_DQ-DQS_FAR_DIMM_NG_M_F_BYTE2\" )
					)
					( Units "uMatchProp" "ns" 1.000000)
					( Status sCSetFlattened )
					( Origin gBackEnd )
				)
				( attribute "RELATIVE_PROPAGATION_DELAY_SCOPE" "G"
					( Parent
						( matchGroupRef "@crescent_city_bb_fab1_lib.crescent_city_bb_fab1(sch_1):\MG_DQ_FAR_DIMM_NG_M_F_BYTE2\" )
					)
					( Status sCSetFlattened )
					( Origin gBackEnd )
				)
				( attribute "RELATIVE_PROPAGATION_DELAY" "-50.00 MIL,50.00 MIL"
					( Parent
						( matchGroupRef "@crescent_city_bb_fab1_lib.crescent_city_bb_fab1(sch_1):\MG_DQ_FAR_DIMM_NG_M_F_BYTE2\" )
					)
					( Units "uMatchProp" "ns" 1.000000)
					( Status sCSetFlattened )
					( Origin gBackEnd )
				)
			)
			( pinPair "@baseboard_fab2_lib.baseboard_fab2(sch_1):\PP4205\"
				( pinRef "@baseboard_fab2_lib.baseboard_fab2(sch_1):page54_i111:DQ(16)" )
				( pinRef "@baseboard_fab2_lib.baseboard_fab2(sch_1):page28_i172:DDR5_DQ(16)" )
				( attribute "RELATIVE_PROPAGATION_DELAY_SCOPE" "G"
					( Parent
						( matchGroupRef "@baseboard_fab2_lib.baseboard_fab2(sch_1):\MG_DQ-DQS_NEAR_DIMM_NG_M_F_BYTE2\" )
					)
					( Status sCSetFlattened )
					( Origin gBackEnd )
				)
				( attribute "RELATIVE_PROPAGATION_DELAY" "0.00 MIL,195.00 MIL"
					( Parent
						( matchGroupRef "@baseboard_fab2_lib.baseboard_fab2(sch_1):\MG_DQ-DQS_NEAR_DIMM_NG_M_F_BYTE2\" )
					)
					( Units "uMatchProp" "ns" 1.000000)
					( Status sCSetFlattened )
					( Origin gBackEnd )
				)
				( attribute "RELATIVE_PROPAGATION_DELAY_SCOPE" "G"
					( Parent
						( matchGroupRef "@baseboard_fab2_lib.baseboard_fab2(sch_1):\MG_DQ_NEAR_DIMM_NG_M_F_BYTE2\" )
					)
					( Status sCSetFlattened )
					( Origin gBackEnd )
				)
				( attribute "RELATIVE_PROPAGATION_DELAY" "-50.00 MIL,50.00 MIL"
					( Parent
						( matchGroupRef "@baseboard_fab2_lib.baseboard_fab2(sch_1):\MG_DQ_NEAR_DIMM_NG_M_F_BYTE2\" )
					)
					( Units "uMatchProp" "ns" 1.000000)
					( Status sCSetFlattened )
					( Origin gBackEnd )
				)
			)
			( pinPair "@baseboard_fab2_lib.baseboard_fab2(sch_1):\PP4206\"
				( pinRef "@baseboard_fab2_lib.baseboard_fab2(sch_1):page28_i172:DDR5_DQ(17)" )
				( pinRef "@baseboard_fab2_lib.baseboard_fab2(sch_1):page53_i111:DQ(16)" )
				( attribute "RELATIVE_PROPAGATION_DELAY_SCOPE" "G"
					( Parent
						( matchGroupRef "@baseboard_fab2_lib.baseboard_fab2(sch_1):\MG_DQ-DQS_FAR_DIMM_NG_M_F_BYTE2\" )
					)
					( Status sCSetFlattened )
					( Origin gBackEnd )
				)
				( attribute "RELATIVE_PROPAGATION_DELAY" "0.00 MIL,195.00 MIL"
					( Parent
						( matchGroupRef "@baseboard_fab2_lib.baseboard_fab2(sch_1):\MG_DQ-DQS_FAR_DIMM_NG_M_F_BYTE2\" )
					)
					( Units "uMatchProp" "ns" 1.000000)
					( Status sCSetFlattened )
					( Origin gBackEnd )
				)
				( attribute "RELATIVE_PROPAGATION_DELAY_SCOPE" "G"
					( Parent
						( matchGroupRef "@crescent_city_bb_fab1_lib.crescent_city_bb_fab1(sch_1):\MG_DQ_FAR_DIMM_NG_M_F_BYTE2\" )
					)
					( Status sCSetFlattened )
					( Origin gBackEnd )
				)
				( attribute "RELATIVE_PROPAGATION_DELAY" "-50.00 MIL,50.00 MIL"
					( Parent
						( matchGroupRef "@crescent_city_bb_fab1_lib.crescent_city_bb_fab1(sch_1):\MG_DQ_FAR_DIMM_NG_M_F_BYTE2\" )
					)
					( Units "uMatchProp" "ns" 1.000000)
					( Status sCSetFlattened )
					( Origin gBackEnd )
				)
			)
			( pinPair "@baseboard_fab2_lib.baseboard_fab2(sch_1):\PP4208\"
				( pinRef "@baseboard_fab2_lib.baseboard_fab2(sch_1):page54_i111:DQ(17)" )
				( pinRef "@baseboard_fab2_lib.baseboard_fab2(sch_1):page28_i172:DDR5_DQ(17)" )
				( attribute "RELATIVE_PROPAGATION_DELAY_SCOPE" "G"
					( Parent
						( matchGroupRef "@baseboard_fab2_lib.baseboard_fab2(sch_1):\MG_DQ-DQS_NEAR_DIMM_NG_M_F_BYTE2\" )
					)
					( Status sCSetFlattened )
					( Origin gBackEnd )
				)
				( attribute "RELATIVE_PROPAGATION_DELAY" "0.00 MIL,195.00 MIL"
					( Parent
						( matchGroupRef "@baseboard_fab2_lib.baseboard_fab2(sch_1):\MG_DQ-DQS_NEAR_DIMM_NG_M_F_BYTE2\" )
					)
					( Units "uMatchProp" "ns" 1.000000)
					( Status sCSetFlattened )
					( Origin gBackEnd )
				)
				( attribute "RELATIVE_PROPAGATION_DELAY_SCOPE" "G"
					( Parent
						( matchGroupRef "@baseboard_fab2_lib.baseboard_fab2(sch_1):\MG_DQ_NEAR_DIMM_NG_M_F_BYTE2\" )
					)
					( Status sCSetFlattened )
					( Origin gBackEnd )
				)
				( attribute "RELATIVE_PROPAGATION_DELAY" "-50.00 MIL,50.00 MIL"
					( Parent
						( matchGroupRef "@baseboard_fab2_lib.baseboard_fab2(sch_1):\MG_DQ_NEAR_DIMM_NG_M_F_BYTE2\" )
					)
					( Units "uMatchProp" "ns" 1.000000)
					( Status sCSetFlattened )
					( Origin gBackEnd )
				)
			)
			( pinPair "@baseboard_fab2_lib.baseboard_fab2(sch_1):\PP4209\"
				( pinRef "@baseboard_fab2_lib.baseboard_fab2(sch_1):page28_i172:DDR5_DQ(18)" )
				( pinRef "@baseboard_fab2_lib.baseboard_fab2(sch_1):page53_i111:DQ(19)" )
				( attribute "RELATIVE_PROPAGATION_DELAY_SCOPE" "G"
					( Parent
						( matchGroupRef "@baseboard_fab2_lib.baseboard_fab2(sch_1):\MG_DQ-DQS_FAR_DIMM_NG_M_F_BYTE2\" )
					)
					( Status sCSetFlattened )
					( Origin gBackEnd )
				)
				( attribute "RELATIVE_PROPAGATION_DELAY" "0.00 MIL,195.00 MIL"
					( Parent
						( matchGroupRef "@baseboard_fab2_lib.baseboard_fab2(sch_1):\MG_DQ-DQS_FAR_DIMM_NG_M_F_BYTE2\" )
					)
					( Units "uMatchProp" "ns" 1.000000)
					( Status sCSetFlattened )
					( Origin gBackEnd )
				)
				( attribute "RELATIVE_PROPAGATION_DELAY_SCOPE" "G"
					( Parent
						( matchGroupRef "@crescent_city_bb_fab1_lib.crescent_city_bb_fab1(sch_1):\MG_DQ_FAR_DIMM_NG_M_F_BYTE2\" )
					)
					( Status sCSetFlattened )
					( Origin gBackEnd )
				)
				( attribute "RELATIVE_PROPAGATION_DELAY" "-50.00 MIL,50.00 MIL"
					( Parent
						( matchGroupRef "@crescent_city_bb_fab1_lib.crescent_city_bb_fab1(sch_1):\MG_DQ_FAR_DIMM_NG_M_F_BYTE2\" )
					)
					( Units "uMatchProp" "ns" 1.000000)
					( Status sCSetFlattened )
					( Origin gBackEnd )
				)
			)
			( pinPair "@baseboard_fab2_lib.baseboard_fab2(sch_1):\PP4211\"
				( pinRef "@baseboard_fab2_lib.baseboard_fab2(sch_1):page54_i111:DQ(18)" )
				( pinRef "@baseboard_fab2_lib.baseboard_fab2(sch_1):page28_i172:DDR5_DQ(18)" )
				( attribute "RELATIVE_PROPAGATION_DELAY_SCOPE" "G"
					( Parent
						( matchGroupRef "@baseboard_fab2_lib.baseboard_fab2(sch_1):\MG_DQ-DQS_NEAR_DIMM_NG_M_F_BYTE2\" )
					)
					( Status sCSetFlattened )
					( Origin gBackEnd )
				)
				( attribute "RELATIVE_PROPAGATION_DELAY" "0.00 MIL,195.00 MIL"
					( Parent
						( matchGroupRef "@baseboard_fab2_lib.baseboard_fab2(sch_1):\MG_DQ-DQS_NEAR_DIMM_NG_M_F_BYTE2\" )
					)
					( Units "uMatchProp" "ns" 1.000000)
					( Status sCSetFlattened )
					( Origin gBackEnd )
				)
				( attribute "RELATIVE_PROPAGATION_DELAY_SCOPE" "G"
					( Parent
						( matchGroupRef "@baseboard_fab2_lib.baseboard_fab2(sch_1):\MG_DQ_NEAR_DIMM_NG_M_F_BYTE2\" )
					)
					( Status sCSetFlattened )
					( Origin gBackEnd )
				)
				( attribute "RELATIVE_PROPAGATION_DELAY" "-50.00 MIL,50.00 MIL"
					( Parent
						( matchGroupRef "@baseboard_fab2_lib.baseboard_fab2(sch_1):\MG_DQ_NEAR_DIMM_NG_M_F_BYTE2\" )
					)
					( Units "uMatchProp" "ns" 1.000000)
					( Status sCSetFlattened )
					( Origin gBackEnd )
				)
			)
			( pinPair "@baseboard_fab2_lib.baseboard_fab2(sch_1):\PP4212\"
				( pinRef "@baseboard_fab2_lib.baseboard_fab2(sch_1):page28_i172:DDR5_DQ(19)" )
				( pinRef "@baseboard_fab2_lib.baseboard_fab2(sch_1):page53_i111:DQ(18)" )
				( attribute "RELATIVE_PROPAGATION_DELAY_SCOPE" "G"
					( Parent
						( matchGroupRef "@baseboard_fab2_lib.baseboard_fab2(sch_1):\MG_DQ-DQS_FAR_DIMM_NG_M_F_BYTE2\" )
					)
					( Status sCSetFlattened )
					( Origin gBackEnd )
				)
				( attribute "RELATIVE_PROPAGATION_DELAY" "0.00 MIL,195.00 MIL"
					( Parent
						( matchGroupRef "@baseboard_fab2_lib.baseboard_fab2(sch_1):\MG_DQ-DQS_FAR_DIMM_NG_M_F_BYTE2\" )
					)
					( Units "uMatchProp" "ns" 1.000000)
					( Status sCSetFlattened )
					( Origin gBackEnd )
				)
				( attribute "RELATIVE_PROPAGATION_DELAY_SCOPE" "G"
					( Parent
						( matchGroupRef "@crescent_city_bb_fab1_lib.crescent_city_bb_fab1(sch_1):\MG_DQ_FAR_DIMM_NG_M_F_BYTE2\" )
					)
					( Status sCSetFlattened )
					( Origin gBackEnd )
				)
				( attribute "RELATIVE_PROPAGATION_DELAY" "-50.00 MIL,50.00 MIL"
					( Parent
						( matchGroupRef "@crescent_city_bb_fab1_lib.crescent_city_bb_fab1(sch_1):\MG_DQ_FAR_DIMM_NG_M_F_BYTE2\" )
					)
					( Units "uMatchProp" "ns" 1.000000)
					( Status sCSetFlattened )
					( Origin gBackEnd )
				)
			)
			( pinPair "@baseboard_fab2_lib.baseboard_fab2(sch_1):\PP4214\"
				( pinRef "@baseboard_fab2_lib.baseboard_fab2(sch_1):page54_i111:DQ(19)" )
				( pinRef "@baseboard_fab2_lib.baseboard_fab2(sch_1):page28_i172:DDR5_DQ(19)" )
				( attribute "RELATIVE_PROPAGATION_DELAY_SCOPE" "G"
					( Parent
						( matchGroupRef "@baseboard_fab2_lib.baseboard_fab2(sch_1):\MG_DQ-DQS_NEAR_DIMM_NG_M_F_BYTE2\" )
					)
					( Status sCSetFlattened )
					( Origin gBackEnd )
				)
				( attribute "RELATIVE_PROPAGATION_DELAY" "0.00 MIL,195.00 MIL"
					( Parent
						( matchGroupRef "@baseboard_fab2_lib.baseboard_fab2(sch_1):\MG_DQ-DQS_NEAR_DIMM_NG_M_F_BYTE2\" )
					)
					( Units "uMatchProp" "ns" 1.000000)
					( Status sCSetFlattened )
					( Origin gBackEnd )
				)
				( attribute "RELATIVE_PROPAGATION_DELAY_SCOPE" "G"
					( Parent
						( matchGroupRef "@baseboard_fab2_lib.baseboard_fab2(sch_1):\MG_DQ_NEAR_DIMM_NG_M_F_BYTE2\" )
					)
					( Status sCSetFlattened )
					( Origin gBackEnd )
				)
				( attribute "RELATIVE_PROPAGATION_DELAY" "-50.00 MIL,50.00 MIL"
					( Parent
						( matchGroupRef "@baseboard_fab2_lib.baseboard_fab2(sch_1):\MG_DQ_NEAR_DIMM_NG_M_F_BYTE2\" )
					)
					( Units "uMatchProp" "ns" 1.000000)
					( Status sCSetFlattened )
					( Origin gBackEnd )
				)
			)
			( pinPair "@baseboard_fab2_lib.baseboard_fab2(sch_1):\PP4215\"
				( pinRef "@baseboard_fab2_lib.baseboard_fab2(sch_1):page28_i172:DDR5_DQ(20)" )
				( pinRef "@baseboard_fab2_lib.baseboard_fab2(sch_1):page53_i111:DQ(21)" )
				( attribute "RELATIVE_PROPAGATION_DELAY_SCOPE" "G"
					( Parent
						( matchGroupRef "@baseboard_fab2_lib.baseboard_fab2(sch_1):\MG_DQ-DQS_FAR_DIMM_NG_M_F_BYTE2\" )
					)
					( Status sCSetFlattened )
					( Origin gBackEnd )
				)
				( attribute "RELATIVE_PROPAGATION_DELAY" "0.00 MIL,195.00 MIL"
					( Parent
						( matchGroupRef "@baseboard_fab2_lib.baseboard_fab2(sch_1):\MG_DQ-DQS_FAR_DIMM_NG_M_F_BYTE2\" )
					)
					( Units "uMatchProp" "ns" 1.000000)
					( Status sCSetFlattened )
					( Origin gBackEnd )
				)
				( attribute "RELATIVE_PROPAGATION_DELAY_SCOPE" "G"
					( Parent
						( matchGroupRef "@crescent_city_bb_fab1_lib.crescent_city_bb_fab1(sch_1):\MG_DQ_FAR_DIMM_NG_M_F_BYTE2\" )
					)
					( Origin gBackEnd )
				)
				( attribute "RELATIVE_PROPAGATION_DELAY" "TARGET,TARGET"
					( Parent
						( matchGroupRef "@crescent_city_bb_fab1_lib.crescent_city_bb_fab1(sch_1):\MG_DQ_FAR_DIMM_NG_M_F_BYTE2\" )
					)
					( Units "uMatchProp" "ns" 1.000000)
					( Origin gBackEnd )
				)
			)
			( pinPair "@baseboard_fab2_lib.baseboard_fab2(sch_1):\PP4217\"
				( pinRef "@baseboard_fab2_lib.baseboard_fab2(sch_1):page54_i111:DQ(20)" )
				( pinRef "@baseboard_fab2_lib.baseboard_fab2(sch_1):page28_i172:DDR5_DQ(20)" )
				( attribute "RELATIVE_PROPAGATION_DELAY_SCOPE" "G"
					( Parent
						( matchGroupRef "@baseboard_fab2_lib.baseboard_fab2(sch_1):\MG_DQ-DQS_NEAR_DIMM_NG_M_F_BYTE2\" )
					)
					( Status sCSetFlattened )
					( Origin gBackEnd )
				)
				( attribute "RELATIVE_PROPAGATION_DELAY" "0.00 MIL,195.00 MIL"
					( Parent
						( matchGroupRef "@baseboard_fab2_lib.baseboard_fab2(sch_1):\MG_DQ-DQS_NEAR_DIMM_NG_M_F_BYTE2\" )
					)
					( Units "uMatchProp" "ns" 1.000000)
					( Status sCSetFlattened )
					( Origin gBackEnd )
				)
				( attribute "RELATIVE_PROPAGATION_DELAY_SCOPE" "G"
					( Parent
						( matchGroupRef "@baseboard_fab2_lib.baseboard_fab2(sch_1):\MG_DQ_NEAR_DIMM_NG_M_F_BYTE2\" )
					)
					( Status sCSetFlattened )
					( Origin gBackEnd )
				)
				( attribute "RELATIVE_PROPAGATION_DELAY" "-50.00 MIL,50.00 MIL"
					( Parent
						( matchGroupRef "@baseboard_fab2_lib.baseboard_fab2(sch_1):\MG_DQ_NEAR_DIMM_NG_M_F_BYTE2\" )
					)
					( Units "uMatchProp" "ns" 1.000000)
					( Status sCSetFlattened )
					( Origin gBackEnd )
				)
			)
			( pinPair "@baseboard_fab2_lib.baseboard_fab2(sch_1):\PP4218\"
				( pinRef "@baseboard_fab2_lib.baseboard_fab2(sch_1):page28_i172:DDR5_DQ(21)" )
				( pinRef "@baseboard_fab2_lib.baseboard_fab2(sch_1):page53_i111:DQ(20)" )
				( attribute "RELATIVE_PROPAGATION_DELAY_SCOPE" "G"
					( Parent
						( matchGroupRef "@baseboard_fab2_lib.baseboard_fab2(sch_1):\MG_DQ-DQS_FAR_DIMM_NG_M_F_BYTE2\" )
					)
					( Status sCSetFlattened )
					( Origin gBackEnd )
				)
				( attribute "RELATIVE_PROPAGATION_DELAY" "0.00 MIL,195.00 MIL"
					( Parent
						( matchGroupRef "@baseboard_fab2_lib.baseboard_fab2(sch_1):\MG_DQ-DQS_FAR_DIMM_NG_M_F_BYTE2\" )
					)
					( Units "uMatchProp" "ns" 1.000000)
					( Status sCSetFlattened )
					( Origin gBackEnd )
				)
				( attribute "RELATIVE_PROPAGATION_DELAY_SCOPE" "G"
					( Parent
						( matchGroupRef "@crescent_city_bb_fab1_lib.crescent_city_bb_fab1(sch_1):\MG_DQ_FAR_DIMM_NG_M_F_BYTE2\" )
					)
					( Status sCSetFlattened )
					( Origin gBackEnd )
				)
				( attribute "RELATIVE_PROPAGATION_DELAY" "-50.00 MIL,50.00 MIL"
					( Parent
						( matchGroupRef "@crescent_city_bb_fab1_lib.crescent_city_bb_fab1(sch_1):\MG_DQ_FAR_DIMM_NG_M_F_BYTE2\" )
					)
					( Units "uMatchProp" "ns" 1.000000)
					( Status sCSetFlattened )
					( Origin gBackEnd )
				)
			)
			( pinPair "@baseboard_fab2_lib.baseboard_fab2(sch_1):\PP4220\"
				( pinRef "@baseboard_fab2_lib.baseboard_fab2(sch_1):page54_i111:DQ(21)" )
				( pinRef "@baseboard_fab2_lib.baseboard_fab2(sch_1):page28_i172:DDR5_DQ(21)" )
				( attribute "RELATIVE_PROPAGATION_DELAY_SCOPE" "G"
					( Parent
						( matchGroupRef "@baseboard_fab2_lib.baseboard_fab2(sch_1):\MG_DQ-DQS_NEAR_DIMM_NG_M_F_BYTE2\" )
					)
					( Status sCSetFlattened )
					( Origin gBackEnd )
				)
				( attribute "RELATIVE_PROPAGATION_DELAY" "0.00 MIL,195.00 MIL"
					( Parent
						( matchGroupRef "@baseboard_fab2_lib.baseboard_fab2(sch_1):\MG_DQ-DQS_NEAR_DIMM_NG_M_F_BYTE2\" )
					)
					( Units "uMatchProp" "ns" 1.000000)
					( Status sCSetFlattened )
					( Origin gBackEnd )
				)
				( attribute "RELATIVE_PROPAGATION_DELAY_SCOPE" "G"
					( Parent
						( matchGroupRef "@baseboard_fab2_lib.baseboard_fab2(sch_1):\MG_DQ_NEAR_DIMM_NG_M_F_BYTE2\" )
					)
					( Status sCSetFlattened )
					( Origin gBackEnd )
				)
				( attribute "RELATIVE_PROPAGATION_DELAY" "-50.00 MIL,50.00 MIL"
					( Parent
						( matchGroupRef "@baseboard_fab2_lib.baseboard_fab2(sch_1):\MG_DQ_NEAR_DIMM_NG_M_F_BYTE2\" )
					)
					( Units "uMatchProp" "ns" 1.000000)
					( Status sCSetFlattened )
					( Origin gBackEnd )
				)
			)
			( pinPair "@baseboard_fab2_lib.baseboard_fab2(sch_1):\PP4221\"
				( pinRef "@baseboard_fab2_lib.baseboard_fab2(sch_1):page28_i172:DDR5_DQ(22)" )
				( pinRef "@baseboard_fab2_lib.baseboard_fab2(sch_1):page53_i111:DQ(23)" )
				( attribute "RELATIVE_PROPAGATION_DELAY_SCOPE" "G"
					( Parent
						( matchGroupRef "@baseboard_fab2_lib.baseboard_fab2(sch_1):\MG_DQ-DQS_FAR_DIMM_NG_M_F_BYTE2\" )
					)
					( Status sCSetFlattened )
					( Origin gBackEnd )
				)
				( attribute "RELATIVE_PROPAGATION_DELAY" "0.00 MIL,195.00 MIL"
					( Parent
						( matchGroupRef "@baseboard_fab2_lib.baseboard_fab2(sch_1):\MG_DQ-DQS_FAR_DIMM_NG_M_F_BYTE2\" )
					)
					( Units "uMatchProp" "ns" 1.000000)
					( Status sCSetFlattened )
					( Origin gBackEnd )
				)
				( attribute "RELATIVE_PROPAGATION_DELAY_SCOPE" "G"
					( Parent
						( matchGroupRef "@crescent_city_bb_fab1_lib.crescent_city_bb_fab1(sch_1):\MG_DQ_FAR_DIMM_NG_M_F_BYTE2\" )
					)
					( Status sCSetFlattened )
					( Origin gBackEnd )
				)
				( attribute "RELATIVE_PROPAGATION_DELAY" "-50.00 MIL,50.00 MIL"
					( Parent
						( matchGroupRef "@crescent_city_bb_fab1_lib.crescent_city_bb_fab1(sch_1):\MG_DQ_FAR_DIMM_NG_M_F_BYTE2\" )
					)
					( Units "uMatchProp" "ns" 1.000000)
					( Status sCSetFlattened )
					( Origin gBackEnd )
				)
			)
			( pinPair "@baseboard_fab2_lib.baseboard_fab2(sch_1):\PP4223\"
				( pinRef "@baseboard_fab2_lib.baseboard_fab2(sch_1):page54_i111:DQ(22)" )
				( pinRef "@baseboard_fab2_lib.baseboard_fab2(sch_1):page28_i172:DDR5_DQ(22)" )
				( attribute "RELATIVE_PROPAGATION_DELAY_SCOPE" "G"
					( Parent
						( matchGroupRef "@baseboard_fab2_lib.baseboard_fab2(sch_1):\MG_DQ-DQS_NEAR_DIMM_NG_M_F_BYTE2\" )
					)
					( Status sCSetFlattened )
					( Origin gBackEnd )
				)
				( attribute "RELATIVE_PROPAGATION_DELAY" "0.00 MIL,195.00 MIL"
					( Parent
						( matchGroupRef "@baseboard_fab2_lib.baseboard_fab2(sch_1):\MG_DQ-DQS_NEAR_DIMM_NG_M_F_BYTE2\" )
					)
					( Units "uMatchProp" "ns" 1.000000)
					( Status sCSetFlattened )
					( Origin gBackEnd )
				)
				( attribute "RELATIVE_PROPAGATION_DELAY_SCOPE" "G"
					( Parent
						( matchGroupRef "@baseboard_fab2_lib.baseboard_fab2(sch_1):\MG_DQ_NEAR_DIMM_NG_M_F_BYTE2\" )
					)
					( Status sCSetFlattened )
					( Origin gBackEnd )
				)
				( attribute "RELATIVE_PROPAGATION_DELAY" "-50.00 MIL,50.00 MIL"
					( Parent
						( matchGroupRef "@baseboard_fab2_lib.baseboard_fab2(sch_1):\MG_DQ_NEAR_DIMM_NG_M_F_BYTE2\" )
					)
					( Units "uMatchProp" "ns" 1.000000)
					( Status sCSetFlattened )
					( Origin gBackEnd )
				)
			)
			( pinPair "@baseboard_fab2_lib.baseboard_fab2(sch_1):\PP4224\"
				( pinRef "@baseboard_fab2_lib.baseboard_fab2(sch_1):page28_i172:DDR5_DQ(23)" )
				( pinRef "@baseboard_fab2_lib.baseboard_fab2(sch_1):page53_i111:DQ(22)" )
				( attribute "RELATIVE_PROPAGATION_DELAY_SCOPE" "G"
					( Parent
						( matchGroupRef "@baseboard_fab2_lib.baseboard_fab2(sch_1):\MG_DQ-DQS_FAR_DIMM_NG_M_F_BYTE2\" )
					)
					( Status sCSetFlattened )
					( Origin gBackEnd )
				)
				( attribute "RELATIVE_PROPAGATION_DELAY" "0.00 MIL,195.00 MIL"
					( Parent
						( matchGroupRef "@baseboard_fab2_lib.baseboard_fab2(sch_1):\MG_DQ-DQS_FAR_DIMM_NG_M_F_BYTE2\" )
					)
					( Units "uMatchProp" "ns" 1.000000)
					( Status sCSetFlattened )
					( Origin gBackEnd )
				)
				( attribute "RELATIVE_PROPAGATION_DELAY_SCOPE" "G"
					( Parent
						( matchGroupRef "@crescent_city_bb_fab1_lib.crescent_city_bb_fab1(sch_1):\MG_DQ_FAR_DIMM_NG_M_F_BYTE2\" )
					)
					( Status sCSetFlattened )
					( Origin gBackEnd )
				)
				( attribute "RELATIVE_PROPAGATION_DELAY" "-50.00 MIL,50.00 MIL"
					( Parent
						( matchGroupRef "@crescent_city_bb_fab1_lib.crescent_city_bb_fab1(sch_1):\MG_DQ_FAR_DIMM_NG_M_F_BYTE2\" )
					)
					( Units "uMatchProp" "ns" 1.000000)
					( Status sCSetFlattened )
					( Origin gBackEnd )
				)
			)
			( pinPair "@baseboard_fab2_lib.baseboard_fab2(sch_1):\PP4226\"
				( pinRef "@baseboard_fab2_lib.baseboard_fab2(sch_1):page54_i111:DQ(23)" )
				( pinRef "@baseboard_fab2_lib.baseboard_fab2(sch_1):page28_i172:DDR5_DQ(23)" )
				( attribute "RELATIVE_PROPAGATION_DELAY_SCOPE" "G"
					( Parent
						( matchGroupRef "@baseboard_fab2_lib.baseboard_fab2(sch_1):\MG_DQ-DQS_NEAR_DIMM_NG_M_F_BYTE2\" )
					)
					( Status sCSetFlattened )
					( Origin gBackEnd )
				)
				( attribute "RELATIVE_PROPAGATION_DELAY" "0.00 MIL,195.00 MIL"
					( Parent
						( matchGroupRef "@baseboard_fab2_lib.baseboard_fab2(sch_1):\MG_DQ-DQS_NEAR_DIMM_NG_M_F_BYTE2\" )
					)
					( Units "uMatchProp" "ns" 1.000000)
					( Status sCSetFlattened )
					( Origin gBackEnd )
				)
				( attribute "RELATIVE_PROPAGATION_DELAY_SCOPE" "G"
					( Parent
						( matchGroupRef "@baseboard_fab2_lib.baseboard_fab2(sch_1):\MG_DQ_NEAR_DIMM_NG_M_F_BYTE2\" )
					)
					( Status sCSetFlattened )
					( Origin gBackEnd )
				)
				( attribute "RELATIVE_PROPAGATION_DELAY" "-50.00 MIL,50.00 MIL"
					( Parent
						( matchGroupRef "@baseboard_fab2_lib.baseboard_fab2(sch_1):\MG_DQ_NEAR_DIMM_NG_M_F_BYTE2\" )
					)
					( Units "uMatchProp" "ns" 1.000000)
					( Status sCSetFlattened )
					( Origin gBackEnd )
				)
			)
			( pinPair "@baseboard_fab2_lib.baseboard_fab2(sch_1):\PP4179\"
				( pinRef "@baseboard_fab2_lib.baseboard_fab2(sch_1):page28_i172:DDR5_DQ(24)" )
				( pinRef "@baseboard_fab2_lib.baseboard_fab2(sch_1):page53_i111:DQ(25)" )
				( attribute "RELATIVE_PROPAGATION_DELAY_SCOPE" "G"
					( Parent
						( matchGroupRef "@baseboard_fab2_lib.baseboard_fab2(sch_1):\MG_DQ-DQS_FAR_DIMM_NG_M_F_BYTE3\" )
					)
					( Status sCSetFlattened )
					( Origin gBackEnd )
				)
				( attribute "RELATIVE_PROPAGATION_DELAY" "0.00 MIL,195.00 MIL"
					( Parent
						( matchGroupRef "@baseboard_fab2_lib.baseboard_fab2(sch_1):\MG_DQ-DQS_FAR_DIMM_NG_M_F_BYTE3\" )
					)
					( Units "uMatchProp" "ns" 1.000000)
					( Status sCSetFlattened )
					( Origin gBackEnd )
				)
				( attribute "RELATIVE_PROPAGATION_DELAY_SCOPE" "G"
					( Parent
						( matchGroupRef "@baseboard_fab2_lib.baseboard_fab2(sch_1):\MG_DQ_FAR_DIMM_NG_M_F_BYTE3\" )
					)
					( Status sCSetFlattened )
					( Origin gBackEnd )
				)
				( attribute "RELATIVE_PROPAGATION_DELAY" "-50.00 MIL,50.00 MIL"
					( Parent
						( matchGroupRef "@baseboard_fab2_lib.baseboard_fab2(sch_1):\MG_DQ_FAR_DIMM_NG_M_F_BYTE3\" )
					)
					( Units "uMatchProp" "ns" 1.000000)
					( Status sCSetFlattened )
					( Origin gBackEnd )
				)
			)
			( pinPair "@baseboard_fab2_lib.baseboard_fab2(sch_1):\PP4181\"
				( pinRef "@baseboard_fab2_lib.baseboard_fab2(sch_1):page54_i111:DQ(24)" )
				( pinRef "@baseboard_fab2_lib.baseboard_fab2(sch_1):page28_i172:DDR5_DQ(24)" )
				( attribute "RELATIVE_PROPAGATION_DELAY_SCOPE" "G"
					( Parent
						( matchGroupRef "@baseboard_fab2_lib.baseboard_fab2(sch_1):\MG_DQ-DQS_NEAR_DIMM_NG_M_F_BYTE3\" )
					)
					( Status sCSetFlattened )
					( Origin gBackEnd )
				)
				( attribute "RELATIVE_PROPAGATION_DELAY" "0.00 MIL,195.00 MIL"
					( Parent
						( matchGroupRef "@baseboard_fab2_lib.baseboard_fab2(sch_1):\MG_DQ-DQS_NEAR_DIMM_NG_M_F_BYTE3\" )
					)
					( Units "uMatchProp" "ns" 1.000000)
					( Status sCSetFlattened )
					( Origin gBackEnd )
				)
				( attribute "RELATIVE_PROPAGATION_DELAY_SCOPE" "G"
					( Parent
						( matchGroupRef "@crescent_city_bb_fab1_lib.crescent_city_bb_fab1(sch_1):\MG_DQ_NEAR_DIMM_NG_M_F_BYTE3\" )
					)
					( Status sCSetFlattened )
					( Origin gBackEnd )
				)
				( attribute "RELATIVE_PROPAGATION_DELAY" "-50.00 MIL,50.00 MIL"
					( Parent
						( matchGroupRef "@crescent_city_bb_fab1_lib.crescent_city_bb_fab1(sch_1):\MG_DQ_NEAR_DIMM_NG_M_F_BYTE3\" )
					)
					( Units "uMatchProp" "ns" 1.000000)
					( Status sCSetFlattened )
					( Origin gBackEnd )
				)
			)
			( pinPair "@baseboard_fab2_lib.baseboard_fab2(sch_1):\PP4182\"
				( pinRef "@baseboard_fab2_lib.baseboard_fab2(sch_1):page28_i172:DDR5_DQ(25)" )
				( pinRef "@baseboard_fab2_lib.baseboard_fab2(sch_1):page53_i111:DQ(24)" )
				( attribute "RELATIVE_PROPAGATION_DELAY_SCOPE" "G"
					( Parent
						( matchGroupRef "@baseboard_fab2_lib.baseboard_fab2(sch_1):\MG_DQ-DQS_FAR_DIMM_NG_M_F_BYTE3\" )
					)
					( Status sCSetFlattened )
					( Origin gBackEnd )
				)
				( attribute "RELATIVE_PROPAGATION_DELAY" "0.00 MIL,195.00 MIL"
					( Parent
						( matchGroupRef "@baseboard_fab2_lib.baseboard_fab2(sch_1):\MG_DQ-DQS_FAR_DIMM_NG_M_F_BYTE3\" )
					)
					( Units "uMatchProp" "ns" 1.000000)
					( Status sCSetFlattened )
					( Origin gBackEnd )
				)
				( attribute "RELATIVE_PROPAGATION_DELAY_SCOPE" "G"
					( Parent
						( matchGroupRef "@baseboard_fab2_lib.baseboard_fab2(sch_1):\MG_DQ_FAR_DIMM_NG_M_F_BYTE3\" )
					)
					( Status sCSetFlattened )
					( Origin gBackEnd )
				)
				( attribute "RELATIVE_PROPAGATION_DELAY" "-50.00 MIL,50.00 MIL"
					( Parent
						( matchGroupRef "@baseboard_fab2_lib.baseboard_fab2(sch_1):\MG_DQ_FAR_DIMM_NG_M_F_BYTE3\" )
					)
					( Units "uMatchProp" "ns" 1.000000)
					( Status sCSetFlattened )
					( Origin gBackEnd )
				)
			)
			( pinPair "@baseboard_fab2_lib.baseboard_fab2(sch_1):\PP4184\"
				( pinRef "@baseboard_fab2_lib.baseboard_fab2(sch_1):page54_i111:DQ(25)" )
				( pinRef "@baseboard_fab2_lib.baseboard_fab2(sch_1):page28_i172:DDR5_DQ(25)" )
				( attribute "RELATIVE_PROPAGATION_DELAY_SCOPE" "G"
					( Parent
						( matchGroupRef "@baseboard_fab2_lib.baseboard_fab2(sch_1):\MG_DQ-DQS_NEAR_DIMM_NG_M_F_BYTE3\" )
					)
					( Status sCSetFlattened )
					( Origin gBackEnd )
				)
				( attribute "RELATIVE_PROPAGATION_DELAY" "0.00 MIL,195.00 MIL"
					( Parent
						( matchGroupRef "@baseboard_fab2_lib.baseboard_fab2(sch_1):\MG_DQ-DQS_NEAR_DIMM_NG_M_F_BYTE3\" )
					)
					( Units "uMatchProp" "ns" 1.000000)
					( Status sCSetFlattened )
					( Origin gBackEnd )
				)
				( attribute "RELATIVE_PROPAGATION_DELAY_SCOPE" "G"
					( Parent
						( matchGroupRef "@crescent_city_bb_fab1_lib.crescent_city_bb_fab1(sch_1):\MG_DQ_NEAR_DIMM_NG_M_F_BYTE3\" )
					)
					( Status sCSetFlattened )
					( Origin gBackEnd )
				)
				( attribute "RELATIVE_PROPAGATION_DELAY" "-50.00 MIL,50.00 MIL"
					( Parent
						( matchGroupRef "@crescent_city_bb_fab1_lib.crescent_city_bb_fab1(sch_1):\MG_DQ_NEAR_DIMM_NG_M_F_BYTE3\" )
					)
					( Units "uMatchProp" "ns" 1.000000)
					( Status sCSetFlattened )
					( Origin gBackEnd )
				)
			)
			( pinPair "@baseboard_fab2_lib.baseboard_fab2(sch_1):\PP4185\"
				( pinRef "@baseboard_fab2_lib.baseboard_fab2(sch_1):page28_i172:DDR5_DQ(26)" )
				( pinRef "@baseboard_fab2_lib.baseboard_fab2(sch_1):page53_i111:DQ(27)" )
				( attribute "RELATIVE_PROPAGATION_DELAY_SCOPE" "G"
					( Parent
						( matchGroupRef "@baseboard_fab2_lib.baseboard_fab2(sch_1):\MG_DQ-DQS_FAR_DIMM_NG_M_F_BYTE3\" )
					)
					( Status sCSetFlattened )
					( Origin gBackEnd )
				)
				( attribute "RELATIVE_PROPAGATION_DELAY" "0.00 MIL,195.00 MIL"
					( Parent
						( matchGroupRef "@baseboard_fab2_lib.baseboard_fab2(sch_1):\MG_DQ-DQS_FAR_DIMM_NG_M_F_BYTE3\" )
					)
					( Units "uMatchProp" "ns" 1.000000)
					( Status sCSetFlattened )
					( Origin gBackEnd )
				)
				( attribute "RELATIVE_PROPAGATION_DELAY_SCOPE" "G"
					( Parent
						( matchGroupRef "@baseboard_fab2_lib.baseboard_fab2(sch_1):\MG_DQ_FAR_DIMM_NG_M_F_BYTE3\" )
					)
					( Status sCSetFlattened )
					( Origin gBackEnd )
				)
				( attribute "RELATIVE_PROPAGATION_DELAY" "-50.00 MIL,50.00 MIL"
					( Parent
						( matchGroupRef "@baseboard_fab2_lib.baseboard_fab2(sch_1):\MG_DQ_FAR_DIMM_NG_M_F_BYTE3\" )
					)
					( Units "uMatchProp" "ns" 1.000000)
					( Status sCSetFlattened )
					( Origin gBackEnd )
				)
			)
			( pinPair "@baseboard_fab2_lib.baseboard_fab2(sch_1):\PP4187\"
				( pinRef "@baseboard_fab2_lib.baseboard_fab2(sch_1):page54_i111:DQ(26)" )
				( pinRef "@baseboard_fab2_lib.baseboard_fab2(sch_1):page28_i172:DDR5_DQ(26)" )
				( attribute "RELATIVE_PROPAGATION_DELAY_SCOPE" "G"
					( Parent
						( matchGroupRef "@baseboard_fab2_lib.baseboard_fab2(sch_1):\MG_DQ-DQS_NEAR_DIMM_NG_M_F_BYTE3\" )
					)
					( Status sCSetFlattened )
					( Origin gBackEnd )
				)
				( attribute "RELATIVE_PROPAGATION_DELAY" "0.00 MIL,195.00 MIL"
					( Parent
						( matchGroupRef "@baseboard_fab2_lib.baseboard_fab2(sch_1):\MG_DQ-DQS_NEAR_DIMM_NG_M_F_BYTE3\" )
					)
					( Units "uMatchProp" "ns" 1.000000)
					( Status sCSetFlattened )
					( Origin gBackEnd )
				)
				( attribute "RELATIVE_PROPAGATION_DELAY_SCOPE" "G"
					( Parent
						( matchGroupRef "@crescent_city_bb_fab1_lib.crescent_city_bb_fab1(sch_1):\MG_DQ_NEAR_DIMM_NG_M_F_BYTE3\" )
					)
					( Status sCSetFlattened )
					( Origin gBackEnd )
				)
				( attribute "RELATIVE_PROPAGATION_DELAY" "-50.00 MIL,50.00 MIL"
					( Parent
						( matchGroupRef "@crescent_city_bb_fab1_lib.crescent_city_bb_fab1(sch_1):\MG_DQ_NEAR_DIMM_NG_M_F_BYTE3\" )
					)
					( Units "uMatchProp" "ns" 1.000000)
					( Status sCSetFlattened )
					( Origin gBackEnd )
				)
			)
			( pinPair "@baseboard_fab2_lib.baseboard_fab2(sch_1):\PP4188\"
				( pinRef "@baseboard_fab2_lib.baseboard_fab2(sch_1):page28_i172:DDR5_DQ(27)" )
				( pinRef "@baseboard_fab2_lib.baseboard_fab2(sch_1):page53_i111:DQ(26)" )
				( attribute "RELATIVE_PROPAGATION_DELAY_SCOPE" "G"
					( Parent
						( matchGroupRef "@baseboard_fab2_lib.baseboard_fab2(sch_1):\MG_DQ-DQS_FAR_DIMM_NG_M_F_BYTE3\" )
					)
					( Status sCSetFlattened )
					( Origin gBackEnd )
				)
				( attribute "RELATIVE_PROPAGATION_DELAY" "0.00 MIL,195.00 MIL"
					( Parent
						( matchGroupRef "@baseboard_fab2_lib.baseboard_fab2(sch_1):\MG_DQ-DQS_FAR_DIMM_NG_M_F_BYTE3\" )
					)
					( Units "uMatchProp" "ns" 1.000000)
					( Status sCSetFlattened )
					( Origin gBackEnd )
				)
				( attribute "RELATIVE_PROPAGATION_DELAY_SCOPE" "G"
					( Parent
						( matchGroupRef "@baseboard_fab2_lib.baseboard_fab2(sch_1):\MG_DQ_FAR_DIMM_NG_M_F_BYTE3\" )
					)
					( Status sCSetFlattened )
					( Origin gBackEnd )
				)
				( attribute "RELATIVE_PROPAGATION_DELAY" "-50.00 MIL,50.00 MIL"
					( Parent
						( matchGroupRef "@baseboard_fab2_lib.baseboard_fab2(sch_1):\MG_DQ_FAR_DIMM_NG_M_F_BYTE3\" )
					)
					( Units "uMatchProp" "ns" 1.000000)
					( Status sCSetFlattened )
					( Origin gBackEnd )
				)
			)
			( pinPair "@baseboard_fab2_lib.baseboard_fab2(sch_1):\PP4190\"
				( pinRef "@baseboard_fab2_lib.baseboard_fab2(sch_1):page54_i111:DQ(27)" )
				( pinRef "@baseboard_fab2_lib.baseboard_fab2(sch_1):page28_i172:DDR5_DQ(27)" )
				( attribute "RELATIVE_PROPAGATION_DELAY_SCOPE" "G"
					( Parent
						( matchGroupRef "@baseboard_fab2_lib.baseboard_fab2(sch_1):\MG_DQ-DQS_NEAR_DIMM_NG_M_F_BYTE3\" )
					)
					( Status sCSetFlattened )
					( Origin gBackEnd )
				)
				( attribute "RELATIVE_PROPAGATION_DELAY" "0.00 MIL,195.00 MIL"
					( Parent
						( matchGroupRef "@baseboard_fab2_lib.baseboard_fab2(sch_1):\MG_DQ-DQS_NEAR_DIMM_NG_M_F_BYTE3\" )
					)
					( Units "uMatchProp" "ns" 1.000000)
					( Status sCSetFlattened )
					( Origin gBackEnd )
				)
				( attribute "RELATIVE_PROPAGATION_DELAY_SCOPE" "G"
					( Parent
						( matchGroupRef "@crescent_city_bb_fab1_lib.crescent_city_bb_fab1(sch_1):\MG_DQ_NEAR_DIMM_NG_M_F_BYTE3\" )
					)
					( Status sCSetFlattened )
					( Origin gBackEnd )
				)
				( attribute "RELATIVE_PROPAGATION_DELAY" "-50.00 MIL,50.00 MIL"
					( Parent
						( matchGroupRef "@crescent_city_bb_fab1_lib.crescent_city_bb_fab1(sch_1):\MG_DQ_NEAR_DIMM_NG_M_F_BYTE3\" )
					)
					( Units "uMatchProp" "ns" 1.000000)
					( Status sCSetFlattened )
					( Origin gBackEnd )
				)
			)
			( pinPair "@baseboard_fab2_lib.baseboard_fab2(sch_1):\PP4191\"
				( pinRef "@baseboard_fab2_lib.baseboard_fab2(sch_1):page28_i172:DDR5_DQ(28)" )
				( pinRef "@baseboard_fab2_lib.baseboard_fab2(sch_1):page53_i111:DQ(29)" )
				( attribute "RELATIVE_PROPAGATION_DELAY_SCOPE" "G"
					( Parent
						( matchGroupRef "@baseboard_fab2_lib.baseboard_fab2(sch_1):\MG_DQ-DQS_FAR_DIMM_NG_M_F_BYTE3\" )
					)
					( Status sCSetFlattened )
					( Origin gBackEnd )
				)
				( attribute "RELATIVE_PROPAGATION_DELAY" "0.00 MIL,195.00 MIL"
					( Parent
						( matchGroupRef "@baseboard_fab2_lib.baseboard_fab2(sch_1):\MG_DQ-DQS_FAR_DIMM_NG_M_F_BYTE3\" )
					)
					( Units "uMatchProp" "ns" 1.000000)
					( Status sCSetFlattened )
					( Origin gBackEnd )
				)
				( attribute "RELATIVE_PROPAGATION_DELAY_SCOPE" "G"
					( Parent
						( matchGroupRef "@baseboard_fab2_lib.baseboard_fab2(sch_1):\MG_DQ_FAR_DIMM_NG_M_F_BYTE3\" )
					)
					( Status sCSetFlattened )
					( Origin gBackEnd )
				)
				( attribute "RELATIVE_PROPAGATION_DELAY" "-50.00 MIL,50.00 MIL"
					( Parent
						( matchGroupRef "@baseboard_fab2_lib.baseboard_fab2(sch_1):\MG_DQ_FAR_DIMM_NG_M_F_BYTE3\" )
					)
					( Units "uMatchProp" "ns" 1.000000)
					( Status sCSetFlattened )
					( Origin gBackEnd )
				)
			)
			( pinPair "@baseboard_fab2_lib.baseboard_fab2(sch_1):\PP4193\"
				( pinRef "@baseboard_fab2_lib.baseboard_fab2(sch_1):page54_i111:DQ(28)" )
				( pinRef "@baseboard_fab2_lib.baseboard_fab2(sch_1):page28_i172:DDR5_DQ(28)" )
				( attribute "RELATIVE_PROPAGATION_DELAY_SCOPE" "G"
					( Parent
						( matchGroupRef "@baseboard_fab2_lib.baseboard_fab2(sch_1):\MG_DQ-DQS_NEAR_DIMM_NG_M_F_BYTE3\" )
					)
					( Status sCSetFlattened )
					( Origin gBackEnd )
				)
				( attribute "RELATIVE_PROPAGATION_DELAY" "0.00 MIL,195.00 MIL"
					( Parent
						( matchGroupRef "@baseboard_fab2_lib.baseboard_fab2(sch_1):\MG_DQ-DQS_NEAR_DIMM_NG_M_F_BYTE3\" )
					)
					( Units "uMatchProp" "ns" 1.000000)
					( Status sCSetFlattened )
					( Origin gBackEnd )
				)
				( attribute "RELATIVE_PROPAGATION_DELAY_SCOPE" "G"
					( Parent
						( matchGroupRef "@crescent_city_bb_fab1_lib.crescent_city_bb_fab1(sch_1):\MG_DQ_NEAR_DIMM_NG_M_F_BYTE3\" )
					)
					( Status sCSetFlattened )
					( Origin gBackEnd )
				)
				( attribute "RELATIVE_PROPAGATION_DELAY" "-50.00 MIL,50.00 MIL"
					( Parent
						( matchGroupRef "@crescent_city_bb_fab1_lib.crescent_city_bb_fab1(sch_1):\MG_DQ_NEAR_DIMM_NG_M_F_BYTE3\" )
					)
					( Units "uMatchProp" "ns" 1.000000)
					( Status sCSetFlattened )
					( Origin gBackEnd )
				)
			)
			( pinPair "@baseboard_fab2_lib.baseboard_fab2(sch_1):\PP4194\"
				( pinRef "@baseboard_fab2_lib.baseboard_fab2(sch_1):page28_i172:DDR5_DQ(29)" )
				( pinRef "@baseboard_fab2_lib.baseboard_fab2(sch_1):page53_i111:DQ(28)" )
				( attribute "RELATIVE_PROPAGATION_DELAY_SCOPE" "G"
					( Parent
						( matchGroupRef "@baseboard_fab2_lib.baseboard_fab2(sch_1):\MG_DQ-DQS_FAR_DIMM_NG_M_F_BYTE3\" )
					)
					( Status sCSetFlattened )
					( Origin gBackEnd )
				)
				( attribute "RELATIVE_PROPAGATION_DELAY" "0.00 MIL,195.00 MIL"
					( Parent
						( matchGroupRef "@baseboard_fab2_lib.baseboard_fab2(sch_1):\MG_DQ-DQS_FAR_DIMM_NG_M_F_BYTE3\" )
					)
					( Units "uMatchProp" "ns" 1.000000)
					( Status sCSetFlattened )
					( Origin gBackEnd )
				)
				( attribute "RELATIVE_PROPAGATION_DELAY_SCOPE" "G"
					( Parent
						( matchGroupRef "@baseboard_fab2_lib.baseboard_fab2(sch_1):\MG_DQ_FAR_DIMM_NG_M_F_BYTE3\" )
					)
					( Status sCSetFlattened )
					( Origin gBackEnd )
				)
				( attribute "RELATIVE_PROPAGATION_DELAY" "-50.00 MIL,50.00 MIL"
					( Parent
						( matchGroupRef "@baseboard_fab2_lib.baseboard_fab2(sch_1):\MG_DQ_FAR_DIMM_NG_M_F_BYTE3\" )
					)
					( Units "uMatchProp" "ns" 1.000000)
					( Status sCSetFlattened )
					( Origin gBackEnd )
				)
			)
			( pinPair "@baseboard_fab2_lib.baseboard_fab2(sch_1):\PP4196\"
				( pinRef "@baseboard_fab2_lib.baseboard_fab2(sch_1):page54_i111:DQ(29)" )
				( pinRef "@baseboard_fab2_lib.baseboard_fab2(sch_1):page28_i172:DDR5_DQ(29)" )
				( attribute "RELATIVE_PROPAGATION_DELAY_SCOPE" "G"
					( Parent
						( matchGroupRef "@baseboard_fab2_lib.baseboard_fab2(sch_1):\MG_DQ-DQS_NEAR_DIMM_NG_M_F_BYTE3\" )
					)
					( Status sCSetFlattened )
					( Origin gBackEnd )
				)
				( attribute "RELATIVE_PROPAGATION_DELAY" "0.00 MIL,195.00 MIL"
					( Parent
						( matchGroupRef "@baseboard_fab2_lib.baseboard_fab2(sch_1):\MG_DQ-DQS_NEAR_DIMM_NG_M_F_BYTE3\" )
					)
					( Units "uMatchProp" "ns" 1.000000)
					( Status sCSetFlattened )
					( Origin gBackEnd )
				)
				( attribute "RELATIVE_PROPAGATION_DELAY_SCOPE" "G"
					( Parent
						( matchGroupRef "@crescent_city_bb_fab1_lib.crescent_city_bb_fab1(sch_1):\MG_DQ_NEAR_DIMM_NG_M_F_BYTE3\" )
					)
					( Origin gBackEnd )
				)
				( attribute "RELATIVE_PROPAGATION_DELAY" "TARGET,TARGET"
					( Parent
						( matchGroupRef "@crescent_city_bb_fab1_lib.crescent_city_bb_fab1(sch_1):\MG_DQ_NEAR_DIMM_NG_M_F_BYTE3\" )
					)
					( Units "uMatchProp" "ns" 1.000000)
					( Origin gBackEnd )
				)
			)
			( pinPair "@baseboard_fab2_lib.baseboard_fab2(sch_1):\PP4197\"
				( pinRef "@baseboard_fab2_lib.baseboard_fab2(sch_1):page28_i172:DDR5_DQ(30)" )
				( pinRef "@baseboard_fab2_lib.baseboard_fab2(sch_1):page53_i111:DQ(31)" )
				( attribute "RELATIVE_PROPAGATION_DELAY_SCOPE" "G"
					( Parent
						( matchGroupRef "@baseboard_fab2_lib.baseboard_fab2(sch_1):\MG_DQ-DQS_FAR_DIMM_NG_M_F_BYTE3\" )
					)
					( Status sCSetFlattened )
					( Origin gBackEnd )
				)
				( attribute "RELATIVE_PROPAGATION_DELAY" "0.00 MIL,195.00 MIL"
					( Parent
						( matchGroupRef "@baseboard_fab2_lib.baseboard_fab2(sch_1):\MG_DQ-DQS_FAR_DIMM_NG_M_F_BYTE3\" )
					)
					( Units "uMatchProp" "ns" 1.000000)
					( Status sCSetFlattened )
					( Origin gBackEnd )
				)
				( attribute "RELATIVE_PROPAGATION_DELAY_SCOPE" "G"
					( Parent
						( matchGroupRef "@baseboard_fab2_lib.baseboard_fab2(sch_1):\MG_DQ_FAR_DIMM_NG_M_F_BYTE3\" )
					)
					( Status sCSetFlattened )
					( Origin gBackEnd )
				)
				( attribute "RELATIVE_PROPAGATION_DELAY" "-50.00 MIL,50.00 MIL"
					( Parent
						( matchGroupRef "@baseboard_fab2_lib.baseboard_fab2(sch_1):\MG_DQ_FAR_DIMM_NG_M_F_BYTE3\" )
					)
					( Units "uMatchProp" "ns" 1.000000)
					( Status sCSetFlattened )
					( Origin gBackEnd )
				)
			)
			( pinPair "@baseboard_fab2_lib.baseboard_fab2(sch_1):\PP4199\"
				( pinRef "@baseboard_fab2_lib.baseboard_fab2(sch_1):page54_i111:DQ(30)" )
				( pinRef "@baseboard_fab2_lib.baseboard_fab2(sch_1):page28_i172:DDR5_DQ(30)" )
				( attribute "RELATIVE_PROPAGATION_DELAY_SCOPE" "G"
					( Parent
						( matchGroupRef "@baseboard_fab2_lib.baseboard_fab2(sch_1):\MG_DQ-DQS_NEAR_DIMM_NG_M_F_BYTE3\" )
					)
					( Status sCSetFlattened )
					( Origin gBackEnd )
				)
				( attribute "RELATIVE_PROPAGATION_DELAY" "0.00 MIL,195.00 MIL"
					( Parent
						( matchGroupRef "@baseboard_fab2_lib.baseboard_fab2(sch_1):\MG_DQ-DQS_NEAR_DIMM_NG_M_F_BYTE3\" )
					)
					( Units "uMatchProp" "ns" 1.000000)
					( Status sCSetFlattened )
					( Origin gBackEnd )
				)
				( attribute "RELATIVE_PROPAGATION_DELAY_SCOPE" "G"
					( Parent
						( matchGroupRef "@crescent_city_bb_fab1_lib.crescent_city_bb_fab1(sch_1):\MG_DQ_NEAR_DIMM_NG_M_F_BYTE3\" )
					)
					( Status sCSetFlattened )
					( Origin gBackEnd )
				)
				( attribute "RELATIVE_PROPAGATION_DELAY" "-50.00 MIL,50.00 MIL"
					( Parent
						( matchGroupRef "@crescent_city_bb_fab1_lib.crescent_city_bb_fab1(sch_1):\MG_DQ_NEAR_DIMM_NG_M_F_BYTE3\" )
					)
					( Units "uMatchProp" "ns" 1.000000)
					( Status sCSetFlattened )
					( Origin gBackEnd )
				)
			)
			( pinPair "@baseboard_fab2_lib.baseboard_fab2(sch_1):\PP4200\"
				( pinRef "@baseboard_fab2_lib.baseboard_fab2(sch_1):page28_i172:DDR5_DQ(31)" )
				( pinRef "@baseboard_fab2_lib.baseboard_fab2(sch_1):page53_i111:DQ(30)" )
				( attribute "RELATIVE_PROPAGATION_DELAY_SCOPE" "G"
					( Parent
						( matchGroupRef "@baseboard_fab2_lib.baseboard_fab2(sch_1):\MG_DQ-DQS_FAR_DIMM_NG_M_F_BYTE3\" )
					)
					( Status sCSetFlattened )
					( Origin gBackEnd )
				)
				( attribute "RELATIVE_PROPAGATION_DELAY" "0.00 MIL,195.00 MIL"
					( Parent
						( matchGroupRef "@baseboard_fab2_lib.baseboard_fab2(sch_1):\MG_DQ-DQS_FAR_DIMM_NG_M_F_BYTE3\" )
					)
					( Units "uMatchProp" "ns" 1.000000)
					( Status sCSetFlattened )
					( Origin gBackEnd )
				)
				( attribute "RELATIVE_PROPAGATION_DELAY_SCOPE" "G"
					( Parent
						( matchGroupRef "@baseboard_fab2_lib.baseboard_fab2(sch_1):\MG_DQ_FAR_DIMM_NG_M_F_BYTE3\" )
					)
					( Status sCSetFlattened )
					( Origin gBackEnd )
				)
				( attribute "RELATIVE_PROPAGATION_DELAY" "-50.00 MIL,50.00 MIL"
					( Parent
						( matchGroupRef "@baseboard_fab2_lib.baseboard_fab2(sch_1):\MG_DQ_FAR_DIMM_NG_M_F_BYTE3\" )
					)
					( Units "uMatchProp" "ns" 1.000000)
					( Status sCSetFlattened )
					( Origin gBackEnd )
				)
			)
			( pinPair "@baseboard_fab2_lib.baseboard_fab2(sch_1):\PP4202\"
				( pinRef "@baseboard_fab2_lib.baseboard_fab2(sch_1):page54_i111:DQ(31)" )
				( pinRef "@baseboard_fab2_lib.baseboard_fab2(sch_1):page28_i172:DDR5_DQ(31)" )
				( attribute "RELATIVE_PROPAGATION_DELAY_SCOPE" "G"
					( Parent
						( matchGroupRef "@baseboard_fab2_lib.baseboard_fab2(sch_1):\MG_DQ-DQS_NEAR_DIMM_NG_M_F_BYTE3\" )
					)
					( Status sCSetFlattened )
					( Origin gBackEnd )
				)
				( attribute "RELATIVE_PROPAGATION_DELAY" "0.00 MIL,195.00 MIL"
					( Parent
						( matchGroupRef "@baseboard_fab2_lib.baseboard_fab2(sch_1):\MG_DQ-DQS_NEAR_DIMM_NG_M_F_BYTE3\" )
					)
					( Units "uMatchProp" "ns" 1.000000)
					( Status sCSetFlattened )
					( Origin gBackEnd )
				)
				( attribute "RELATIVE_PROPAGATION_DELAY_SCOPE" "G"
					( Parent
						( matchGroupRef "@crescent_city_bb_fab1_lib.crescent_city_bb_fab1(sch_1):\MG_DQ_NEAR_DIMM_NG_M_F_BYTE3\" )
					)
					( Status sCSetFlattened )
					( Origin gBackEnd )
				)
				( attribute "RELATIVE_PROPAGATION_DELAY" "-50.00 MIL,50.00 MIL"
					( Parent
						( matchGroupRef "@crescent_city_bb_fab1_lib.crescent_city_bb_fab1(sch_1):\MG_DQ_NEAR_DIMM_NG_M_F_BYTE3\" )
					)
					( Units "uMatchProp" "ns" 1.000000)
					( Status sCSetFlattened )
					( Origin gBackEnd )
				)
			)
			( pinPair "@baseboard_fab2_lib.baseboard_fab2(sch_1):\PP4155\"
				( pinRef "@baseboard_fab2_lib.baseboard_fab2(sch_1):page28_i172:DDR5_DQ(32)" )
				( pinRef "@baseboard_fab2_lib.baseboard_fab2(sch_1):page53_i111:DQ(33)" )
				( attribute "RELATIVE_PROPAGATION_DELAY_SCOPE" "G"
					( Parent
						( matchGroupRef "@baseboard_fab2_lib.baseboard_fab2(sch_1):\MG_DQ-DQS_FAR_DIMM_NG_M_F_BYTE4\" )
					)
					( Status sCSetFlattened )
					( Origin gBackEnd )
				)
				( attribute "RELATIVE_PROPAGATION_DELAY" "0.00 MIL,195.00 MIL"
					( Parent
						( matchGroupRef "@baseboard_fab2_lib.baseboard_fab2(sch_1):\MG_DQ-DQS_FAR_DIMM_NG_M_F_BYTE4\" )
					)
					( Units "uMatchProp" "ns" 1.000000)
					( Status sCSetFlattened )
					( Origin gBackEnd )
				)
				( attribute "RELATIVE_PROPAGATION_DELAY_SCOPE" "G"
					( Parent
						( matchGroupRef "@crescent_city_bb_fab1_lib.crescent_city_bb_fab1(sch_1):\MG_DQ_FAR_DIMM_NG_M_F_BYTE4\" )
					)
					( Status sCSetFlattened )
					( Origin gBackEnd )
				)
				( attribute "RELATIVE_PROPAGATION_DELAY" "-50.00 MIL,50.00 MIL"
					( Parent
						( matchGroupRef "@crescent_city_bb_fab1_lib.crescent_city_bb_fab1(sch_1):\MG_DQ_FAR_DIMM_NG_M_F_BYTE4\" )
					)
					( Units "uMatchProp" "ns" 1.000000)
					( Status sCSetFlattened )
					( Origin gBackEnd )
				)
			)
			( pinPair "@baseboard_fab2_lib.baseboard_fab2(sch_1):\PP4156\"
				( pinRef "@baseboard_fab2_lib.baseboard_fab2(sch_1):page28_i172:DDR5_DQ(32)" )
				( pinRef "@baseboard_fab2_lib.baseboard_fab2(sch_1):page54_i111:DQ(32)" )
				( attribute "RELATIVE_PROPAGATION_DELAY_SCOPE" "G"
					( Parent
						( matchGroupRef "@baseboard_fab2_lib.baseboard_fab2(sch_1):\MG_DQ-DQS_NEAR_DIMM_NG_M_F_BYTE4\" )
					)
					( Status sCSetFlattened )
					( Origin gBackEnd )
				)
				( attribute "RELATIVE_PROPAGATION_DELAY" "0.00 MIL,195.00 MIL"
					( Parent
						( matchGroupRef "@baseboard_fab2_lib.baseboard_fab2(sch_1):\MG_DQ-DQS_NEAR_DIMM_NG_M_F_BYTE4\" )
					)
					( Units "uMatchProp" "ns" 1.000000)
					( Status sCSetFlattened )
					( Origin gBackEnd )
				)
				( attribute "RELATIVE_PROPAGATION_DELAY_SCOPE" "G"
					( Parent
						( matchGroupRef "@crescent_city_bb_fab1_lib.crescent_city_bb_fab1(sch_1):\MG_DQ_NEAR_DIMM_NG_M_F_BYTE4\" )
					)
					( Status sCSetFlattened )
					( Origin gBackEnd )
				)
				( attribute "RELATIVE_PROPAGATION_DELAY" "-50.00 MIL,50.00 MIL"
					( Parent
						( matchGroupRef "@crescent_city_bb_fab1_lib.crescent_city_bb_fab1(sch_1):\MG_DQ_NEAR_DIMM_NG_M_F_BYTE4\" )
					)
					( Units "uMatchProp" "ns" 1.000000)
					( Status sCSetFlattened )
					( Origin gBackEnd )
				)
			)
			( pinPair "@baseboard_fab2_lib.baseboard_fab2(sch_1):\PP4158\"
				( pinRef "@baseboard_fab2_lib.baseboard_fab2(sch_1):page28_i172:DDR5_DQ(33)" )
				( pinRef "@baseboard_fab2_lib.baseboard_fab2(sch_1):page53_i111:DQ(32)" )
				( attribute "RELATIVE_PROPAGATION_DELAY_SCOPE" "G"
					( Parent
						( matchGroupRef "@baseboard_fab2_lib.baseboard_fab2(sch_1):\MG_DQ-DQS_FAR_DIMM_NG_M_F_BYTE4\" )
					)
					( Status sCSetFlattened )
					( Origin gBackEnd )
				)
				( attribute "RELATIVE_PROPAGATION_DELAY" "0.00 MIL,195.00 MIL"
					( Parent
						( matchGroupRef "@baseboard_fab2_lib.baseboard_fab2(sch_1):\MG_DQ-DQS_FAR_DIMM_NG_M_F_BYTE4\" )
					)
					( Units "uMatchProp" "ns" 1.000000)
					( Status sCSetFlattened )
					( Origin gBackEnd )
				)
				( attribute "RELATIVE_PROPAGATION_DELAY_SCOPE" "G"
					( Parent
						( matchGroupRef "@crescent_city_bb_fab1_lib.crescent_city_bb_fab1(sch_1):\MG_DQ_FAR_DIMM_NG_M_F_BYTE4\" )
					)
					( Status sCSetFlattened )
					( Origin gBackEnd )
				)
				( attribute "RELATIVE_PROPAGATION_DELAY" "-50.00 MIL,50.00 MIL"
					( Parent
						( matchGroupRef "@crescent_city_bb_fab1_lib.crescent_city_bb_fab1(sch_1):\MG_DQ_FAR_DIMM_NG_M_F_BYTE4\" )
					)
					( Units "uMatchProp" "ns" 1.000000)
					( Status sCSetFlattened )
					( Origin gBackEnd )
				)
			)
			( pinPair "@baseboard_fab2_lib.baseboard_fab2(sch_1):\PP4159\"
				( pinRef "@baseboard_fab2_lib.baseboard_fab2(sch_1):page28_i172:DDR5_DQ(33)" )
				( pinRef "@baseboard_fab2_lib.baseboard_fab2(sch_1):page54_i111:DQ(33)" )
				( attribute "RELATIVE_PROPAGATION_DELAY_SCOPE" "G"
					( Parent
						( matchGroupRef "@baseboard_fab2_lib.baseboard_fab2(sch_1):\MG_DQ-DQS_NEAR_DIMM_NG_M_F_BYTE4\" )
					)
					( Status sCSetFlattened )
					( Origin gBackEnd )
				)
				( attribute "RELATIVE_PROPAGATION_DELAY" "0.00 MIL,195.00 MIL"
					( Parent
						( matchGroupRef "@baseboard_fab2_lib.baseboard_fab2(sch_1):\MG_DQ-DQS_NEAR_DIMM_NG_M_F_BYTE4\" )
					)
					( Units "uMatchProp" "ns" 1.000000)
					( Status sCSetFlattened )
					( Origin gBackEnd )
				)
				( attribute "RELATIVE_PROPAGATION_DELAY_SCOPE" "G"
					( Parent
						( matchGroupRef "@crescent_city_bb_fab1_lib.crescent_city_bb_fab1(sch_1):\MG_DQ_NEAR_DIMM_NG_M_F_BYTE4\" )
					)
					( Status sCSetFlattened )
					( Origin gBackEnd )
				)
				( attribute "RELATIVE_PROPAGATION_DELAY" "-50.00 MIL,50.00 MIL"
					( Parent
						( matchGroupRef "@crescent_city_bb_fab1_lib.crescent_city_bb_fab1(sch_1):\MG_DQ_NEAR_DIMM_NG_M_F_BYTE4\" )
					)
					( Units "uMatchProp" "ns" 1.000000)
					( Status sCSetFlattened )
					( Origin gBackEnd )
				)
			)
			( pinPair "@baseboard_fab2_lib.baseboard_fab2(sch_1):\PP4161\"
				( pinRef "@baseboard_fab2_lib.baseboard_fab2(sch_1):page28_i172:DDR5_DQ(34)" )
				( pinRef "@baseboard_fab2_lib.baseboard_fab2(sch_1):page53_i111:DQ(35)" )
				( attribute "RELATIVE_PROPAGATION_DELAY_SCOPE" "G"
					( Parent
						( matchGroupRef "@baseboard_fab2_lib.baseboard_fab2(sch_1):\MG_DQ-DQS_FAR_DIMM_NG_M_F_BYTE4\" )
					)
					( Status sCSetFlattened )
					( Origin gBackEnd )
				)
				( attribute "RELATIVE_PROPAGATION_DELAY" "0.00 MIL,195.00 MIL"
					( Parent
						( matchGroupRef "@baseboard_fab2_lib.baseboard_fab2(sch_1):\MG_DQ-DQS_FAR_DIMM_NG_M_F_BYTE4\" )
					)
					( Units "uMatchProp" "ns" 1.000000)
					( Status sCSetFlattened )
					( Origin gBackEnd )
				)
				( attribute "RELATIVE_PROPAGATION_DELAY_SCOPE" "G"
					( Parent
						( matchGroupRef "@crescent_city_bb_fab1_lib.crescent_city_bb_fab1(sch_1):\MG_DQ_FAR_DIMM_NG_M_F_BYTE4\" )
					)
					( Status sCSetFlattened )
					( Origin gBackEnd )
				)
				( attribute "RELATIVE_PROPAGATION_DELAY" "-50.00 MIL,50.00 MIL"
					( Parent
						( matchGroupRef "@crescent_city_bb_fab1_lib.crescent_city_bb_fab1(sch_1):\MG_DQ_FAR_DIMM_NG_M_F_BYTE4\" )
					)
					( Units "uMatchProp" "ns" 1.000000)
					( Status sCSetFlattened )
					( Origin gBackEnd )
				)
			)
			( pinPair "@baseboard_fab2_lib.baseboard_fab2(sch_1):\PP4163\"
				( pinRef "@baseboard_fab2_lib.baseboard_fab2(sch_1):page28_i172:DDR5_DQ(34)" )
				( pinRef "@baseboard_fab2_lib.baseboard_fab2(sch_1):page54_i111:DQ(34)" )
				( attribute "RELATIVE_PROPAGATION_DELAY_SCOPE" "G"
					( Parent
						( matchGroupRef "@baseboard_fab2_lib.baseboard_fab2(sch_1):\MG_DQ-DQS_NEAR_DIMM_NG_M_F_BYTE4\" )
					)
					( Status sCSetFlattened )
					( Origin gBackEnd )
				)
				( attribute "RELATIVE_PROPAGATION_DELAY" "0.00 MIL,195.00 MIL"
					( Parent
						( matchGroupRef "@baseboard_fab2_lib.baseboard_fab2(sch_1):\MG_DQ-DQS_NEAR_DIMM_NG_M_F_BYTE4\" )
					)
					( Units "uMatchProp" "ns" 1.000000)
					( Status sCSetFlattened )
					( Origin gBackEnd )
				)
				( attribute "RELATIVE_PROPAGATION_DELAY_SCOPE" "G"
					( Parent
						( matchGroupRef "@crescent_city_bb_fab1_lib.crescent_city_bb_fab1(sch_1):\MG_DQ_NEAR_DIMM_NG_M_F_BYTE4\" )
					)
					( Status sCSetFlattened )
					( Origin gBackEnd )
				)
				( attribute "RELATIVE_PROPAGATION_DELAY" "-50.00 MIL,50.00 MIL"
					( Parent
						( matchGroupRef "@crescent_city_bb_fab1_lib.crescent_city_bb_fab1(sch_1):\MG_DQ_NEAR_DIMM_NG_M_F_BYTE4\" )
					)
					( Units "uMatchProp" "ns" 1.000000)
					( Status sCSetFlattened )
					( Origin gBackEnd )
				)
			)
			( pinPair "@baseboard_fab2_lib.baseboard_fab2(sch_1):\PP4164\"
				( pinRef "@baseboard_fab2_lib.baseboard_fab2(sch_1):page28_i172:DDR5_DQ(35)" )
				( pinRef "@baseboard_fab2_lib.baseboard_fab2(sch_1):page53_i111:DQ(34)" )
				( attribute "RELATIVE_PROPAGATION_DELAY_SCOPE" "G"
					( Parent
						( matchGroupRef "@baseboard_fab2_lib.baseboard_fab2(sch_1):\MG_DQ-DQS_FAR_DIMM_NG_M_F_BYTE4\" )
					)
					( Status sCSetFlattened )
					( Origin gBackEnd )
				)
				( attribute "RELATIVE_PROPAGATION_DELAY" "0.00 MIL,195.00 MIL"
					( Parent
						( matchGroupRef "@baseboard_fab2_lib.baseboard_fab2(sch_1):\MG_DQ-DQS_FAR_DIMM_NG_M_F_BYTE4\" )
					)
					( Units "uMatchProp" "ns" 1.000000)
					( Status sCSetFlattened )
					( Origin gBackEnd )
				)
				( attribute "RELATIVE_PROPAGATION_DELAY_SCOPE" "G"
					( Parent
						( matchGroupRef "@crescent_city_bb_fab1_lib.crescent_city_bb_fab1(sch_1):\MG_DQ_FAR_DIMM_NG_M_F_BYTE4\" )
					)
					( Status sCSetFlattened )
					( Origin gBackEnd )
				)
				( attribute "RELATIVE_PROPAGATION_DELAY" "-50.00 MIL,50.00 MIL"
					( Parent
						( matchGroupRef "@crescent_city_bb_fab1_lib.crescent_city_bb_fab1(sch_1):\MG_DQ_FAR_DIMM_NG_M_F_BYTE4\" )
					)
					( Units "uMatchProp" "ns" 1.000000)
					( Status sCSetFlattened )
					( Origin gBackEnd )
				)
			)
			( pinPair "@baseboard_fab2_lib.baseboard_fab2(sch_1):\PP4166\"
				( pinRef "@baseboard_fab2_lib.baseboard_fab2(sch_1):page28_i172:DDR5_DQ(35)" )
				( pinRef "@baseboard_fab2_lib.baseboard_fab2(sch_1):page54_i111:DQ(35)" )
				( attribute "RELATIVE_PROPAGATION_DELAY_SCOPE" "G"
					( Parent
						( matchGroupRef "@baseboard_fab2_lib.baseboard_fab2(sch_1):\MG_DQ-DQS_NEAR_DIMM_NG_M_F_BYTE4\" )
					)
					( Status sCSetFlattened )
					( Origin gBackEnd )
				)
				( attribute "RELATIVE_PROPAGATION_DELAY" "0.00 MIL,195.00 MIL"
					( Parent
						( matchGroupRef "@baseboard_fab2_lib.baseboard_fab2(sch_1):\MG_DQ-DQS_NEAR_DIMM_NG_M_F_BYTE4\" )
					)
					( Units "uMatchProp" "ns" 1.000000)
					( Status sCSetFlattened )
					( Origin gBackEnd )
				)
				( attribute "RELATIVE_PROPAGATION_DELAY_SCOPE" "G"
					( Parent
						( matchGroupRef "@crescent_city_bb_fab1_lib.crescent_city_bb_fab1(sch_1):\MG_DQ_NEAR_DIMM_NG_M_F_BYTE4\" )
					)
					( Origin gBackEnd )
				)
				( attribute "RELATIVE_PROPAGATION_DELAY" "TARGET,TARGET"
					( Parent
						( matchGroupRef "@crescent_city_bb_fab1_lib.crescent_city_bb_fab1(sch_1):\MG_DQ_NEAR_DIMM_NG_M_F_BYTE4\" )
					)
					( Units "uMatchProp" "ns" 1.000000)
					( Origin gBackEnd )
				)
			)
			( pinPair "@baseboard_fab2_lib.baseboard_fab2(sch_1):\PP4167\"
				( pinRef "@baseboard_fab2_lib.baseboard_fab2(sch_1):page28_i172:DDR5_DQ(36)" )
				( pinRef "@baseboard_fab2_lib.baseboard_fab2(sch_1):page53_i111:DQ(37)" )
				( attribute "RELATIVE_PROPAGATION_DELAY_SCOPE" "G"
					( Parent
						( matchGroupRef "@baseboard_fab2_lib.baseboard_fab2(sch_1):\MG_DQ-DQS_FAR_DIMM_NG_M_F_BYTE4\" )
					)
					( Status sCSetFlattened )
					( Origin gBackEnd )
				)
				( attribute "RELATIVE_PROPAGATION_DELAY" "0.00 MIL,195.00 MIL"
					( Parent
						( matchGroupRef "@baseboard_fab2_lib.baseboard_fab2(sch_1):\MG_DQ-DQS_FAR_DIMM_NG_M_F_BYTE4\" )
					)
					( Units "uMatchProp" "ns" 1.000000)
					( Status sCSetFlattened )
					( Origin gBackEnd )
				)
				( attribute "RELATIVE_PROPAGATION_DELAY_SCOPE" "G"
					( Parent
						( matchGroupRef "@crescent_city_bb_fab1_lib.crescent_city_bb_fab1(sch_1):\MG_DQ_FAR_DIMM_NG_M_F_BYTE4\" )
					)
					( Origin gBackEnd )
				)
				( attribute "RELATIVE_PROPAGATION_DELAY" "TARGET,TARGET"
					( Parent
						( matchGroupRef "@crescent_city_bb_fab1_lib.crescent_city_bb_fab1(sch_1):\MG_DQ_FAR_DIMM_NG_M_F_BYTE4\" )
					)
					( Units "uMatchProp" "ns" 1.000000)
					( Origin gBackEnd )
				)
			)
			( pinPair "@baseboard_fab2_lib.baseboard_fab2(sch_1):\PP4168\"
				( pinRef "@baseboard_fab2_lib.baseboard_fab2(sch_1):page28_i172:DDR5_DQ(36)" )
				( pinRef "@baseboard_fab2_lib.baseboard_fab2(sch_1):page54_i111:DQ(36)" )
				( attribute "RELATIVE_PROPAGATION_DELAY_SCOPE" "G"
					( Parent
						( matchGroupRef "@baseboard_fab2_lib.baseboard_fab2(sch_1):\MG_DQ-DQS_NEAR_DIMM_NG_M_F_BYTE4\" )
					)
					( Status sCSetFlattened )
					( Origin gBackEnd )
				)
				( attribute "RELATIVE_PROPAGATION_DELAY" "0.00 MIL,195.00 MIL"
					( Parent
						( matchGroupRef "@baseboard_fab2_lib.baseboard_fab2(sch_1):\MG_DQ-DQS_NEAR_DIMM_NG_M_F_BYTE4\" )
					)
					( Units "uMatchProp" "ns" 1.000000)
					( Status sCSetFlattened )
					( Origin gBackEnd )
				)
				( attribute "RELATIVE_PROPAGATION_DELAY_SCOPE" "G"
					( Parent
						( matchGroupRef "@crescent_city_bb_fab1_lib.crescent_city_bb_fab1(sch_1):\MG_DQ_NEAR_DIMM_NG_M_F_BYTE4\" )
					)
					( Status sCSetFlattened )
					( Origin gBackEnd )
				)
				( attribute "RELATIVE_PROPAGATION_DELAY" "-50.00 MIL,50.00 MIL"
					( Parent
						( matchGroupRef "@crescent_city_bb_fab1_lib.crescent_city_bb_fab1(sch_1):\MG_DQ_NEAR_DIMM_NG_M_F_BYTE4\" )
					)
					( Units "uMatchProp" "ns" 1.000000)
					( Status sCSetFlattened )
					( Origin gBackEnd )
				)
			)
			( pinPair "@baseboard_fab2_lib.baseboard_fab2(sch_1):\PP4170\"
				( pinRef "@baseboard_fab2_lib.baseboard_fab2(sch_1):page28_i172:DDR5_DQ(37)" )
				( pinRef "@baseboard_fab2_lib.baseboard_fab2(sch_1):page53_i111:DQ(36)" )
				( attribute "RELATIVE_PROPAGATION_DELAY_SCOPE" "G"
					( Parent
						( matchGroupRef "@baseboard_fab2_lib.baseboard_fab2(sch_1):\MG_DQ-DQS_FAR_DIMM_NG_M_F_BYTE4\" )
					)
					( Status sCSetFlattened )
					( Origin gBackEnd )
				)
				( attribute "RELATIVE_PROPAGATION_DELAY" "0.00 MIL,195.00 MIL"
					( Parent
						( matchGroupRef "@baseboard_fab2_lib.baseboard_fab2(sch_1):\MG_DQ-DQS_FAR_DIMM_NG_M_F_BYTE4\" )
					)
					( Units "uMatchProp" "ns" 1.000000)
					( Status sCSetFlattened )
					( Origin gBackEnd )
				)
				( attribute "RELATIVE_PROPAGATION_DELAY_SCOPE" "G"
					( Parent
						( matchGroupRef "@crescent_city_bb_fab1_lib.crescent_city_bb_fab1(sch_1):\MG_DQ_FAR_DIMM_NG_M_F_BYTE4\" )
					)
					( Status sCSetFlattened )
					( Origin gBackEnd )
				)
				( attribute "RELATIVE_PROPAGATION_DELAY" "-50.00 MIL,50.00 MIL"
					( Parent
						( matchGroupRef "@crescent_city_bb_fab1_lib.crescent_city_bb_fab1(sch_1):\MG_DQ_FAR_DIMM_NG_M_F_BYTE4\" )
					)
					( Units "uMatchProp" "ns" 1.000000)
					( Status sCSetFlattened )
					( Origin gBackEnd )
				)
			)
			( pinPair "@baseboard_fab2_lib.baseboard_fab2(sch_1):\PP4172\"
				( pinRef "@baseboard_fab2_lib.baseboard_fab2(sch_1):page28_i172:DDR5_DQ(37)" )
				( pinRef "@baseboard_fab2_lib.baseboard_fab2(sch_1):page54_i111:DQ(37)" )
				( attribute "RELATIVE_PROPAGATION_DELAY_SCOPE" "G"
					( Parent
						( matchGroupRef "@baseboard_fab2_lib.baseboard_fab2(sch_1):\MG_DQ-DQS_NEAR_DIMM_NG_M_F_BYTE4\" )
					)
					( Status sCSetFlattened )
					( Origin gBackEnd )
				)
				( attribute "RELATIVE_PROPAGATION_DELAY" "0.00 MIL,195.00 MIL"
					( Parent
						( matchGroupRef "@baseboard_fab2_lib.baseboard_fab2(sch_1):\MG_DQ-DQS_NEAR_DIMM_NG_M_F_BYTE4\" )
					)
					( Units "uMatchProp" "ns" 1.000000)
					( Status sCSetFlattened )
					( Origin gBackEnd )
				)
				( attribute "RELATIVE_PROPAGATION_DELAY_SCOPE" "G"
					( Parent
						( matchGroupRef "@crescent_city_bb_fab1_lib.crescent_city_bb_fab1(sch_1):\MG_DQ_NEAR_DIMM_NG_M_F_BYTE4\" )
					)
					( Status sCSetFlattened )
					( Origin gBackEnd )
				)
				( attribute "RELATIVE_PROPAGATION_DELAY" "-50.00 MIL,50.00 MIL"
					( Parent
						( matchGroupRef "@crescent_city_bb_fab1_lib.crescent_city_bb_fab1(sch_1):\MG_DQ_NEAR_DIMM_NG_M_F_BYTE4\" )
					)
					( Units "uMatchProp" "ns" 1.000000)
					( Status sCSetFlattened )
					( Origin gBackEnd )
				)
			)
			( pinPair "@baseboard_fab2_lib.baseboard_fab2(sch_1):\PP4173\"
				( pinRef "@baseboard_fab2_lib.baseboard_fab2(sch_1):page28_i172:DDR5_DQ(38)" )
				( pinRef "@baseboard_fab2_lib.baseboard_fab2(sch_1):page53_i111:DQ(39)" )
				( attribute "RELATIVE_PROPAGATION_DELAY_SCOPE" "G"
					( Parent
						( matchGroupRef "@baseboard_fab2_lib.baseboard_fab2(sch_1):\MG_DQ-DQS_FAR_DIMM_NG_M_F_BYTE4\" )
					)
					( Status sCSetFlattened )
					( Origin gBackEnd )
				)
				( attribute "RELATIVE_PROPAGATION_DELAY" "0.00 MIL,195.00 MIL"
					( Parent
						( matchGroupRef "@baseboard_fab2_lib.baseboard_fab2(sch_1):\MG_DQ-DQS_FAR_DIMM_NG_M_F_BYTE4\" )
					)
					( Units "uMatchProp" "ns" 1.000000)
					( Status sCSetFlattened )
					( Origin gBackEnd )
				)
				( attribute "RELATIVE_PROPAGATION_DELAY_SCOPE" "G"
					( Parent
						( matchGroupRef "@crescent_city_bb_fab1_lib.crescent_city_bb_fab1(sch_1):\MG_DQ_FAR_DIMM_NG_M_F_BYTE4\" )
					)
					( Status sCSetFlattened )
					( Origin gBackEnd )
				)
				( attribute "RELATIVE_PROPAGATION_DELAY" "-50.00 MIL,50.00 MIL"
					( Parent
						( matchGroupRef "@crescent_city_bb_fab1_lib.crescent_city_bb_fab1(sch_1):\MG_DQ_FAR_DIMM_NG_M_F_BYTE4\" )
					)
					( Units "uMatchProp" "ns" 1.000000)
					( Status sCSetFlattened )
					( Origin gBackEnd )
				)
			)
			( pinPair "@baseboard_fab2_lib.baseboard_fab2(sch_1):\PP4175\"
				( pinRef "@baseboard_fab2_lib.baseboard_fab2(sch_1):page28_i172:DDR5_DQ(38)" )
				( pinRef "@baseboard_fab2_lib.baseboard_fab2(sch_1):page54_i111:DQ(38)" )
				( attribute "RELATIVE_PROPAGATION_DELAY_SCOPE" "G"
					( Parent
						( matchGroupRef "@baseboard_fab2_lib.baseboard_fab2(sch_1):\MG_DQ-DQS_NEAR_DIMM_NG_M_F_BYTE4\" )
					)
					( Status sCSetFlattened )
					( Origin gBackEnd )
				)
				( attribute "RELATIVE_PROPAGATION_DELAY" "0.00 MIL,195.00 MIL"
					( Parent
						( matchGroupRef "@baseboard_fab2_lib.baseboard_fab2(sch_1):\MG_DQ-DQS_NEAR_DIMM_NG_M_F_BYTE4\" )
					)
					( Units "uMatchProp" "ns" 1.000000)
					( Status sCSetFlattened )
					( Origin gBackEnd )
				)
				( attribute "RELATIVE_PROPAGATION_DELAY_SCOPE" "G"
					( Parent
						( matchGroupRef "@crescent_city_bb_fab1_lib.crescent_city_bb_fab1(sch_1):\MG_DQ_NEAR_DIMM_NG_M_F_BYTE4\" )
					)
					( Status sCSetFlattened )
					( Origin gBackEnd )
				)
				( attribute "RELATIVE_PROPAGATION_DELAY" "-50.00 MIL,50.00 MIL"
					( Parent
						( matchGroupRef "@crescent_city_bb_fab1_lib.crescent_city_bb_fab1(sch_1):\MG_DQ_NEAR_DIMM_NG_M_F_BYTE4\" )
					)
					( Units "uMatchProp" "ns" 1.000000)
					( Status sCSetFlattened )
					( Origin gBackEnd )
				)
			)
			( pinPair "@baseboard_fab2_lib.baseboard_fab2(sch_1):\PP4176\"
				( pinRef "@baseboard_fab2_lib.baseboard_fab2(sch_1):page28_i172:DDR5_DQ(39)" )
				( pinRef "@baseboard_fab2_lib.baseboard_fab2(sch_1):page53_i111:DQ(38)" )
				( attribute "RELATIVE_PROPAGATION_DELAY_SCOPE" "G"
					( Parent
						( matchGroupRef "@baseboard_fab2_lib.baseboard_fab2(sch_1):\MG_DQ-DQS_FAR_DIMM_NG_M_F_BYTE4\" )
					)
					( Status sCSetFlattened )
					( Origin gBackEnd )
				)
				( attribute "RELATIVE_PROPAGATION_DELAY" "0.00 MIL,195.00 MIL"
					( Parent
						( matchGroupRef "@baseboard_fab2_lib.baseboard_fab2(sch_1):\MG_DQ-DQS_FAR_DIMM_NG_M_F_BYTE4\" )
					)
					( Units "uMatchProp" "ns" 1.000000)
					( Status sCSetFlattened )
					( Origin gBackEnd )
				)
				( attribute "RELATIVE_PROPAGATION_DELAY_SCOPE" "G"
					( Parent
						( matchGroupRef "@crescent_city_bb_fab1_lib.crescent_city_bb_fab1(sch_1):\MG_DQ_FAR_DIMM_NG_M_F_BYTE4\" )
					)
					( Status sCSetFlattened )
					( Origin gBackEnd )
				)
				( attribute "RELATIVE_PROPAGATION_DELAY" "-50.00 MIL,50.00 MIL"
					( Parent
						( matchGroupRef "@crescent_city_bb_fab1_lib.crescent_city_bb_fab1(sch_1):\MG_DQ_FAR_DIMM_NG_M_F_BYTE4\" )
					)
					( Units "uMatchProp" "ns" 1.000000)
					( Status sCSetFlattened )
					( Origin gBackEnd )
				)
			)
			( pinPair "@baseboard_fab2_lib.baseboard_fab2(sch_1):\PP4178\"
				( pinRef "@baseboard_fab2_lib.baseboard_fab2(sch_1):page28_i172:DDR5_DQ(39)" )
				( pinRef "@baseboard_fab2_lib.baseboard_fab2(sch_1):page54_i111:DQ(39)" )
				( attribute "RELATIVE_PROPAGATION_DELAY_SCOPE" "G"
					( Parent
						( matchGroupRef "@baseboard_fab2_lib.baseboard_fab2(sch_1):\MG_DQ-DQS_NEAR_DIMM_NG_M_F_BYTE4\" )
					)
					( Status sCSetFlattened )
					( Origin gBackEnd )
				)
				( attribute "RELATIVE_PROPAGATION_DELAY" "0.00 MIL,195.00 MIL"
					( Parent
						( matchGroupRef "@baseboard_fab2_lib.baseboard_fab2(sch_1):\MG_DQ-DQS_NEAR_DIMM_NG_M_F_BYTE4\" )
					)
					( Units "uMatchProp" "ns" 1.000000)
					( Status sCSetFlattened )
					( Origin gBackEnd )
				)
				( attribute "RELATIVE_PROPAGATION_DELAY_SCOPE" "G"
					( Parent
						( matchGroupRef "@crescent_city_bb_fab1_lib.crescent_city_bb_fab1(sch_1):\MG_DQ_NEAR_DIMM_NG_M_F_BYTE4\" )
					)
					( Status sCSetFlattened )
					( Origin gBackEnd )
				)
				( attribute "RELATIVE_PROPAGATION_DELAY" "-50.00 MIL,50.00 MIL"
					( Parent
						( matchGroupRef "@crescent_city_bb_fab1_lib.crescent_city_bb_fab1(sch_1):\MG_DQ_NEAR_DIMM_NG_M_F_BYTE4\" )
					)
					( Units "uMatchProp" "ns" 1.000000)
					( Status sCSetFlattened )
					( Origin gBackEnd )
				)
			)
			( pinPair "@baseboard_fab2_lib.baseboard_fab2(sch_1):\PP4131\"
				( pinRef "@baseboard_fab2_lib.baseboard_fab2(sch_1):page28_i172:DDR5_DQ(40)" )
				( pinRef "@baseboard_fab2_lib.baseboard_fab2(sch_1):page53_i111:DQ(41)" )
				( attribute "RELATIVE_PROPAGATION_DELAY_SCOPE" "G"
					( Parent
						( matchGroupRef "@baseboard_fab2_lib.baseboard_fab2(sch_1):\MG_DQ-DQS_FAR_DIMM_NG_M_F_BYTE5\" )
					)
					( Status sCSetFlattened )
					( Origin gBackEnd )
				)
				( attribute "RELATIVE_PROPAGATION_DELAY" "0.00 MIL,195.00 MIL"
					( Parent
						( matchGroupRef "@baseboard_fab2_lib.baseboard_fab2(sch_1):\MG_DQ-DQS_FAR_DIMM_NG_M_F_BYTE5\" )
					)
					( Units "uMatchProp" "ns" 1.000000)
					( Status sCSetFlattened )
					( Origin gBackEnd )
				)
				( attribute "RELATIVE_PROPAGATION_DELAY_SCOPE" "G"
					( Parent
						( matchGroupRef "@baseboard_fab2_lib.baseboard_fab2(sch_1):\MG_DQ_FAR_DIMM_NG_M_F_BYTE5\" )
					)
					( Status sCSetFlattened )
					( Origin gBackEnd )
				)
				( attribute "RELATIVE_PROPAGATION_DELAY" "-50.00 MIL,50.00 MIL"
					( Parent
						( matchGroupRef "@baseboard_fab2_lib.baseboard_fab2(sch_1):\MG_DQ_FAR_DIMM_NG_M_F_BYTE5\" )
					)
					( Units "uMatchProp" "ns" 1.000000)
					( Status sCSetFlattened )
					( Origin gBackEnd )
				)
			)
			( pinPair "@baseboard_fab2_lib.baseboard_fab2(sch_1):\PP4133\"
				( pinRef "@baseboard_fab2_lib.baseboard_fab2(sch_1):page28_i172:DDR5_DQ(40)" )
				( pinRef "@baseboard_fab2_lib.baseboard_fab2(sch_1):page54_i111:DQ(40)" )
				( attribute "RELATIVE_PROPAGATION_DELAY_SCOPE" "G"
					( Parent
						( matchGroupRef "@baseboard_fab2_lib.baseboard_fab2(sch_1):\MG_DQ-DQS_NEAR_DIMM_NG_M_F_BYTE5\" )
					)
					( Status sCSetFlattened )
					( Origin gBackEnd )
				)
				( attribute "RELATIVE_PROPAGATION_DELAY" "0.00 MIL,195.00 MIL"
					( Parent
						( matchGroupRef "@baseboard_fab2_lib.baseboard_fab2(sch_1):\MG_DQ-DQS_NEAR_DIMM_NG_M_F_BYTE5\" )
					)
					( Units "uMatchProp" "ns" 1.000000)
					( Status sCSetFlattened )
					( Origin gBackEnd )
				)
				( attribute "RELATIVE_PROPAGATION_DELAY_SCOPE" "G"
					( Parent
						( matchGroupRef "@crescent_city_bb_fab1_lib.crescent_city_bb_fab1(sch_1):\MG_DQ_NEAR_DIMM_NG_M_F_BYTE5\" )
					)
					( Status sCSetFlattened )
					( Origin gBackEnd )
				)
				( attribute "RELATIVE_PROPAGATION_DELAY" "-50.00 MIL,50.00 MIL"
					( Parent
						( matchGroupRef "@crescent_city_bb_fab1_lib.crescent_city_bb_fab1(sch_1):\MG_DQ_NEAR_DIMM_NG_M_F_BYTE5\" )
					)
					( Units "uMatchProp" "ns" 1.000000)
					( Status sCSetFlattened )
					( Origin gBackEnd )
				)
			)
			( pinPair "@baseboard_fab2_lib.baseboard_fab2(sch_1):\PP4134\"
				( pinRef "@baseboard_fab2_lib.baseboard_fab2(sch_1):page28_i172:DDR5_DQ(41)" )
				( pinRef "@baseboard_fab2_lib.baseboard_fab2(sch_1):page53_i111:DQ(40)" )
				( attribute "RELATIVE_PROPAGATION_DELAY_SCOPE" "G"
					( Parent
						( matchGroupRef "@baseboard_fab2_lib.baseboard_fab2(sch_1):\MG_DQ-DQS_FAR_DIMM_NG_M_F_BYTE5\" )
					)
					( Status sCSetFlattened )
					( Origin gBackEnd )
				)
				( attribute "RELATIVE_PROPAGATION_DELAY" "0.00 MIL,195.00 MIL"
					( Parent
						( matchGroupRef "@baseboard_fab2_lib.baseboard_fab2(sch_1):\MG_DQ-DQS_FAR_DIMM_NG_M_F_BYTE5\" )
					)
					( Units "uMatchProp" "ns" 1.000000)
					( Status sCSetFlattened )
					( Origin gBackEnd )
				)
				( attribute "RELATIVE_PROPAGATION_DELAY_SCOPE" "G"
					( Parent
						( matchGroupRef "@baseboard_fab2_lib.baseboard_fab2(sch_1):\MG_DQ_FAR_DIMM_NG_M_F_BYTE5\" )
					)
					( Status sCSetFlattened )
					( Origin gBackEnd )
				)
				( attribute "RELATIVE_PROPAGATION_DELAY" "-50.00 MIL,50.00 MIL"
					( Parent
						( matchGroupRef "@baseboard_fab2_lib.baseboard_fab2(sch_1):\MG_DQ_FAR_DIMM_NG_M_F_BYTE5\" )
					)
					( Units "uMatchProp" "ns" 1.000000)
					( Status sCSetFlattened )
					( Origin gBackEnd )
				)
			)
			( pinPair "@baseboard_fab2_lib.baseboard_fab2(sch_1):\PP4136\"
				( pinRef "@baseboard_fab2_lib.baseboard_fab2(sch_1):page28_i172:DDR5_DQ(41)" )
				( pinRef "@baseboard_fab2_lib.baseboard_fab2(sch_1):page54_i111:DQ(41)" )
				( attribute "RELATIVE_PROPAGATION_DELAY_SCOPE" "G"
					( Parent
						( matchGroupRef "@baseboard_fab2_lib.baseboard_fab2(sch_1):\MG_DQ-DQS_NEAR_DIMM_NG_M_F_BYTE5\" )
					)
					( Status sCSetFlattened )
					( Origin gBackEnd )
				)
				( attribute "RELATIVE_PROPAGATION_DELAY" "0.00 MIL,195.00 MIL"
					( Parent
						( matchGroupRef "@baseboard_fab2_lib.baseboard_fab2(sch_1):\MG_DQ-DQS_NEAR_DIMM_NG_M_F_BYTE5\" )
					)
					( Units "uMatchProp" "ns" 1.000000)
					( Status sCSetFlattened )
					( Origin gBackEnd )
				)
				( attribute "RELATIVE_PROPAGATION_DELAY_SCOPE" "G"
					( Parent
						( matchGroupRef "@crescent_city_bb_fab1_lib.crescent_city_bb_fab1(sch_1):\MG_DQ_NEAR_DIMM_NG_M_F_BYTE5\" )
					)
					( Status sCSetFlattened )
					( Origin gBackEnd )
				)
				( attribute "RELATIVE_PROPAGATION_DELAY" "-50.00 MIL,50.00 MIL"
					( Parent
						( matchGroupRef "@crescent_city_bb_fab1_lib.crescent_city_bb_fab1(sch_1):\MG_DQ_NEAR_DIMM_NG_M_F_BYTE5\" )
					)
					( Units "uMatchProp" "ns" 1.000000)
					( Status sCSetFlattened )
					( Origin gBackEnd )
				)
			)
			( pinPair "@baseboard_fab2_lib.baseboard_fab2(sch_1):\PP4137\"
				( pinRef "@baseboard_fab2_lib.baseboard_fab2(sch_1):page28_i172:DDR5_DQ(42)" )
				( pinRef "@baseboard_fab2_lib.baseboard_fab2(sch_1):page53_i111:DQ(43)" )
				( attribute "RELATIVE_PROPAGATION_DELAY_SCOPE" "G"
					( Parent
						( matchGroupRef "@baseboard_fab2_lib.baseboard_fab2(sch_1):\MG_DQ-DQS_FAR_DIMM_NG_M_F_BYTE5\" )
					)
					( Status sCSetFlattened )
					( Origin gBackEnd )
				)
				( attribute "RELATIVE_PROPAGATION_DELAY" "0.00 MIL,195.00 MIL"
					( Parent
						( matchGroupRef "@baseboard_fab2_lib.baseboard_fab2(sch_1):\MG_DQ-DQS_FAR_DIMM_NG_M_F_BYTE5\" )
					)
					( Units "uMatchProp" "ns" 1.000000)
					( Status sCSetFlattened )
					( Origin gBackEnd )
				)
				( attribute "RELATIVE_PROPAGATION_DELAY_SCOPE" "G"
					( Parent
						( matchGroupRef "@baseboard_fab2_lib.baseboard_fab2(sch_1):\MG_DQ_FAR_DIMM_NG_M_F_BYTE5\" )
					)
					( Status sCSetFlattened )
					( Origin gBackEnd )
				)
				( attribute "RELATIVE_PROPAGATION_DELAY" "-50.00 MIL,50.00 MIL"
					( Parent
						( matchGroupRef "@baseboard_fab2_lib.baseboard_fab2(sch_1):\MG_DQ_FAR_DIMM_NG_M_F_BYTE5\" )
					)
					( Units "uMatchProp" "ns" 1.000000)
					( Status sCSetFlattened )
					( Origin gBackEnd )
				)
			)
			( pinPair "@baseboard_fab2_lib.baseboard_fab2(sch_1):\PP4139\"
				( pinRef "@baseboard_fab2_lib.baseboard_fab2(sch_1):page28_i172:DDR5_DQ(42)" )
				( pinRef "@baseboard_fab2_lib.baseboard_fab2(sch_1):page54_i111:DQ(42)" )
				( attribute "RELATIVE_PROPAGATION_DELAY_SCOPE" "G"
					( Parent
						( matchGroupRef "@baseboard_fab2_lib.baseboard_fab2(sch_1):\MG_DQ-DQS_NEAR_DIMM_NG_M_F_BYTE5\" )
					)
					( Status sCSetFlattened )
					( Origin gBackEnd )
				)
				( attribute "RELATIVE_PROPAGATION_DELAY" "0.00 MIL,195.00 MIL"
					( Parent
						( matchGroupRef "@baseboard_fab2_lib.baseboard_fab2(sch_1):\MG_DQ-DQS_NEAR_DIMM_NG_M_F_BYTE5\" )
					)
					( Units "uMatchProp" "ns" 1.000000)
					( Status sCSetFlattened )
					( Origin gBackEnd )
				)
				( attribute "RELATIVE_PROPAGATION_DELAY_SCOPE" "G"
					( Parent
						( matchGroupRef "@crescent_city_bb_fab1_lib.crescent_city_bb_fab1(sch_1):\MG_DQ_NEAR_DIMM_NG_M_F_BYTE5\" )
					)
					( Status sCSetFlattened )
					( Origin gBackEnd )
				)
				( attribute "RELATIVE_PROPAGATION_DELAY" "-50.00 MIL,50.00 MIL"
					( Parent
						( matchGroupRef "@crescent_city_bb_fab1_lib.crescent_city_bb_fab1(sch_1):\MG_DQ_NEAR_DIMM_NG_M_F_BYTE5\" )
					)
					( Units "uMatchProp" "ns" 1.000000)
					( Status sCSetFlattened )
					( Origin gBackEnd )
				)
			)
			( pinPair "@baseboard_fab2_lib.baseboard_fab2(sch_1):\PP4140\"
				( pinRef "@baseboard_fab2_lib.baseboard_fab2(sch_1):page28_i172:DDR5_DQ(43)" )
				( pinRef "@baseboard_fab2_lib.baseboard_fab2(sch_1):page53_i111:DQ(42)" )
				( attribute "RELATIVE_PROPAGATION_DELAY_SCOPE" "G"
					( Parent
						( matchGroupRef "@baseboard_fab2_lib.baseboard_fab2(sch_1):\MG_DQ-DQS_FAR_DIMM_NG_M_F_BYTE5\" )
					)
					( Status sCSetFlattened )
					( Origin gBackEnd )
				)
				( attribute "RELATIVE_PROPAGATION_DELAY" "0.00 MIL,195.00 MIL"
					( Parent
						( matchGroupRef "@baseboard_fab2_lib.baseboard_fab2(sch_1):\MG_DQ-DQS_FAR_DIMM_NG_M_F_BYTE5\" )
					)
					( Units "uMatchProp" "ns" 1.000000)
					( Status sCSetFlattened )
					( Origin gBackEnd )
				)
				( attribute "RELATIVE_PROPAGATION_DELAY_SCOPE" "G"
					( Parent
						( matchGroupRef "@baseboard_fab2_lib.baseboard_fab2(sch_1):\MG_DQ_FAR_DIMM_NG_M_F_BYTE5\" )
					)
					( Status sCSetFlattened )
					( Origin gBackEnd )
				)
				( attribute "RELATIVE_PROPAGATION_DELAY" "-50.00 MIL,50.00 MIL"
					( Parent
						( matchGroupRef "@baseboard_fab2_lib.baseboard_fab2(sch_1):\MG_DQ_FAR_DIMM_NG_M_F_BYTE5\" )
					)
					( Units "uMatchProp" "ns" 1.000000)
					( Status sCSetFlattened )
					( Origin gBackEnd )
				)
			)
			( pinPair "@baseboard_fab2_lib.baseboard_fab2(sch_1):\PP4142\"
				( pinRef "@baseboard_fab2_lib.baseboard_fab2(sch_1):page28_i172:DDR5_DQ(43)" )
				( pinRef "@baseboard_fab2_lib.baseboard_fab2(sch_1):page54_i111:DQ(43)" )
				( attribute "RELATIVE_PROPAGATION_DELAY_SCOPE" "G"
					( Parent
						( matchGroupRef "@baseboard_fab2_lib.baseboard_fab2(sch_1):\MG_DQ-DQS_NEAR_DIMM_NG_M_F_BYTE5\" )
					)
					( Status sCSetFlattened )
					( Origin gBackEnd )
				)
				( attribute "RELATIVE_PROPAGATION_DELAY" "0.00 MIL,195.00 MIL"
					( Parent
						( matchGroupRef "@baseboard_fab2_lib.baseboard_fab2(sch_1):\MG_DQ-DQS_NEAR_DIMM_NG_M_F_BYTE5\" )
					)
					( Units "uMatchProp" "ns" 1.000000)
					( Status sCSetFlattened )
					( Origin gBackEnd )
				)
				( attribute "RELATIVE_PROPAGATION_DELAY_SCOPE" "G"
					( Parent
						( matchGroupRef "@crescent_city_bb_fab1_lib.crescent_city_bb_fab1(sch_1):\MG_DQ_NEAR_DIMM_NG_M_F_BYTE5\" )
					)
					( Status sCSetFlattened )
					( Origin gBackEnd )
				)
				( attribute "RELATIVE_PROPAGATION_DELAY" "-50.00 MIL,50.00 MIL"
					( Parent
						( matchGroupRef "@crescent_city_bb_fab1_lib.crescent_city_bb_fab1(sch_1):\MG_DQ_NEAR_DIMM_NG_M_F_BYTE5\" )
					)
					( Units "uMatchProp" "ns" 1.000000)
					( Status sCSetFlattened )
					( Origin gBackEnd )
				)
			)
			( pinPair "@baseboard_fab2_lib.baseboard_fab2(sch_1):\PP4143\"
				( pinRef "@baseboard_fab2_lib.baseboard_fab2(sch_1):page28_i172:DDR5_DQ(44)" )
				( pinRef "@baseboard_fab2_lib.baseboard_fab2(sch_1):page53_i111:DQ(45)" )
				( attribute "RELATIVE_PROPAGATION_DELAY_SCOPE" "G"
					( Parent
						( matchGroupRef "@baseboard_fab2_lib.baseboard_fab2(sch_1):\MG_DQ-DQS_FAR_DIMM_NG_M_F_BYTE5\" )
					)
					( Status sCSetFlattened )
					( Origin gBackEnd )
				)
				( attribute "RELATIVE_PROPAGATION_DELAY" "0.00 MIL,195.00 MIL"
					( Parent
						( matchGroupRef "@baseboard_fab2_lib.baseboard_fab2(sch_1):\MG_DQ-DQS_FAR_DIMM_NG_M_F_BYTE5\" )
					)
					( Units "uMatchProp" "ns" 1.000000)
					( Status sCSetFlattened )
					( Origin gBackEnd )
				)
				( attribute "RELATIVE_PROPAGATION_DELAY_SCOPE" "G"
					( Parent
						( matchGroupRef "@baseboard_fab2_lib.baseboard_fab2(sch_1):\MG_DQ_FAR_DIMM_NG_M_F_BYTE5\" )
					)
					( Status sCSetFlattened )
					( Origin gBackEnd )
				)
				( attribute "RELATIVE_PROPAGATION_DELAY" "-50.00 MIL,50.00 MIL"
					( Parent
						( matchGroupRef "@baseboard_fab2_lib.baseboard_fab2(sch_1):\MG_DQ_FAR_DIMM_NG_M_F_BYTE5\" )
					)
					( Units "uMatchProp" "ns" 1.000000)
					( Status sCSetFlattened )
					( Origin gBackEnd )
				)
			)
			( pinPair "@baseboard_fab2_lib.baseboard_fab2(sch_1):\PP4145\"
				( pinRef "@baseboard_fab2_lib.baseboard_fab2(sch_1):page28_i172:DDR5_DQ(44)" )
				( pinRef "@baseboard_fab2_lib.baseboard_fab2(sch_1):page54_i111:DQ(44)" )
				( attribute "RELATIVE_PROPAGATION_DELAY_SCOPE" "G"
					( Parent
						( matchGroupRef "@baseboard_fab2_lib.baseboard_fab2(sch_1):\MG_DQ-DQS_NEAR_DIMM_NG_M_F_BYTE5\" )
					)
					( Status sCSetFlattened )
					( Origin gBackEnd )
				)
				( attribute "RELATIVE_PROPAGATION_DELAY" "0.00 MIL,195.00 MIL"
					( Parent
						( matchGroupRef "@baseboard_fab2_lib.baseboard_fab2(sch_1):\MG_DQ-DQS_NEAR_DIMM_NG_M_F_BYTE5\" )
					)
					( Units "uMatchProp" "ns" 1.000000)
					( Status sCSetFlattened )
					( Origin gBackEnd )
				)
				( attribute "RELATIVE_PROPAGATION_DELAY_SCOPE" "G"
					( Parent
						( matchGroupRef "@crescent_city_bb_fab1_lib.crescent_city_bb_fab1(sch_1):\MG_DQ_NEAR_DIMM_NG_M_F_BYTE5\" )
					)
					( Status sCSetFlattened )
					( Origin gBackEnd )
				)
				( attribute "RELATIVE_PROPAGATION_DELAY" "-50.00 MIL,50.00 MIL"
					( Parent
						( matchGroupRef "@crescent_city_bb_fab1_lib.crescent_city_bb_fab1(sch_1):\MG_DQ_NEAR_DIMM_NG_M_F_BYTE5\" )
					)
					( Units "uMatchProp" "ns" 1.000000)
					( Status sCSetFlattened )
					( Origin gBackEnd )
				)
			)
			( pinPair "@baseboard_fab2_lib.baseboard_fab2(sch_1):\PP4146\"
				( pinRef "@baseboard_fab2_lib.baseboard_fab2(sch_1):page28_i172:DDR5_DQ(45)" )
				( pinRef "@baseboard_fab2_lib.baseboard_fab2(sch_1):page53_i111:DQ(44)" )
				( attribute "RELATIVE_PROPAGATION_DELAY_SCOPE" "G"
					( Parent
						( matchGroupRef "@baseboard_fab2_lib.baseboard_fab2(sch_1):\MG_DQ-DQS_FAR_DIMM_NG_M_F_BYTE5\" )
					)
					( Status sCSetFlattened )
					( Origin gBackEnd )
				)
				( attribute "RELATIVE_PROPAGATION_DELAY" "0.00 MIL,195.00 MIL"
					( Parent
						( matchGroupRef "@baseboard_fab2_lib.baseboard_fab2(sch_1):\MG_DQ-DQS_FAR_DIMM_NG_M_F_BYTE5\" )
					)
					( Units "uMatchProp" "ns" 1.000000)
					( Status sCSetFlattened )
					( Origin gBackEnd )
				)
				( attribute "RELATIVE_PROPAGATION_DELAY_SCOPE" "G"
					( Parent
						( matchGroupRef "@baseboard_fab2_lib.baseboard_fab2(sch_1):\MG_DQ_FAR_DIMM_NG_M_F_BYTE5\" )
					)
					( Status sCSetFlattened )
					( Origin gBackEnd )
				)
				( attribute "RELATIVE_PROPAGATION_DELAY" "-50.00 MIL,50.00 MIL"
					( Parent
						( matchGroupRef "@baseboard_fab2_lib.baseboard_fab2(sch_1):\MG_DQ_FAR_DIMM_NG_M_F_BYTE5\" )
					)
					( Units "uMatchProp" "ns" 1.000000)
					( Status sCSetFlattened )
					( Origin gBackEnd )
				)
			)
			( pinPair "@baseboard_fab2_lib.baseboard_fab2(sch_1):\PP4148\"
				( pinRef "@baseboard_fab2_lib.baseboard_fab2(sch_1):page28_i172:DDR5_DQ(45)" )
				( pinRef "@baseboard_fab2_lib.baseboard_fab2(sch_1):page54_i111:DQ(45)" )
				( attribute "RELATIVE_PROPAGATION_DELAY_SCOPE" "G"
					( Parent
						( matchGroupRef "@baseboard_fab2_lib.baseboard_fab2(sch_1):\MG_DQ-DQS_NEAR_DIMM_NG_M_F_BYTE5\" )
					)
					( Status sCSetFlattened )
					( Origin gBackEnd )
				)
				( attribute "RELATIVE_PROPAGATION_DELAY" "0.00 MIL,195.00 MIL"
					( Parent
						( matchGroupRef "@baseboard_fab2_lib.baseboard_fab2(sch_1):\MG_DQ-DQS_NEAR_DIMM_NG_M_F_BYTE5\" )
					)
					( Units "uMatchProp" "ns" 1.000000)
					( Status sCSetFlattened )
					( Origin gBackEnd )
				)
				( attribute "RELATIVE_PROPAGATION_DELAY_SCOPE" "G"
					( Parent
						( matchGroupRef "@crescent_city_bb_fab1_lib.crescent_city_bb_fab1(sch_1):\MG_DQ_NEAR_DIMM_NG_M_F_BYTE5\" )
					)
					( Origin gBackEnd )
				)
				( attribute "RELATIVE_PROPAGATION_DELAY" "TARGET,TARGET"
					( Parent
						( matchGroupRef "@crescent_city_bb_fab1_lib.crescent_city_bb_fab1(sch_1):\MG_DQ_NEAR_DIMM_NG_M_F_BYTE5\" )
					)
					( Units "uMatchProp" "ns" 1.000000)
					( Origin gBackEnd )
				)
			)
			( pinPair "@baseboard_fab2_lib.baseboard_fab2(sch_1):\PP4149\"
				( pinRef "@baseboard_fab2_lib.baseboard_fab2(sch_1):page28_i172:DDR5_DQ(46)" )
				( pinRef "@baseboard_fab2_lib.baseboard_fab2(sch_1):page53_i111:DQ(47)" )
				( attribute "RELATIVE_PROPAGATION_DELAY_SCOPE" "G"
					( Parent
						( matchGroupRef "@baseboard_fab2_lib.baseboard_fab2(sch_1):\MG_DQ-DQS_FAR_DIMM_NG_M_F_BYTE5\" )
					)
					( Status sCSetFlattened )
					( Origin gBackEnd )
				)
				( attribute "RELATIVE_PROPAGATION_DELAY" "0.00 MIL,195.00 MIL"
					( Parent
						( matchGroupRef "@baseboard_fab2_lib.baseboard_fab2(sch_1):\MG_DQ-DQS_FAR_DIMM_NG_M_F_BYTE5\" )
					)
					( Units "uMatchProp" "ns" 1.000000)
					( Status sCSetFlattened )
					( Origin gBackEnd )
				)
				( attribute "RELATIVE_PROPAGATION_DELAY_SCOPE" "G"
					( Parent
						( matchGroupRef "@baseboard_fab2_lib.baseboard_fab2(sch_1):\MG_DQ_FAR_DIMM_NG_M_F_BYTE5\" )
					)
					( Status sCSetFlattened )
					( Origin gBackEnd )
				)
				( attribute "RELATIVE_PROPAGATION_DELAY" "-50.00 MIL,50.00 MIL"
					( Parent
						( matchGroupRef "@baseboard_fab2_lib.baseboard_fab2(sch_1):\MG_DQ_FAR_DIMM_NG_M_F_BYTE5\" )
					)
					( Units "uMatchProp" "ns" 1.000000)
					( Status sCSetFlattened )
					( Origin gBackEnd )
				)
			)
			( pinPair "@baseboard_fab2_lib.baseboard_fab2(sch_1):\PP4151\"
				( pinRef "@baseboard_fab2_lib.baseboard_fab2(sch_1):page28_i172:DDR5_DQ(46)" )
				( pinRef "@baseboard_fab2_lib.baseboard_fab2(sch_1):page54_i111:DQ(46)" )
				( attribute "RELATIVE_PROPAGATION_DELAY_SCOPE" "G"
					( Parent
						( matchGroupRef "@baseboard_fab2_lib.baseboard_fab2(sch_1):\MG_DQ-DQS_NEAR_DIMM_NG_M_F_BYTE5\" )
					)
					( Status sCSetFlattened )
					( Origin gBackEnd )
				)
				( attribute "RELATIVE_PROPAGATION_DELAY" "0.00 MIL,195.00 MIL"
					( Parent
						( matchGroupRef "@baseboard_fab2_lib.baseboard_fab2(sch_1):\MG_DQ-DQS_NEAR_DIMM_NG_M_F_BYTE5\" )
					)
					( Units "uMatchProp" "ns" 1.000000)
					( Status sCSetFlattened )
					( Origin gBackEnd )
				)
				( attribute "RELATIVE_PROPAGATION_DELAY_SCOPE" "G"
					( Parent
						( matchGroupRef "@crescent_city_bb_fab1_lib.crescent_city_bb_fab1(sch_1):\MG_DQ_NEAR_DIMM_NG_M_F_BYTE5\" )
					)
					( Status sCSetFlattened )
					( Origin gBackEnd )
				)
				( attribute "RELATIVE_PROPAGATION_DELAY" "-50.00 MIL,50.00 MIL"
					( Parent
						( matchGroupRef "@crescent_city_bb_fab1_lib.crescent_city_bb_fab1(sch_1):\MG_DQ_NEAR_DIMM_NG_M_F_BYTE5\" )
					)
					( Units "uMatchProp" "ns" 1.000000)
					( Status sCSetFlattened )
					( Origin gBackEnd )
				)
			)
			( pinPair "@baseboard_fab2_lib.baseboard_fab2(sch_1):\PP4152\"
				( pinRef "@baseboard_fab2_lib.baseboard_fab2(sch_1):page28_i172:DDR5_DQ(47)" )
				( pinRef "@baseboard_fab2_lib.baseboard_fab2(sch_1):page53_i111:DQ(46)" )
				( attribute "RELATIVE_PROPAGATION_DELAY_SCOPE" "G"
					( Parent
						( matchGroupRef "@baseboard_fab2_lib.baseboard_fab2(sch_1):\MG_DQ-DQS_FAR_DIMM_NG_M_F_BYTE5\" )
					)
					( Status sCSetFlattened )
					( Origin gBackEnd )
				)
				( attribute "RELATIVE_PROPAGATION_DELAY" "0.00 MIL,195.00 MIL"
					( Parent
						( matchGroupRef "@baseboard_fab2_lib.baseboard_fab2(sch_1):\MG_DQ-DQS_FAR_DIMM_NG_M_F_BYTE5\" )
					)
					( Units "uMatchProp" "ns" 1.000000)
					( Status sCSetFlattened )
					( Origin gBackEnd )
				)
				( attribute "RELATIVE_PROPAGATION_DELAY_SCOPE" "G"
					( Parent
						( matchGroupRef "@baseboard_fab2_lib.baseboard_fab2(sch_1):\MG_DQ_FAR_DIMM_NG_M_F_BYTE5\" )
					)
					( Status sCSetFlattened )
					( Origin gBackEnd )
				)
				( attribute "RELATIVE_PROPAGATION_DELAY" "-50.00 MIL,50.00 MIL"
					( Parent
						( matchGroupRef "@baseboard_fab2_lib.baseboard_fab2(sch_1):\MG_DQ_FAR_DIMM_NG_M_F_BYTE5\" )
					)
					( Units "uMatchProp" "ns" 1.000000)
					( Status sCSetFlattened )
					( Origin gBackEnd )
				)
			)
			( pinPair "@baseboard_fab2_lib.baseboard_fab2(sch_1):\PP4154\"
				( pinRef "@baseboard_fab2_lib.baseboard_fab2(sch_1):page28_i172:DDR5_DQ(47)" )
				( pinRef "@baseboard_fab2_lib.baseboard_fab2(sch_1):page54_i111:DQ(47)" )
				( attribute "RELATIVE_PROPAGATION_DELAY_SCOPE" "G"
					( Parent
						( matchGroupRef "@baseboard_fab2_lib.baseboard_fab2(sch_1):\MG_DQ-DQS_NEAR_DIMM_NG_M_F_BYTE5\" )
					)
					( Status sCSetFlattened )
					( Origin gBackEnd )
				)
				( attribute "RELATIVE_PROPAGATION_DELAY" "0.00 MIL,195.00 MIL"
					( Parent
						( matchGroupRef "@baseboard_fab2_lib.baseboard_fab2(sch_1):\MG_DQ-DQS_NEAR_DIMM_NG_M_F_BYTE5\" )
					)
					( Units "uMatchProp" "ns" 1.000000)
					( Status sCSetFlattened )
					( Origin gBackEnd )
				)
				( attribute "RELATIVE_PROPAGATION_DELAY_SCOPE" "G"
					( Parent
						( matchGroupRef "@crescent_city_bb_fab1_lib.crescent_city_bb_fab1(sch_1):\MG_DQ_NEAR_DIMM_NG_M_F_BYTE5\" )
					)
					( Status sCSetFlattened )
					( Origin gBackEnd )
				)
				( attribute "RELATIVE_PROPAGATION_DELAY" "-50.00 MIL,50.00 MIL"
					( Parent
						( matchGroupRef "@crescent_city_bb_fab1_lib.crescent_city_bb_fab1(sch_1):\MG_DQ_NEAR_DIMM_NG_M_F_BYTE5\" )
					)
					( Units "uMatchProp" "ns" 1.000000)
					( Status sCSetFlattened )
					( Origin gBackEnd )
				)
			)
			( pinPair "@baseboard_fab2_lib.baseboard_fab2(sch_1):\PP4107\"
				( pinRef "@baseboard_fab2_lib.baseboard_fab2(sch_1):page28_i172:DDR5_DQ(48)" )
				( pinRef "@baseboard_fab2_lib.baseboard_fab2(sch_1):page53_i111:DQ(49)" )
				( attribute "RELATIVE_PROPAGATION_DELAY_SCOPE" "G"
					( Parent
						( matchGroupRef "@baseboard_fab2_lib.baseboard_fab2(sch_1):\MG_DQ-DQS_FAR_DIMM_NG_M_F_BYTE6\" )
					)
					( Status sCSetFlattened )
					( Origin gBackEnd )
				)
				( attribute "RELATIVE_PROPAGATION_DELAY" "0.00 MIL,195.00 MIL"
					( Parent
						( matchGroupRef "@baseboard_fab2_lib.baseboard_fab2(sch_1):\MG_DQ-DQS_FAR_DIMM_NG_M_F_BYTE6\" )
					)
					( Units "uMatchProp" "ns" 1.000000)
					( Status sCSetFlattened )
					( Origin gBackEnd )
				)
				( attribute "RELATIVE_PROPAGATION_DELAY_SCOPE" "G"
					( Parent
						( matchGroupRef "@baseboard_fab2_lib.baseboard_fab2(sch_1):\MG_DQ_FAR_DIMM_NG_M_F_BYTE6\" )
					)
					( Status sCSetFlattened )
					( Origin gBackEnd )
				)
				( attribute "RELATIVE_PROPAGATION_DELAY" "-50.00 MIL,50.00 MIL"
					( Parent
						( matchGroupRef "@baseboard_fab2_lib.baseboard_fab2(sch_1):\MG_DQ_FAR_DIMM_NG_M_F_BYTE6\" )
					)
					( Units "uMatchProp" "ns" 1.000000)
					( Status sCSetFlattened )
					( Origin gBackEnd )
				)
			)
			( pinPair "@baseboard_fab2_lib.baseboard_fab2(sch_1):\PP4109\"
				( pinRef "@baseboard_fab2_lib.baseboard_fab2(sch_1):page28_i172:DDR5_DQ(48)" )
				( pinRef "@baseboard_fab2_lib.baseboard_fab2(sch_1):page54_i111:DQ(48)" )
				( attribute "RELATIVE_PROPAGATION_DELAY_SCOPE" "G"
					( Parent
						( matchGroupRef "@baseboard_fab2_lib.baseboard_fab2(sch_1):\MG_DQ-DQS_NEAR_DIMM_NG_M_F_BYTE6\" )
					)
					( Status sCSetFlattened )
					( Origin gBackEnd )
				)
				( attribute "RELATIVE_PROPAGATION_DELAY" "0.00 MIL,195.00 MIL"
					( Parent
						( matchGroupRef "@baseboard_fab2_lib.baseboard_fab2(sch_1):\MG_DQ-DQS_NEAR_DIMM_NG_M_F_BYTE6\" )
					)
					( Units "uMatchProp" "ns" 1.000000)
					( Status sCSetFlattened )
					( Origin gBackEnd )
				)
				( attribute "RELATIVE_PROPAGATION_DELAY_SCOPE" "G"
					( Parent
						( matchGroupRef "@crescent_city_bb_fab1_lib.crescent_city_bb_fab1(sch_1):\MG_DQ_NEAR_DIMM_NG_M_F_BYTE6\" )
					)
					( Status sCSetFlattened )
					( Origin gBackEnd )
				)
				( attribute "RELATIVE_PROPAGATION_DELAY" "-50.00 MIL,50.00 MIL"
					( Parent
						( matchGroupRef "@crescent_city_bb_fab1_lib.crescent_city_bb_fab1(sch_1):\MG_DQ_NEAR_DIMM_NG_M_F_BYTE6\" )
					)
					( Units "uMatchProp" "ns" 1.000000)
					( Status sCSetFlattened )
					( Origin gBackEnd )
				)
			)
			( pinPair "@baseboard_fab2_lib.baseboard_fab2(sch_1):\PP4110\"
				( pinRef "@baseboard_fab2_lib.baseboard_fab2(sch_1):page28_i172:DDR5_DQ(49)" )
				( pinRef "@baseboard_fab2_lib.baseboard_fab2(sch_1):page53_i111:DQ(48)" )
				( attribute "RELATIVE_PROPAGATION_DELAY_SCOPE" "G"
					( Parent
						( matchGroupRef "@baseboard_fab2_lib.baseboard_fab2(sch_1):\MG_DQ-DQS_FAR_DIMM_NG_M_F_BYTE6\" )
					)
					( Status sCSetFlattened )
					( Origin gBackEnd )
				)
				( attribute "RELATIVE_PROPAGATION_DELAY" "0.00 MIL,195.00 MIL"
					( Parent
						( matchGroupRef "@baseboard_fab2_lib.baseboard_fab2(sch_1):\MG_DQ-DQS_FAR_DIMM_NG_M_F_BYTE6\" )
					)
					( Units "uMatchProp" "ns" 1.000000)
					( Status sCSetFlattened )
					( Origin gBackEnd )
				)
				( attribute "RELATIVE_PROPAGATION_DELAY_SCOPE" "G"
					( Parent
						( matchGroupRef "@baseboard_fab2_lib.baseboard_fab2(sch_1):\MG_DQ_FAR_DIMM_NG_M_F_BYTE6\" )
					)
					( Status sCSetFlattened )
					( Origin gBackEnd )
				)
				( attribute "RELATIVE_PROPAGATION_DELAY" "-50.00 MIL,50.00 MIL"
					( Parent
						( matchGroupRef "@baseboard_fab2_lib.baseboard_fab2(sch_1):\MG_DQ_FAR_DIMM_NG_M_F_BYTE6\" )
					)
					( Units "uMatchProp" "ns" 1.000000)
					( Status sCSetFlattened )
					( Origin gBackEnd )
				)
			)
			( pinPair "@baseboard_fab2_lib.baseboard_fab2(sch_1):\PP4112\"
				( pinRef "@baseboard_fab2_lib.baseboard_fab2(sch_1):page28_i172:DDR5_DQ(49)" )
				( pinRef "@baseboard_fab2_lib.baseboard_fab2(sch_1):page54_i111:DQ(49)" )
				( attribute "RELATIVE_PROPAGATION_DELAY_SCOPE" "G"
					( Parent
						( matchGroupRef "@baseboard_fab2_lib.baseboard_fab2(sch_1):\MG_DQ-DQS_NEAR_DIMM_NG_M_F_BYTE6\" )
					)
					( Status sCSetFlattened )
					( Origin gBackEnd )
				)
				( attribute "RELATIVE_PROPAGATION_DELAY" "0.00 MIL,195.00 MIL"
					( Parent
						( matchGroupRef "@baseboard_fab2_lib.baseboard_fab2(sch_1):\MG_DQ-DQS_NEAR_DIMM_NG_M_F_BYTE6\" )
					)
					( Units "uMatchProp" "ns" 1.000000)
					( Status sCSetFlattened )
					( Origin gBackEnd )
				)
				( attribute "RELATIVE_PROPAGATION_DELAY_SCOPE" "G"
					( Parent
						( matchGroupRef "@crescent_city_bb_fab1_lib.crescent_city_bb_fab1(sch_1):\MG_DQ_NEAR_DIMM_NG_M_F_BYTE6\" )
					)
					( Origin gBackEnd )
				)
				( attribute "RELATIVE_PROPAGATION_DELAY" "TARGET,TARGET"
					( Parent
						( matchGroupRef "@crescent_city_bb_fab1_lib.crescent_city_bb_fab1(sch_1):\MG_DQ_NEAR_DIMM_NG_M_F_BYTE6\" )
					)
					( Units "uMatchProp" "ns" 1.000000)
					( Origin gBackEnd )
				)
			)
			( pinPair "@baseboard_fab2_lib.baseboard_fab2(sch_1):\PP4113\"
				( pinRef "@baseboard_fab2_lib.baseboard_fab2(sch_1):page28_i172:DDR5_DQ(50)" )
				( pinRef "@baseboard_fab2_lib.baseboard_fab2(sch_1):page53_i111:DQ(51)" )
				( attribute "RELATIVE_PROPAGATION_DELAY_SCOPE" "G"
					( Parent
						( matchGroupRef "@baseboard_fab2_lib.baseboard_fab2(sch_1):\MG_DQ-DQS_FAR_DIMM_NG_M_F_BYTE6\" )
					)
					( Status sCSetFlattened )
					( Origin gBackEnd )
				)
				( attribute "RELATIVE_PROPAGATION_DELAY" "0.00 MIL,195.00 MIL"
					( Parent
						( matchGroupRef "@baseboard_fab2_lib.baseboard_fab2(sch_1):\MG_DQ-DQS_FAR_DIMM_NG_M_F_BYTE6\" )
					)
					( Units "uMatchProp" "ns" 1.000000)
					( Status sCSetFlattened )
					( Origin gBackEnd )
				)
				( attribute "RELATIVE_PROPAGATION_DELAY_SCOPE" "G"
					( Parent
						( matchGroupRef "@baseboard_fab2_lib.baseboard_fab2(sch_1):\MG_DQ_FAR_DIMM_NG_M_F_BYTE6\" )
					)
					( Status sCSetFlattened )
					( Origin gBackEnd )
				)
				( attribute "RELATIVE_PROPAGATION_DELAY" "-50.00 MIL,50.00 MIL"
					( Parent
						( matchGroupRef "@baseboard_fab2_lib.baseboard_fab2(sch_1):\MG_DQ_FAR_DIMM_NG_M_F_BYTE6\" )
					)
					( Units "uMatchProp" "ns" 1.000000)
					( Status sCSetFlattened )
					( Origin gBackEnd )
				)
			)
			( pinPair "@baseboard_fab2_lib.baseboard_fab2(sch_1):\PP4115\"
				( pinRef "@baseboard_fab2_lib.baseboard_fab2(sch_1):page28_i172:DDR5_DQ(50)" )
				( pinRef "@baseboard_fab2_lib.baseboard_fab2(sch_1):page54_i111:DQ(50)" )
				( attribute "RELATIVE_PROPAGATION_DELAY_SCOPE" "G"
					( Parent
						( matchGroupRef "@baseboard_fab2_lib.baseboard_fab2(sch_1):\MG_DQ-DQS_NEAR_DIMM_NG_M_F_BYTE6\" )
					)
					( Status sCSetFlattened )
					( Origin gBackEnd )
				)
				( attribute "RELATIVE_PROPAGATION_DELAY" "0.00 MIL,195.00 MIL"
					( Parent
						( matchGroupRef "@baseboard_fab2_lib.baseboard_fab2(sch_1):\MG_DQ-DQS_NEAR_DIMM_NG_M_F_BYTE6\" )
					)
					( Units "uMatchProp" "ns" 1.000000)
					( Status sCSetFlattened )
					( Origin gBackEnd )
				)
				( attribute "RELATIVE_PROPAGATION_DELAY_SCOPE" "G"
					( Parent
						( matchGroupRef "@crescent_city_bb_fab1_lib.crescent_city_bb_fab1(sch_1):\MG_DQ_NEAR_DIMM_NG_M_F_BYTE6\" )
					)
					( Status sCSetFlattened )
					( Origin gBackEnd )
				)
				( attribute "RELATIVE_PROPAGATION_DELAY" "-50.00 MIL,50.00 MIL"
					( Parent
						( matchGroupRef "@crescent_city_bb_fab1_lib.crescent_city_bb_fab1(sch_1):\MG_DQ_NEAR_DIMM_NG_M_F_BYTE6\" )
					)
					( Units "uMatchProp" "ns" 1.000000)
					( Status sCSetFlattened )
					( Origin gBackEnd )
				)
			)
			( pinPair "@baseboard_fab2_lib.baseboard_fab2(sch_1):\PP4116\"
				( pinRef "@baseboard_fab2_lib.baseboard_fab2(sch_1):page28_i172:DDR5_DQ(51)" )
				( pinRef "@baseboard_fab2_lib.baseboard_fab2(sch_1):page53_i111:DQ(50)" )
				( attribute "RELATIVE_PROPAGATION_DELAY_SCOPE" "G"
					( Parent
						( matchGroupRef "@baseboard_fab2_lib.baseboard_fab2(sch_1):\MG_DQ-DQS_FAR_DIMM_NG_M_F_BYTE6\" )
					)
					( Status sCSetFlattened )
					( Origin gBackEnd )
				)
				( attribute "RELATIVE_PROPAGATION_DELAY" "0.00 MIL,195.00 MIL"
					( Parent
						( matchGroupRef "@baseboard_fab2_lib.baseboard_fab2(sch_1):\MG_DQ-DQS_FAR_DIMM_NG_M_F_BYTE6\" )
					)
					( Units "uMatchProp" "ns" 1.000000)
					( Status sCSetFlattened )
					( Origin gBackEnd )
				)
				( attribute "RELATIVE_PROPAGATION_DELAY_SCOPE" "G"
					( Parent
						( matchGroupRef "@baseboard_fab2_lib.baseboard_fab2(sch_1):\MG_DQ_FAR_DIMM_NG_M_F_BYTE6\" )
					)
					( Status sCSetFlattened )
					( Origin gBackEnd )
				)
				( attribute "RELATIVE_PROPAGATION_DELAY" "-50.00 MIL,50.00 MIL"
					( Parent
						( matchGroupRef "@baseboard_fab2_lib.baseboard_fab2(sch_1):\MG_DQ_FAR_DIMM_NG_M_F_BYTE6\" )
					)
					( Units "uMatchProp" "ns" 1.000000)
					( Status sCSetFlattened )
					( Origin gBackEnd )
				)
			)
			( pinPair "@baseboard_fab2_lib.baseboard_fab2(sch_1):\PP4118\"
				( pinRef "@baseboard_fab2_lib.baseboard_fab2(sch_1):page28_i172:DDR5_DQ(51)" )
				( pinRef "@baseboard_fab2_lib.baseboard_fab2(sch_1):page54_i111:DQ(51)" )
				( attribute "RELATIVE_PROPAGATION_DELAY_SCOPE" "G"
					( Parent
						( matchGroupRef "@baseboard_fab2_lib.baseboard_fab2(sch_1):\MG_DQ-DQS_NEAR_DIMM_NG_M_F_BYTE6\" )
					)
					( Status sCSetFlattened )
					( Origin gBackEnd )
				)
				( attribute "RELATIVE_PROPAGATION_DELAY" "0.00 MIL,195.00 MIL"
					( Parent
						( matchGroupRef "@baseboard_fab2_lib.baseboard_fab2(sch_1):\MG_DQ-DQS_NEAR_DIMM_NG_M_F_BYTE6\" )
					)
					( Units "uMatchProp" "ns" 1.000000)
					( Status sCSetFlattened )
					( Origin gBackEnd )
				)
				( attribute "RELATIVE_PROPAGATION_DELAY_SCOPE" "G"
					( Parent
						( matchGroupRef "@crescent_city_bb_fab1_lib.crescent_city_bb_fab1(sch_1):\MG_DQ_NEAR_DIMM_NG_M_F_BYTE6\" )
					)
					( Status sCSetFlattened )
					( Origin gBackEnd )
				)
				( attribute "RELATIVE_PROPAGATION_DELAY" "-50.00 MIL,50.00 MIL"
					( Parent
						( matchGroupRef "@crescent_city_bb_fab1_lib.crescent_city_bb_fab1(sch_1):\MG_DQ_NEAR_DIMM_NG_M_F_BYTE6\" )
					)
					( Units "uMatchProp" "ns" 1.000000)
					( Status sCSetFlattened )
					( Origin gBackEnd )
				)
			)
			( pinPair "@baseboard_fab2_lib.baseboard_fab2(sch_1):\PP4119\"
				( pinRef "@baseboard_fab2_lib.baseboard_fab2(sch_1):page28_i172:DDR5_DQ(52)" )
				( pinRef "@baseboard_fab2_lib.baseboard_fab2(sch_1):page53_i111:DQ(53)" )
				( attribute "RELATIVE_PROPAGATION_DELAY_SCOPE" "G"
					( Parent
						( matchGroupRef "@baseboard_fab2_lib.baseboard_fab2(sch_1):\MG_DQ-DQS_FAR_DIMM_NG_M_F_BYTE6\" )
					)
					( Status sCSetFlattened )
					( Origin gBackEnd )
				)
				( attribute "RELATIVE_PROPAGATION_DELAY" "0.00 MIL,195.00 MIL"
					( Parent
						( matchGroupRef "@baseboard_fab2_lib.baseboard_fab2(sch_1):\MG_DQ-DQS_FAR_DIMM_NG_M_F_BYTE6\" )
					)
					( Units "uMatchProp" "ns" 1.000000)
					( Status sCSetFlattened )
					( Origin gBackEnd )
				)
				( attribute "RELATIVE_PROPAGATION_DELAY_SCOPE" "G"
					( Parent
						( matchGroupRef "@baseboard_fab2_lib.baseboard_fab2(sch_1):\MG_DQ_FAR_DIMM_NG_M_F_BYTE6\" )
					)
					( Status sCSetFlattened )
					( Origin gBackEnd )
				)
				( attribute "RELATIVE_PROPAGATION_DELAY" "-50.00 MIL,50.00 MIL"
					( Parent
						( matchGroupRef "@baseboard_fab2_lib.baseboard_fab2(sch_1):\MG_DQ_FAR_DIMM_NG_M_F_BYTE6\" )
					)
					( Units "uMatchProp" "ns" 1.000000)
					( Status sCSetFlattened )
					( Origin gBackEnd )
				)
			)
			( pinPair "@baseboard_fab2_lib.baseboard_fab2(sch_1):\PP4121\"
				( pinRef "@baseboard_fab2_lib.baseboard_fab2(sch_1):page28_i172:DDR5_DQ(52)" )
				( pinRef "@baseboard_fab2_lib.baseboard_fab2(sch_1):page54_i111:DQ(52)" )
				( attribute "RELATIVE_PROPAGATION_DELAY_SCOPE" "G"
					( Parent
						( matchGroupRef "@baseboard_fab2_lib.baseboard_fab2(sch_1):\MG_DQ-DQS_NEAR_DIMM_NG_M_F_BYTE6\" )
					)
					( Status sCSetFlattened )
					( Origin gBackEnd )
				)
				( attribute "RELATIVE_PROPAGATION_DELAY" "0.00 MIL,195.00 MIL"
					( Parent
						( matchGroupRef "@baseboard_fab2_lib.baseboard_fab2(sch_1):\MG_DQ-DQS_NEAR_DIMM_NG_M_F_BYTE6\" )
					)
					( Units "uMatchProp" "ns" 1.000000)
					( Status sCSetFlattened )
					( Origin gBackEnd )
				)
				( attribute "RELATIVE_PROPAGATION_DELAY_SCOPE" "G"
					( Parent
						( matchGroupRef "@crescent_city_bb_fab1_lib.crescent_city_bb_fab1(sch_1):\MG_DQ_NEAR_DIMM_NG_M_F_BYTE6\" )
					)
					( Status sCSetFlattened )
					( Origin gBackEnd )
				)
				( attribute "RELATIVE_PROPAGATION_DELAY" "-50.00 MIL,50.00 MIL"
					( Parent
						( matchGroupRef "@crescent_city_bb_fab1_lib.crescent_city_bb_fab1(sch_1):\MG_DQ_NEAR_DIMM_NG_M_F_BYTE6\" )
					)
					( Units "uMatchProp" "ns" 1.000000)
					( Status sCSetFlattened )
					( Origin gBackEnd )
				)
			)
			( pinPair "@baseboard_fab2_lib.baseboard_fab2(sch_1):\PP4122\"
				( pinRef "@baseboard_fab2_lib.baseboard_fab2(sch_1):page28_i172:DDR5_DQ(53)" )
				( pinRef "@baseboard_fab2_lib.baseboard_fab2(sch_1):page53_i111:DQ(52)" )
				( attribute "RELATIVE_PROPAGATION_DELAY_SCOPE" "G"
					( Parent
						( matchGroupRef "@baseboard_fab2_lib.baseboard_fab2(sch_1):\MG_DQ-DQS_FAR_DIMM_NG_M_F_BYTE6\" )
					)
					( Status sCSetFlattened )
					( Origin gBackEnd )
				)
				( attribute "RELATIVE_PROPAGATION_DELAY" "0.00 MIL,195.00 MIL"
					( Parent
						( matchGroupRef "@baseboard_fab2_lib.baseboard_fab2(sch_1):\MG_DQ-DQS_FAR_DIMM_NG_M_F_BYTE6\" )
					)
					( Units "uMatchProp" "ns" 1.000000)
					( Status sCSetFlattened )
					( Origin gBackEnd )
				)
				( attribute "RELATIVE_PROPAGATION_DELAY_SCOPE" "G"
					( Parent
						( matchGroupRef "@baseboard_fab2_lib.baseboard_fab2(sch_1):\MG_DQ_FAR_DIMM_NG_M_F_BYTE6\" )
					)
					( Status sCSetFlattened )
					( Origin gBackEnd )
				)
				( attribute "RELATIVE_PROPAGATION_DELAY" "-50.00 MIL,50.00 MIL"
					( Parent
						( matchGroupRef "@baseboard_fab2_lib.baseboard_fab2(sch_1):\MG_DQ_FAR_DIMM_NG_M_F_BYTE6\" )
					)
					( Units "uMatchProp" "ns" 1.000000)
					( Status sCSetFlattened )
					( Origin gBackEnd )
				)
			)
			( pinPair "@baseboard_fab2_lib.baseboard_fab2(sch_1):\PP4124\"
				( pinRef "@baseboard_fab2_lib.baseboard_fab2(sch_1):page28_i172:DDR5_DQ(53)" )
				( pinRef "@baseboard_fab2_lib.baseboard_fab2(sch_1):page54_i111:DQ(53)" )
				( attribute "RELATIVE_PROPAGATION_DELAY_SCOPE" "G"
					( Parent
						( matchGroupRef "@baseboard_fab2_lib.baseboard_fab2(sch_1):\MG_DQ-DQS_NEAR_DIMM_NG_M_F_BYTE6\" )
					)
					( Status sCSetFlattened )
					( Origin gBackEnd )
				)
				( attribute "RELATIVE_PROPAGATION_DELAY" "0.00 MIL,195.00 MIL"
					( Parent
						( matchGroupRef "@baseboard_fab2_lib.baseboard_fab2(sch_1):\MG_DQ-DQS_NEAR_DIMM_NG_M_F_BYTE6\" )
					)
					( Units "uMatchProp" "ns" 1.000000)
					( Status sCSetFlattened )
					( Origin gBackEnd )
				)
				( attribute "RELATIVE_PROPAGATION_DELAY_SCOPE" "G"
					( Parent
						( matchGroupRef "@crescent_city_bb_fab1_lib.crescent_city_bb_fab1(sch_1):\MG_DQ_NEAR_DIMM_NG_M_F_BYTE6\" )
					)
					( Status sCSetFlattened )
					( Origin gBackEnd )
				)
				( attribute "RELATIVE_PROPAGATION_DELAY" "-50.00 MIL,50.00 MIL"
					( Parent
						( matchGroupRef "@crescent_city_bb_fab1_lib.crescent_city_bb_fab1(sch_1):\MG_DQ_NEAR_DIMM_NG_M_F_BYTE6\" )
					)
					( Units "uMatchProp" "ns" 1.000000)
					( Status sCSetFlattened )
					( Origin gBackEnd )
				)
			)
			( pinPair "@baseboard_fab2_lib.baseboard_fab2(sch_1):\PP4125\"
				( pinRef "@baseboard_fab2_lib.baseboard_fab2(sch_1):page28_i172:DDR5_DQ(54)" )
				( pinRef "@baseboard_fab2_lib.baseboard_fab2(sch_1):page53_i111:DQ(55)" )
				( attribute "RELATIVE_PROPAGATION_DELAY_SCOPE" "G"
					( Parent
						( matchGroupRef "@baseboard_fab2_lib.baseboard_fab2(sch_1):\MG_DQ-DQS_FAR_DIMM_NG_M_F_BYTE6\" )
					)
					( Status sCSetFlattened )
					( Origin gBackEnd )
				)
				( attribute "RELATIVE_PROPAGATION_DELAY" "0.00 MIL,195.00 MIL"
					( Parent
						( matchGroupRef "@baseboard_fab2_lib.baseboard_fab2(sch_1):\MG_DQ-DQS_FAR_DIMM_NG_M_F_BYTE6\" )
					)
					( Units "uMatchProp" "ns" 1.000000)
					( Status sCSetFlattened )
					( Origin gBackEnd )
				)
				( attribute "RELATIVE_PROPAGATION_DELAY_SCOPE" "G"
					( Parent
						( matchGroupRef "@baseboard_fab2_lib.baseboard_fab2(sch_1):\MG_DQ_FAR_DIMM_NG_M_F_BYTE6\" )
					)
					( Status sCSetFlattened )
					( Origin gBackEnd )
				)
				( attribute "RELATIVE_PROPAGATION_DELAY" "-50.00 MIL,50.00 MIL"
					( Parent
						( matchGroupRef "@baseboard_fab2_lib.baseboard_fab2(sch_1):\MG_DQ_FAR_DIMM_NG_M_F_BYTE6\" )
					)
					( Units "uMatchProp" "ns" 1.000000)
					( Status sCSetFlattened )
					( Origin gBackEnd )
				)
			)
			( pinPair "@baseboard_fab2_lib.baseboard_fab2(sch_1):\PP4127\"
				( pinRef "@baseboard_fab2_lib.baseboard_fab2(sch_1):page28_i172:DDR5_DQ(54)" )
				( pinRef "@baseboard_fab2_lib.baseboard_fab2(sch_1):page54_i111:DQ(54)" )
				( attribute "RELATIVE_PROPAGATION_DELAY_SCOPE" "G"
					( Parent
						( matchGroupRef "@baseboard_fab2_lib.baseboard_fab2(sch_1):\MG_DQ-DQS_NEAR_DIMM_NG_M_F_BYTE6\" )
					)
					( Status sCSetFlattened )
					( Origin gBackEnd )
				)
				( attribute "RELATIVE_PROPAGATION_DELAY" "0.00 MIL,195.00 MIL"
					( Parent
						( matchGroupRef "@baseboard_fab2_lib.baseboard_fab2(sch_1):\MG_DQ-DQS_NEAR_DIMM_NG_M_F_BYTE6\" )
					)
					( Units "uMatchProp" "ns" 1.000000)
					( Status sCSetFlattened )
					( Origin gBackEnd )
				)
				( attribute "RELATIVE_PROPAGATION_DELAY_SCOPE" "G"
					( Parent
						( matchGroupRef "@crescent_city_bb_fab1_lib.crescent_city_bb_fab1(sch_1):\MG_DQ_NEAR_DIMM_NG_M_F_BYTE6\" )
					)
					( Status sCSetFlattened )
					( Origin gBackEnd )
				)
				( attribute "RELATIVE_PROPAGATION_DELAY" "-50.00 MIL,50.00 MIL"
					( Parent
						( matchGroupRef "@crescent_city_bb_fab1_lib.crescent_city_bb_fab1(sch_1):\MG_DQ_NEAR_DIMM_NG_M_F_BYTE6\" )
					)
					( Units "uMatchProp" "ns" 1.000000)
					( Status sCSetFlattened )
					( Origin gBackEnd )
				)
			)
			( pinPair "@baseboard_fab2_lib.baseboard_fab2(sch_1):\PP4128\"
				( pinRef "@baseboard_fab2_lib.baseboard_fab2(sch_1):page28_i172:DDR5_DQ(55)" )
				( pinRef "@baseboard_fab2_lib.baseboard_fab2(sch_1):page53_i111:DQ(54)" )
				( attribute "RELATIVE_PROPAGATION_DELAY_SCOPE" "G"
					( Parent
						( matchGroupRef "@baseboard_fab2_lib.baseboard_fab2(sch_1):\MG_DQ-DQS_FAR_DIMM_NG_M_F_BYTE6\" )
					)
					( Status sCSetFlattened )
					( Origin gBackEnd )
				)
				( attribute "RELATIVE_PROPAGATION_DELAY" "0.00 MIL,195.00 MIL"
					( Parent
						( matchGroupRef "@baseboard_fab2_lib.baseboard_fab2(sch_1):\MG_DQ-DQS_FAR_DIMM_NG_M_F_BYTE6\" )
					)
					( Units "uMatchProp" "ns" 1.000000)
					( Status sCSetFlattened )
					( Origin gBackEnd )
				)
				( attribute "RELATIVE_PROPAGATION_DELAY_SCOPE" "G"
					( Parent
						( matchGroupRef "@baseboard_fab2_lib.baseboard_fab2(sch_1):\MG_DQ_FAR_DIMM_NG_M_F_BYTE6\" )
					)
					( Status sCSetFlattened )
					( Origin gBackEnd )
				)
				( attribute "RELATIVE_PROPAGATION_DELAY" "-50.00 MIL,50.00 MIL"
					( Parent
						( matchGroupRef "@baseboard_fab2_lib.baseboard_fab2(sch_1):\MG_DQ_FAR_DIMM_NG_M_F_BYTE6\" )
					)
					( Units "uMatchProp" "ns" 1.000000)
					( Status sCSetFlattened )
					( Origin gBackEnd )
				)
			)
			( pinPair "@baseboard_fab2_lib.baseboard_fab2(sch_1):\PP4130\"
				( pinRef "@baseboard_fab2_lib.baseboard_fab2(sch_1):page28_i172:DDR5_DQ(55)" )
				( pinRef "@baseboard_fab2_lib.baseboard_fab2(sch_1):page54_i111:DQ(55)" )
				( attribute "RELATIVE_PROPAGATION_DELAY_SCOPE" "G"
					( Parent
						( matchGroupRef "@baseboard_fab2_lib.baseboard_fab2(sch_1):\MG_DQ-DQS_NEAR_DIMM_NG_M_F_BYTE6\" )
					)
					( Status sCSetFlattened )
					( Origin gBackEnd )
				)
				( attribute "RELATIVE_PROPAGATION_DELAY" "0.00 MIL,195.00 MIL"
					( Parent
						( matchGroupRef "@baseboard_fab2_lib.baseboard_fab2(sch_1):\MG_DQ-DQS_NEAR_DIMM_NG_M_F_BYTE6\" )
					)
					( Units "uMatchProp" "ns" 1.000000)
					( Status sCSetFlattened )
					( Origin gBackEnd )
				)
				( attribute "RELATIVE_PROPAGATION_DELAY_SCOPE" "G"
					( Parent
						( matchGroupRef "@crescent_city_bb_fab1_lib.crescent_city_bb_fab1(sch_1):\MG_DQ_NEAR_DIMM_NG_M_F_BYTE6\" )
					)
					( Status sCSetFlattened )
					( Origin gBackEnd )
				)
				( attribute "RELATIVE_PROPAGATION_DELAY" "-50.00 MIL,50.00 MIL"
					( Parent
						( matchGroupRef "@crescent_city_bb_fab1_lib.crescent_city_bb_fab1(sch_1):\MG_DQ_NEAR_DIMM_NG_M_F_BYTE6\" )
					)
					( Units "uMatchProp" "ns" 1.000000)
					( Status sCSetFlattened )
					( Origin gBackEnd )
				)
			)
			( pinPair "@baseboard_fab2_lib.baseboard_fab2(sch_1):\PP4083\"
				( pinRef "@baseboard_fab2_lib.baseboard_fab2(sch_1):page28_i172:DDR5_DQ(56)" )
				( pinRef "@baseboard_fab2_lib.baseboard_fab2(sch_1):page53_i111:DQ(57)" )
				( attribute "RELATIVE_PROPAGATION_DELAY_SCOPE" "G"
					( Parent
						( matchGroupRef "@baseboard_fab2_lib.baseboard_fab2(sch_1):\MG_DQ-DQS_FAR_DIMM_NG_M_F_BYTE7\" )
					)
					( Status sCSetFlattened )
					( Origin gBackEnd )
				)
				( attribute "RELATIVE_PROPAGATION_DELAY" "0.00 MIL,195.00 MIL"
					( Parent
						( matchGroupRef "@baseboard_fab2_lib.baseboard_fab2(sch_1):\MG_DQ-DQS_FAR_DIMM_NG_M_F_BYTE7\" )
					)
					( Units "uMatchProp" "ns" 1.000000)
					( Status sCSetFlattened )
					( Origin gBackEnd )
				)
				( attribute "RELATIVE_PROPAGATION_DELAY_SCOPE" "G"
					( Parent
						( matchGroupRef "@crescent_city_bb_fab1_lib.crescent_city_bb_fab1(sch_1):\MG_DQ_FAR_DIMM_NG_M_F_BYTE7\" )
					)
					( Status sCSetFlattened )
					( Origin gBackEnd )
				)
				( attribute "RELATIVE_PROPAGATION_DELAY" "-50.00 MIL,50.00 MIL"
					( Parent
						( matchGroupRef "@crescent_city_bb_fab1_lib.crescent_city_bb_fab1(sch_1):\MG_DQ_FAR_DIMM_NG_M_F_BYTE7\" )
					)
					( Units "uMatchProp" "ns" 1.000000)
					( Status sCSetFlattened )
					( Origin gBackEnd )
				)
			)
			( pinPair "@baseboard_fab2_lib.baseboard_fab2(sch_1):\PP4085\"
				( pinRef "@baseboard_fab2_lib.baseboard_fab2(sch_1):page28_i172:DDR5_DQ(56)" )
				( pinRef "@baseboard_fab2_lib.baseboard_fab2(sch_1):page54_i111:DQ(56)" )
				( attribute "RELATIVE_PROPAGATION_DELAY_SCOPE" "G"
					( Parent
						( matchGroupRef "@baseboard_fab2_lib.baseboard_fab2(sch_1):\MG_DQ-DQS_NEAR_DIMM_NG_M_F_BYTE7\" )
					)
					( Status sCSetFlattened )
					( Origin gBackEnd )
				)
				( attribute "RELATIVE_PROPAGATION_DELAY" "0.00 MIL,195.00 MIL"
					( Parent
						( matchGroupRef "@baseboard_fab2_lib.baseboard_fab2(sch_1):\MG_DQ-DQS_NEAR_DIMM_NG_M_F_BYTE7\" )
					)
					( Units "uMatchProp" "ns" 1.000000)
					( Status sCSetFlattened )
					( Origin gBackEnd )
				)
				( attribute "RELATIVE_PROPAGATION_DELAY_SCOPE" "G"
					( Parent
						( matchGroupRef "@crescent_city_bb_fab1_lib.crescent_city_bb_fab1(sch_1):\MG_DQ_NEAR_DIMM_NG_M_F_BYTE7\" )
					)
					( Status sCSetFlattened )
					( Origin gBackEnd )
				)
				( attribute "RELATIVE_PROPAGATION_DELAY" "-50.00 MIL,50.00 MIL"
					( Parent
						( matchGroupRef "@crescent_city_bb_fab1_lib.crescent_city_bb_fab1(sch_1):\MG_DQ_NEAR_DIMM_NG_M_F_BYTE7\" )
					)
					( Units "uMatchProp" "ns" 1.000000)
					( Status sCSetFlattened )
					( Origin gBackEnd )
				)
			)
			( pinPair "@baseboard_fab2_lib.baseboard_fab2(sch_1):\PP4086\"
				( pinRef "@baseboard_fab2_lib.baseboard_fab2(sch_1):page28_i172:DDR5_DQ(57)" )
				( pinRef "@baseboard_fab2_lib.baseboard_fab2(sch_1):page53_i111:DQ(56)" )
				( attribute "RELATIVE_PROPAGATION_DELAY_SCOPE" "G"
					( Parent
						( matchGroupRef "@baseboard_fab2_lib.baseboard_fab2(sch_1):\MG_DQ-DQS_FAR_DIMM_NG_M_F_BYTE7\" )
					)
					( Status sCSetFlattened )
					( Origin gBackEnd )
				)
				( attribute "RELATIVE_PROPAGATION_DELAY" "0.00 MIL,195.00 MIL"
					( Parent
						( matchGroupRef "@baseboard_fab2_lib.baseboard_fab2(sch_1):\MG_DQ-DQS_FAR_DIMM_NG_M_F_BYTE7\" )
					)
					( Units "uMatchProp" "ns" 1.000000)
					( Status sCSetFlattened )
					( Origin gBackEnd )
				)
				( attribute "RELATIVE_PROPAGATION_DELAY_SCOPE" "G"
					( Parent
						( matchGroupRef "@crescent_city_bb_fab1_lib.crescent_city_bb_fab1(sch_1):\MG_DQ_FAR_DIMM_NG_M_F_BYTE7\" )
					)
					( Status sCSetFlattened )
					( Origin gBackEnd )
				)
				( attribute "RELATIVE_PROPAGATION_DELAY" "-50.00 MIL,50.00 MIL"
					( Parent
						( matchGroupRef "@crescent_city_bb_fab1_lib.crescent_city_bb_fab1(sch_1):\MG_DQ_FAR_DIMM_NG_M_F_BYTE7\" )
					)
					( Units "uMatchProp" "ns" 1.000000)
					( Status sCSetFlattened )
					( Origin gBackEnd )
				)
			)
			( pinPair "@baseboard_fab2_lib.baseboard_fab2(sch_1):\PP4088\"
				( pinRef "@baseboard_fab2_lib.baseboard_fab2(sch_1):page28_i172:DDR5_DQ(57)" )
				( pinRef "@baseboard_fab2_lib.baseboard_fab2(sch_1):page54_i111:DQ(57)" )
				( attribute "RELATIVE_PROPAGATION_DELAY_SCOPE" "G"
					( Parent
						( matchGroupRef "@baseboard_fab2_lib.baseboard_fab2(sch_1):\MG_DQ-DQS_NEAR_DIMM_NG_M_F_BYTE7\" )
					)
					( Status sCSetFlattened )
					( Origin gBackEnd )
				)
				( attribute "RELATIVE_PROPAGATION_DELAY" "0.00 MIL,195.00 MIL"
					( Parent
						( matchGroupRef "@baseboard_fab2_lib.baseboard_fab2(sch_1):\MG_DQ-DQS_NEAR_DIMM_NG_M_F_BYTE7\" )
					)
					( Units "uMatchProp" "ns" 1.000000)
					( Status sCSetFlattened )
					( Origin gBackEnd )
				)
				( attribute "RELATIVE_PROPAGATION_DELAY_SCOPE" "G"
					( Parent
						( matchGroupRef "@crescent_city_bb_fab1_lib.crescent_city_bb_fab1(sch_1):\MG_DQ_NEAR_DIMM_NG_M_F_BYTE7\" )
					)
					( Status sCSetFlattened )
					( Origin gBackEnd )
				)
				( attribute "RELATIVE_PROPAGATION_DELAY" "-50.00 MIL,50.00 MIL"
					( Parent
						( matchGroupRef "@crescent_city_bb_fab1_lib.crescent_city_bb_fab1(sch_1):\MG_DQ_NEAR_DIMM_NG_M_F_BYTE7\" )
					)
					( Units "uMatchProp" "ns" 1.000000)
					( Status sCSetFlattened )
					( Origin gBackEnd )
				)
			)
			( pinPair "@baseboard_fab2_lib.baseboard_fab2(sch_1):\PP4089\"
				( pinRef "@baseboard_fab2_lib.baseboard_fab2(sch_1):page28_i172:DDR5_DQ(58)" )
				( pinRef "@baseboard_fab2_lib.baseboard_fab2(sch_1):page53_i111:DQ(59)" )
				( attribute "RELATIVE_PROPAGATION_DELAY_SCOPE" "G"
					( Parent
						( matchGroupRef "@baseboard_fab2_lib.baseboard_fab2(sch_1):\MG_DQ-DQS_FAR_DIMM_NG_M_F_BYTE7\" )
					)
					( Status sCSetFlattened )
					( Origin gBackEnd )
				)
				( attribute "RELATIVE_PROPAGATION_DELAY" "0.00 MIL,195.00 MIL"
					( Parent
						( matchGroupRef "@baseboard_fab2_lib.baseboard_fab2(sch_1):\MG_DQ-DQS_FAR_DIMM_NG_M_F_BYTE7\" )
					)
					( Units "uMatchProp" "ns" 1.000000)
					( Status sCSetFlattened )
					( Origin gBackEnd )
				)
				( attribute "RELATIVE_PROPAGATION_DELAY_SCOPE" "G"
					( Parent
						( matchGroupRef "@crescent_city_bb_fab1_lib.crescent_city_bb_fab1(sch_1):\MG_DQ_FAR_DIMM_NG_M_F_BYTE7\" )
					)
					( Status sCSetFlattened )
					( Origin gBackEnd )
				)
				( attribute "RELATIVE_PROPAGATION_DELAY" "-50.00 MIL,50.00 MIL"
					( Parent
						( matchGroupRef "@crescent_city_bb_fab1_lib.crescent_city_bb_fab1(sch_1):\MG_DQ_FAR_DIMM_NG_M_F_BYTE7\" )
					)
					( Units "uMatchProp" "ns" 1.000000)
					( Status sCSetFlattened )
					( Origin gBackEnd )
				)
			)
			( pinPair "@baseboard_fab2_lib.baseboard_fab2(sch_1):\PP4091\"
				( pinRef "@baseboard_fab2_lib.baseboard_fab2(sch_1):page28_i172:DDR5_DQ(58)" )
				( pinRef "@baseboard_fab2_lib.baseboard_fab2(sch_1):page54_i111:DQ(58)" )
				( attribute "RELATIVE_PROPAGATION_DELAY_SCOPE" "G"
					( Parent
						( matchGroupRef "@baseboard_fab2_lib.baseboard_fab2(sch_1):\MG_DQ-DQS_NEAR_DIMM_NG_M_F_BYTE7\" )
					)
					( Status sCSetFlattened )
					( Origin gBackEnd )
				)
				( attribute "RELATIVE_PROPAGATION_DELAY" "0.00 MIL,195.00 MIL"
					( Parent
						( matchGroupRef "@baseboard_fab2_lib.baseboard_fab2(sch_1):\MG_DQ-DQS_NEAR_DIMM_NG_M_F_BYTE7\" )
					)
					( Units "uMatchProp" "ns" 1.000000)
					( Status sCSetFlattened )
					( Origin gBackEnd )
				)
				( attribute "RELATIVE_PROPAGATION_DELAY_SCOPE" "G"
					( Parent
						( matchGroupRef "@crescent_city_bb_fab1_lib.crescent_city_bb_fab1(sch_1):\MG_DQ_NEAR_DIMM_NG_M_F_BYTE7\" )
					)
					( Status sCSetFlattened )
					( Origin gBackEnd )
				)
				( attribute "RELATIVE_PROPAGATION_DELAY" "-50.00 MIL,50.00 MIL"
					( Parent
						( matchGroupRef "@crescent_city_bb_fab1_lib.crescent_city_bb_fab1(sch_1):\MG_DQ_NEAR_DIMM_NG_M_F_BYTE7\" )
					)
					( Units "uMatchProp" "ns" 1.000000)
					( Status sCSetFlattened )
					( Origin gBackEnd )
				)
			)
			( pinPair "@baseboard_fab2_lib.baseboard_fab2(sch_1):\PP4092\"
				( pinRef "@baseboard_fab2_lib.baseboard_fab2(sch_1):page28_i172:DDR5_DQ(59)" )
				( pinRef "@baseboard_fab2_lib.baseboard_fab2(sch_1):page53_i111:DQ(58)" )
				( attribute "RELATIVE_PROPAGATION_DELAY_SCOPE" "G"
					( Parent
						( matchGroupRef "@baseboard_fab2_lib.baseboard_fab2(sch_1):\MG_DQ-DQS_FAR_DIMM_NG_M_F_BYTE7\" )
					)
					( Status sCSetFlattened )
					( Origin gBackEnd )
				)
				( attribute "RELATIVE_PROPAGATION_DELAY" "0.00 MIL,195.00 MIL"
					( Parent
						( matchGroupRef "@baseboard_fab2_lib.baseboard_fab2(sch_1):\MG_DQ-DQS_FAR_DIMM_NG_M_F_BYTE7\" )
					)
					( Units "uMatchProp" "ns" 1.000000)
					( Status sCSetFlattened )
					( Origin gBackEnd )
				)
				( attribute "RELATIVE_PROPAGATION_DELAY_SCOPE" "G"
					( Parent
						( matchGroupRef "@crescent_city_bb_fab1_lib.crescent_city_bb_fab1(sch_1):\MG_DQ_FAR_DIMM_NG_M_F_BYTE7\" )
					)
					( Status sCSetFlattened )
					( Origin gBackEnd )
				)
				( attribute "RELATIVE_PROPAGATION_DELAY" "-50.00 MIL,50.00 MIL"
					( Parent
						( matchGroupRef "@crescent_city_bb_fab1_lib.crescent_city_bb_fab1(sch_1):\MG_DQ_FAR_DIMM_NG_M_F_BYTE7\" )
					)
					( Units "uMatchProp" "ns" 1.000000)
					( Status sCSetFlattened )
					( Origin gBackEnd )
				)
			)
			( pinPair "@baseboard_fab2_lib.baseboard_fab2(sch_1):\PP4094\"
				( pinRef "@baseboard_fab2_lib.baseboard_fab2(sch_1):page28_i172:DDR5_DQ(59)" )
				( pinRef "@baseboard_fab2_lib.baseboard_fab2(sch_1):page54_i111:DQ(59)" )
				( attribute "RELATIVE_PROPAGATION_DELAY_SCOPE" "G"
					( Parent
						( matchGroupRef "@baseboard_fab2_lib.baseboard_fab2(sch_1):\MG_DQ-DQS_NEAR_DIMM_NG_M_F_BYTE7\" )
					)
					( Status sCSetFlattened )
					( Origin gBackEnd )
				)
				( attribute "RELATIVE_PROPAGATION_DELAY" "0.00 MIL,195.00 MIL"
					( Parent
						( matchGroupRef "@baseboard_fab2_lib.baseboard_fab2(sch_1):\MG_DQ-DQS_NEAR_DIMM_NG_M_F_BYTE7\" )
					)
					( Units "uMatchProp" "ns" 1.000000)
					( Status sCSetFlattened )
					( Origin gBackEnd )
				)
				( attribute "RELATIVE_PROPAGATION_DELAY_SCOPE" "G"
					( Parent
						( matchGroupRef "@crescent_city_bb_fab1_lib.crescent_city_bb_fab1(sch_1):\MG_DQ_NEAR_DIMM_NG_M_F_BYTE7\" )
					)
					( Status sCSetFlattened )
					( Origin gBackEnd )
				)
				( attribute "RELATIVE_PROPAGATION_DELAY" "-50.00 MIL,50.00 MIL"
					( Parent
						( matchGroupRef "@crescent_city_bb_fab1_lib.crescent_city_bb_fab1(sch_1):\MG_DQ_NEAR_DIMM_NG_M_F_BYTE7\" )
					)
					( Units "uMatchProp" "ns" 1.000000)
					( Status sCSetFlattened )
					( Origin gBackEnd )
				)
			)
			( pinPair "@baseboard_fab2_lib.baseboard_fab2(sch_1):\PP4095\"
				( pinRef "@baseboard_fab2_lib.baseboard_fab2(sch_1):page28_i172:DDR5_DQ(60)" )
				( pinRef "@baseboard_fab2_lib.baseboard_fab2(sch_1):page53_i111:DQ(61)" )
				( attribute "RELATIVE_PROPAGATION_DELAY_SCOPE" "G"
					( Parent
						( matchGroupRef "@baseboard_fab2_lib.baseboard_fab2(sch_1):\MG_DQ-DQS_FAR_DIMM_NG_M_F_BYTE7\" )
					)
					( Status sCSetFlattened )
					( Origin gBackEnd )
				)
				( attribute "RELATIVE_PROPAGATION_DELAY" "0.00 MIL,195.00 MIL"
					( Parent
						( matchGroupRef "@baseboard_fab2_lib.baseboard_fab2(sch_1):\MG_DQ-DQS_FAR_DIMM_NG_M_F_BYTE7\" )
					)
					( Units "uMatchProp" "ns" 1.000000)
					( Status sCSetFlattened )
					( Origin gBackEnd )
				)
				( attribute "RELATIVE_PROPAGATION_DELAY_SCOPE" "G"
					( Parent
						( matchGroupRef "@crescent_city_bb_fab1_lib.crescent_city_bb_fab1(sch_1):\MG_DQ_FAR_DIMM_NG_M_F_BYTE7\" )
					)
					( Origin gBackEnd )
				)
				( attribute "RELATIVE_PROPAGATION_DELAY" "TARGET,TARGET"
					( Parent
						( matchGroupRef "@crescent_city_bb_fab1_lib.crescent_city_bb_fab1(sch_1):\MG_DQ_FAR_DIMM_NG_M_F_BYTE7\" )
					)
					( Units "uMatchProp" "ns" 1.000000)
					( Origin gBackEnd )
				)
			)
			( pinPair "@baseboard_fab2_lib.baseboard_fab2(sch_1):\PP4097\"
				( pinRef "@baseboard_fab2_lib.baseboard_fab2(sch_1):page28_i172:DDR5_DQ(60)" )
				( pinRef "@baseboard_fab2_lib.baseboard_fab2(sch_1):page54_i111:DQ(60)" )
				( attribute "RELATIVE_PROPAGATION_DELAY_SCOPE" "G"
					( Parent
						( matchGroupRef "@baseboard_fab2_lib.baseboard_fab2(sch_1):\MG_DQ-DQS_NEAR_DIMM_NG_M_F_BYTE7\" )
					)
					( Status sCSetFlattened )
					( Origin gBackEnd )
				)
				( attribute "RELATIVE_PROPAGATION_DELAY" "0.00 MIL,195.00 MIL"
					( Parent
						( matchGroupRef "@baseboard_fab2_lib.baseboard_fab2(sch_1):\MG_DQ-DQS_NEAR_DIMM_NG_M_F_BYTE7\" )
					)
					( Units "uMatchProp" "ns" 1.000000)
					( Status sCSetFlattened )
					( Origin gBackEnd )
				)
				( attribute "RELATIVE_PROPAGATION_DELAY_SCOPE" "G"
					( Parent
						( matchGroupRef "@crescent_city_bb_fab1_lib.crescent_city_bb_fab1(sch_1):\MG_DQ_NEAR_DIMM_NG_M_F_BYTE7\" )
					)
					( Origin gBackEnd )
				)
				( attribute "RELATIVE_PROPAGATION_DELAY" "TARGET,TARGET"
					( Parent
						( matchGroupRef "@crescent_city_bb_fab1_lib.crescent_city_bb_fab1(sch_1):\MG_DQ_NEAR_DIMM_NG_M_F_BYTE7\" )
					)
					( Units "uMatchProp" "ns" 1.000000)
					( Origin gBackEnd )
				)
			)
			( pinPair "@baseboard_fab2_lib.baseboard_fab2(sch_1):\PP4098\"
				( pinRef "@baseboard_fab2_lib.baseboard_fab2(sch_1):page28_i172:DDR5_DQ(61)" )
				( pinRef "@baseboard_fab2_lib.baseboard_fab2(sch_1):page53_i111:DQ(60)" )
				( attribute "RELATIVE_PROPAGATION_DELAY_SCOPE" "G"
					( Parent
						( matchGroupRef "@baseboard_fab2_lib.baseboard_fab2(sch_1):\MG_DQ-DQS_FAR_DIMM_NG_M_F_BYTE7\" )
					)
					( Status sCSetFlattened )
					( Origin gBackEnd )
				)
				( attribute "RELATIVE_PROPAGATION_DELAY" "0.00 MIL,195.00 MIL"
					( Parent
						( matchGroupRef "@baseboard_fab2_lib.baseboard_fab2(sch_1):\MG_DQ-DQS_FAR_DIMM_NG_M_F_BYTE7\" )
					)
					( Units "uMatchProp" "ns" 1.000000)
					( Status sCSetFlattened )
					( Origin gBackEnd )
				)
				( attribute "RELATIVE_PROPAGATION_DELAY_SCOPE" "G"
					( Parent
						( matchGroupRef "@crescent_city_bb_fab1_lib.crescent_city_bb_fab1(sch_1):\MG_DQ_FAR_DIMM_NG_M_F_BYTE7\" )
					)
					( Status sCSetFlattened )
					( Origin gBackEnd )
				)
				( attribute "RELATIVE_PROPAGATION_DELAY" "-50.00 MIL,50.00 MIL"
					( Parent
						( matchGroupRef "@crescent_city_bb_fab1_lib.crescent_city_bb_fab1(sch_1):\MG_DQ_FAR_DIMM_NG_M_F_BYTE7\" )
					)
					( Units "uMatchProp" "ns" 1.000000)
					( Status sCSetFlattened )
					( Origin gBackEnd )
				)
			)
			( pinPair "@baseboard_fab2_lib.baseboard_fab2(sch_1):\PP4100\"
				( pinRef "@baseboard_fab2_lib.baseboard_fab2(sch_1):page28_i172:DDR5_DQ(61)" )
				( pinRef "@baseboard_fab2_lib.baseboard_fab2(sch_1):page54_i111:DQ(61)" )
				( attribute "RELATIVE_PROPAGATION_DELAY_SCOPE" "G"
					( Parent
						( matchGroupRef "@baseboard_fab2_lib.baseboard_fab2(sch_1):\MG_DQ-DQS_NEAR_DIMM_NG_M_F_BYTE7\" )
					)
					( Status sCSetFlattened )
					( Origin gBackEnd )
				)
				( attribute "RELATIVE_PROPAGATION_DELAY" "0.00 MIL,195.00 MIL"
					( Parent
						( matchGroupRef "@baseboard_fab2_lib.baseboard_fab2(sch_1):\MG_DQ-DQS_NEAR_DIMM_NG_M_F_BYTE7\" )
					)
					( Units "uMatchProp" "ns" 1.000000)
					( Status sCSetFlattened )
					( Origin gBackEnd )
				)
				( attribute "RELATIVE_PROPAGATION_DELAY_SCOPE" "G"
					( Parent
						( matchGroupRef "@crescent_city_bb_fab1_lib.crescent_city_bb_fab1(sch_1):\MG_DQ_NEAR_DIMM_NG_M_F_BYTE7\" )
					)
					( Status sCSetFlattened )
					( Origin gBackEnd )
				)
				( attribute "RELATIVE_PROPAGATION_DELAY" "-50.00 MIL,50.00 MIL"
					( Parent
						( matchGroupRef "@crescent_city_bb_fab1_lib.crescent_city_bb_fab1(sch_1):\MG_DQ_NEAR_DIMM_NG_M_F_BYTE7\" )
					)
					( Units "uMatchProp" "ns" 1.000000)
					( Status sCSetFlattened )
					( Origin gBackEnd )
				)
			)
			( pinPair "@baseboard_fab2_lib.baseboard_fab2(sch_1):\PP4101\"
				( pinRef "@baseboard_fab2_lib.baseboard_fab2(sch_1):page28_i172:DDR5_DQ(62)" )
				( pinRef "@baseboard_fab2_lib.baseboard_fab2(sch_1):page53_i111:DQ(63)" )
				( attribute "RELATIVE_PROPAGATION_DELAY_SCOPE" "G"
					( Parent
						( matchGroupRef "@baseboard_fab2_lib.baseboard_fab2(sch_1):\MG_DQ-DQS_FAR_DIMM_NG_M_F_BYTE7\" )
					)
					( Status sCSetFlattened )
					( Origin gBackEnd )
				)
				( attribute "RELATIVE_PROPAGATION_DELAY" "0.00 MIL,195.00 MIL"
					( Parent
						( matchGroupRef "@baseboard_fab2_lib.baseboard_fab2(sch_1):\MG_DQ-DQS_FAR_DIMM_NG_M_F_BYTE7\" )
					)
					( Units "uMatchProp" "ns" 1.000000)
					( Status sCSetFlattened )
					( Origin gBackEnd )
				)
				( attribute "RELATIVE_PROPAGATION_DELAY_SCOPE" "G"
					( Parent
						( matchGroupRef "@crescent_city_bb_fab1_lib.crescent_city_bb_fab1(sch_1):\MG_DQ_FAR_DIMM_NG_M_F_BYTE7\" )
					)
					( Status sCSetFlattened )
					( Origin gBackEnd )
				)
				( attribute "RELATIVE_PROPAGATION_DELAY" "-50.00 MIL,50.00 MIL"
					( Parent
						( matchGroupRef "@crescent_city_bb_fab1_lib.crescent_city_bb_fab1(sch_1):\MG_DQ_FAR_DIMM_NG_M_F_BYTE7\" )
					)
					( Units "uMatchProp" "ns" 1.000000)
					( Status sCSetFlattened )
					( Origin gBackEnd )
				)
			)
			( pinPair "@baseboard_fab2_lib.baseboard_fab2(sch_1):\PP4103\"
				( pinRef "@baseboard_fab2_lib.baseboard_fab2(sch_1):page28_i172:DDR5_DQ(62)" )
				( pinRef "@baseboard_fab2_lib.baseboard_fab2(sch_1):page54_i111:DQ(62)" )
				( attribute "RELATIVE_PROPAGATION_DELAY_SCOPE" "G"
					( Parent
						( matchGroupRef "@baseboard_fab2_lib.baseboard_fab2(sch_1):\MG_DQ-DQS_NEAR_DIMM_NG_M_F_BYTE7\" )
					)
					( Status sCSetFlattened )
					( Origin gBackEnd )
				)
				( attribute "RELATIVE_PROPAGATION_DELAY" "0.00 MIL,195.00 MIL"
					( Parent
						( matchGroupRef "@baseboard_fab2_lib.baseboard_fab2(sch_1):\MG_DQ-DQS_NEAR_DIMM_NG_M_F_BYTE7\" )
					)
					( Units "uMatchProp" "ns" 1.000000)
					( Status sCSetFlattened )
					( Origin gBackEnd )
				)
				( attribute "RELATIVE_PROPAGATION_DELAY_SCOPE" "G"
					( Parent
						( matchGroupRef "@crescent_city_bb_fab1_lib.crescent_city_bb_fab1(sch_1):\MG_DQ_NEAR_DIMM_NG_M_F_BYTE7\" )
					)
					( Status sCSetFlattened )
					( Origin gBackEnd )
				)
				( attribute "RELATIVE_PROPAGATION_DELAY" "-50.00 MIL,50.00 MIL"
					( Parent
						( matchGroupRef "@crescent_city_bb_fab1_lib.crescent_city_bb_fab1(sch_1):\MG_DQ_NEAR_DIMM_NG_M_F_BYTE7\" )
					)
					( Units "uMatchProp" "ns" 1.000000)
					( Status sCSetFlattened )
					( Origin gBackEnd )
				)
			)
			( pinPair "@baseboard_fab2_lib.baseboard_fab2(sch_1):\PP4104\"
				( pinRef "@baseboard_fab2_lib.baseboard_fab2(sch_1):page28_i172:DDR5_DQ(63)" )
				( pinRef "@baseboard_fab2_lib.baseboard_fab2(sch_1):page53_i111:DQ(62)" )
				( attribute "RELATIVE_PROPAGATION_DELAY_SCOPE" "G"
					( Parent
						( matchGroupRef "@baseboard_fab2_lib.baseboard_fab2(sch_1):\MG_DQ-DQS_FAR_DIMM_NG_M_F_BYTE7\" )
					)
					( Status sCSetFlattened )
					( Origin gBackEnd )
				)
				( attribute "RELATIVE_PROPAGATION_DELAY" "0.00 MIL,195.00 MIL"
					( Parent
						( matchGroupRef "@baseboard_fab2_lib.baseboard_fab2(sch_1):\MG_DQ-DQS_FAR_DIMM_NG_M_F_BYTE7\" )
					)
					( Units "uMatchProp" "ns" 1.000000)
					( Status sCSetFlattened )
					( Origin gBackEnd )
				)
				( attribute "RELATIVE_PROPAGATION_DELAY_SCOPE" "G"
					( Parent
						( matchGroupRef "@crescent_city_bb_fab1_lib.crescent_city_bb_fab1(sch_1):\MG_DQ_FAR_DIMM_NG_M_F_BYTE7\" )
					)
					( Status sCSetFlattened )
					( Origin gBackEnd )
				)
				( attribute "RELATIVE_PROPAGATION_DELAY" "-50.00 MIL,50.00 MIL"
					( Parent
						( matchGroupRef "@crescent_city_bb_fab1_lib.crescent_city_bb_fab1(sch_1):\MG_DQ_FAR_DIMM_NG_M_F_BYTE7\" )
					)
					( Units "uMatchProp" "ns" 1.000000)
					( Status sCSetFlattened )
					( Origin gBackEnd )
				)
			)
			( pinPair "@baseboard_fab2_lib.baseboard_fab2(sch_1):\PP4106\"
				( pinRef "@baseboard_fab2_lib.baseboard_fab2(sch_1):page28_i172:DDR5_DQ(63)" )
				( pinRef "@baseboard_fab2_lib.baseboard_fab2(sch_1):page54_i111:DQ(63)" )
				( attribute "RELATIVE_PROPAGATION_DELAY_SCOPE" "G"
					( Parent
						( matchGroupRef "@baseboard_fab2_lib.baseboard_fab2(sch_1):\MG_DQ-DQS_NEAR_DIMM_NG_M_F_BYTE7\" )
					)
					( Status sCSetFlattened )
					( Origin gBackEnd )
				)
				( attribute "RELATIVE_PROPAGATION_DELAY" "0.00 MIL,195.00 MIL"
					( Parent
						( matchGroupRef "@baseboard_fab2_lib.baseboard_fab2(sch_1):\MG_DQ-DQS_NEAR_DIMM_NG_M_F_BYTE7\" )
					)
					( Units "uMatchProp" "ns" 1.000000)
					( Status sCSetFlattened )
					( Origin gBackEnd )
				)
				( attribute "RELATIVE_PROPAGATION_DELAY_SCOPE" "G"
					( Parent
						( matchGroupRef "@crescent_city_bb_fab1_lib.crescent_city_bb_fab1(sch_1):\MG_DQ_NEAR_DIMM_NG_M_F_BYTE7\" )
					)
					( Status sCSetFlattened )
					( Origin gBackEnd )
				)
				( attribute "RELATIVE_PROPAGATION_DELAY" "-50.00 MIL,50.00 MIL"
					( Parent
						( matchGroupRef "@crescent_city_bb_fab1_lib.crescent_city_bb_fab1(sch_1):\MG_DQ_NEAR_DIMM_NG_M_F_BYTE7\" )
					)
					( Units "uMatchProp" "ns" 1.000000)
					( Status sCSetFlattened )
					( Origin gBackEnd )
				)
			)
			( pinPair "@baseboard_fab2_lib.baseboard_fab2(sch_1):\PP2905\"
				( pinRef "@baseboard_fab2_lib.baseboard_fab2(sch_1):page57_i172:DDR0_DQ(10)" )
				( pinRef "@baseboard_fab2_lib.baseboard_fab2(sch_1):page77_i111:DQ(11)" )
				( attribute "RELATIVE_PROPAGATION_DELAY_SCOPE" "G"
					( Parent
						( matchGroupRef "@baseboard_fab2_lib.baseboard_fab2(sch_1):\MG_DQ-DQS_FAR_DIMM_NG_M_G_BYTE1\" )
					)
					( Status sCSetFlattened )
					( Origin gBackEnd )
				)
				( attribute "RELATIVE_PROPAGATION_DELAY" "0.00 MIL,195.00 MIL"
					( Parent
						( matchGroupRef "@baseboard_fab2_lib.baseboard_fab2(sch_1):\MG_DQ-DQS_FAR_DIMM_NG_M_G_BYTE1\" )
					)
					( Units "uMatchProp" "ns" 1.000000)
					( Status sCSetFlattened )
					( Origin gBackEnd )
				)
				( attribute "RELATIVE_PROPAGATION_DELAY_SCOPE" "G"
					( Parent
						( matchGroupRef "@baseboard_fab2_lib.baseboard_fab2(sch_1):\MG_DQ_FAR_DIMM_NG_M_G_BYTE1\" )
					)
					( Status sCSetFlattened )
					( Origin gBackEnd )
				)
				( attribute "RELATIVE_PROPAGATION_DELAY" "-50.00 MIL,50.00 MIL"
					( Parent
						( matchGroupRef "@baseboard_fab2_lib.baseboard_fab2(sch_1):\MG_DQ_FAR_DIMM_NG_M_G_BYTE1\" )
					)
					( Units "uMatchProp" "ns" 1.000000)
					( Status sCSetFlattened )
					( Origin gBackEnd )
				)
			)
			( pinPair "@baseboard_fab2_lib.baseboard_fab2(sch_1):\PP2907\"
				( pinRef "@baseboard_fab2_lib.baseboard_fab2(sch_1):page78_i13:DQ(10)" )
				( pinRef "@baseboard_fab2_lib.baseboard_fab2(sch_1):page57_i172:DDR0_DQ(10)" )
				( attribute "RELATIVE_PROPAGATION_DELAY_SCOPE" "G"
					( Parent
						( matchGroupRef "@baseboard_fab2_lib.baseboard_fab2(sch_1):\MG_DQ-DQS_NEAR_DIMM_NG_M_G_BYTE1\" )
					)
					( Status sCSetFlattened )
					( Origin gBackEnd )
				)
				( attribute "RELATIVE_PROPAGATION_DELAY" "0.00 MIL,195.00 MIL"
					( Parent
						( matchGroupRef "@baseboard_fab2_lib.baseboard_fab2(sch_1):\MG_DQ-DQS_NEAR_DIMM_NG_M_G_BYTE1\" )
					)
					( Units "uMatchProp" "ns" 1.000000)
					( Status sCSetFlattened )
					( Origin gBackEnd )
				)
				( attribute "RELATIVE_PROPAGATION_DELAY_SCOPE" "G"
					( Parent
						( matchGroupRef "@baseboard_fab2_lib.baseboard_fab2(sch_1):\MG_DQ_NEAR_DIMM_NG_M_G_BYTE1\" )
					)
					( Status sCSetFlattened )
					( Origin gBackEnd )
				)
				( attribute "RELATIVE_PROPAGATION_DELAY" "-50.00 MIL,50.00 MIL"
					( Parent
						( matchGroupRef "@baseboard_fab2_lib.baseboard_fab2(sch_1):\MG_DQ_NEAR_DIMM_NG_M_G_BYTE1\" )
					)
					( Units "uMatchProp" "ns" 1.000000)
					( Status sCSetFlattened )
					( Origin gBackEnd )
				)
			)
			( pinPair "@baseboard_fab2_lib.baseboard_fab2(sch_1):\PP2698\"
				( pinRef "@baseboard_fab2_lib.baseboard_fab2(sch_1):page58_i172:DDR1_DQ(13)" )
				( pinRef "@baseboard_fab2_lib.baseboard_fab2(sch_1):page79_i111:DQ(12)" )
				( attribute "RELATIVE_PROPAGATION_DELAY_SCOPE" "G"
					( Parent
						( matchGroupRef "@baseboard_fab2_lib.baseboard_fab2(sch_1):\MG_DQ-DQS_FAR_DIMM_NG_M_H_BYTE1\" )
					)
					( Status sCSetFlattened )
					( Origin gBackEnd )
				)
				( attribute "RELATIVE_PROPAGATION_DELAY" "0.00 MIL,195.00 MIL"
					( Parent
						( matchGroupRef "@baseboard_fab2_lib.baseboard_fab2(sch_1):\MG_DQ-DQS_FAR_DIMM_NG_M_H_BYTE1\" )
					)
					( Units "uMatchProp" "ns" 1.000000)
					( Status sCSetFlattened )
					( Origin gBackEnd )
				)
				( attribute "RELATIVE_PROPAGATION_DELAY_SCOPE" "G"
					( Parent
						( matchGroupRef "@baseboard_fab2_lib.baseboard_fab2(sch_1):\MG_DQ_FAR_DIMM_NG_M_H_BYTE1\" )
					)
					( Status sCSetFlattened )
					( Origin gBackEnd )
				)
				( attribute "RELATIVE_PROPAGATION_DELAY" "-50.00 MIL,50.00 MIL"
					( Parent
						( matchGroupRef "@baseboard_fab2_lib.baseboard_fab2(sch_1):\MG_DQ_FAR_DIMM_NG_M_H_BYTE1\" )
					)
					( Units "uMatchProp" "ns" 1.000000)
					( Status sCSetFlattened )
					( Origin gBackEnd )
				)
			)
			( pinPair "@baseboard_fab2_lib.baseboard_fab2(sch_1):\PP2700\"
				( pinRef "@baseboard_fab2_lib.baseboard_fab2(sch_1):page80_i24:DQ(13)" )
				( pinRef "@baseboard_fab2_lib.baseboard_fab2(sch_1):page58_i172:DDR1_DQ(13)" )
				( attribute "RELATIVE_PROPAGATION_DELAY_SCOPE" "G"
					( Parent
						( matchGroupRef "@baseboard_fab2_lib.baseboard_fab2(sch_1):\MG_DQ-DQS_NEAR_DIMM_NG_M_H_BYTE1\" )
					)
					( Status sCSetFlattened )
					( Origin gBackEnd )
				)
				( attribute "RELATIVE_PROPAGATION_DELAY" "0.00 MIL,195.00 MIL"
					( Parent
						( matchGroupRef "@baseboard_fab2_lib.baseboard_fab2(sch_1):\MG_DQ-DQS_NEAR_DIMM_NG_M_H_BYTE1\" )
					)
					( Units "uMatchProp" "ns" 1.000000)
					( Status sCSetFlattened )
					( Origin gBackEnd )
				)
				( attribute "RELATIVE_PROPAGATION_DELAY_SCOPE" "G"
					( Parent
						( matchGroupRef "@baseboard_fab2_lib.baseboard_fab2(sch_1):\MG_DQ_NEAR_DIMM_NG_M_H_BYTE1\" )
					)
					( Status sCSetFlattened )
					( Origin gBackEnd )
				)
				( attribute "RELATIVE_PROPAGATION_DELAY" "-50.00 MIL,50.00 MIL"
					( Parent
						( matchGroupRef "@baseboard_fab2_lib.baseboard_fab2(sch_1):\MG_DQ_NEAR_DIMM_NG_M_H_BYTE1\" )
					)
					( Units "uMatchProp" "ns" 1.000000)
					( Status sCSetFlattened )
					( Origin gBackEnd )
				)
			)
			( pinPair "@baseboard_fab2_lib.baseboard_fab2(sch_1):\PP2701\"
				( pinRef "@baseboard_fab2_lib.baseboard_fab2(sch_1):page58_i172:DDR1_DQ(14)" )
				( pinRef "@baseboard_fab2_lib.baseboard_fab2(sch_1):page79_i111:DQ(15)" )
				( attribute "RELATIVE_PROPAGATION_DELAY_SCOPE" "G"
					( Parent
						( matchGroupRef "@baseboard_fab2_lib.baseboard_fab2(sch_1):\MG_DQ-DQS_FAR_DIMM_NG_M_H_BYTE1\" )
					)
					( Status sCSetFlattened )
					( Origin gBackEnd )
				)
				( attribute "RELATIVE_PROPAGATION_DELAY" "0.00 MIL,195.00 MIL"
					( Parent
						( matchGroupRef "@baseboard_fab2_lib.baseboard_fab2(sch_1):\MG_DQ-DQS_FAR_DIMM_NG_M_H_BYTE1\" )
					)
					( Units "uMatchProp" "ns" 1.000000)
					( Status sCSetFlattened )
					( Origin gBackEnd )
				)
				( attribute "RELATIVE_PROPAGATION_DELAY_SCOPE" "G"
					( Parent
						( matchGroupRef "@baseboard_fab2_lib.baseboard_fab2(sch_1):\MG_DQ_FAR_DIMM_NG_M_H_BYTE1\" )
					)
					( Status sCSetFlattened )
					( Origin gBackEnd )
				)
				( attribute "RELATIVE_PROPAGATION_DELAY" "-50.00 MIL,50.00 MIL"
					( Parent
						( matchGroupRef "@baseboard_fab2_lib.baseboard_fab2(sch_1):\MG_DQ_FAR_DIMM_NG_M_H_BYTE1\" )
					)
					( Units "uMatchProp" "ns" 1.000000)
					( Status sCSetFlattened )
					( Origin gBackEnd )
				)
			)
			( pinPair "@baseboard_fab2_lib.baseboard_fab2(sch_1):\PP2703\"
				( pinRef "@baseboard_fab2_lib.baseboard_fab2(sch_1):page80_i24:DQ(14)" )
				( pinRef "@baseboard_fab2_lib.baseboard_fab2(sch_1):page58_i172:DDR1_DQ(14)" )
				( attribute "RELATIVE_PROPAGATION_DELAY_SCOPE" "G"
					( Parent
						( matchGroupRef "@baseboard_fab2_lib.baseboard_fab2(sch_1):\MG_DQ-DQS_NEAR_DIMM_NG_M_H_BYTE1\" )
					)
					( Status sCSetFlattened )
					( Origin gBackEnd )
				)
				( attribute "RELATIVE_PROPAGATION_DELAY" "0.00 MIL,195.00 MIL"
					( Parent
						( matchGroupRef "@baseboard_fab2_lib.baseboard_fab2(sch_1):\MG_DQ-DQS_NEAR_DIMM_NG_M_H_BYTE1\" )
					)
					( Units "uMatchProp" "ns" 1.000000)
					( Status sCSetFlattened )
					( Origin gBackEnd )
				)
				( attribute "RELATIVE_PROPAGATION_DELAY_SCOPE" "G"
					( Parent
						( matchGroupRef "@baseboard_fab2_lib.baseboard_fab2(sch_1):\MG_DQ_NEAR_DIMM_NG_M_H_BYTE1\" )
					)
					( Status sCSetFlattened )
					( Origin gBackEnd )
				)
				( attribute "RELATIVE_PROPAGATION_DELAY" "-50.00 MIL,50.00 MIL"
					( Parent
						( matchGroupRef "@baseboard_fab2_lib.baseboard_fab2(sch_1):\MG_DQ_NEAR_DIMM_NG_M_H_BYTE1\" )
					)
					( Units "uMatchProp" "ns" 1.000000)
					( Status sCSetFlattened )
					( Origin gBackEnd )
				)
			)
			( pinPair "@baseboard_fab2_lib.baseboard_fab2(sch_1):\PP2704\"
				( pinRef "@baseboard_fab2_lib.baseboard_fab2(sch_1):page58_i172:DDR1_DQ(15)" )
				( pinRef "@baseboard_fab2_lib.baseboard_fab2(sch_1):page79_i111:DQ(14)" )
				( attribute "RELATIVE_PROPAGATION_DELAY_SCOPE" "G"
					( Parent
						( matchGroupRef "@baseboard_fab2_lib.baseboard_fab2(sch_1):\MG_DQ-DQS_FAR_DIMM_NG_M_H_BYTE1\" )
					)
					( Status sCSetFlattened )
					( Origin gBackEnd )
				)
				( attribute "RELATIVE_PROPAGATION_DELAY" "0.00 MIL,195.00 MIL"
					( Parent
						( matchGroupRef "@baseboard_fab2_lib.baseboard_fab2(sch_1):\MG_DQ-DQS_FAR_DIMM_NG_M_H_BYTE1\" )
					)
					( Units "uMatchProp" "ns" 1.000000)
					( Status sCSetFlattened )
					( Origin gBackEnd )
				)
				( attribute "RELATIVE_PROPAGATION_DELAY_SCOPE" "G"
					( Parent
						( matchGroupRef "@baseboard_fab2_lib.baseboard_fab2(sch_1):\MG_DQ_FAR_DIMM_NG_M_H_BYTE1\" )
					)
					( Status sCSetFlattened )
					( Origin gBackEnd )
				)
				( attribute "RELATIVE_PROPAGATION_DELAY" "-50.00 MIL,50.00 MIL"
					( Parent
						( matchGroupRef "@baseboard_fab2_lib.baseboard_fab2(sch_1):\MG_DQ_FAR_DIMM_NG_M_H_BYTE1\" )
					)
					( Units "uMatchProp" "ns" 1.000000)
					( Status sCSetFlattened )
					( Origin gBackEnd )
				)
			)
			( pinPair "@baseboard_fab2_lib.baseboard_fab2(sch_1):\PP2706\"
				( pinRef "@baseboard_fab2_lib.baseboard_fab2(sch_1):page80_i24:DQ(15)" )
				( pinRef "@baseboard_fab2_lib.baseboard_fab2(sch_1):page58_i172:DDR1_DQ(15)" )
				( attribute "RELATIVE_PROPAGATION_DELAY_SCOPE" "G"
					( Parent
						( matchGroupRef "@baseboard_fab2_lib.baseboard_fab2(sch_1):\MG_DQ-DQS_NEAR_DIMM_NG_M_H_BYTE1\" )
					)
					( Status sCSetFlattened )
					( Origin gBackEnd )
				)
				( attribute "RELATIVE_PROPAGATION_DELAY" "0.00 MIL,195.00 MIL"
					( Parent
						( matchGroupRef "@baseboard_fab2_lib.baseboard_fab2(sch_1):\MG_DQ-DQS_NEAR_DIMM_NG_M_H_BYTE1\" )
					)
					( Units "uMatchProp" "ns" 1.000000)
					( Status sCSetFlattened )
					( Origin gBackEnd )
				)
				( attribute "RELATIVE_PROPAGATION_DELAY_SCOPE" "G"
					( Parent
						( matchGroupRef "@baseboard_fab2_lib.baseboard_fab2(sch_1):\MG_DQ_NEAR_DIMM_NG_M_H_BYTE1\" )
					)
					( Status sCSetFlattened )
					( Origin gBackEnd )
				)
				( attribute "RELATIVE_PROPAGATION_DELAY" "-50.00 MIL,50.00 MIL"
					( Parent
						( matchGroupRef "@baseboard_fab2_lib.baseboard_fab2(sch_1):\MG_DQ_NEAR_DIMM_NG_M_H_BYTE1\" )
					)
					( Units "uMatchProp" "ns" 1.000000)
					( Status sCSetFlattened )
					( Origin gBackEnd )
				)
			)
			( pinPair "@baseboard_fab2_lib.baseboard_fab2(sch_1):\PP2659\"
				( pinRef "@baseboard_fab2_lib.baseboard_fab2(sch_1):page58_i172:DDR1_DQ(16)" )
				( pinRef "@baseboard_fab2_lib.baseboard_fab2(sch_1):page79_i111:DQ(17)" )
				( attribute "RELATIVE_PROPAGATION_DELAY_SCOPE" "G"
					( Parent
						( matchGroupRef "@baseboard_fab2_lib.baseboard_fab2(sch_1):\MG_DQ-DQS_FAR_DIMM_NG_M_H_BYTE2\" )
					)
					( Status sCSetFlattened )
					( Origin gBackEnd )
				)
				( attribute "RELATIVE_PROPAGATION_DELAY" "0.00 MIL,195.00 MIL"
					( Parent
						( matchGroupRef "@baseboard_fab2_lib.baseboard_fab2(sch_1):\MG_DQ-DQS_FAR_DIMM_NG_M_H_BYTE2\" )
					)
					( Units "uMatchProp" "ns" 1.000000)
					( Status sCSetFlattened )
					( Origin gBackEnd )
				)
				( attribute "RELATIVE_PROPAGATION_DELAY_SCOPE" "G"
					( Parent
						( matchGroupRef "@baseboard_fab2_lib.baseboard_fab2(sch_1):\MG_DQ_FAR_DIMM_NG_M_H_BYTE2\" )
					)
					( Status sCSetFlattened )
					( Origin gBackEnd )
				)
				( attribute "RELATIVE_PROPAGATION_DELAY" "-50.00 MIL,50.00 MIL"
					( Parent
						( matchGroupRef "@baseboard_fab2_lib.baseboard_fab2(sch_1):\MG_DQ_FAR_DIMM_NG_M_H_BYTE2\" )
					)
					( Units "uMatchProp" "ns" 1.000000)
					( Status sCSetFlattened )
					( Origin gBackEnd )
				)
			)
			( pinPair "@baseboard_fab2_lib.baseboard_fab2(sch_1):\PP2661\"
				( pinRef "@baseboard_fab2_lib.baseboard_fab2(sch_1):page80_i24:DQ(16)" )
				( pinRef "@baseboard_fab2_lib.baseboard_fab2(sch_1):page58_i172:DDR1_DQ(16)" )
				( attribute "RELATIVE_PROPAGATION_DELAY_SCOPE" "G"
					( Parent
						( matchGroupRef "@baseboard_fab2_lib.baseboard_fab2(sch_1):\MG_DQ-DQS_NEAR_DIMM_NG_M_H_BYTE2\" )
					)
					( Status sCSetFlattened )
					( Origin gBackEnd )
				)
				( attribute "RELATIVE_PROPAGATION_DELAY" "0.00 MIL,195.00 MIL"
					( Parent
						( matchGroupRef "@baseboard_fab2_lib.baseboard_fab2(sch_1):\MG_DQ-DQS_NEAR_DIMM_NG_M_H_BYTE2\" )
					)
					( Units "uMatchProp" "ns" 1.000000)
					( Status sCSetFlattened )
					( Origin gBackEnd )
				)
				( attribute "RELATIVE_PROPAGATION_DELAY_SCOPE" "G"
					( Parent
						( matchGroupRef "@baseboard_fab2_lib.baseboard_fab2(sch_1):\MG_DQ_NEAR_DIMM_NG_M_H_BYTE2\" )
					)
					( Status sCSetFlattened )
					( Origin gBackEnd )
				)
				( attribute "RELATIVE_PROPAGATION_DELAY" "-50.00 MIL,50.00 MIL"
					( Parent
						( matchGroupRef "@baseboard_fab2_lib.baseboard_fab2(sch_1):\MG_DQ_NEAR_DIMM_NG_M_H_BYTE2\" )
					)
					( Units "uMatchProp" "ns" 1.000000)
					( Status sCSetFlattened )
					( Origin gBackEnd )
				)
			)
			( pinPair "@baseboard_fab2_lib.baseboard_fab2(sch_1):\PP5139\"
				( pinRef "@baseboard_fab2_lib.baseboard_fab2(sch_1):page23_i172:DDR0_ECC(0)" )
				( pinRef "@baseboard_fab2_lib.baseboard_fab2(sch_1):page43_i1:CB(1)" )
				( attribute "RELATIVE_PROPAGATION_DELAY_SCOPE" "G"
					( Parent
						( matchGroupRef "@baseboard_fab2_lib.baseboard_fab2(sch_1):\MG_DQ-DQS_FAR_DIMM_NG_M_A_BYTE-ECC\" )
					)
					( Status sCSetFlattened )
					( Origin gBackEnd )
				)
				( attribute "RELATIVE_PROPAGATION_DELAY" "0.00 MIL,195.00 MIL"
					( Parent
						( matchGroupRef "@baseboard_fab2_lib.baseboard_fab2(sch_1):\MG_DQ-DQS_FAR_DIMM_NG_M_A_BYTE-ECC\" )
					)
					( Units "uMatchProp" "ns" 1.000000)
					( Status sCSetFlattened )
					( Origin gBackEnd )
				)
				( attribute "RELATIVE_PROPAGATION_DELAY_SCOPE" "G"
					( Parent
						( matchGroupRef "@crescent_city_bb_fab1_lib.crescent_city_bb_fab1(sch_1):\MG_DQ_FAR_DIMM_NG_M_A_BYTE-ECC\" )
					)
					( Status sCSetFlattened )
					( Origin gBackEnd )
				)
				( attribute "RELATIVE_PROPAGATION_DELAY" "-50.00 MIL,50.00 MIL"
					( Parent
						( matchGroupRef "@crescent_city_bb_fab1_lib.crescent_city_bb_fab1(sch_1):\MG_DQ_FAR_DIMM_NG_M_A_BYTE-ECC\" )
					)
					( Units "uMatchProp" "ns" 1.000000)
					( Status sCSetFlattened )
					( Origin gBackEnd )
				)
			)
			( pinPair "@baseboard_fab2_lib.baseboard_fab2(sch_1):\PP5141\"
				( pinRef "@baseboard_fab2_lib.baseboard_fab2(sch_1):page23_i172:DDR0_ECC(0)" )
				( pinRef "@baseboard_fab2_lib.baseboard_fab2(sch_1):page44_i13:CB(0)" )
				( attribute "RELATIVE_PROPAGATION_DELAY_SCOPE" "G"
					( Parent
						( matchGroupRef "@baseboard_fab2_lib.baseboard_fab2(sch_1):\MG_DQ-DQS_NEAR_DIMM_NG_M_A_BYTE-ECC\" )
					)
					( Status sCSetFlattened )
					( Origin gBackEnd )
				)
				( attribute "RELATIVE_PROPAGATION_DELAY" "0.00 MIL,195.00 MIL"
					( Parent
						( matchGroupRef "@baseboard_fab2_lib.baseboard_fab2(sch_1):\MG_DQ-DQS_NEAR_DIMM_NG_M_A_BYTE-ECC\" )
					)
					( Units "uMatchProp" "ns" 1.000000)
					( Status sCSetFlattened )
					( Origin gBackEnd )
				)
				( attribute "RELATIVE_PROPAGATION_DELAY_SCOPE" "G"
					( Parent
						( matchGroupRef "@crescent_city_bb_fab1_lib.crescent_city_bb_fab1(sch_1):\MG_DQ_NEAR_DIMM_NG_M_A_BYTE-ECC\" )
					)
					( Status sCSetFlattened )
					( Origin gBackEnd )
				)
				( attribute "RELATIVE_PROPAGATION_DELAY" "-50.00 MIL,50.00 MIL"
					( Parent
						( matchGroupRef "@crescent_city_bb_fab1_lib.crescent_city_bb_fab1(sch_1):\MG_DQ_NEAR_DIMM_NG_M_A_BYTE-ECC\" )
					)
					( Units "uMatchProp" "ns" 1.000000)
					( Status sCSetFlattened )
					( Origin gBackEnd )
				)
			)
			( pinPair "@baseboard_fab2_lib.baseboard_fab2(sch_1):\PP5142\"
				( pinRef "@baseboard_fab2_lib.baseboard_fab2(sch_1):page23_i172:DDR0_ECC(1)" )
				( pinRef "@baseboard_fab2_lib.baseboard_fab2(sch_1):page43_i1:CB(0)" )
				( attribute "RELATIVE_PROPAGATION_DELAY_SCOPE" "G"
					( Parent
						( matchGroupRef "@baseboard_fab2_lib.baseboard_fab2(sch_1):\MG_DQ-DQS_FAR_DIMM_NG_M_A_BYTE-ECC\" )
					)
					( Status sCSetFlattened )
					( Origin gBackEnd )
				)
				( attribute "RELATIVE_PROPAGATION_DELAY" "0.00 MIL,195.00 MIL"
					( Parent
						( matchGroupRef "@baseboard_fab2_lib.baseboard_fab2(sch_1):\MG_DQ-DQS_FAR_DIMM_NG_M_A_BYTE-ECC\" )
					)
					( Units "uMatchProp" "ns" 1.000000)
					( Status sCSetFlattened )
					( Origin gBackEnd )
				)
				( attribute "RELATIVE_PROPAGATION_DELAY_SCOPE" "G"
					( Parent
						( matchGroupRef "@crescent_city_bb_fab1_lib.crescent_city_bb_fab1(sch_1):\MG_DQ_FAR_DIMM_NG_M_A_BYTE-ECC\" )
					)
					( Origin gBackEnd )
				)
				( attribute "RELATIVE_PROPAGATION_DELAY" "TARGET,TARGET"
					( Parent
						( matchGroupRef "@crescent_city_bb_fab1_lib.crescent_city_bb_fab1(sch_1):\MG_DQ_FAR_DIMM_NG_M_A_BYTE-ECC\" )
					)
					( Units "uMatchProp" "ns" 1.000000)
					( Origin gBackEnd )
				)
			)
			( pinPair "@baseboard_fab2_lib.baseboard_fab2(sch_1):\PP5144\"
				( pinRef "@baseboard_fab2_lib.baseboard_fab2(sch_1):page23_i172:DDR0_ECC(1)" )
				( pinRef "@baseboard_fab2_lib.baseboard_fab2(sch_1):page44_i13:CB(1)" )
				( attribute "RELATIVE_PROPAGATION_DELAY_SCOPE" "G"
					( Parent
						( matchGroupRef "@baseboard_fab2_lib.baseboard_fab2(sch_1):\MG_DQ-DQS_NEAR_DIMM_NG_M_A_BYTE-ECC\" )
					)
					( Status sCSetFlattened )
					( Origin gBackEnd )
				)
				( attribute "RELATIVE_PROPAGATION_DELAY" "0.00 MIL,195.00 MIL"
					( Parent
						( matchGroupRef "@baseboard_fab2_lib.baseboard_fab2(sch_1):\MG_DQ-DQS_NEAR_DIMM_NG_M_A_BYTE-ECC\" )
					)
					( Units "uMatchProp" "ns" 1.000000)
					( Status sCSetFlattened )
					( Origin gBackEnd )
				)
				( attribute "RELATIVE_PROPAGATION_DELAY_SCOPE" "G"
					( Parent
						( matchGroupRef "@crescent_city_bb_fab1_lib.crescent_city_bb_fab1(sch_1):\MG_DQ_NEAR_DIMM_NG_M_A_BYTE-ECC\" )
					)
					( Origin gBackEnd )
				)
				( attribute "RELATIVE_PROPAGATION_DELAY" "TARGET,TARGET"
					( Parent
						( matchGroupRef "@crescent_city_bb_fab1_lib.crescent_city_bb_fab1(sch_1):\MG_DQ_NEAR_DIMM_NG_M_A_BYTE-ECC\" )
					)
					( Units "uMatchProp" "ns" 1.000000)
					( Origin gBackEnd )
				)
			)
			( pinPair "@baseboard_fab2_lib.baseboard_fab2(sch_1):\PP5145\"
				( pinRef "@baseboard_fab2_lib.baseboard_fab2(sch_1):page23_i172:DDR0_ECC(2)" )
				( pinRef "@baseboard_fab2_lib.baseboard_fab2(sch_1):page43_i1:CB(3)" )
				( attribute "RELATIVE_PROPAGATION_DELAY_SCOPE" "G"
					( Parent
						( matchGroupRef "@baseboard_fab2_lib.baseboard_fab2(sch_1):\MG_DQ-DQS_FAR_DIMM_NG_M_A_BYTE-ECC\" )
					)
					( Status sCSetFlattened )
					( Origin gBackEnd )
				)
				( attribute "RELATIVE_PROPAGATION_DELAY" "0.00 MIL,195.00 MIL"
					( Parent
						( matchGroupRef "@baseboard_fab2_lib.baseboard_fab2(sch_1):\MG_DQ-DQS_FAR_DIMM_NG_M_A_BYTE-ECC\" )
					)
					( Units "uMatchProp" "ns" 1.000000)
					( Status sCSetFlattened )
					( Origin gBackEnd )
				)
				( attribute "RELATIVE_PROPAGATION_DELAY_SCOPE" "G"
					( Parent
						( matchGroupRef "@crescent_city_bb_fab1_lib.crescent_city_bb_fab1(sch_1):\MG_DQ_FAR_DIMM_NG_M_A_BYTE-ECC\" )
					)
					( Status sCSetFlattened )
					( Origin gBackEnd )
				)
				( attribute "RELATIVE_PROPAGATION_DELAY" "-50.00 MIL,50.00 MIL"
					( Parent
						( matchGroupRef "@crescent_city_bb_fab1_lib.crescent_city_bb_fab1(sch_1):\MG_DQ_FAR_DIMM_NG_M_A_BYTE-ECC\" )
					)
					( Units "uMatchProp" "ns" 1.000000)
					( Status sCSetFlattened )
					( Origin gBackEnd )
				)
			)
			( pinPair "@baseboard_fab2_lib.baseboard_fab2(sch_1):\PP5147\"
				( pinRef "@baseboard_fab2_lib.baseboard_fab2(sch_1):page23_i172:DDR0_ECC(2)" )
				( pinRef "@baseboard_fab2_lib.baseboard_fab2(sch_1):page44_i13:CB(2)" )
				( attribute "RELATIVE_PROPAGATION_DELAY_SCOPE" "G"
					( Parent
						( matchGroupRef "@baseboard_fab2_lib.baseboard_fab2(sch_1):\MG_DQ-DQS_NEAR_DIMM_NG_M_A_BYTE-ECC\" )
					)
					( Status sCSetFlattened )
					( Origin gBackEnd )
				)
				( attribute "RELATIVE_PROPAGATION_DELAY" "0.00 MIL,195.00 MIL"
					( Parent
						( matchGroupRef "@baseboard_fab2_lib.baseboard_fab2(sch_1):\MG_DQ-DQS_NEAR_DIMM_NG_M_A_BYTE-ECC\" )
					)
					( Units "uMatchProp" "ns" 1.000000)
					( Status sCSetFlattened )
					( Origin gBackEnd )
				)
				( attribute "RELATIVE_PROPAGATION_DELAY_SCOPE" "G"
					( Parent
						( matchGroupRef "@crescent_city_bb_fab1_lib.crescent_city_bb_fab1(sch_1):\MG_DQ_NEAR_DIMM_NG_M_A_BYTE-ECC\" )
					)
					( Status sCSetFlattened )
					( Origin gBackEnd )
				)
				( attribute "RELATIVE_PROPAGATION_DELAY" "-50.00 MIL,50.00 MIL"
					( Parent
						( matchGroupRef "@crescent_city_bb_fab1_lib.crescent_city_bb_fab1(sch_1):\MG_DQ_NEAR_DIMM_NG_M_A_BYTE-ECC\" )
					)
					( Units "uMatchProp" "ns" 1.000000)
					( Status sCSetFlattened )
					( Origin gBackEnd )
				)
			)
			( pinPair "@baseboard_fab2_lib.baseboard_fab2(sch_1):\PP5148\"
				( pinRef "@baseboard_fab2_lib.baseboard_fab2(sch_1):page23_i172:DDR0_ECC(3)" )
				( pinRef "@baseboard_fab2_lib.baseboard_fab2(sch_1):page43_i1:CB(2)" )
				( attribute "RELATIVE_PROPAGATION_DELAY_SCOPE" "G"
					( Parent
						( matchGroupRef "@baseboard_fab2_lib.baseboard_fab2(sch_1):\MG_DQ-DQS_FAR_DIMM_NG_M_A_BYTE-ECC\" )
					)
					( Status sCSetFlattened )
					( Origin gBackEnd )
				)
				( attribute "RELATIVE_PROPAGATION_DELAY" "0.00 MIL,195.00 MIL"
					( Parent
						( matchGroupRef "@baseboard_fab2_lib.baseboard_fab2(sch_1):\MG_DQ-DQS_FAR_DIMM_NG_M_A_BYTE-ECC\" )
					)
					( Units "uMatchProp" "ns" 1.000000)
					( Status sCSetFlattened )
					( Origin gBackEnd )
				)
				( attribute "RELATIVE_PROPAGATION_DELAY_SCOPE" "G"
					( Parent
						( matchGroupRef "@crescent_city_bb_fab1_lib.crescent_city_bb_fab1(sch_1):\MG_DQ_FAR_DIMM_NG_M_A_BYTE-ECC\" )
					)
					( Status sCSetFlattened )
					( Origin gBackEnd )
				)
				( attribute "RELATIVE_PROPAGATION_DELAY" "-50.00 MIL,50.00 MIL"
					( Parent
						( matchGroupRef "@crescent_city_bb_fab1_lib.crescent_city_bb_fab1(sch_1):\MG_DQ_FAR_DIMM_NG_M_A_BYTE-ECC\" )
					)
					( Units "uMatchProp" "ns" 1.000000)
					( Status sCSetFlattened )
					( Origin gBackEnd )
				)
			)
			( pinPair "@baseboard_fab2_lib.baseboard_fab2(sch_1):\PP5150\"
				( pinRef "@baseboard_fab2_lib.baseboard_fab2(sch_1):page23_i172:DDR0_ECC(3)" )
				( pinRef "@baseboard_fab2_lib.baseboard_fab2(sch_1):page44_i13:CB(3)" )
				( attribute "RELATIVE_PROPAGATION_DELAY_SCOPE" "G"
					( Parent
						( matchGroupRef "@baseboard_fab2_lib.baseboard_fab2(sch_1):\MG_DQ-DQS_NEAR_DIMM_NG_M_A_BYTE-ECC\" )
					)
					( Status sCSetFlattened )
					( Origin gBackEnd )
				)
				( attribute "RELATIVE_PROPAGATION_DELAY" "0.00 MIL,195.00 MIL"
					( Parent
						( matchGroupRef "@baseboard_fab2_lib.baseboard_fab2(sch_1):\MG_DQ-DQS_NEAR_DIMM_NG_M_A_BYTE-ECC\" )
					)
					( Units "uMatchProp" "ns" 1.000000)
					( Status sCSetFlattened )
					( Origin gBackEnd )
				)
				( attribute "RELATIVE_PROPAGATION_DELAY_SCOPE" "G"
					( Parent
						( matchGroupRef "@crescent_city_bb_fab1_lib.crescent_city_bb_fab1(sch_1):\MG_DQ_NEAR_DIMM_NG_M_A_BYTE-ECC\" )
					)
					( Status sCSetFlattened )
					( Origin gBackEnd )
				)
				( attribute "RELATIVE_PROPAGATION_DELAY" "-50.00 MIL,50.00 MIL"
					( Parent
						( matchGroupRef "@crescent_city_bb_fab1_lib.crescent_city_bb_fab1(sch_1):\MG_DQ_NEAR_DIMM_NG_M_A_BYTE-ECC\" )
					)
					( Units "uMatchProp" "ns" 1.000000)
					( Status sCSetFlattened )
					( Origin gBackEnd )
				)
			)
			( pinPair "@baseboard_fab2_lib.baseboard_fab2(sch_1):\PP5151\"
				( pinRef "@baseboard_fab2_lib.baseboard_fab2(sch_1):page23_i172:DDR0_ECC(4)" )
				( pinRef "@baseboard_fab2_lib.baseboard_fab2(sch_1):page43_i1:CB(5)" )
				( attribute "RELATIVE_PROPAGATION_DELAY_SCOPE" "G"
					( Parent
						( matchGroupRef "@baseboard_fab2_lib.baseboard_fab2(sch_1):\MG_DQ-DQS_FAR_DIMM_NG_M_A_BYTE-ECC\" )
					)
					( Status sCSetFlattened )
					( Origin gBackEnd )
				)
				( attribute "RELATIVE_PROPAGATION_DELAY" "0.00 MIL,195.00 MIL"
					( Parent
						( matchGroupRef "@baseboard_fab2_lib.baseboard_fab2(sch_1):\MG_DQ-DQS_FAR_DIMM_NG_M_A_BYTE-ECC\" )
					)
					( Units "uMatchProp" "ns" 1.000000)
					( Status sCSetFlattened )
					( Origin gBackEnd )
				)
				( attribute "RELATIVE_PROPAGATION_DELAY_SCOPE" "G"
					( Parent
						( matchGroupRef "@crescent_city_bb_fab1_lib.crescent_city_bb_fab1(sch_1):\MG_DQ_FAR_DIMM_NG_M_A_BYTE-ECC\" )
					)
					( Status sCSetFlattened )
					( Origin gBackEnd )
				)
				( attribute "RELATIVE_PROPAGATION_DELAY" "-50.00 MIL,50.00 MIL"
					( Parent
						( matchGroupRef "@crescent_city_bb_fab1_lib.crescent_city_bb_fab1(sch_1):\MG_DQ_FAR_DIMM_NG_M_A_BYTE-ECC\" )
					)
					( Units "uMatchProp" "ns" 1.000000)
					( Status sCSetFlattened )
					( Origin gBackEnd )
				)
			)
			( pinPair "@baseboard_fab2_lib.baseboard_fab2(sch_1):\PP5153\"
				( pinRef "@baseboard_fab2_lib.baseboard_fab2(sch_1):page23_i172:DDR0_ECC(4)" )
				( pinRef "@baseboard_fab2_lib.baseboard_fab2(sch_1):page44_i13:CB(4)" )
				( attribute "RELATIVE_PROPAGATION_DELAY_SCOPE" "G"
					( Parent
						( matchGroupRef "@baseboard_fab2_lib.baseboard_fab2(sch_1):\MG_DQ-DQS_NEAR_DIMM_NG_M_A_BYTE-ECC\" )
					)
					( Status sCSetFlattened )
					( Origin gBackEnd )
				)
				( attribute "RELATIVE_PROPAGATION_DELAY" "0.00 MIL,195.00 MIL"
					( Parent
						( matchGroupRef "@baseboard_fab2_lib.baseboard_fab2(sch_1):\MG_DQ-DQS_NEAR_DIMM_NG_M_A_BYTE-ECC\" )
					)
					( Units "uMatchProp" "ns" 1.000000)
					( Status sCSetFlattened )
					( Origin gBackEnd )
				)
				( attribute "RELATIVE_PROPAGATION_DELAY_SCOPE" "G"
					( Parent
						( matchGroupRef "@crescent_city_bb_fab1_lib.crescent_city_bb_fab1(sch_1):\MG_DQ_NEAR_DIMM_NG_M_A_BYTE-ECC\" )
					)
					( Status sCSetFlattened )
					( Origin gBackEnd )
				)
				( attribute "RELATIVE_PROPAGATION_DELAY" "-50.00 MIL,50.00 MIL"
					( Parent
						( matchGroupRef "@crescent_city_bb_fab1_lib.crescent_city_bb_fab1(sch_1):\MG_DQ_NEAR_DIMM_NG_M_A_BYTE-ECC\" )
					)
					( Units "uMatchProp" "ns" 1.000000)
					( Status sCSetFlattened )
					( Origin gBackEnd )
				)
			)
			( pinPair "@baseboard_fab2_lib.baseboard_fab2(sch_1):\PP5154\"
				( pinRef "@baseboard_fab2_lib.baseboard_fab2(sch_1):page23_i172:DDR0_ECC(5)" )
				( pinRef "@baseboard_fab2_lib.baseboard_fab2(sch_1):page43_i1:CB(4)" )
				( attribute "RELATIVE_PROPAGATION_DELAY_SCOPE" "G"
					( Parent
						( matchGroupRef "@baseboard_fab2_lib.baseboard_fab2(sch_1):\MG_DQ-DQS_FAR_DIMM_NG_M_A_BYTE-ECC\" )
					)
					( Status sCSetFlattened )
					( Origin gBackEnd )
				)
				( attribute "RELATIVE_PROPAGATION_DELAY" "0.00 MIL,195.00 MIL"
					( Parent
						( matchGroupRef "@baseboard_fab2_lib.baseboard_fab2(sch_1):\MG_DQ-DQS_FAR_DIMM_NG_M_A_BYTE-ECC\" )
					)
					( Units "uMatchProp" "ns" 1.000000)
					( Status sCSetFlattened )
					( Origin gBackEnd )
				)
				( attribute "RELATIVE_PROPAGATION_DELAY_SCOPE" "G"
					( Parent
						( matchGroupRef "@crescent_city_bb_fab1_lib.crescent_city_bb_fab1(sch_1):\MG_DQ_FAR_DIMM_NG_M_A_BYTE-ECC\" )
					)
					( Status sCSetFlattened )
					( Origin gBackEnd )
				)
				( attribute "RELATIVE_PROPAGATION_DELAY" "-50.00 MIL,50.00 MIL"
					( Parent
						( matchGroupRef "@crescent_city_bb_fab1_lib.crescent_city_bb_fab1(sch_1):\MG_DQ_FAR_DIMM_NG_M_A_BYTE-ECC\" )
					)
					( Units "uMatchProp" "ns" 1.000000)
					( Status sCSetFlattened )
					( Origin gBackEnd )
				)
			)
			( pinPair "@baseboard_fab2_lib.baseboard_fab2(sch_1):\PP5156\"
				( pinRef "@baseboard_fab2_lib.baseboard_fab2(sch_1):page23_i172:DDR0_ECC(5)" )
				( pinRef "@baseboard_fab2_lib.baseboard_fab2(sch_1):page44_i13:CB(5)" )
				( attribute "RELATIVE_PROPAGATION_DELAY_SCOPE" "G"
					( Parent
						( matchGroupRef "@baseboard_fab2_lib.baseboard_fab2(sch_1):\MG_DQ-DQS_NEAR_DIMM_NG_M_A_BYTE-ECC\" )
					)
					( Status sCSetFlattened )
					( Origin gBackEnd )
				)
				( attribute "RELATIVE_PROPAGATION_DELAY" "0.00 MIL,195.00 MIL"
					( Parent
						( matchGroupRef "@baseboard_fab2_lib.baseboard_fab2(sch_1):\MG_DQ-DQS_NEAR_DIMM_NG_M_A_BYTE-ECC\" )
					)
					( Units "uMatchProp" "ns" 1.000000)
					( Status sCSetFlattened )
					( Origin gBackEnd )
				)
				( attribute "RELATIVE_PROPAGATION_DELAY_SCOPE" "G"
					( Parent
						( matchGroupRef "@crescent_city_bb_fab1_lib.crescent_city_bb_fab1(sch_1):\MG_DQ_NEAR_DIMM_NG_M_A_BYTE-ECC\" )
					)
					( Status sCSetFlattened )
					( Origin gBackEnd )
				)
				( attribute "RELATIVE_PROPAGATION_DELAY" "-50.00 MIL,50.00 MIL"
					( Parent
						( matchGroupRef "@crescent_city_bb_fab1_lib.crescent_city_bb_fab1(sch_1):\MG_DQ_NEAR_DIMM_NG_M_A_BYTE-ECC\" )
					)
					( Units "uMatchProp" "ns" 1.000000)
					( Status sCSetFlattened )
					( Origin gBackEnd )
				)
			)
			( pinPair "@baseboard_fab2_lib.baseboard_fab2(sch_1):\PP5157\"
				( pinRef "@baseboard_fab2_lib.baseboard_fab2(sch_1):page23_i172:DDR0_ECC(6)" )
				( pinRef "@baseboard_fab2_lib.baseboard_fab2(sch_1):page43_i1:CB(7)" )
				( attribute "RELATIVE_PROPAGATION_DELAY_SCOPE" "G"
					( Parent
						( matchGroupRef "@baseboard_fab2_lib.baseboard_fab2(sch_1):\MG_DQ-DQS_FAR_DIMM_NG_M_A_BYTE-ECC\" )
					)
					( Status sCSetFlattened )
					( Origin gBackEnd )
				)
				( attribute "RELATIVE_PROPAGATION_DELAY" "0.00 MIL,195.00 MIL"
					( Parent
						( matchGroupRef "@baseboard_fab2_lib.baseboard_fab2(sch_1):\MG_DQ-DQS_FAR_DIMM_NG_M_A_BYTE-ECC\" )
					)
					( Units "uMatchProp" "ns" 1.000000)
					( Status sCSetFlattened )
					( Origin gBackEnd )
				)
				( attribute "RELATIVE_PROPAGATION_DELAY_SCOPE" "G"
					( Parent
						( matchGroupRef "@crescent_city_bb_fab1_lib.crescent_city_bb_fab1(sch_1):\MG_DQ_FAR_DIMM_NG_M_A_BYTE-ECC\" )
					)
					( Status sCSetFlattened )
					( Origin gBackEnd )
				)
				( attribute "RELATIVE_PROPAGATION_DELAY" "-50.00 MIL,50.00 MIL"
					( Parent
						( matchGroupRef "@crescent_city_bb_fab1_lib.crescent_city_bb_fab1(sch_1):\MG_DQ_FAR_DIMM_NG_M_A_BYTE-ECC\" )
					)
					( Units "uMatchProp" "ns" 1.000000)
					( Status sCSetFlattened )
					( Origin gBackEnd )
				)
			)
			( pinPair "@baseboard_fab2_lib.baseboard_fab2(sch_1):\PP5159\"
				( pinRef "@baseboard_fab2_lib.baseboard_fab2(sch_1):page23_i172:DDR0_ECC(6)" )
				( pinRef "@baseboard_fab2_lib.baseboard_fab2(sch_1):page44_i13:CB(6)" )
				( attribute "RELATIVE_PROPAGATION_DELAY_SCOPE" "G"
					( Parent
						( matchGroupRef "@baseboard_fab2_lib.baseboard_fab2(sch_1):\MG_DQ-DQS_NEAR_DIMM_NG_M_A_BYTE-ECC\" )
					)
					( Status sCSetFlattened )
					( Origin gBackEnd )
				)
				( attribute "RELATIVE_PROPAGATION_DELAY" "0.00 MIL,195.00 MIL"
					( Parent
						( matchGroupRef "@baseboard_fab2_lib.baseboard_fab2(sch_1):\MG_DQ-DQS_NEAR_DIMM_NG_M_A_BYTE-ECC\" )
					)
					( Units "uMatchProp" "ns" 1.000000)
					( Status sCSetFlattened )
					( Origin gBackEnd )
				)
				( attribute "RELATIVE_PROPAGATION_DELAY_SCOPE" "G"
					( Parent
						( matchGroupRef "@crescent_city_bb_fab1_lib.crescent_city_bb_fab1(sch_1):\MG_DQ_NEAR_DIMM_NG_M_A_BYTE-ECC\" )
					)
					( Status sCSetFlattened )
					( Origin gBackEnd )
				)
				( attribute "RELATIVE_PROPAGATION_DELAY" "-50.00 MIL,50.00 MIL"
					( Parent
						( matchGroupRef "@crescent_city_bb_fab1_lib.crescent_city_bb_fab1(sch_1):\MG_DQ_NEAR_DIMM_NG_M_A_BYTE-ECC\" )
					)
					( Units "uMatchProp" "ns" 1.000000)
					( Status sCSetFlattened )
					( Origin gBackEnd )
				)
			)
			( pinPair "@baseboard_fab2_lib.baseboard_fab2(sch_1):\PP5160\"
				( pinRef "@baseboard_fab2_lib.baseboard_fab2(sch_1):page23_i172:DDR0_ECC(7)" )
				( pinRef "@baseboard_fab2_lib.baseboard_fab2(sch_1):page43_i1:CB(6)" )
				( attribute "RELATIVE_PROPAGATION_DELAY_SCOPE" "G"
					( Parent
						( matchGroupRef "@baseboard_fab2_lib.baseboard_fab2(sch_1):\MG_DQ-DQS_FAR_DIMM_NG_M_A_BYTE-ECC\" )
					)
					( Status sCSetFlattened )
					( Origin gBackEnd )
				)
				( attribute "RELATIVE_PROPAGATION_DELAY" "0.00 MIL,195.00 MIL"
					( Parent
						( matchGroupRef "@baseboard_fab2_lib.baseboard_fab2(sch_1):\MG_DQ-DQS_FAR_DIMM_NG_M_A_BYTE-ECC\" )
					)
					( Units "uMatchProp" "ns" 1.000000)
					( Status sCSetFlattened )
					( Origin gBackEnd )
				)
				( attribute "RELATIVE_PROPAGATION_DELAY_SCOPE" "G"
					( Parent
						( matchGroupRef "@crescent_city_bb_fab1_lib.crescent_city_bb_fab1(sch_1):\MG_DQ_FAR_DIMM_NG_M_A_BYTE-ECC\" )
					)
					( Status sCSetFlattened )
					( Origin gBackEnd )
				)
				( attribute "RELATIVE_PROPAGATION_DELAY" "-50.00 MIL,50.00 MIL"
					( Parent
						( matchGroupRef "@crescent_city_bb_fab1_lib.crescent_city_bb_fab1(sch_1):\MG_DQ_FAR_DIMM_NG_M_A_BYTE-ECC\" )
					)
					( Units "uMatchProp" "ns" 1.000000)
					( Status sCSetFlattened )
					( Origin gBackEnd )
				)
			)
			( pinPair "@baseboard_fab2_lib.baseboard_fab2(sch_1):\PP5162\"
				( pinRef "@baseboard_fab2_lib.baseboard_fab2(sch_1):page23_i172:DDR0_ECC(7)" )
				( pinRef "@baseboard_fab2_lib.baseboard_fab2(sch_1):page44_i13:CB(7)" )
				( attribute "RELATIVE_PROPAGATION_DELAY_SCOPE" "G"
					( Parent
						( matchGroupRef "@baseboard_fab2_lib.baseboard_fab2(sch_1):\MG_DQ-DQS_NEAR_DIMM_NG_M_A_BYTE-ECC\" )
					)
					( Status sCSetFlattened )
					( Origin gBackEnd )
				)
				( attribute "RELATIVE_PROPAGATION_DELAY" "0.00 MIL,195.00 MIL"
					( Parent
						( matchGroupRef "@baseboard_fab2_lib.baseboard_fab2(sch_1):\MG_DQ-DQS_NEAR_DIMM_NG_M_A_BYTE-ECC\" )
					)
					( Units "uMatchProp" "ns" 1.000000)
					( Status sCSetFlattened )
					( Origin gBackEnd )
				)
				( attribute "RELATIVE_PROPAGATION_DELAY_SCOPE" "G"
					( Parent
						( matchGroupRef "@crescent_city_bb_fab1_lib.crescent_city_bb_fab1(sch_1):\MG_DQ_NEAR_DIMM_NG_M_A_BYTE-ECC\" )
					)
					( Status sCSetFlattened )
					( Origin gBackEnd )
				)
				( attribute "RELATIVE_PROPAGATION_DELAY" "-50.00 MIL,50.00 MIL"
					( Parent
						( matchGroupRef "@crescent_city_bb_fab1_lib.crescent_city_bb_fab1(sch_1):\MG_DQ_NEAR_DIMM_NG_M_A_BYTE-ECC\" )
					)
					( Units "uMatchProp" "ns" 1.000000)
					( Status sCSetFlattened )
					( Origin gBackEnd )
				)
			)
			( pinPair "@baseboard_fab2_lib.baseboard_fab2(sch_1):\PP5115\"
				( pinRef "@baseboard_fab2_lib.baseboard_fab2(sch_1):page24_i172:DDR1_ECC(0)" )
				( pinRef "@baseboard_fab2_lib.baseboard_fab2(sch_1):page45_i111:CB(1)" )
				( attribute "RELATIVE_PROPAGATION_DELAY_SCOPE" "G"
					( Parent
						( matchGroupRef "@baseboard_fab2_lib.baseboard_fab2(sch_1):\MG_DQ-DQS_FAR_DIMM_NG_M_B_BYTE-ECC\" )
					)
					( Status sCSetFlattened )
					( Origin gBackEnd )
				)
				( attribute "RELATIVE_PROPAGATION_DELAY" "0.00 MIL,195.00 MIL"
					( Parent
						( matchGroupRef "@baseboard_fab2_lib.baseboard_fab2(sch_1):\MG_DQ-DQS_FAR_DIMM_NG_M_B_BYTE-ECC\" )
					)
					( Units "uMatchProp" "ns" 1.000000)
					( Status sCSetFlattened )
					( Origin gBackEnd )
				)
				( attribute "RELATIVE_PROPAGATION_DELAY_SCOPE" "G"
					( Parent
						( matchGroupRef "@crescent_city_bb_fab1_lib.crescent_city_bb_fab1(sch_1):\MG_DQ_FAR_DIMM_NG_M_B_BYTE-ECC\" )
					)
					( Origin gBackEnd )
				)
				( attribute "RELATIVE_PROPAGATION_DELAY" "-48.18 MIL,50.00 MIL"
					( Parent
						( matchGroupRef "@crescent_city_bb_fab1_lib.crescent_city_bb_fab1(sch_1):\MG_DQ_FAR_DIMM_NG_M_B_BYTE-ECC\" )
					)
					( Units "uMatchProp" "ns" 1.000000)
					( Origin gBackEnd )
				)
			)
			( pinPair "@baseboard_fab2_lib.baseboard_fab2(sch_1):\PP5117\"
				( pinRef "@baseboard_fab2_lib.baseboard_fab2(sch_1):page24_i172:DDR1_ECC(0)" )
				( pinRef "@baseboard_fab2_lib.baseboard_fab2(sch_1):page46_i14:CB(0)" )
				( attribute "RELATIVE_PROPAGATION_DELAY_SCOPE" "G"
					( Parent
						( matchGroupRef "@baseboard_fab2_lib.baseboard_fab2(sch_1):\MG_DQ-DQS_NEAR_DIMM_NG_M_B_BYTE-ECC\" )
					)
					( Status sCSetFlattened )
					( Origin gBackEnd )
				)
				( attribute "RELATIVE_PROPAGATION_DELAY" "0.00 MIL,195.00 MIL"
					( Parent
						( matchGroupRef "@baseboard_fab2_lib.baseboard_fab2(sch_1):\MG_DQ-DQS_NEAR_DIMM_NG_M_B_BYTE-ECC\" )
					)
					( Units "uMatchProp" "ns" 1.000000)
					( Status sCSetFlattened )
					( Origin gBackEnd )
				)
				( attribute "RELATIVE_PROPAGATION_DELAY_SCOPE" "G"
					( Parent
						( matchGroupRef "@crescent_city_bb_fab1_lib.crescent_city_bb_fab1(sch_1):\MG_DQ_NEAR_DIMM_NG_M_B_BYTE-ECC\" )
					)
					( Origin gBackEnd )
				)
				( attribute "RELATIVE_PROPAGATION_DELAY" "-48.18 MIL,50.00 MIL"
					( Parent
						( matchGroupRef "@crescent_city_bb_fab1_lib.crescent_city_bb_fab1(sch_1):\MG_DQ_NEAR_DIMM_NG_M_B_BYTE-ECC\" )
					)
					( Units "uMatchProp" "ns" 1.000000)
					( Origin gBackEnd )
				)
			)
			( pinPair "@baseboard_fab2_lib.baseboard_fab2(sch_1):\PP5118\"
				( pinRef "@baseboard_fab2_lib.baseboard_fab2(sch_1):page24_i172:DDR1_ECC(1)" )
				( pinRef "@baseboard_fab2_lib.baseboard_fab2(sch_1):page45_i111:CB(0)" )
				( attribute "RELATIVE_PROPAGATION_DELAY_SCOPE" "G"
					( Parent
						( matchGroupRef "@baseboard_fab2_lib.baseboard_fab2(sch_1):\MG_DQ-DQS_FAR_DIMM_NG_M_B_BYTE-ECC\" )
					)
					( Status sCSetFlattened )
					( Origin gBackEnd )
				)
				( attribute "RELATIVE_PROPAGATION_DELAY" "0.00 MIL,195.00 MIL"
					( Parent
						( matchGroupRef "@baseboard_fab2_lib.baseboard_fab2(sch_1):\MG_DQ-DQS_FAR_DIMM_NG_M_B_BYTE-ECC\" )
					)
					( Units "uMatchProp" "ns" 1.000000)
					( Status sCSetFlattened )
					( Origin gBackEnd )
				)
				( attribute "RELATIVE_PROPAGATION_DELAY_SCOPE" "G"
					( Parent
						( matchGroupRef "@crescent_city_bb_fab1_lib.crescent_city_bb_fab1(sch_1):\MG_DQ_FAR_DIMM_NG_M_B_BYTE-ECC\" )
					)
					( Origin gBackEnd )
				)
				( attribute "RELATIVE_PROPAGATION_DELAY" "-49.62 MIL,50.00 MIL"
					( Parent
						( matchGroupRef "@crescent_city_bb_fab1_lib.crescent_city_bb_fab1(sch_1):\MG_DQ_FAR_DIMM_NG_M_B_BYTE-ECC\" )
					)
					( Units "uMatchProp" "ns" 1.000000)
					( Origin gBackEnd )
				)
			)
			( pinPair "@baseboard_fab2_lib.baseboard_fab2(sch_1):\PP5120\"
				( pinRef "@baseboard_fab2_lib.baseboard_fab2(sch_1):page24_i172:DDR1_ECC(1)" )
				( pinRef "@baseboard_fab2_lib.baseboard_fab2(sch_1):page46_i14:CB(1)" )
				( attribute "RELATIVE_PROPAGATION_DELAY_SCOPE" "G"
					( Parent
						( matchGroupRef "@baseboard_fab2_lib.baseboard_fab2(sch_1):\MG_DQ-DQS_NEAR_DIMM_NG_M_B_BYTE-ECC\" )
					)
					( Status sCSetFlattened )
					( Origin gBackEnd )
				)
				( attribute "RELATIVE_PROPAGATION_DELAY" "0.00 MIL,195.00 MIL"
					( Parent
						( matchGroupRef "@baseboard_fab2_lib.baseboard_fab2(sch_1):\MG_DQ-DQS_NEAR_DIMM_NG_M_B_BYTE-ECC\" )
					)
					( Units "uMatchProp" "ns" 1.000000)
					( Status sCSetFlattened )
					( Origin gBackEnd )
				)
				( attribute "RELATIVE_PROPAGATION_DELAY_SCOPE" "G"
					( Parent
						( matchGroupRef "@crescent_city_bb_fab1_lib.crescent_city_bb_fab1(sch_1):\MG_DQ_NEAR_DIMM_NG_M_B_BYTE-ECC\" )
					)
					( Origin gBackEnd )
				)
				( attribute "RELATIVE_PROPAGATION_DELAY" "-49.26 MIL,50.00 MIL"
					( Parent
						( matchGroupRef "@crescent_city_bb_fab1_lib.crescent_city_bb_fab1(sch_1):\MG_DQ_NEAR_DIMM_NG_M_B_BYTE-ECC\" )
					)
					( Units "uMatchProp" "ns" 1.000000)
					( Origin gBackEnd )
				)
			)
			( pinPair "@baseboard_fab2_lib.baseboard_fab2(sch_1):\PP5121\"
				( pinRef "@baseboard_fab2_lib.baseboard_fab2(sch_1):page24_i172:DDR1_ECC(2)" )
				( pinRef "@baseboard_fab2_lib.baseboard_fab2(sch_1):page45_i111:CB(3)" )
				( attribute "RELATIVE_PROPAGATION_DELAY_SCOPE" "G"
					( Parent
						( matchGroupRef "@baseboard_fab2_lib.baseboard_fab2(sch_1):\MG_DQ-DQS_FAR_DIMM_NG_M_B_BYTE-ECC\" )
					)
					( Status sCSetFlattened )
					( Origin gBackEnd )
				)
				( attribute "RELATIVE_PROPAGATION_DELAY" "0.00 MIL,195.00 MIL"
					( Parent
						( matchGroupRef "@baseboard_fab2_lib.baseboard_fab2(sch_1):\MG_DQ-DQS_FAR_DIMM_NG_M_B_BYTE-ECC\" )
					)
					( Units "uMatchProp" "ns" 1.000000)
					( Status sCSetFlattened )
					( Origin gBackEnd )
				)
				( attribute "RELATIVE_PROPAGATION_DELAY_SCOPE" "G"
					( Parent
						( matchGroupRef "@crescent_city_bb_fab1_lib.crescent_city_bb_fab1(sch_1):\MG_DQ_FAR_DIMM_NG_M_B_BYTE-ECC\" )
					)
					( Origin gBackEnd )
				)
				( attribute "RELATIVE_PROPAGATION_DELAY" "-48.50 MIL,50.00 MIL"
					( Parent
						( matchGroupRef "@crescent_city_bb_fab1_lib.crescent_city_bb_fab1(sch_1):\MG_DQ_FAR_DIMM_NG_M_B_BYTE-ECC\" )
					)
					( Units "uMatchProp" "ns" 1.000000)
					( Origin gBackEnd )
				)
			)
			( pinPair "@baseboard_fab2_lib.baseboard_fab2(sch_1):\PP5123\"
				( pinRef "@baseboard_fab2_lib.baseboard_fab2(sch_1):page24_i172:DDR1_ECC(2)" )
				( pinRef "@baseboard_fab2_lib.baseboard_fab2(sch_1):page46_i14:CB(2)" )
				( attribute "RELATIVE_PROPAGATION_DELAY_SCOPE" "G"
					( Parent
						( matchGroupRef "@baseboard_fab2_lib.baseboard_fab2(sch_1):\MG_DQ-DQS_NEAR_DIMM_NG_M_B_BYTE-ECC\" )
					)
					( Status sCSetFlattened )
					( Origin gBackEnd )
				)
				( attribute "RELATIVE_PROPAGATION_DELAY" "0.00 MIL,195.00 MIL"
					( Parent
						( matchGroupRef "@baseboard_fab2_lib.baseboard_fab2(sch_1):\MG_DQ-DQS_NEAR_DIMM_NG_M_B_BYTE-ECC\" )
					)
					( Units "uMatchProp" "ns" 1.000000)
					( Status sCSetFlattened )
					( Origin gBackEnd )
				)
				( attribute "RELATIVE_PROPAGATION_DELAY_SCOPE" "G"
					( Parent
						( matchGroupRef "@crescent_city_bb_fab1_lib.crescent_city_bb_fab1(sch_1):\MG_DQ_NEAR_DIMM_NG_M_B_BYTE-ECC\" )
					)
					( Origin gBackEnd )
				)
				( attribute "RELATIVE_PROPAGATION_DELAY" "-48.50 MIL,50.00 MIL"
					( Parent
						( matchGroupRef "@crescent_city_bb_fab1_lib.crescent_city_bb_fab1(sch_1):\MG_DQ_NEAR_DIMM_NG_M_B_BYTE-ECC\" )
					)
					( Units "uMatchProp" "ns" 1.000000)
					( Origin gBackEnd )
				)
			)
			( pinPair "@baseboard_fab2_lib.baseboard_fab2(sch_1):\PP5124\"
				( pinRef "@baseboard_fab2_lib.baseboard_fab2(sch_1):page24_i172:DDR1_ECC(3)" )
				( pinRef "@baseboard_fab2_lib.baseboard_fab2(sch_1):page45_i111:CB(2)" )
				( attribute "RELATIVE_PROPAGATION_DELAY_SCOPE" "G"
					( Parent
						( matchGroupRef "@baseboard_fab2_lib.baseboard_fab2(sch_1):\MG_DQ-DQS_FAR_DIMM_NG_M_B_BYTE-ECC\" )
					)
					( Status sCSetFlattened )
					( Origin gBackEnd )
				)
				( attribute "RELATIVE_PROPAGATION_DELAY" "0.00 MIL,195.00 MIL"
					( Parent
						( matchGroupRef "@baseboard_fab2_lib.baseboard_fab2(sch_1):\MG_DQ-DQS_FAR_DIMM_NG_M_B_BYTE-ECC\" )
					)
					( Units "uMatchProp" "ns" 1.000000)
					( Status sCSetFlattened )
					( Origin gBackEnd )
				)
				( attribute "RELATIVE_PROPAGATION_DELAY_SCOPE" "G"
					( Parent
						( matchGroupRef "@crescent_city_bb_fab1_lib.crescent_city_bb_fab1(sch_1):\MG_DQ_FAR_DIMM_NG_M_B_BYTE-ECC\" )
					)
					( Origin gBackEnd )
				)
				( attribute "RELATIVE_PROPAGATION_DELAY" "-24.41 MIL,50.00 MIL"
					( Parent
						( matchGroupRef "@crescent_city_bb_fab1_lib.crescent_city_bb_fab1(sch_1):\MG_DQ_FAR_DIMM_NG_M_B_BYTE-ECC\" )
					)
					( Units "uMatchProp" "ns" 1.000000)
					( Origin gBackEnd )
				)
			)
			( pinPair "@baseboard_fab2_lib.baseboard_fab2(sch_1):\PP5126\"
				( pinRef "@baseboard_fab2_lib.baseboard_fab2(sch_1):page24_i172:DDR1_ECC(3)" )
				( pinRef "@baseboard_fab2_lib.baseboard_fab2(sch_1):page46_i14:CB(3)" )
				( attribute "RELATIVE_PROPAGATION_DELAY_SCOPE" "G"
					( Parent
						( matchGroupRef "@baseboard_fab2_lib.baseboard_fab2(sch_1):\MG_DQ-DQS_NEAR_DIMM_NG_M_B_BYTE-ECC\" )
					)
					( Status sCSetFlattened )
					( Origin gBackEnd )
				)
				( attribute "RELATIVE_PROPAGATION_DELAY" "0.00 MIL,195.00 MIL"
					( Parent
						( matchGroupRef "@baseboard_fab2_lib.baseboard_fab2(sch_1):\MG_DQ-DQS_NEAR_DIMM_NG_M_B_BYTE-ECC\" )
					)
					( Units "uMatchProp" "ns" 1.000000)
					( Status sCSetFlattened )
					( Origin gBackEnd )
				)
				( attribute "RELATIVE_PROPAGATION_DELAY_SCOPE" "G"
					( Parent
						( matchGroupRef "@crescent_city_bb_fab1_lib.crescent_city_bb_fab1(sch_1):\MG_DQ_NEAR_DIMM_NG_M_B_BYTE-ECC\" )
					)
					( Origin gBackEnd )
				)
				( attribute "RELATIVE_PROPAGATION_DELAY" "-24.41 MIL,50.00 MIL"
					( Parent
						( matchGroupRef "@crescent_city_bb_fab1_lib.crescent_city_bb_fab1(sch_1):\MG_DQ_NEAR_DIMM_NG_M_B_BYTE-ECC\" )
					)
					( Units "uMatchProp" "ns" 1.000000)
					( Origin gBackEnd )
				)
			)
			( pinPair "@baseboard_fab2_lib.baseboard_fab2(sch_1):\PP5127\"
				( pinRef "@baseboard_fab2_lib.baseboard_fab2(sch_1):page24_i172:DDR1_ECC(4)" )
				( pinRef "@baseboard_fab2_lib.baseboard_fab2(sch_1):page45_i111:CB(5)" )
				( attribute "RELATIVE_PROPAGATION_DELAY_SCOPE" "G"
					( Parent
						( matchGroupRef "@baseboard_fab2_lib.baseboard_fab2(sch_1):\MG_DQ-DQS_FAR_DIMM_NG_M_B_BYTE-ECC\" )
					)
					( Status sCSetFlattened )
					( Origin gBackEnd )
				)
				( attribute "RELATIVE_PROPAGATION_DELAY" "0.00 MIL,195.00 MIL"
					( Parent
						( matchGroupRef "@baseboard_fab2_lib.baseboard_fab2(sch_1):\MG_DQ-DQS_FAR_DIMM_NG_M_B_BYTE-ECC\" )
					)
					( Units "uMatchProp" "ns" 1.000000)
					( Status sCSetFlattened )
					( Origin gBackEnd )
				)
				( attribute "RELATIVE_PROPAGATION_DELAY_SCOPE" "G"
					( Parent
						( matchGroupRef "@crescent_city_bb_fab1_lib.crescent_city_bb_fab1(sch_1):\MG_DQ_FAR_DIMM_NG_M_B_BYTE-ECC\" )
					)
					( Origin gBackEnd )
				)
				( attribute "RELATIVE_PROPAGATION_DELAY" "-23.54 MIL,50.00 MIL"
					( Parent
						( matchGroupRef "@crescent_city_bb_fab1_lib.crescent_city_bb_fab1(sch_1):\MG_DQ_FAR_DIMM_NG_M_B_BYTE-ECC\" )
					)
					( Units "uMatchProp" "ns" 1.000000)
					( Origin gBackEnd )
				)
			)
			( pinPair "@baseboard_fab2_lib.baseboard_fab2(sch_1):\PP5129\"
				( pinRef "@baseboard_fab2_lib.baseboard_fab2(sch_1):page24_i172:DDR1_ECC(4)" )
				( pinRef "@baseboard_fab2_lib.baseboard_fab2(sch_1):page46_i14:CB(4)" )
				( attribute "RELATIVE_PROPAGATION_DELAY_SCOPE" "G"
					( Parent
						( matchGroupRef "@baseboard_fab2_lib.baseboard_fab2(sch_1):\MG_DQ-DQS_NEAR_DIMM_NG_M_B_BYTE-ECC\" )
					)
					( Status sCSetFlattened )
					( Origin gBackEnd )
				)
				( attribute "RELATIVE_PROPAGATION_DELAY" "0.00 MIL,195.00 MIL"
					( Parent
						( matchGroupRef "@baseboard_fab2_lib.baseboard_fab2(sch_1):\MG_DQ-DQS_NEAR_DIMM_NG_M_B_BYTE-ECC\" )
					)
					( Units "uMatchProp" "ns" 1.000000)
					( Status sCSetFlattened )
					( Origin gBackEnd )
				)
				( attribute "RELATIVE_PROPAGATION_DELAY_SCOPE" "G"
					( Parent
						( matchGroupRef "@crescent_city_bb_fab1_lib.crescent_city_bb_fab1(sch_1):\MG_DQ_NEAR_DIMM_NG_M_B_BYTE-ECC\" )
					)
					( Origin gBackEnd )
				)
				( attribute "RELATIVE_PROPAGATION_DELAY" "-23.54 MIL,50.00 MIL"
					( Parent
						( matchGroupRef "@crescent_city_bb_fab1_lib.crescent_city_bb_fab1(sch_1):\MG_DQ_NEAR_DIMM_NG_M_B_BYTE-ECC\" )
					)
					( Units "uMatchProp" "ns" 1.000000)
					( Origin gBackEnd )
				)
			)
			( pinPair "@baseboard_fab2_lib.baseboard_fab2(sch_1):\PP5130\"
				( pinRef "@baseboard_fab2_lib.baseboard_fab2(sch_1):page24_i172:DDR1_ECC(5)" )
				( pinRef "@baseboard_fab2_lib.baseboard_fab2(sch_1):page45_i111:CB(4)" )
				( attribute "RELATIVE_PROPAGATION_DELAY_SCOPE" "G"
					( Parent
						( matchGroupRef "@baseboard_fab2_lib.baseboard_fab2(sch_1):\MG_DQ-DQS_FAR_DIMM_NG_M_B_BYTE-ECC\" )
					)
					( Status sCSetFlattened )
					( Origin gBackEnd )
				)
				( attribute "RELATIVE_PROPAGATION_DELAY" "0.00 MIL,195.00 MIL"
					( Parent
						( matchGroupRef "@baseboard_fab2_lib.baseboard_fab2(sch_1):\MG_DQ-DQS_FAR_DIMM_NG_M_B_BYTE-ECC\" )
					)
					( Units "uMatchProp" "ns" 1.000000)
					( Status sCSetFlattened )
					( Origin gBackEnd )
				)
				( attribute "RELATIVE_PROPAGATION_DELAY_SCOPE" "G"
					( Parent
						( matchGroupRef "@crescent_city_bb_fab1_lib.crescent_city_bb_fab1(sch_1):\MG_DQ_FAR_DIMM_NG_M_B_BYTE-ECC\" )
					)
					( Origin gBackEnd )
				)
				( attribute "RELATIVE_PROPAGATION_DELAY" "TARGET,TARGET"
					( Parent
						( matchGroupRef "@crescent_city_bb_fab1_lib.crescent_city_bb_fab1(sch_1):\MG_DQ_FAR_DIMM_NG_M_B_BYTE-ECC\" )
					)
					( Units "uMatchProp" "ns" 1.000000)
					( Origin gBackEnd )
				)
			)
			( pinPair "@baseboard_fab2_lib.baseboard_fab2(sch_1):\PP5132\"
				( pinRef "@baseboard_fab2_lib.baseboard_fab2(sch_1):page24_i172:DDR1_ECC(5)" )
				( pinRef "@baseboard_fab2_lib.baseboard_fab2(sch_1):page46_i14:CB(5)" )
				( attribute "RELATIVE_PROPAGATION_DELAY_SCOPE" "G"
					( Parent
						( matchGroupRef "@baseboard_fab2_lib.baseboard_fab2(sch_1):\MG_DQ-DQS_NEAR_DIMM_NG_M_B_BYTE-ECC\" )
					)
					( Status sCSetFlattened )
					( Origin gBackEnd )
				)
				( attribute "RELATIVE_PROPAGATION_DELAY" "0.00 MIL,195.00 MIL"
					( Parent
						( matchGroupRef "@baseboard_fab2_lib.baseboard_fab2(sch_1):\MG_DQ-DQS_NEAR_DIMM_NG_M_B_BYTE-ECC\" )
					)
					( Units "uMatchProp" "ns" 1.000000)
					( Status sCSetFlattened )
					( Origin gBackEnd )
				)
				( attribute "RELATIVE_PROPAGATION_DELAY_SCOPE" "G"
					( Parent
						( matchGroupRef "@crescent_city_bb_fab1_lib.crescent_city_bb_fab1(sch_1):\MG_DQ_NEAR_DIMM_NG_M_B_BYTE-ECC\" )
					)
					( Origin gBackEnd )
				)
				( attribute "RELATIVE_PROPAGATION_DELAY" "TARGET,TARGET"
					( Parent
						( matchGroupRef "@crescent_city_bb_fab1_lib.crescent_city_bb_fab1(sch_1):\MG_DQ_NEAR_DIMM_NG_M_B_BYTE-ECC\" )
					)
					( Units "uMatchProp" "ns" 1.000000)
					( Origin gBackEnd )
				)
			)
			( pinPair "@baseboard_fab2_lib.baseboard_fab2(sch_1):\PP5133\"
				( pinRef "@baseboard_fab2_lib.baseboard_fab2(sch_1):page24_i172:DDR1_ECC(6)" )
				( pinRef "@baseboard_fab2_lib.baseboard_fab2(sch_1):page45_i111:CB(7)" )
				( attribute "RELATIVE_PROPAGATION_DELAY_SCOPE" "G"
					( Parent
						( matchGroupRef "@baseboard_fab2_lib.baseboard_fab2(sch_1):\MG_DQ-DQS_FAR_DIMM_NG_M_B_BYTE-ECC\" )
					)
					( Status sCSetFlattened )
					( Origin gBackEnd )
				)
				( attribute "RELATIVE_PROPAGATION_DELAY" "0.00 MIL,195.00 MIL"
					( Parent
						( matchGroupRef "@baseboard_fab2_lib.baseboard_fab2(sch_1):\MG_DQ-DQS_FAR_DIMM_NG_M_B_BYTE-ECC\" )
					)
					( Units "uMatchProp" "ns" 1.000000)
					( Status sCSetFlattened )
					( Origin gBackEnd )
				)
				( attribute "RELATIVE_PROPAGATION_DELAY_SCOPE" "G"
					( Parent
						( matchGroupRef "@crescent_city_bb_fab1_lib.crescent_city_bb_fab1(sch_1):\MG_DQ_FAR_DIMM_NG_M_B_BYTE-ECC\" )
					)
					( Origin gBackEnd )
				)
				( attribute "RELATIVE_PROPAGATION_DELAY" "-51.75 MIL,50.00 MIL"
					( Parent
						( matchGroupRef "@crescent_city_bb_fab1_lib.crescent_city_bb_fab1(sch_1):\MG_DQ_FAR_DIMM_NG_M_B_BYTE-ECC\" )
					)
					( Units "uMatchProp" "ns" 1.000000)
					( Origin gBackEnd )
				)
			)
			( pinPair "@baseboard_fab2_lib.baseboard_fab2(sch_1):\PP5135\"
				( pinRef "@baseboard_fab2_lib.baseboard_fab2(sch_1):page24_i172:DDR1_ECC(6)" )
				( pinRef "@baseboard_fab2_lib.baseboard_fab2(sch_1):page46_i14:CB(6)" )
				( attribute "RELATIVE_PROPAGATION_DELAY_SCOPE" "G"
					( Parent
						( matchGroupRef "@baseboard_fab2_lib.baseboard_fab2(sch_1):\MG_DQ-DQS_NEAR_DIMM_NG_M_B_BYTE-ECC\" )
					)
					( Status sCSetFlattened )
					( Origin gBackEnd )
				)
				( attribute "RELATIVE_PROPAGATION_DELAY" "0.00 MIL,195.00 MIL"
					( Parent
						( matchGroupRef "@baseboard_fab2_lib.baseboard_fab2(sch_1):\MG_DQ-DQS_NEAR_DIMM_NG_M_B_BYTE-ECC\" )
					)
					( Units "uMatchProp" "ns" 1.000000)
					( Status sCSetFlattened )
					( Origin gBackEnd )
				)
				( attribute "RELATIVE_PROPAGATION_DELAY_SCOPE" "G"
					( Parent
						( matchGroupRef "@crescent_city_bb_fab1_lib.crescent_city_bb_fab1(sch_1):\MG_DQ_NEAR_DIMM_NG_M_B_BYTE-ECC\" )
					)
					( Origin gBackEnd )
				)
				( attribute "RELATIVE_PROPAGATION_DELAY" "-51.75 MIL,50.00 MIL"
					( Parent
						( matchGroupRef "@crescent_city_bb_fab1_lib.crescent_city_bb_fab1(sch_1):\MG_DQ_NEAR_DIMM_NG_M_B_BYTE-ECC\" )
					)
					( Units "uMatchProp" "ns" 1.000000)
					( Origin gBackEnd )
				)
			)
			( pinPair "@baseboard_fab2_lib.baseboard_fab2(sch_1):\PP5136\"
				( pinRef "@baseboard_fab2_lib.baseboard_fab2(sch_1):page24_i172:DDR1_ECC(7)" )
				( pinRef "@baseboard_fab2_lib.baseboard_fab2(sch_1):page45_i111:CB(6)" )
				( attribute "RELATIVE_PROPAGATION_DELAY_SCOPE" "G"
					( Parent
						( matchGroupRef "@baseboard_fab2_lib.baseboard_fab2(sch_1):\MG_DQ-DQS_FAR_DIMM_NG_M_B_BYTE-ECC\" )
					)
					( Status sCSetFlattened )
					( Origin gBackEnd )
				)
				( attribute "RELATIVE_PROPAGATION_DELAY" "0.00 MIL,195.00 MIL"
					( Parent
						( matchGroupRef "@baseboard_fab2_lib.baseboard_fab2(sch_1):\MG_DQ-DQS_FAR_DIMM_NG_M_B_BYTE-ECC\" )
					)
					( Units "uMatchProp" "ns" 1.000000)
					( Status sCSetFlattened )
					( Origin gBackEnd )
				)
				( attribute "RELATIVE_PROPAGATION_DELAY_SCOPE" "G"
					( Parent
						( matchGroupRef "@crescent_city_bb_fab1_lib.crescent_city_bb_fab1(sch_1):\MG_DQ_FAR_DIMM_NG_M_B_BYTE-ECC\" )
					)
					( Origin gBackEnd )
				)
				( attribute "RELATIVE_PROPAGATION_DELAY" "-52.28 MIL,50.00 MIL"
					( Parent
						( matchGroupRef "@crescent_city_bb_fab1_lib.crescent_city_bb_fab1(sch_1):\MG_DQ_FAR_DIMM_NG_M_B_BYTE-ECC\" )
					)
					( Units "uMatchProp" "ns" 1.000000)
					( Origin gBackEnd )
				)
			)
			( pinPair "@baseboard_fab2_lib.baseboard_fab2(sch_1):\PP5138\"
				( pinRef "@baseboard_fab2_lib.baseboard_fab2(sch_1):page24_i172:DDR1_ECC(7)" )
				( pinRef "@baseboard_fab2_lib.baseboard_fab2(sch_1):page46_i14:CB(7)" )
				( attribute "RELATIVE_PROPAGATION_DELAY_SCOPE" "G"
					( Parent
						( matchGroupRef "@baseboard_fab2_lib.baseboard_fab2(sch_1):\MG_DQ-DQS_NEAR_DIMM_NG_M_B_BYTE-ECC\" )
					)
					( Status sCSetFlattened )
					( Origin gBackEnd )
				)
				( attribute "RELATIVE_PROPAGATION_DELAY" "0.00 MIL,195.00 MIL"
					( Parent
						( matchGroupRef "@baseboard_fab2_lib.baseboard_fab2(sch_1):\MG_DQ-DQS_NEAR_DIMM_NG_M_B_BYTE-ECC\" )
					)
					( Units "uMatchProp" "ns" 1.000000)
					( Status sCSetFlattened )
					( Origin gBackEnd )
				)
				( attribute "RELATIVE_PROPAGATION_DELAY_SCOPE" "G"
					( Parent
						( matchGroupRef "@crescent_city_bb_fab1_lib.crescent_city_bb_fab1(sch_1):\MG_DQ_NEAR_DIMM_NG_M_B_BYTE-ECC\" )
					)
					( Origin gBackEnd )
				)
				( attribute "RELATIVE_PROPAGATION_DELAY" "-52.28 MIL,50.00 MIL"
					( Parent
						( matchGroupRef "@crescent_city_bb_fab1_lib.crescent_city_bb_fab1(sch_1):\MG_DQ_NEAR_DIMM_NG_M_B_BYTE-ECC\" )
					)
					( Units "uMatchProp" "ns" 1.000000)
					( Origin gBackEnd )
				)
			)
			( pinPair "@baseboard_fab2_lib.baseboard_fab2(sch_1):\PP4899\"
				( pinRef "@baseboard_fab2_lib.baseboard_fab2(sch_1):page25_i172:DDR2_ECC(0)" )
				( pinRef "@baseboard_fab2_lib.baseboard_fab2(sch_1):page47_i111:CB(1)" )
				( attribute "RELATIVE_PROPAGATION_DELAY_SCOPE" "G"
					( Parent
						( matchGroupRef "@baseboard_fab2_lib.baseboard_fab2(sch_1):\MG_DQ-DQS_FAR_DIMM_NG_M_C_BYTE-ECC\" )
					)
					( Status sCSetFlattened )
					( Origin gBackEnd )
				)
				( attribute "RELATIVE_PROPAGATION_DELAY" "0.00 MIL,195.00 MIL"
					( Parent
						( matchGroupRef "@baseboard_fab2_lib.baseboard_fab2(sch_1):\MG_DQ-DQS_FAR_DIMM_NG_M_C_BYTE-ECC\" )
					)
					( Units "uMatchProp" "ns" 1.000000)
					( Status sCSetFlattened )
					( Origin gBackEnd )
				)
				( attribute "RELATIVE_PROPAGATION_DELAY_SCOPE" "G"
					( Parent
						( matchGroupRef "@baseboard_fab2_lib.baseboard_fab2(sch_1):\MG_DQ_FAR_DIMM_NG_M_C_BYTE-ECC\" )
					)
					( Status sCSetFlattened )
					( Origin gBackEnd )
				)
				( attribute "RELATIVE_PROPAGATION_DELAY" "-50.00 MIL,50.00 MIL"
					( Parent
						( matchGroupRef "@baseboard_fab2_lib.baseboard_fab2(sch_1):\MG_DQ_FAR_DIMM_NG_M_C_BYTE-ECC\" )
					)
					( Units "uMatchProp" "ns" 1.000000)
					( Status sCSetFlattened )
					( Origin gBackEnd )
				)
			)
			( pinPair "@baseboard_fab2_lib.baseboard_fab2(sch_1):\PP4901\"
				( pinRef "@baseboard_fab2_lib.baseboard_fab2(sch_1):page25_i172:DDR2_ECC(0)" )
				( pinRef "@baseboard_fab2_lib.baseboard_fab2(sch_1):page48_i111:CB(0)" )
				( attribute "RELATIVE_PROPAGATION_DELAY_SCOPE" "G"
					( Parent
						( matchGroupRef "@baseboard_fab2_lib.baseboard_fab2(sch_1):\MG_DQ-DQS_NEAR_DIMM_NG_M_C_BYTE-ECC\" )
					)
					( Status sCSetFlattened )
					( Origin gBackEnd )
				)
				( attribute "RELATIVE_PROPAGATION_DELAY" "0.00 MIL,195.00 MIL"
					( Parent
						( matchGroupRef "@baseboard_fab2_lib.baseboard_fab2(sch_1):\MG_DQ-DQS_NEAR_DIMM_NG_M_C_BYTE-ECC\" )
					)
					( Units "uMatchProp" "ns" 1.000000)
					( Status sCSetFlattened )
					( Origin gBackEnd )
				)
				( attribute "RELATIVE_PROPAGATION_DELAY_SCOPE" "G"
					( Parent
						( matchGroupRef "@baseboard_fab2_lib.baseboard_fab2(sch_1):\MG_DQ_NEAR_DIMM_NG_M_C_BYTE-ECC\" )
					)
					( Status sCSetFlattened )
					( Origin gBackEnd )
				)
				( attribute "RELATIVE_PROPAGATION_DELAY" "-50.00 MIL,50.00 MIL"
					( Parent
						( matchGroupRef "@baseboard_fab2_lib.baseboard_fab2(sch_1):\MG_DQ_NEAR_DIMM_NG_M_C_BYTE-ECC\" )
					)
					( Units "uMatchProp" "ns" 1.000000)
					( Status sCSetFlattened )
					( Origin gBackEnd )
				)
			)
			( pinPair "@baseboard_fab2_lib.baseboard_fab2(sch_1):\PP4902\"
				( pinRef "@baseboard_fab2_lib.baseboard_fab2(sch_1):page25_i172:DDR2_ECC(1)" )
				( pinRef "@baseboard_fab2_lib.baseboard_fab2(sch_1):page47_i111:CB(0)" )
				( attribute "RELATIVE_PROPAGATION_DELAY_SCOPE" "G"
					( Parent
						( matchGroupRef "@baseboard_fab2_lib.baseboard_fab2(sch_1):\MG_DQ-DQS_FAR_DIMM_NG_M_C_BYTE-ECC\" )
					)
					( Status sCSetFlattened )
					( Origin gBackEnd )
				)
				( attribute "RELATIVE_PROPAGATION_DELAY" "0.00 MIL,195.00 MIL"
					( Parent
						( matchGroupRef "@baseboard_fab2_lib.baseboard_fab2(sch_1):\MG_DQ-DQS_FAR_DIMM_NG_M_C_BYTE-ECC\" )
					)
					( Units "uMatchProp" "ns" 1.000000)
					( Status sCSetFlattened )
					( Origin gBackEnd )
				)
				( attribute "RELATIVE_PROPAGATION_DELAY_SCOPE" "G"
					( Parent
						( matchGroupRef "@baseboard_fab2_lib.baseboard_fab2(sch_1):\MG_DQ_FAR_DIMM_NG_M_C_BYTE-ECC\" )
					)
					( Status sCSetFlattened )
					( Origin gBackEnd )
				)
				( attribute "RELATIVE_PROPAGATION_DELAY" "-50.00 MIL,50.00 MIL"
					( Parent
						( matchGroupRef "@baseboard_fab2_lib.baseboard_fab2(sch_1):\MG_DQ_FAR_DIMM_NG_M_C_BYTE-ECC\" )
					)
					( Units "uMatchProp" "ns" 1.000000)
					( Status sCSetFlattened )
					( Origin gBackEnd )
				)
			)
			( pinPair "@baseboard_fab2_lib.baseboard_fab2(sch_1):\PP4904\"
				( pinRef "@baseboard_fab2_lib.baseboard_fab2(sch_1):page25_i172:DDR2_ECC(1)" )
				( pinRef "@baseboard_fab2_lib.baseboard_fab2(sch_1):page48_i111:CB(1)" )
				( attribute "RELATIVE_PROPAGATION_DELAY_SCOPE" "G"
					( Parent
						( matchGroupRef "@baseboard_fab2_lib.baseboard_fab2(sch_1):\MG_DQ-DQS_NEAR_DIMM_NG_M_C_BYTE-ECC\" )
					)
					( Status sCSetFlattened )
					( Origin gBackEnd )
				)
				( attribute "RELATIVE_PROPAGATION_DELAY" "0.00 MIL,195.00 MIL"
					( Parent
						( matchGroupRef "@baseboard_fab2_lib.baseboard_fab2(sch_1):\MG_DQ-DQS_NEAR_DIMM_NG_M_C_BYTE-ECC\" )
					)
					( Units "uMatchProp" "ns" 1.000000)
					( Status sCSetFlattened )
					( Origin gBackEnd )
				)
				( attribute "RELATIVE_PROPAGATION_DELAY_SCOPE" "G"
					( Parent
						( matchGroupRef "@baseboard_fab2_lib.baseboard_fab2(sch_1):\MG_DQ_NEAR_DIMM_NG_M_C_BYTE-ECC\" )
					)
					( Status sCSetFlattened )
					( Origin gBackEnd )
				)
				( attribute "RELATIVE_PROPAGATION_DELAY" "-50.00 MIL,50.00 MIL"
					( Parent
						( matchGroupRef "@baseboard_fab2_lib.baseboard_fab2(sch_1):\MG_DQ_NEAR_DIMM_NG_M_C_BYTE-ECC\" )
					)
					( Units "uMatchProp" "ns" 1.000000)
					( Status sCSetFlattened )
					( Origin gBackEnd )
				)
			)
			( pinPair "@baseboard_fab2_lib.baseboard_fab2(sch_1):\PP4905\"
				( pinRef "@baseboard_fab2_lib.baseboard_fab2(sch_1):page25_i172:DDR2_ECC(2)" )
				( pinRef "@baseboard_fab2_lib.baseboard_fab2(sch_1):page47_i111:CB(3)" )
				( attribute "RELATIVE_PROPAGATION_DELAY_SCOPE" "G"
					( Parent
						( matchGroupRef "@baseboard_fab2_lib.baseboard_fab2(sch_1):\MG_DQ-DQS_FAR_DIMM_NG_M_C_BYTE-ECC\" )
					)
					( Status sCSetFlattened )
					( Origin gBackEnd )
				)
				( attribute "RELATIVE_PROPAGATION_DELAY" "0.00 MIL,195.00 MIL"
					( Parent
						( matchGroupRef "@baseboard_fab2_lib.baseboard_fab2(sch_1):\MG_DQ-DQS_FAR_DIMM_NG_M_C_BYTE-ECC\" )
					)
					( Units "uMatchProp" "ns" 1.000000)
					( Status sCSetFlattened )
					( Origin gBackEnd )
				)
				( attribute "RELATIVE_PROPAGATION_DELAY_SCOPE" "G"
					( Parent
						( matchGroupRef "@baseboard_fab2_lib.baseboard_fab2(sch_1):\MG_DQ_FAR_DIMM_NG_M_C_BYTE-ECC\" )
					)
					( Status sCSetFlattened )
					( Origin gBackEnd )
				)
				( attribute "RELATIVE_PROPAGATION_DELAY" "-50.00 MIL,50.00 MIL"
					( Parent
						( matchGroupRef "@baseboard_fab2_lib.baseboard_fab2(sch_1):\MG_DQ_FAR_DIMM_NG_M_C_BYTE-ECC\" )
					)
					( Units "uMatchProp" "ns" 1.000000)
					( Status sCSetFlattened )
					( Origin gBackEnd )
				)
			)
			( pinPair "@baseboard_fab2_lib.baseboard_fab2(sch_1):\PP4907\"
				( pinRef "@baseboard_fab2_lib.baseboard_fab2(sch_1):page25_i172:DDR2_ECC(2)" )
				( pinRef "@baseboard_fab2_lib.baseboard_fab2(sch_1):page48_i111:CB(2)" )
				( attribute "RELATIVE_PROPAGATION_DELAY_SCOPE" "G"
					( Parent
						( matchGroupRef "@baseboard_fab2_lib.baseboard_fab2(sch_1):\MG_DQ-DQS_NEAR_DIMM_NG_M_C_BYTE-ECC\" )
					)
					( Status sCSetFlattened )
					( Origin gBackEnd )
				)
				( attribute "RELATIVE_PROPAGATION_DELAY" "0.00 MIL,195.00 MIL"
					( Parent
						( matchGroupRef "@baseboard_fab2_lib.baseboard_fab2(sch_1):\MG_DQ-DQS_NEAR_DIMM_NG_M_C_BYTE-ECC\" )
					)
					( Units "uMatchProp" "ns" 1.000000)
					( Status sCSetFlattened )
					( Origin gBackEnd )
				)
				( attribute "RELATIVE_PROPAGATION_DELAY_SCOPE" "G"
					( Parent
						( matchGroupRef "@baseboard_fab2_lib.baseboard_fab2(sch_1):\MG_DQ_NEAR_DIMM_NG_M_C_BYTE-ECC\" )
					)
					( Status sCSetFlattened )
					( Origin gBackEnd )
				)
				( attribute "RELATIVE_PROPAGATION_DELAY" "-50.00 MIL,50.00 MIL"
					( Parent
						( matchGroupRef "@baseboard_fab2_lib.baseboard_fab2(sch_1):\MG_DQ_NEAR_DIMM_NG_M_C_BYTE-ECC\" )
					)
					( Units "uMatchProp" "ns" 1.000000)
					( Status sCSetFlattened )
					( Origin gBackEnd )
				)
			)
			( pinPair "@baseboard_fab2_lib.baseboard_fab2(sch_1):\PP4908\"
				( pinRef "@baseboard_fab2_lib.baseboard_fab2(sch_1):page25_i172:DDR2_ECC(3)" )
				( pinRef "@baseboard_fab2_lib.baseboard_fab2(sch_1):page47_i111:CB(2)" )
				( attribute "RELATIVE_PROPAGATION_DELAY_SCOPE" "G"
					( Parent
						( matchGroupRef "@baseboard_fab2_lib.baseboard_fab2(sch_1):\MG_DQ-DQS_FAR_DIMM_NG_M_C_BYTE-ECC\" )
					)
					( Status sCSetFlattened )
					( Origin gBackEnd )
				)
				( attribute "RELATIVE_PROPAGATION_DELAY" "0.00 MIL,195.00 MIL"
					( Parent
						( matchGroupRef "@baseboard_fab2_lib.baseboard_fab2(sch_1):\MG_DQ-DQS_FAR_DIMM_NG_M_C_BYTE-ECC\" )
					)
					( Units "uMatchProp" "ns" 1.000000)
					( Status sCSetFlattened )
					( Origin gBackEnd )
				)
				( attribute "RELATIVE_PROPAGATION_DELAY_SCOPE" "G"
					( Parent
						( matchGroupRef "@baseboard_fab2_lib.baseboard_fab2(sch_1):\MG_DQ_FAR_DIMM_NG_M_C_BYTE-ECC\" )
					)
					( Status sCSetFlattened )
					( Origin gBackEnd )
				)
				( attribute "RELATIVE_PROPAGATION_DELAY" "-50.00 MIL,50.00 MIL"
					( Parent
						( matchGroupRef "@baseboard_fab2_lib.baseboard_fab2(sch_1):\MG_DQ_FAR_DIMM_NG_M_C_BYTE-ECC\" )
					)
					( Units "uMatchProp" "ns" 1.000000)
					( Status sCSetFlattened )
					( Origin gBackEnd )
				)
			)
			( pinPair "@baseboard_fab2_lib.baseboard_fab2(sch_1):\PP4910\"
				( pinRef "@baseboard_fab2_lib.baseboard_fab2(sch_1):page25_i172:DDR2_ECC(3)" )
				( pinRef "@baseboard_fab2_lib.baseboard_fab2(sch_1):page48_i111:CB(3)" )
				( attribute "RELATIVE_PROPAGATION_DELAY_SCOPE" "G"
					( Parent
						( matchGroupRef "@baseboard_fab2_lib.baseboard_fab2(sch_1):\MG_DQ-DQS_NEAR_DIMM_NG_M_C_BYTE-ECC\" )
					)
					( Status sCSetFlattened )
					( Origin gBackEnd )
				)
				( attribute "RELATIVE_PROPAGATION_DELAY" "0.00 MIL,195.00 MIL"
					( Parent
						( matchGroupRef "@baseboard_fab2_lib.baseboard_fab2(sch_1):\MG_DQ-DQS_NEAR_DIMM_NG_M_C_BYTE-ECC\" )
					)
					( Units "uMatchProp" "ns" 1.000000)
					( Status sCSetFlattened )
					( Origin gBackEnd )
				)
				( attribute "RELATIVE_PROPAGATION_DELAY_SCOPE" "G"
					( Parent
						( matchGroupRef "@baseboard_fab2_lib.baseboard_fab2(sch_1):\MG_DQ_NEAR_DIMM_NG_M_C_BYTE-ECC\" )
					)
					( Status sCSetFlattened )
					( Origin gBackEnd )
				)
				( attribute "RELATIVE_PROPAGATION_DELAY" "-50.00 MIL,50.00 MIL"
					( Parent
						( matchGroupRef "@baseboard_fab2_lib.baseboard_fab2(sch_1):\MG_DQ_NEAR_DIMM_NG_M_C_BYTE-ECC\" )
					)
					( Units "uMatchProp" "ns" 1.000000)
					( Status sCSetFlattened )
					( Origin gBackEnd )
				)
			)
			( pinPair "@baseboard_fab2_lib.baseboard_fab2(sch_1):\PP4911\"
				( pinRef "@baseboard_fab2_lib.baseboard_fab2(sch_1):page25_i172:DDR2_ECC(4)" )
				( pinRef "@baseboard_fab2_lib.baseboard_fab2(sch_1):page47_i111:CB(5)" )
				( attribute "RELATIVE_PROPAGATION_DELAY_SCOPE" "G"
					( Parent
						( matchGroupRef "@baseboard_fab2_lib.baseboard_fab2(sch_1):\MG_DQ-DQS_FAR_DIMM_NG_M_C_BYTE-ECC\" )
					)
					( Status sCSetFlattened )
					( Origin gBackEnd )
				)
				( attribute "RELATIVE_PROPAGATION_DELAY" "0.00 MIL,195.00 MIL"
					( Parent
						( matchGroupRef "@baseboard_fab2_lib.baseboard_fab2(sch_1):\MG_DQ-DQS_FAR_DIMM_NG_M_C_BYTE-ECC\" )
					)
					( Units "uMatchProp" "ns" 1.000000)
					( Status sCSetFlattened )
					( Origin gBackEnd )
				)
				( attribute "RELATIVE_PROPAGATION_DELAY_SCOPE" "G"
					( Parent
						( matchGroupRef "@baseboard_fab2_lib.baseboard_fab2(sch_1):\MG_DQ_FAR_DIMM_NG_M_C_BYTE-ECC\" )
					)
					( Status sCSetFlattened )
					( Origin gBackEnd )
				)
				( attribute "RELATIVE_PROPAGATION_DELAY" "-50.00 MIL,50.00 MIL"
					( Parent
						( matchGroupRef "@baseboard_fab2_lib.baseboard_fab2(sch_1):\MG_DQ_FAR_DIMM_NG_M_C_BYTE-ECC\" )
					)
					( Units "uMatchProp" "ns" 1.000000)
					( Status sCSetFlattened )
					( Origin gBackEnd )
				)
			)
			( pinPair "@baseboard_fab2_lib.baseboard_fab2(sch_1):\PP4913\"
				( pinRef "@baseboard_fab2_lib.baseboard_fab2(sch_1):page25_i172:DDR2_ECC(4)" )
				( pinRef "@baseboard_fab2_lib.baseboard_fab2(sch_1):page48_i111:CB(4)" )
				( attribute "RELATIVE_PROPAGATION_DELAY_SCOPE" "G"
					( Parent
						( matchGroupRef "@baseboard_fab2_lib.baseboard_fab2(sch_1):\MG_DQ-DQS_NEAR_DIMM_NG_M_C_BYTE-ECC\" )
					)
					( Status sCSetFlattened )
					( Origin gBackEnd )
				)
				( attribute "RELATIVE_PROPAGATION_DELAY" "0.00 MIL,195.00 MIL"
					( Parent
						( matchGroupRef "@baseboard_fab2_lib.baseboard_fab2(sch_1):\MG_DQ-DQS_NEAR_DIMM_NG_M_C_BYTE-ECC\" )
					)
					( Units "uMatchProp" "ns" 1.000000)
					( Status sCSetFlattened )
					( Origin gBackEnd )
				)
				( attribute "RELATIVE_PROPAGATION_DELAY_SCOPE" "G"
					( Parent
						( matchGroupRef "@baseboard_fab2_lib.baseboard_fab2(sch_1):\MG_DQ_NEAR_DIMM_NG_M_C_BYTE-ECC\" )
					)
					( Status sCSetFlattened )
					( Origin gBackEnd )
				)
				( attribute "RELATIVE_PROPAGATION_DELAY" "-50.00 MIL,50.00 MIL"
					( Parent
						( matchGroupRef "@baseboard_fab2_lib.baseboard_fab2(sch_1):\MG_DQ_NEAR_DIMM_NG_M_C_BYTE-ECC\" )
					)
					( Units "uMatchProp" "ns" 1.000000)
					( Status sCSetFlattened )
					( Origin gBackEnd )
				)
			)
			( pinPair "@baseboard_fab2_lib.baseboard_fab2(sch_1):\PP4914\"
				( pinRef "@baseboard_fab2_lib.baseboard_fab2(sch_1):page25_i172:DDR2_ECC(5)" )
				( pinRef "@baseboard_fab2_lib.baseboard_fab2(sch_1):page47_i111:CB(4)" )
				( attribute "RELATIVE_PROPAGATION_DELAY_SCOPE" "G"
					( Parent
						( matchGroupRef "@baseboard_fab2_lib.baseboard_fab2(sch_1):\MG_DQ-DQS_FAR_DIMM_NG_M_C_BYTE-ECC\" )
					)
					( Status sCSetFlattened )
					( Origin gBackEnd )
				)
				( attribute "RELATIVE_PROPAGATION_DELAY" "0.00 MIL,195.00 MIL"
					( Parent
						( matchGroupRef "@baseboard_fab2_lib.baseboard_fab2(sch_1):\MG_DQ-DQS_FAR_DIMM_NG_M_C_BYTE-ECC\" )
					)
					( Units "uMatchProp" "ns" 1.000000)
					( Status sCSetFlattened )
					( Origin gBackEnd )
				)
				( attribute "RELATIVE_PROPAGATION_DELAY_SCOPE" "G"
					( Parent
						( matchGroupRef "@baseboard_fab2_lib.baseboard_fab2(sch_1):\MG_DQ_FAR_DIMM_NG_M_C_BYTE-ECC\" )
					)
					( Status sCSetFlattened )
					( Origin gBackEnd )
				)
				( attribute "RELATIVE_PROPAGATION_DELAY" "-50.00 MIL,50.00 MIL"
					( Parent
						( matchGroupRef "@baseboard_fab2_lib.baseboard_fab2(sch_1):\MG_DQ_FAR_DIMM_NG_M_C_BYTE-ECC\" )
					)
					( Units "uMatchProp" "ns" 1.000000)
					( Status sCSetFlattened )
					( Origin gBackEnd )
				)
			)
			( pinPair "@baseboard_fab2_lib.baseboard_fab2(sch_1):\PP4916\"
				( pinRef "@baseboard_fab2_lib.baseboard_fab2(sch_1):page25_i172:DDR2_ECC(5)" )
				( pinRef "@baseboard_fab2_lib.baseboard_fab2(sch_1):page48_i111:CB(5)" )
				( attribute "RELATIVE_PROPAGATION_DELAY_SCOPE" "G"
					( Parent
						( matchGroupRef "@baseboard_fab2_lib.baseboard_fab2(sch_1):\MG_DQ-DQS_NEAR_DIMM_NG_M_C_BYTE-ECC\" )
					)
					( Status sCSetFlattened )
					( Origin gBackEnd )
				)
				( attribute "RELATIVE_PROPAGATION_DELAY" "0.00 MIL,195.00 MIL"
					( Parent
						( matchGroupRef "@baseboard_fab2_lib.baseboard_fab2(sch_1):\MG_DQ-DQS_NEAR_DIMM_NG_M_C_BYTE-ECC\" )
					)
					( Units "uMatchProp" "ns" 1.000000)
					( Status sCSetFlattened )
					( Origin gBackEnd )
				)
				( attribute "RELATIVE_PROPAGATION_DELAY_SCOPE" "G"
					( Parent
						( matchGroupRef "@baseboard_fab2_lib.baseboard_fab2(sch_1):\MG_DQ_NEAR_DIMM_NG_M_C_BYTE-ECC\" )
					)
					( Status sCSetFlattened )
					( Origin gBackEnd )
				)
				( attribute "RELATIVE_PROPAGATION_DELAY" "-50.00 MIL,50.00 MIL"
					( Parent
						( matchGroupRef "@baseboard_fab2_lib.baseboard_fab2(sch_1):\MG_DQ_NEAR_DIMM_NG_M_C_BYTE-ECC\" )
					)
					( Units "uMatchProp" "ns" 1.000000)
					( Status sCSetFlattened )
					( Origin gBackEnd )
				)
			)
			( pinPair "@baseboard_fab2_lib.baseboard_fab2(sch_1):\PP4917\"
				( pinRef "@baseboard_fab2_lib.baseboard_fab2(sch_1):page25_i172:DDR2_ECC(6)" )
				( pinRef "@baseboard_fab2_lib.baseboard_fab2(sch_1):page47_i111:CB(7)" )
				( attribute "RELATIVE_PROPAGATION_DELAY_SCOPE" "G"
					( Parent
						( matchGroupRef "@baseboard_fab2_lib.baseboard_fab2(sch_1):\MG_DQ-DQS_FAR_DIMM_NG_M_C_BYTE-ECC\" )
					)
					( Status sCSetFlattened )
					( Origin gBackEnd )
				)
				( attribute "RELATIVE_PROPAGATION_DELAY" "0.00 MIL,195.00 MIL"
					( Parent
						( matchGroupRef "@baseboard_fab2_lib.baseboard_fab2(sch_1):\MG_DQ-DQS_FAR_DIMM_NG_M_C_BYTE-ECC\" )
					)
					( Units "uMatchProp" "ns" 1.000000)
					( Status sCSetFlattened )
					( Origin gBackEnd )
				)
				( attribute "RELATIVE_PROPAGATION_DELAY_SCOPE" "G"
					( Parent
						( matchGroupRef "@baseboard_fab2_lib.baseboard_fab2(sch_1):\MG_DQ_FAR_DIMM_NG_M_C_BYTE-ECC\" )
					)
					( Status sCSetFlattened )
					( Origin gBackEnd )
				)
				( attribute "RELATIVE_PROPAGATION_DELAY" "-50.00 MIL,50.00 MIL"
					( Parent
						( matchGroupRef "@baseboard_fab2_lib.baseboard_fab2(sch_1):\MG_DQ_FAR_DIMM_NG_M_C_BYTE-ECC\" )
					)
					( Units "uMatchProp" "ns" 1.000000)
					( Status sCSetFlattened )
					( Origin gBackEnd )
				)
			)
			( pinPair "@baseboard_fab2_lib.baseboard_fab2(sch_1):\PP4919\"
				( pinRef "@baseboard_fab2_lib.baseboard_fab2(sch_1):page25_i172:DDR2_ECC(6)" )
				( pinRef "@baseboard_fab2_lib.baseboard_fab2(sch_1):page48_i111:CB(6)" )
				( attribute "RELATIVE_PROPAGATION_DELAY_SCOPE" "G"
					( Parent
						( matchGroupRef "@baseboard_fab2_lib.baseboard_fab2(sch_1):\MG_DQ-DQS_NEAR_DIMM_NG_M_C_BYTE-ECC\" )
					)
					( Status sCSetFlattened )
					( Origin gBackEnd )
				)
				( attribute "RELATIVE_PROPAGATION_DELAY" "0.00 MIL,195.00 MIL"
					( Parent
						( matchGroupRef "@baseboard_fab2_lib.baseboard_fab2(sch_1):\MG_DQ-DQS_NEAR_DIMM_NG_M_C_BYTE-ECC\" )
					)
					( Units "uMatchProp" "ns" 1.000000)
					( Status sCSetFlattened )
					( Origin gBackEnd )
				)
				( attribute "RELATIVE_PROPAGATION_DELAY_SCOPE" "G"
					( Parent
						( matchGroupRef "@baseboard_fab2_lib.baseboard_fab2(sch_1):\MG_DQ_NEAR_DIMM_NG_M_C_BYTE-ECC\" )
					)
					( Status sCSetFlattened )
					( Origin gBackEnd )
				)
				( attribute "RELATIVE_PROPAGATION_DELAY" "-50.00 MIL,50.00 MIL"
					( Parent
						( matchGroupRef "@baseboard_fab2_lib.baseboard_fab2(sch_1):\MG_DQ_NEAR_DIMM_NG_M_C_BYTE-ECC\" )
					)
					( Units "uMatchProp" "ns" 1.000000)
					( Status sCSetFlattened )
					( Origin gBackEnd )
				)
			)
			( pinPair "@baseboard_fab2_lib.baseboard_fab2(sch_1):\PP4920\"
				( pinRef "@baseboard_fab2_lib.baseboard_fab2(sch_1):page25_i172:DDR2_ECC(7)" )
				( pinRef "@baseboard_fab2_lib.baseboard_fab2(sch_1):page47_i111:CB(6)" )
				( attribute "RELATIVE_PROPAGATION_DELAY_SCOPE" "G"
					( Parent
						( matchGroupRef "@baseboard_fab2_lib.baseboard_fab2(sch_1):\MG_DQ-DQS_FAR_DIMM_NG_M_C_BYTE-ECC\" )
					)
					( Status sCSetFlattened )
					( Origin gBackEnd )
				)
				( attribute "RELATIVE_PROPAGATION_DELAY" "0.00 MIL,195.00 MIL"
					( Parent
						( matchGroupRef "@baseboard_fab2_lib.baseboard_fab2(sch_1):\MG_DQ-DQS_FAR_DIMM_NG_M_C_BYTE-ECC\" )
					)
					( Units "uMatchProp" "ns" 1.000000)
					( Status sCSetFlattened )
					( Origin gBackEnd )
				)
				( attribute "RELATIVE_PROPAGATION_DELAY_SCOPE" "G"
					( Parent
						( matchGroupRef "@baseboard_fab2_lib.baseboard_fab2(sch_1):\MG_DQ_FAR_DIMM_NG_M_C_BYTE-ECC\" )
					)
					( Status sCSetFlattened )
					( Origin gBackEnd )
				)
				( attribute "RELATIVE_PROPAGATION_DELAY" "-50.00 MIL,50.00 MIL"
					( Parent
						( matchGroupRef "@baseboard_fab2_lib.baseboard_fab2(sch_1):\MG_DQ_FAR_DIMM_NG_M_C_BYTE-ECC\" )
					)
					( Units "uMatchProp" "ns" 1.000000)
					( Status sCSetFlattened )
					( Origin gBackEnd )
				)
			)
			( pinPair "@baseboard_fab2_lib.baseboard_fab2(sch_1):\PP4922\"
				( pinRef "@baseboard_fab2_lib.baseboard_fab2(sch_1):page25_i172:DDR2_ECC(7)" )
				( pinRef "@baseboard_fab2_lib.baseboard_fab2(sch_1):page48_i111:CB(7)" )
				( attribute "RELATIVE_PROPAGATION_DELAY_SCOPE" "G"
					( Parent
						( matchGroupRef "@baseboard_fab2_lib.baseboard_fab2(sch_1):\MG_DQ-DQS_NEAR_DIMM_NG_M_C_BYTE-ECC\" )
					)
					( Status sCSetFlattened )
					( Origin gBackEnd )
				)
				( attribute "RELATIVE_PROPAGATION_DELAY" "0.00 MIL,195.00 MIL"
					( Parent
						( matchGroupRef "@baseboard_fab2_lib.baseboard_fab2(sch_1):\MG_DQ-DQS_NEAR_DIMM_NG_M_C_BYTE-ECC\" )
					)
					( Units "uMatchProp" "ns" 1.000000)
					( Status sCSetFlattened )
					( Origin gBackEnd )
				)
				( attribute "RELATIVE_PROPAGATION_DELAY_SCOPE" "G"
					( Parent
						( matchGroupRef "@baseboard_fab2_lib.baseboard_fab2(sch_1):\MG_DQ_NEAR_DIMM_NG_M_C_BYTE-ECC\" )
					)
					( Status sCSetFlattened )
					( Origin gBackEnd )
				)
				( attribute "RELATIVE_PROPAGATION_DELAY" "-50.00 MIL,50.00 MIL"
					( Parent
						( matchGroupRef "@baseboard_fab2_lib.baseboard_fab2(sch_1):\MG_DQ_NEAR_DIMM_NG_M_C_BYTE-ECC\" )
					)
					( Units "uMatchProp" "ns" 1.000000)
					( Status sCSetFlattened )
					( Origin gBackEnd )
				)
			)
			( pinPair "@baseboard_fab2_lib.baseboard_fab2(sch_1):\PP4491\"
				( pinRef "@baseboard_fab2_lib.baseboard_fab2(sch_1):page26_i172:DDR3_ECC(0)" )
				( pinRef "@baseboard_fab2_lib.baseboard_fab2(sch_1):page49_i111:CB(1)" )
				( attribute "RELATIVE_PROPAGATION_DELAY_SCOPE" "G"
					( Parent
						( matchGroupRef "@baseboard_fab2_lib.baseboard_fab2(sch_1):\MG_DQ-DQS_FAR_DIMM_NG_M_D_BYTE-ECC\" )
					)
					( Status sCSetFlattened )
					( Origin gBackEnd )
				)
				( attribute "RELATIVE_PROPAGATION_DELAY" "0.00 MIL,195.00 MIL"
					( Parent
						( matchGroupRef "@baseboard_fab2_lib.baseboard_fab2(sch_1):\MG_DQ-DQS_FAR_DIMM_NG_M_D_BYTE-ECC\" )
					)
					( Units "uMatchProp" "ns" 1.000000)
					( Status sCSetFlattened )
					( Origin gBackEnd )
				)
				( attribute "RELATIVE_PROPAGATION_DELAY_SCOPE" "G"
					( Parent
						( matchGroupRef "@baseboard_fab2_lib.baseboard_fab2(sch_1):\MG_DQ_FAR_DIMM_NG_M_D_BYTE-ECC\" )
					)
					( Status sCSetFlattened )
					( Origin gBackEnd )
				)
				( attribute "RELATIVE_PROPAGATION_DELAY" "-50.00 MIL,50.00 MIL"
					( Parent
						( matchGroupRef "@baseboard_fab2_lib.baseboard_fab2(sch_1):\MG_DQ_FAR_DIMM_NG_M_D_BYTE-ECC\" )
					)
					( Units "uMatchProp" "ns" 1.000000)
					( Status sCSetFlattened )
					( Origin gBackEnd )
				)
			)
			( pinPair "@baseboard_fab2_lib.baseboard_fab2(sch_1):\PP4493\"
				( pinRef "@baseboard_fab2_lib.baseboard_fab2(sch_1):page50_i158:CB(0)" )
				( pinRef "@baseboard_fab2_lib.baseboard_fab2(sch_1):page26_i172:DDR3_ECC(0)" )
				( attribute "RELATIVE_PROPAGATION_DELAY_SCOPE" "G"
					( Parent
						( matchGroupRef "@baseboard_fab2_lib.baseboard_fab2(sch_1):\MG_DQ-DQS_NEAR_DIMM_NG_M_D_BYTE-ECC\" )
					)
					( Status sCSetFlattened )
					( Origin gBackEnd )
				)
				( attribute "RELATIVE_PROPAGATION_DELAY" "0.00 MIL,195.00 MIL"
					( Parent
						( matchGroupRef "@baseboard_fab2_lib.baseboard_fab2(sch_1):\MG_DQ-DQS_NEAR_DIMM_NG_M_D_BYTE-ECC\" )
					)
					( Units "uMatchProp" "ns" 1.000000)
					( Status sCSetFlattened )
					( Origin gBackEnd )
				)
				( attribute "RELATIVE_PROPAGATION_DELAY_SCOPE" "G"
					( Parent
						( matchGroupRef "@baseboard_fab2_lib.baseboard_fab2(sch_1):\MG_DQ_NEAR_DIMM_NG_M_D_BYTE-ECC\" )
					)
					( Status sCSetFlattened )
					( Origin gBackEnd )
				)
				( attribute "RELATIVE_PROPAGATION_DELAY" "-50.00 MIL,50.00 MIL"
					( Parent
						( matchGroupRef "@baseboard_fab2_lib.baseboard_fab2(sch_1):\MG_DQ_NEAR_DIMM_NG_M_D_BYTE-ECC\" )
					)
					( Units "uMatchProp" "ns" 1.000000)
					( Status sCSetFlattened )
					( Origin gBackEnd )
				)
			)
			( pinPair "@baseboard_fab2_lib.baseboard_fab2(sch_1):\PP4494\"
				( pinRef "@baseboard_fab2_lib.baseboard_fab2(sch_1):page26_i172:DDR3_ECC(1)" )
				( pinRef "@baseboard_fab2_lib.baseboard_fab2(sch_1):page49_i111:CB(0)" )
				( attribute "RELATIVE_PROPAGATION_DELAY_SCOPE" "G"
					( Parent
						( matchGroupRef "@baseboard_fab2_lib.baseboard_fab2(sch_1):\MG_DQ-DQS_FAR_DIMM_NG_M_D_BYTE-ECC\" )
					)
					( Status sCSetFlattened )
					( Origin gBackEnd )
				)
				( attribute "RELATIVE_PROPAGATION_DELAY" "0.00 MIL,195.00 MIL"
					( Parent
						( matchGroupRef "@baseboard_fab2_lib.baseboard_fab2(sch_1):\MG_DQ-DQS_FAR_DIMM_NG_M_D_BYTE-ECC\" )
					)
					( Units "uMatchProp" "ns" 1.000000)
					( Status sCSetFlattened )
					( Origin gBackEnd )
				)
				( attribute "RELATIVE_PROPAGATION_DELAY_SCOPE" "G"
					( Parent
						( matchGroupRef "@baseboard_fab2_lib.baseboard_fab2(sch_1):\MG_DQ_FAR_DIMM_NG_M_D_BYTE-ECC\" )
					)
					( Status sCSetFlattened )
					( Origin gBackEnd )
				)
				( attribute "RELATIVE_PROPAGATION_DELAY" "-50.00 MIL,50.00 MIL"
					( Parent
						( matchGroupRef "@baseboard_fab2_lib.baseboard_fab2(sch_1):\MG_DQ_FAR_DIMM_NG_M_D_BYTE-ECC\" )
					)
					( Units "uMatchProp" "ns" 1.000000)
					( Status sCSetFlattened )
					( Origin gBackEnd )
				)
			)
			( pinPair "@baseboard_fab2_lib.baseboard_fab2(sch_1):\PP4496\"
				( pinRef "@baseboard_fab2_lib.baseboard_fab2(sch_1):page50_i158:CB(1)" )
				( pinRef "@baseboard_fab2_lib.baseboard_fab2(sch_1):page26_i172:DDR3_ECC(1)" )
				( attribute "RELATIVE_PROPAGATION_DELAY_SCOPE" "G"
					( Parent
						( matchGroupRef "@baseboard_fab2_lib.baseboard_fab2(sch_1):\MG_DQ-DQS_NEAR_DIMM_NG_M_D_BYTE-ECC\" )
					)
					( Status sCSetFlattened )
					( Origin gBackEnd )
				)
				( attribute "RELATIVE_PROPAGATION_DELAY" "0.00 MIL,195.00 MIL"
					( Parent
						( matchGroupRef "@baseboard_fab2_lib.baseboard_fab2(sch_1):\MG_DQ-DQS_NEAR_DIMM_NG_M_D_BYTE-ECC\" )
					)
					( Units "uMatchProp" "ns" 1.000000)
					( Status sCSetFlattened )
					( Origin gBackEnd )
				)
				( attribute "RELATIVE_PROPAGATION_DELAY_SCOPE" "G"
					( Parent
						( matchGroupRef "@baseboard_fab2_lib.baseboard_fab2(sch_1):\MG_DQ_NEAR_DIMM_NG_M_D_BYTE-ECC\" )
					)
					( Status sCSetFlattened )
					( Origin gBackEnd )
				)
				( attribute "RELATIVE_PROPAGATION_DELAY" "-50.00 MIL,50.00 MIL"
					( Parent
						( matchGroupRef "@baseboard_fab2_lib.baseboard_fab2(sch_1):\MG_DQ_NEAR_DIMM_NG_M_D_BYTE-ECC\" )
					)
					( Units "uMatchProp" "ns" 1.000000)
					( Status sCSetFlattened )
					( Origin gBackEnd )
				)
			)
			( pinPair "@baseboard_fab2_lib.baseboard_fab2(sch_1):\PP4497\"
				( pinRef "@baseboard_fab2_lib.baseboard_fab2(sch_1):page26_i172:DDR3_ECC(2)" )
				( pinRef "@baseboard_fab2_lib.baseboard_fab2(sch_1):page49_i111:CB(3)" )
				( attribute "RELATIVE_PROPAGATION_DELAY_SCOPE" "G"
					( Parent
						( matchGroupRef "@baseboard_fab2_lib.baseboard_fab2(sch_1):\MG_DQ-DQS_FAR_DIMM_NG_M_D_BYTE-ECC\" )
					)
					( Status sCSetFlattened )
					( Origin gBackEnd )
				)
				( attribute "RELATIVE_PROPAGATION_DELAY" "0.00 MIL,195.00 MIL"
					( Parent
						( matchGroupRef "@baseboard_fab2_lib.baseboard_fab2(sch_1):\MG_DQ-DQS_FAR_DIMM_NG_M_D_BYTE-ECC\" )
					)
					( Units "uMatchProp" "ns" 1.000000)
					( Status sCSetFlattened )
					( Origin gBackEnd )
				)
				( attribute "RELATIVE_PROPAGATION_DELAY_SCOPE" "G"
					( Parent
						( matchGroupRef "@baseboard_fab2_lib.baseboard_fab2(sch_1):\MG_DQ_FAR_DIMM_NG_M_D_BYTE-ECC\" )
					)
					( Status sCSetFlattened )
					( Origin gBackEnd )
				)
				( attribute "RELATIVE_PROPAGATION_DELAY" "-50.00 MIL,50.00 MIL"
					( Parent
						( matchGroupRef "@baseboard_fab2_lib.baseboard_fab2(sch_1):\MG_DQ_FAR_DIMM_NG_M_D_BYTE-ECC\" )
					)
					( Units "uMatchProp" "ns" 1.000000)
					( Status sCSetFlattened )
					( Origin gBackEnd )
				)
			)
			( pinPair "@baseboard_fab2_lib.baseboard_fab2(sch_1):\PP4499\"
				( pinRef "@baseboard_fab2_lib.baseboard_fab2(sch_1):page50_i158:CB(2)" )
				( pinRef "@baseboard_fab2_lib.baseboard_fab2(sch_1):page26_i172:DDR3_ECC(2)" )
				( attribute "RELATIVE_PROPAGATION_DELAY_SCOPE" "G"
					( Parent
						( matchGroupRef "@baseboard_fab2_lib.baseboard_fab2(sch_1):\MG_DQ-DQS_NEAR_DIMM_NG_M_D_BYTE-ECC\" )
					)
					( Status sCSetFlattened )
					( Origin gBackEnd )
				)
				( attribute "RELATIVE_PROPAGATION_DELAY" "0.00 MIL,195.00 MIL"
					( Parent
						( matchGroupRef "@baseboard_fab2_lib.baseboard_fab2(sch_1):\MG_DQ-DQS_NEAR_DIMM_NG_M_D_BYTE-ECC\" )
					)
					( Units "uMatchProp" "ns" 1.000000)
					( Status sCSetFlattened )
					( Origin gBackEnd )
				)
				( attribute "RELATIVE_PROPAGATION_DELAY_SCOPE" "G"
					( Parent
						( matchGroupRef "@baseboard_fab2_lib.baseboard_fab2(sch_1):\MG_DQ_NEAR_DIMM_NG_M_D_BYTE-ECC\" )
					)
					( Status sCSetFlattened )
					( Origin gBackEnd )
				)
				( attribute "RELATIVE_PROPAGATION_DELAY" "-50.00 MIL,50.00 MIL"
					( Parent
						( matchGroupRef "@baseboard_fab2_lib.baseboard_fab2(sch_1):\MG_DQ_NEAR_DIMM_NG_M_D_BYTE-ECC\" )
					)
					( Units "uMatchProp" "ns" 1.000000)
					( Status sCSetFlattened )
					( Origin gBackEnd )
				)
			)
			( pinPair "@baseboard_fab2_lib.baseboard_fab2(sch_1):\PP4500\"
				( pinRef "@baseboard_fab2_lib.baseboard_fab2(sch_1):page26_i172:DDR3_ECC(3)" )
				( pinRef "@baseboard_fab2_lib.baseboard_fab2(sch_1):page49_i111:CB(2)" )
				( attribute "RELATIVE_PROPAGATION_DELAY_SCOPE" "G"
					( Parent
						( matchGroupRef "@baseboard_fab2_lib.baseboard_fab2(sch_1):\MG_DQ-DQS_FAR_DIMM_NG_M_D_BYTE-ECC\" )
					)
					( Status sCSetFlattened )
					( Origin gBackEnd )
				)
				( attribute "RELATIVE_PROPAGATION_DELAY" "0.00 MIL,195.00 MIL"
					( Parent
						( matchGroupRef "@baseboard_fab2_lib.baseboard_fab2(sch_1):\MG_DQ-DQS_FAR_DIMM_NG_M_D_BYTE-ECC\" )
					)
					( Units "uMatchProp" "ns" 1.000000)
					( Status sCSetFlattened )
					( Origin gBackEnd )
				)
				( attribute "RELATIVE_PROPAGATION_DELAY_SCOPE" "G"
					( Parent
						( matchGroupRef "@baseboard_fab2_lib.baseboard_fab2(sch_1):\MG_DQ_FAR_DIMM_NG_M_D_BYTE-ECC\" )
					)
					( Status sCSetFlattened )
					( Origin gBackEnd )
				)
				( attribute "RELATIVE_PROPAGATION_DELAY" "-50.00 MIL,50.00 MIL"
					( Parent
						( matchGroupRef "@baseboard_fab2_lib.baseboard_fab2(sch_1):\MG_DQ_FAR_DIMM_NG_M_D_BYTE-ECC\" )
					)
					( Units "uMatchProp" "ns" 1.000000)
					( Status sCSetFlattened )
					( Origin gBackEnd )
				)
			)
			( pinPair "@baseboard_fab2_lib.baseboard_fab2(sch_1):\PP4502\"
				( pinRef "@baseboard_fab2_lib.baseboard_fab2(sch_1):page50_i158:CB(3)" )
				( pinRef "@baseboard_fab2_lib.baseboard_fab2(sch_1):page26_i172:DDR3_ECC(3)" )
				( attribute "RELATIVE_PROPAGATION_DELAY_SCOPE" "G"
					( Parent
						( matchGroupRef "@baseboard_fab2_lib.baseboard_fab2(sch_1):\MG_DQ-DQS_NEAR_DIMM_NG_M_D_BYTE-ECC\" )
					)
					( Status sCSetFlattened )
					( Origin gBackEnd )
				)
				( attribute "RELATIVE_PROPAGATION_DELAY" "0.00 MIL,195.00 MIL"
					( Parent
						( matchGroupRef "@baseboard_fab2_lib.baseboard_fab2(sch_1):\MG_DQ-DQS_NEAR_DIMM_NG_M_D_BYTE-ECC\" )
					)
					( Units "uMatchProp" "ns" 1.000000)
					( Status sCSetFlattened )
					( Origin gBackEnd )
				)
				( attribute "RELATIVE_PROPAGATION_DELAY_SCOPE" "G"
					( Parent
						( matchGroupRef "@baseboard_fab2_lib.baseboard_fab2(sch_1):\MG_DQ_NEAR_DIMM_NG_M_D_BYTE-ECC\" )
					)
					( Status sCSetFlattened )
					( Origin gBackEnd )
				)
				( attribute "RELATIVE_PROPAGATION_DELAY" "-50.00 MIL,50.00 MIL"
					( Parent
						( matchGroupRef "@baseboard_fab2_lib.baseboard_fab2(sch_1):\MG_DQ_NEAR_DIMM_NG_M_D_BYTE-ECC\" )
					)
					( Units "uMatchProp" "ns" 1.000000)
					( Status sCSetFlattened )
					( Origin gBackEnd )
				)
			)
			( pinPair "@baseboard_fab2_lib.baseboard_fab2(sch_1):\PP4503\"
				( pinRef "@baseboard_fab2_lib.baseboard_fab2(sch_1):page26_i172:DDR3_ECC(4)" )
				( pinRef "@baseboard_fab2_lib.baseboard_fab2(sch_1):page49_i111:CB(5)" )
				( attribute "RELATIVE_PROPAGATION_DELAY_SCOPE" "G"
					( Parent
						( matchGroupRef "@baseboard_fab2_lib.baseboard_fab2(sch_1):\MG_DQ-DQS_FAR_DIMM_NG_M_D_BYTE-ECC\" )
					)
					( Status sCSetFlattened )
					( Origin gBackEnd )
				)
				( attribute "RELATIVE_PROPAGATION_DELAY" "0.00 MIL,195.00 MIL"
					( Parent
						( matchGroupRef "@baseboard_fab2_lib.baseboard_fab2(sch_1):\MG_DQ-DQS_FAR_DIMM_NG_M_D_BYTE-ECC\" )
					)
					( Units "uMatchProp" "ns" 1.000000)
					( Status sCSetFlattened )
					( Origin gBackEnd )
				)
				( attribute "RELATIVE_PROPAGATION_DELAY_SCOPE" "G"
					( Parent
						( matchGroupRef "@baseboard_fab2_lib.baseboard_fab2(sch_1):\MG_DQ_FAR_DIMM_NG_M_D_BYTE-ECC\" )
					)
					( Status sCSetFlattened )
					( Origin gBackEnd )
				)
				( attribute "RELATIVE_PROPAGATION_DELAY" "-50.00 MIL,50.00 MIL"
					( Parent
						( matchGroupRef "@baseboard_fab2_lib.baseboard_fab2(sch_1):\MG_DQ_FAR_DIMM_NG_M_D_BYTE-ECC\" )
					)
					( Units "uMatchProp" "ns" 1.000000)
					( Status sCSetFlattened )
					( Origin gBackEnd )
				)
			)
			( pinPair "@baseboard_fab2_lib.baseboard_fab2(sch_1):\PP4505\"
				( pinRef "@baseboard_fab2_lib.baseboard_fab2(sch_1):page50_i158:CB(4)" )
				( pinRef "@baseboard_fab2_lib.baseboard_fab2(sch_1):page26_i172:DDR3_ECC(4)" )
				( attribute "RELATIVE_PROPAGATION_DELAY_SCOPE" "G"
					( Parent
						( matchGroupRef "@baseboard_fab2_lib.baseboard_fab2(sch_1):\MG_DQ-DQS_NEAR_DIMM_NG_M_D_BYTE-ECC\" )
					)
					( Status sCSetFlattened )
					( Origin gBackEnd )
				)
				( attribute "RELATIVE_PROPAGATION_DELAY" "0.00 MIL,195.00 MIL"
					( Parent
						( matchGroupRef "@baseboard_fab2_lib.baseboard_fab2(sch_1):\MG_DQ-DQS_NEAR_DIMM_NG_M_D_BYTE-ECC\" )
					)
					( Units "uMatchProp" "ns" 1.000000)
					( Status sCSetFlattened )
					( Origin gBackEnd )
				)
				( attribute "RELATIVE_PROPAGATION_DELAY_SCOPE" "G"
					( Parent
						( matchGroupRef "@baseboard_fab2_lib.baseboard_fab2(sch_1):\MG_DQ_NEAR_DIMM_NG_M_D_BYTE-ECC\" )
					)
					( Status sCSetFlattened )
					( Origin gBackEnd )
				)
				( attribute "RELATIVE_PROPAGATION_DELAY" "-50.00 MIL,50.00 MIL"
					( Parent
						( matchGroupRef "@baseboard_fab2_lib.baseboard_fab2(sch_1):\MG_DQ_NEAR_DIMM_NG_M_D_BYTE-ECC\" )
					)
					( Units "uMatchProp" "ns" 1.000000)
					( Status sCSetFlattened )
					( Origin gBackEnd )
				)
			)
			( pinPair "@baseboard_fab2_lib.baseboard_fab2(sch_1):\PP4506\"
				( pinRef "@baseboard_fab2_lib.baseboard_fab2(sch_1):page26_i172:DDR3_ECC(5)" )
				( pinRef "@baseboard_fab2_lib.baseboard_fab2(sch_1):page49_i111:CB(4)" )
				( attribute "RELATIVE_PROPAGATION_DELAY_SCOPE" "G"
					( Parent
						( matchGroupRef "@baseboard_fab2_lib.baseboard_fab2(sch_1):\MG_DQ-DQS_FAR_DIMM_NG_M_D_BYTE-ECC\" )
					)
					( Status sCSetFlattened )
					( Origin gBackEnd )
				)
				( attribute "RELATIVE_PROPAGATION_DELAY" "0.00 MIL,195.00 MIL"
					( Parent
						( matchGroupRef "@baseboard_fab2_lib.baseboard_fab2(sch_1):\MG_DQ-DQS_FAR_DIMM_NG_M_D_BYTE-ECC\" )
					)
					( Units "uMatchProp" "ns" 1.000000)
					( Status sCSetFlattened )
					( Origin gBackEnd )
				)
				( attribute "RELATIVE_PROPAGATION_DELAY_SCOPE" "G"
					( Parent
						( matchGroupRef "@baseboard_fab2_lib.baseboard_fab2(sch_1):\MG_DQ_FAR_DIMM_NG_M_D_BYTE-ECC\" )
					)
					( Status sCSetFlattened )
					( Origin gBackEnd )
				)
				( attribute "RELATIVE_PROPAGATION_DELAY" "-50.00 MIL,50.00 MIL"
					( Parent
						( matchGroupRef "@baseboard_fab2_lib.baseboard_fab2(sch_1):\MG_DQ_FAR_DIMM_NG_M_D_BYTE-ECC\" )
					)
					( Units "uMatchProp" "ns" 1.000000)
					( Status sCSetFlattened )
					( Origin gBackEnd )
				)
			)
			( pinPair "@baseboard_fab2_lib.baseboard_fab2(sch_1):\PP4508\"
				( pinRef "@baseboard_fab2_lib.baseboard_fab2(sch_1):page50_i158:CB(5)" )
				( pinRef "@baseboard_fab2_lib.baseboard_fab2(sch_1):page26_i172:DDR3_ECC(5)" )
				( attribute "RELATIVE_PROPAGATION_DELAY_SCOPE" "G"
					( Parent
						( matchGroupRef "@baseboard_fab2_lib.baseboard_fab2(sch_1):\MG_DQ-DQS_NEAR_DIMM_NG_M_D_BYTE-ECC\" )
					)
					( Status sCSetFlattened )
					( Origin gBackEnd )
				)
				( attribute "RELATIVE_PROPAGATION_DELAY" "0.00 MIL,195.00 MIL"
					( Parent
						( matchGroupRef "@baseboard_fab2_lib.baseboard_fab2(sch_1):\MG_DQ-DQS_NEAR_DIMM_NG_M_D_BYTE-ECC\" )
					)
					( Units "uMatchProp" "ns" 1.000000)
					( Status sCSetFlattened )
					( Origin gBackEnd )
				)
				( attribute "RELATIVE_PROPAGATION_DELAY_SCOPE" "G"
					( Parent
						( matchGroupRef "@baseboard_fab2_lib.baseboard_fab2(sch_1):\MG_DQ_NEAR_DIMM_NG_M_D_BYTE-ECC\" )
					)
					( Status sCSetFlattened )
					( Origin gBackEnd )
				)
				( attribute "RELATIVE_PROPAGATION_DELAY" "-50.00 MIL,50.00 MIL"
					( Parent
						( matchGroupRef "@baseboard_fab2_lib.baseboard_fab2(sch_1):\MG_DQ_NEAR_DIMM_NG_M_D_BYTE-ECC\" )
					)
					( Units "uMatchProp" "ns" 1.000000)
					( Status sCSetFlattened )
					( Origin gBackEnd )
				)
			)
			( pinPair "@baseboard_fab2_lib.baseboard_fab2(sch_1):\PP4509\"
				( pinRef "@baseboard_fab2_lib.baseboard_fab2(sch_1):page26_i172:DDR3_ECC(6)" )
				( pinRef "@baseboard_fab2_lib.baseboard_fab2(sch_1):page49_i111:CB(7)" )
				( attribute "RELATIVE_PROPAGATION_DELAY_SCOPE" "G"
					( Parent
						( matchGroupRef "@baseboard_fab2_lib.baseboard_fab2(sch_1):\MG_DQ-DQS_FAR_DIMM_NG_M_D_BYTE-ECC\" )
					)
					( Status sCSetFlattened )
					( Origin gBackEnd )
				)
				( attribute "RELATIVE_PROPAGATION_DELAY" "0.00 MIL,195.00 MIL"
					( Parent
						( matchGroupRef "@baseboard_fab2_lib.baseboard_fab2(sch_1):\MG_DQ-DQS_FAR_DIMM_NG_M_D_BYTE-ECC\" )
					)
					( Units "uMatchProp" "ns" 1.000000)
					( Status sCSetFlattened )
					( Origin gBackEnd )
				)
				( attribute "RELATIVE_PROPAGATION_DELAY_SCOPE" "G"
					( Parent
						( matchGroupRef "@baseboard_fab2_lib.baseboard_fab2(sch_1):\MG_DQ_FAR_DIMM_NG_M_D_BYTE-ECC\" )
					)
					( Status sCSetFlattened )
					( Origin gBackEnd )
				)
				( attribute "RELATIVE_PROPAGATION_DELAY" "-50.00 MIL,50.00 MIL"
					( Parent
						( matchGroupRef "@baseboard_fab2_lib.baseboard_fab2(sch_1):\MG_DQ_FAR_DIMM_NG_M_D_BYTE-ECC\" )
					)
					( Units "uMatchProp" "ns" 1.000000)
					( Status sCSetFlattened )
					( Origin gBackEnd )
				)
			)
			( pinPair "@baseboard_fab2_lib.baseboard_fab2(sch_1):\PP4511\"
				( pinRef "@baseboard_fab2_lib.baseboard_fab2(sch_1):page50_i158:CB(6)" )
				( pinRef "@baseboard_fab2_lib.baseboard_fab2(sch_1):page26_i172:DDR3_ECC(6)" )
				( attribute "RELATIVE_PROPAGATION_DELAY_SCOPE" "G"
					( Parent
						( matchGroupRef "@baseboard_fab2_lib.baseboard_fab2(sch_1):\MG_DQ-DQS_NEAR_DIMM_NG_M_D_BYTE-ECC\" )
					)
					( Status sCSetFlattened )
					( Origin gBackEnd )
				)
				( attribute "RELATIVE_PROPAGATION_DELAY" "0.00 MIL,195.00 MIL"
					( Parent
						( matchGroupRef "@baseboard_fab2_lib.baseboard_fab2(sch_1):\MG_DQ-DQS_NEAR_DIMM_NG_M_D_BYTE-ECC\" )
					)
					( Units "uMatchProp" "ns" 1.000000)
					( Status sCSetFlattened )
					( Origin gBackEnd )
				)
				( attribute "RELATIVE_PROPAGATION_DELAY_SCOPE" "G"
					( Parent
						( matchGroupRef "@baseboard_fab2_lib.baseboard_fab2(sch_1):\MG_DQ_NEAR_DIMM_NG_M_D_BYTE-ECC\" )
					)
					( Status sCSetFlattened )
					( Origin gBackEnd )
				)
				( attribute "RELATIVE_PROPAGATION_DELAY" "-50.00 MIL,50.00 MIL"
					( Parent
						( matchGroupRef "@baseboard_fab2_lib.baseboard_fab2(sch_1):\MG_DQ_NEAR_DIMM_NG_M_D_BYTE-ECC\" )
					)
					( Units "uMatchProp" "ns" 1.000000)
					( Status sCSetFlattened )
					( Origin gBackEnd )
				)
			)
			( pinPair "@baseboard_fab2_lib.baseboard_fab2(sch_1):\PP4512\"
				( pinRef "@baseboard_fab2_lib.baseboard_fab2(sch_1):page26_i172:DDR3_ECC(7)" )
				( pinRef "@baseboard_fab2_lib.baseboard_fab2(sch_1):page49_i111:CB(6)" )
				( attribute "RELATIVE_PROPAGATION_DELAY_SCOPE" "G"
					( Parent
						( matchGroupRef "@baseboard_fab2_lib.baseboard_fab2(sch_1):\MG_DQ-DQS_FAR_DIMM_NG_M_D_BYTE-ECC\" )
					)
					( Status sCSetFlattened )
					( Origin gBackEnd )
				)
				( attribute "RELATIVE_PROPAGATION_DELAY" "0.00 MIL,195.00 MIL"
					( Parent
						( matchGroupRef "@baseboard_fab2_lib.baseboard_fab2(sch_1):\MG_DQ-DQS_FAR_DIMM_NG_M_D_BYTE-ECC\" )
					)
					( Units "uMatchProp" "ns" 1.000000)
					( Status sCSetFlattened )
					( Origin gBackEnd )
				)
				( attribute "RELATIVE_PROPAGATION_DELAY_SCOPE" "G"
					( Parent
						( matchGroupRef "@baseboard_fab2_lib.baseboard_fab2(sch_1):\MG_DQ_FAR_DIMM_NG_M_D_BYTE-ECC\" )
					)
					( Status sCSetFlattened )
					( Origin gBackEnd )
				)
				( attribute "RELATIVE_PROPAGATION_DELAY" "-50.00 MIL,50.00 MIL"
					( Parent
						( matchGroupRef "@baseboard_fab2_lib.baseboard_fab2(sch_1):\MG_DQ_FAR_DIMM_NG_M_D_BYTE-ECC\" )
					)
					( Units "uMatchProp" "ns" 1.000000)
					( Status sCSetFlattened )
					( Origin gBackEnd )
				)
			)
			( pinPair "@baseboard_fab2_lib.baseboard_fab2(sch_1):\PP4514\"
				( pinRef "@baseboard_fab2_lib.baseboard_fab2(sch_1):page50_i158:CB(7)" )
				( pinRef "@baseboard_fab2_lib.baseboard_fab2(sch_1):page26_i172:DDR3_ECC(7)" )
				( attribute "RELATIVE_PROPAGATION_DELAY_SCOPE" "G"
					( Parent
						( matchGroupRef "@baseboard_fab2_lib.baseboard_fab2(sch_1):\MG_DQ-DQS_NEAR_DIMM_NG_M_D_BYTE-ECC\" )
					)
					( Status sCSetFlattened )
					( Origin gBackEnd )
				)
				( attribute "RELATIVE_PROPAGATION_DELAY" "0.00 MIL,195.00 MIL"
					( Parent
						( matchGroupRef "@baseboard_fab2_lib.baseboard_fab2(sch_1):\MG_DQ-DQS_NEAR_DIMM_NG_M_D_BYTE-ECC\" )
					)
					( Units "uMatchProp" "ns" 1.000000)
					( Status sCSetFlattened )
					( Origin gBackEnd )
				)
				( attribute "RELATIVE_PROPAGATION_DELAY_SCOPE" "G"
					( Parent
						( matchGroupRef "@baseboard_fab2_lib.baseboard_fab2(sch_1):\MG_DQ_NEAR_DIMM_NG_M_D_BYTE-ECC\" )
					)
					( Status sCSetFlattened )
					( Origin gBackEnd )
				)
				( attribute "RELATIVE_PROPAGATION_DELAY" "-50.00 MIL,50.00 MIL"
					( Parent
						( matchGroupRef "@baseboard_fab2_lib.baseboard_fab2(sch_1):\MG_DQ_NEAR_DIMM_NG_M_D_BYTE-ECC\" )
					)
					( Units "uMatchProp" "ns" 1.000000)
					( Status sCSetFlattened )
					( Origin gBackEnd )
				)
			)
			( pinPair "@baseboard_fab2_lib.baseboard_fab2(sch_1):\PP4275\"
				( pinRef "@baseboard_fab2_lib.baseboard_fab2(sch_1):page27_i172:DDR4_ECC(0)" )
				( pinRef "@baseboard_fab2_lib.baseboard_fab2(sch_1):page51_i111:CB(1)" )
				( attribute "RELATIVE_PROPAGATION_DELAY_SCOPE" "G"
					( Parent
						( matchGroupRef "@baseboard_fab2_lib.baseboard_fab2(sch_1):\MG_DQ-DQS_FAR_DIMM_NG_M_E_BYTE-ECC\" )
					)
					( Status sCSetFlattened )
					( Origin gBackEnd )
				)
				( attribute "RELATIVE_PROPAGATION_DELAY" "0.00 MIL,195.00 MIL"
					( Parent
						( matchGroupRef "@baseboard_fab2_lib.baseboard_fab2(sch_1):\MG_DQ-DQS_FAR_DIMM_NG_M_E_BYTE-ECC\" )
					)
					( Units "uMatchProp" "ns" 1.000000)
					( Status sCSetFlattened )
					( Origin gBackEnd )
				)
				( attribute "RELATIVE_PROPAGATION_DELAY_SCOPE" "G"
					( Parent
						( matchGroupRef "@crescent_city_bb_fab1_lib.crescent_city_bb_fab1(sch_1):\MG_DQ_FAR_DIMM_NG_M_E_BYTE-ECC\" )
					)
					( Origin gBackEnd )
				)
				( attribute "RELATIVE_PROPAGATION_DELAY" "-83.78 MIL,50.00 MIL"
					( Parent
						( matchGroupRef "@crescent_city_bb_fab1_lib.crescent_city_bb_fab1(sch_1):\MG_DQ_FAR_DIMM_NG_M_E_BYTE-ECC\" )
					)
					( Units "uMatchProp" "ns" 1.000000)
					( Origin gBackEnd )
				)
			)
			( pinPair "@baseboard_fab2_lib.baseboard_fab2(sch_1):\PP4277\"
				( pinRef "@baseboard_fab2_lib.baseboard_fab2(sch_1):page27_i172:DDR4_ECC(0)" )
				( pinRef "@baseboard_fab2_lib.baseboard_fab2(sch_1):page52_i12:CB(0)" )
				( attribute "RELATIVE_PROPAGATION_DELAY_SCOPE" "G"
					( Parent
						( matchGroupRef "@baseboard_fab2_lib.baseboard_fab2(sch_1):\MG_DQ-DQS_NEAR_DIMM_NG_M_E_BYTE-ECC\" )
					)
					( Status sCSetFlattened )
					( Origin gBackEnd )
				)
				( attribute "RELATIVE_PROPAGATION_DELAY" "0.00 MIL,195.00 MIL"
					( Parent
						( matchGroupRef "@baseboard_fab2_lib.baseboard_fab2(sch_1):\MG_DQ-DQS_NEAR_DIMM_NG_M_E_BYTE-ECC\" )
					)
					( Units "uMatchProp" "ns" 1.000000)
					( Status sCSetFlattened )
					( Origin gBackEnd )
				)
				( attribute "RELATIVE_PROPAGATION_DELAY_SCOPE" "G"
					( Parent
						( matchGroupRef "@crescent_city_bb_fab1_lib.crescent_city_bb_fab1(sch_1):\MG_DQ_NEAR_DIMM_NG_M_E_BYTE-ECC\" )
					)
					( Origin gBackEnd )
				)
				( attribute "RELATIVE_PROPAGATION_DELAY" "-83.78 MIL,50.00 MIL"
					( Parent
						( matchGroupRef "@crescent_city_bb_fab1_lib.crescent_city_bb_fab1(sch_1):\MG_DQ_NEAR_DIMM_NG_M_E_BYTE-ECC\" )
					)
					( Units "uMatchProp" "ns" 1.000000)
					( Origin gBackEnd )
				)
			)
			( pinPair "@baseboard_fab2_lib.baseboard_fab2(sch_1):\PP4278\"
				( pinRef "@baseboard_fab2_lib.baseboard_fab2(sch_1):page27_i172:DDR4_ECC(1)" )
				( pinRef "@baseboard_fab2_lib.baseboard_fab2(sch_1):page51_i111:CB(0)" )
				( attribute "RELATIVE_PROPAGATION_DELAY_SCOPE" "G"
					( Parent
						( matchGroupRef "@baseboard_fab2_lib.baseboard_fab2(sch_1):\MG_DQ-DQS_FAR_DIMM_NG_M_E_BYTE-ECC\" )
					)
					( Status sCSetFlattened )
					( Origin gBackEnd )
				)
				( attribute "RELATIVE_PROPAGATION_DELAY" "0.00 MIL,195.00 MIL"
					( Parent
						( matchGroupRef "@baseboard_fab2_lib.baseboard_fab2(sch_1):\MG_DQ-DQS_FAR_DIMM_NG_M_E_BYTE-ECC\" )
					)
					( Units "uMatchProp" "ns" 1.000000)
					( Status sCSetFlattened )
					( Origin gBackEnd )
				)
				( attribute "RELATIVE_PROPAGATION_DELAY_SCOPE" "G"
					( Parent
						( matchGroupRef "@crescent_city_bb_fab1_lib.crescent_city_bb_fab1(sch_1):\MG_DQ_FAR_DIMM_NG_M_E_BYTE-ECC\" )
					)
					( Origin gBackEnd )
				)
				( attribute "RELATIVE_PROPAGATION_DELAY" "-82.30 MIL,50.00 MIL"
					( Parent
						( matchGroupRef "@crescent_city_bb_fab1_lib.crescent_city_bb_fab1(sch_1):\MG_DQ_FAR_DIMM_NG_M_E_BYTE-ECC\" )
					)
					( Units "uMatchProp" "ns" 1.000000)
					( Origin gBackEnd )
				)
			)
			( pinPair "@baseboard_fab2_lib.baseboard_fab2(sch_1):\PP4280\"
				( pinRef "@baseboard_fab2_lib.baseboard_fab2(sch_1):page27_i172:DDR4_ECC(1)" )
				( pinRef "@baseboard_fab2_lib.baseboard_fab2(sch_1):page52_i12:CB(1)" )
				( attribute "RELATIVE_PROPAGATION_DELAY_SCOPE" "G"
					( Parent
						( matchGroupRef "@baseboard_fab2_lib.baseboard_fab2(sch_1):\MG_DQ-DQS_NEAR_DIMM_NG_M_E_BYTE-ECC\" )
					)
					( Status sCSetFlattened )
					( Origin gBackEnd )
				)
				( attribute "RELATIVE_PROPAGATION_DELAY" "0.00 MIL,195.00 MIL"
					( Parent
						( matchGroupRef "@baseboard_fab2_lib.baseboard_fab2(sch_1):\MG_DQ-DQS_NEAR_DIMM_NG_M_E_BYTE-ECC\" )
					)
					( Units "uMatchProp" "ns" 1.000000)
					( Status sCSetFlattened )
					( Origin gBackEnd )
				)
				( attribute "RELATIVE_PROPAGATION_DELAY_SCOPE" "G"
					( Parent
						( matchGroupRef "@crescent_city_bb_fab1_lib.crescent_city_bb_fab1(sch_1):\MG_DQ_NEAR_DIMM_NG_M_E_BYTE-ECC\" )
					)
					( Origin gBackEnd )
				)
				( attribute "RELATIVE_PROPAGATION_DELAY" "-82.30 MIL,50.00 MIL"
					( Parent
						( matchGroupRef "@crescent_city_bb_fab1_lib.crescent_city_bb_fab1(sch_1):\MG_DQ_NEAR_DIMM_NG_M_E_BYTE-ECC\" )
					)
					( Units "uMatchProp" "ns" 1.000000)
					( Origin gBackEnd )
				)
			)
			( pinPair "@baseboard_fab2_lib.baseboard_fab2(sch_1):\PP4281\"
				( pinRef "@baseboard_fab2_lib.baseboard_fab2(sch_1):page27_i172:DDR4_ECC(2)" )
				( pinRef "@baseboard_fab2_lib.baseboard_fab2(sch_1):page51_i111:CB(3)" )
				( attribute "RELATIVE_PROPAGATION_DELAY_SCOPE" "G"
					( Parent
						( matchGroupRef "@baseboard_fab2_lib.baseboard_fab2(sch_1):\MG_DQ-DQS_FAR_DIMM_NG_M_E_BYTE-ECC\" )
					)
					( Status sCSetFlattened )
					( Origin gBackEnd )
				)
				( attribute "RELATIVE_PROPAGATION_DELAY" "0.00 MIL,195.00 MIL"
					( Parent
						( matchGroupRef "@baseboard_fab2_lib.baseboard_fab2(sch_1):\MG_DQ-DQS_FAR_DIMM_NG_M_E_BYTE-ECC\" )
					)
					( Units "uMatchProp" "ns" 1.000000)
					( Status sCSetFlattened )
					( Origin gBackEnd )
				)
				( attribute "RELATIVE_PROPAGATION_DELAY_SCOPE" "G"
					( Parent
						( matchGroupRef "@crescent_city_bb_fab1_lib.crescent_city_bb_fab1(sch_1):\MG_DQ_FAR_DIMM_NG_M_E_BYTE-ECC\" )
					)
					( Origin gBackEnd )
				)
				( attribute "RELATIVE_PROPAGATION_DELAY" "-88.70 MIL,50.00 MIL"
					( Parent
						( matchGroupRef "@crescent_city_bb_fab1_lib.crescent_city_bb_fab1(sch_1):\MG_DQ_FAR_DIMM_NG_M_E_BYTE-ECC\" )
					)
					( Units "uMatchProp" "ns" 1.000000)
					( Origin gBackEnd )
				)
			)
			( pinPair "@baseboard_fab2_lib.baseboard_fab2(sch_1):\PP4283\"
				( pinRef "@baseboard_fab2_lib.baseboard_fab2(sch_1):page52_i12:CB(2)" )
				( pinRef "@baseboard_fab2_lib.baseboard_fab2(sch_1):page27_i172:DDR4_ECC(2)" )
				( attribute "RELATIVE_PROPAGATION_DELAY_SCOPE" "G"
					( Parent
						( matchGroupRef "@baseboard_fab2_lib.baseboard_fab2(sch_1):\MG_DQ-DQS_NEAR_DIMM_NG_M_E_BYTE-ECC\" )
					)
					( Status sCSetFlattened )
					( Origin gBackEnd )
				)
				( attribute "RELATIVE_PROPAGATION_DELAY" "0.00 MIL,195.00 MIL"
					( Parent
						( matchGroupRef "@baseboard_fab2_lib.baseboard_fab2(sch_1):\MG_DQ-DQS_NEAR_DIMM_NG_M_E_BYTE-ECC\" )
					)
					( Units "uMatchProp" "ns" 1.000000)
					( Status sCSetFlattened )
					( Origin gBackEnd )
				)
				( attribute "RELATIVE_PROPAGATION_DELAY_SCOPE" "G"
					( Parent
						( matchGroupRef "@crescent_city_bb_fab1_lib.crescent_city_bb_fab1(sch_1):\MG_DQ_NEAR_DIMM_NG_M_E_BYTE-ECC\" )
					)
					( Origin gBackEnd )
				)
				( attribute "RELATIVE_PROPAGATION_DELAY" "-88.70 MIL,50.00 MIL"
					( Parent
						( matchGroupRef "@crescent_city_bb_fab1_lib.crescent_city_bb_fab1(sch_1):\MG_DQ_NEAR_DIMM_NG_M_E_BYTE-ECC\" )
					)
					( Units "uMatchProp" "ns" 1.000000)
					( Origin gBackEnd )
				)
			)
			( pinPair "@baseboard_fab2_lib.baseboard_fab2(sch_1):\PP4284\"
				( pinRef "@baseboard_fab2_lib.baseboard_fab2(sch_1):page27_i172:DDR4_ECC(3)" )
				( pinRef "@baseboard_fab2_lib.baseboard_fab2(sch_1):page51_i111:CB(2)" )
				( attribute "RELATIVE_PROPAGATION_DELAY_SCOPE" "G"
					( Parent
						( matchGroupRef "@baseboard_fab2_lib.baseboard_fab2(sch_1):\MG_DQ-DQS_FAR_DIMM_NG_M_E_BYTE-ECC\" )
					)
					( Status sCSetFlattened )
					( Origin gBackEnd )
				)
				( attribute "RELATIVE_PROPAGATION_DELAY" "0.00 MIL,195.00 MIL"
					( Parent
						( matchGroupRef "@baseboard_fab2_lib.baseboard_fab2(sch_1):\MG_DQ-DQS_FAR_DIMM_NG_M_E_BYTE-ECC\" )
					)
					( Units "uMatchProp" "ns" 1.000000)
					( Status sCSetFlattened )
					( Origin gBackEnd )
				)
				( attribute "RELATIVE_PROPAGATION_DELAY_SCOPE" "G"
					( Parent
						( matchGroupRef "@crescent_city_bb_fab1_lib.crescent_city_bb_fab1(sch_1):\MG_DQ_FAR_DIMM_NG_M_E_BYTE-ECC\" )
					)
					( Origin gBackEnd )
				)
				( attribute "RELATIVE_PROPAGATION_DELAY" "-57.52 MIL,50.00 MIL"
					( Parent
						( matchGroupRef "@crescent_city_bb_fab1_lib.crescent_city_bb_fab1(sch_1):\MG_DQ_FAR_DIMM_NG_M_E_BYTE-ECC\" )
					)
					( Units "uMatchProp" "ns" 1.000000)
					( Origin gBackEnd )
				)
			)
			( pinPair "@baseboard_fab2_lib.baseboard_fab2(sch_1):\PP4286\"
				( pinRef "@baseboard_fab2_lib.baseboard_fab2(sch_1):page52_i12:CB(3)" )
				( pinRef "@baseboard_fab2_lib.baseboard_fab2(sch_1):page27_i172:DDR4_ECC(3)" )
				( attribute "RELATIVE_PROPAGATION_DELAY_SCOPE" "G"
					( Parent
						( matchGroupRef "@baseboard_fab2_lib.baseboard_fab2(sch_1):\MG_DQ-DQS_NEAR_DIMM_NG_M_E_BYTE-ECC\" )
					)
					( Status sCSetFlattened )
					( Origin gBackEnd )
				)
				( attribute "RELATIVE_PROPAGATION_DELAY" "0.00 MIL,195.00 MIL"
					( Parent
						( matchGroupRef "@baseboard_fab2_lib.baseboard_fab2(sch_1):\MG_DQ-DQS_NEAR_DIMM_NG_M_E_BYTE-ECC\" )
					)
					( Units "uMatchProp" "ns" 1.000000)
					( Status sCSetFlattened )
					( Origin gBackEnd )
				)
				( attribute "RELATIVE_PROPAGATION_DELAY_SCOPE" "G"
					( Parent
						( matchGroupRef "@crescent_city_bb_fab1_lib.crescent_city_bb_fab1(sch_1):\MG_DQ_NEAR_DIMM_NG_M_E_BYTE-ECC\" )
					)
					( Origin gBackEnd )
				)
				( attribute "RELATIVE_PROPAGATION_DELAY" "-57.52 MIL,50.00 MIL"
					( Parent
						( matchGroupRef "@crescent_city_bb_fab1_lib.crescent_city_bb_fab1(sch_1):\MG_DQ_NEAR_DIMM_NG_M_E_BYTE-ECC\" )
					)
					( Units "uMatchProp" "ns" 1.000000)
					( Origin gBackEnd )
				)
			)
			( pinPair "@baseboard_fab2_lib.baseboard_fab2(sch_1):\PP4287\"
				( pinRef "@baseboard_fab2_lib.baseboard_fab2(sch_1):page27_i172:DDR4_ECC(4)" )
				( pinRef "@baseboard_fab2_lib.baseboard_fab2(sch_1):page51_i111:CB(5)" )
				( attribute "RELATIVE_PROPAGATION_DELAY_SCOPE" "G"
					( Parent
						( matchGroupRef "@baseboard_fab2_lib.baseboard_fab2(sch_1):\MG_DQ-DQS_FAR_DIMM_NG_M_E_BYTE-ECC\" )
					)
					( Status sCSetFlattened )
					( Origin gBackEnd )
				)
				( attribute "RELATIVE_PROPAGATION_DELAY" "0.00 MIL,195.00 MIL"
					( Parent
						( matchGroupRef "@baseboard_fab2_lib.baseboard_fab2(sch_1):\MG_DQ-DQS_FAR_DIMM_NG_M_E_BYTE-ECC\" )
					)
					( Units "uMatchProp" "ns" 1.000000)
					( Status sCSetFlattened )
					( Origin gBackEnd )
				)
				( attribute "RELATIVE_PROPAGATION_DELAY_SCOPE" "G"
					( Parent
						( matchGroupRef "@crescent_city_bb_fab1_lib.crescent_city_bb_fab1(sch_1):\MG_DQ_FAR_DIMM_NG_M_E_BYTE-ECC\" )
					)
					( Status sCSetFlattened )
					( Origin gBackEnd )
				)
				( attribute "RELATIVE_PROPAGATION_DELAY" "-50.00 MIL,50.00 MIL"
					( Parent
						( matchGroupRef "@crescent_city_bb_fab1_lib.crescent_city_bb_fab1(sch_1):\MG_DQ_FAR_DIMM_NG_M_E_BYTE-ECC\" )
					)
					( Units "uMatchProp" "ns" 1.000000)
					( Status sCSetFlattened )
					( Origin gBackEnd )
				)
			)
			( pinPair "@baseboard_fab2_lib.baseboard_fab2(sch_1):\PP4289\"
				( pinRef "@baseboard_fab2_lib.baseboard_fab2(sch_1):page27_i172:DDR4_ECC(4)" )
				( pinRef "@baseboard_fab2_lib.baseboard_fab2(sch_1):page52_i12:CB(4)" )
				( attribute "RELATIVE_PROPAGATION_DELAY_SCOPE" "G"
					( Parent
						( matchGroupRef "@baseboard_fab2_lib.baseboard_fab2(sch_1):\MG_DQ-DQS_NEAR_DIMM_NG_M_E_BYTE-ECC\" )
					)
					( Status sCSetFlattened )
					( Origin gBackEnd )
				)
				( attribute "RELATIVE_PROPAGATION_DELAY" "0.00 MIL,195.00 MIL"
					( Parent
						( matchGroupRef "@baseboard_fab2_lib.baseboard_fab2(sch_1):\MG_DQ-DQS_NEAR_DIMM_NG_M_E_BYTE-ECC\" )
					)
					( Units "uMatchProp" "ns" 1.000000)
					( Status sCSetFlattened )
					( Origin gBackEnd )
				)
				( attribute "RELATIVE_PROPAGATION_DELAY_SCOPE" "G"
					( Parent
						( matchGroupRef "@crescent_city_bb_fab1_lib.crescent_city_bb_fab1(sch_1):\MG_DQ_NEAR_DIMM_NG_M_E_BYTE-ECC\" )
					)
					( Status sCSetFlattened )
					( Origin gBackEnd )
				)
				( attribute "RELATIVE_PROPAGATION_DELAY" "-50.00 MIL,50.00 MIL"
					( Parent
						( matchGroupRef "@crescent_city_bb_fab1_lib.crescent_city_bb_fab1(sch_1):\MG_DQ_NEAR_DIMM_NG_M_E_BYTE-ECC\" )
					)
					( Units "uMatchProp" "ns" 1.000000)
					( Status sCSetFlattened )
					( Origin gBackEnd )
				)
			)
			( pinPair "@baseboard_fab2_lib.baseboard_fab2(sch_1):\PP4290\"
				( pinRef "@baseboard_fab2_lib.baseboard_fab2(sch_1):page27_i172:DDR4_ECC(5)" )
				( pinRef "@baseboard_fab2_lib.baseboard_fab2(sch_1):page51_i111:CB(4)" )
				( attribute "RELATIVE_PROPAGATION_DELAY_SCOPE" "G"
					( Parent
						( matchGroupRef "@baseboard_fab2_lib.baseboard_fab2(sch_1):\MG_DQ-DQS_FAR_DIMM_NG_M_E_BYTE-ECC\" )
					)
					( Status sCSetFlattened )
					( Origin gBackEnd )
				)
				( attribute "RELATIVE_PROPAGATION_DELAY" "0.00 MIL,195.00 MIL"
					( Parent
						( matchGroupRef "@baseboard_fab2_lib.baseboard_fab2(sch_1):\MG_DQ-DQS_FAR_DIMM_NG_M_E_BYTE-ECC\" )
					)
					( Units "uMatchProp" "ns" 1.000000)
					( Status sCSetFlattened )
					( Origin gBackEnd )
				)
				( attribute "RELATIVE_PROPAGATION_DELAY_SCOPE" "G"
					( Parent
						( matchGroupRef "@crescent_city_bb_fab1_lib.crescent_city_bb_fab1(sch_1):\MG_DQ_FAR_DIMM_NG_M_E_BYTE-ECC\" )
					)
					( Origin gBackEnd )
				)
				( attribute "RELATIVE_PROPAGATION_DELAY" "-75.02 MIL,50.00 MIL"
					( Parent
						( matchGroupRef "@crescent_city_bb_fab1_lib.crescent_city_bb_fab1(sch_1):\MG_DQ_FAR_DIMM_NG_M_E_BYTE-ECC\" )
					)
					( Units "uMatchProp" "ns" 1.000000)
					( Origin gBackEnd )
				)
			)
			( pinPair "@baseboard_fab2_lib.baseboard_fab2(sch_1):\PP4292\"
				( pinRef "@baseboard_fab2_lib.baseboard_fab2(sch_1):page27_i172:DDR4_ECC(5)" )
				( pinRef "@baseboard_fab2_lib.baseboard_fab2(sch_1):page52_i12:CB(5)" )
				( attribute "RELATIVE_PROPAGATION_DELAY_SCOPE" "G"
					( Parent
						( matchGroupRef "@baseboard_fab2_lib.baseboard_fab2(sch_1):\MG_DQ-DQS_NEAR_DIMM_NG_M_E_BYTE-ECC\" )
					)
					( Status sCSetFlattened )
					( Origin gBackEnd )
				)
				( attribute "RELATIVE_PROPAGATION_DELAY" "0.00 MIL,195.00 MIL"
					( Parent
						( matchGroupRef "@baseboard_fab2_lib.baseboard_fab2(sch_1):\MG_DQ-DQS_NEAR_DIMM_NG_M_E_BYTE-ECC\" )
					)
					( Units "uMatchProp" "ns" 1.000000)
					( Status sCSetFlattened )
					( Origin gBackEnd )
				)
				( attribute "RELATIVE_PROPAGATION_DELAY_SCOPE" "G"
					( Parent
						( matchGroupRef "@crescent_city_bb_fab1_lib.crescent_city_bb_fab1(sch_1):\MG_DQ_NEAR_DIMM_NG_M_E_BYTE-ECC\" )
					)
					( Origin gBackEnd )
				)
				( attribute "RELATIVE_PROPAGATION_DELAY" "-75.02 MIL,50.00 MIL"
					( Parent
						( matchGroupRef "@crescent_city_bb_fab1_lib.crescent_city_bb_fab1(sch_1):\MG_DQ_NEAR_DIMM_NG_M_E_BYTE-ECC\" )
					)
					( Units "uMatchProp" "ns" 1.000000)
					( Origin gBackEnd )
				)
			)
			( pinPair "@baseboard_fab2_lib.baseboard_fab2(sch_1):\PP4293\"
				( pinRef "@baseboard_fab2_lib.baseboard_fab2(sch_1):page27_i172:DDR4_ECC(6)" )
				( pinRef "@baseboard_fab2_lib.baseboard_fab2(sch_1):page51_i111:CB(7)" )
				( attribute "RELATIVE_PROPAGATION_DELAY_SCOPE" "G"
					( Parent
						( matchGroupRef "@baseboard_fab2_lib.baseboard_fab2(sch_1):\MG_DQ-DQS_FAR_DIMM_NG_M_E_BYTE-ECC\" )
					)
					( Status sCSetFlattened )
					( Origin gBackEnd )
				)
				( attribute "RELATIVE_PROPAGATION_DELAY" "0.00 MIL,195.00 MIL"
					( Parent
						( matchGroupRef "@baseboard_fab2_lib.baseboard_fab2(sch_1):\MG_DQ-DQS_FAR_DIMM_NG_M_E_BYTE-ECC\" )
					)
					( Units "uMatchProp" "ns" 1.000000)
					( Status sCSetFlattened )
					( Origin gBackEnd )
				)
				( attribute "RELATIVE_PROPAGATION_DELAY_SCOPE" "G"
					( Parent
						( matchGroupRef "@crescent_city_bb_fab1_lib.crescent_city_bb_fab1(sch_1):\MG_DQ_FAR_DIMM_NG_M_E_BYTE-ECC\" )
					)
					( Origin gBackEnd )
				)
				( attribute "RELATIVE_PROPAGATION_DELAY" "-84.73 MIL,50.00 MIL"
					( Parent
						( matchGroupRef "@crescent_city_bb_fab1_lib.crescent_city_bb_fab1(sch_1):\MG_DQ_FAR_DIMM_NG_M_E_BYTE-ECC\" )
					)
					( Units "uMatchProp" "ns" 1.000000)
					( Origin gBackEnd )
				)
			)
			( pinPair "@baseboard_fab2_lib.baseboard_fab2(sch_1):\PP4295\"
				( pinRef "@baseboard_fab2_lib.baseboard_fab2(sch_1):page27_i172:DDR4_ECC(6)" )
				( pinRef "@baseboard_fab2_lib.baseboard_fab2(sch_1):page52_i12:CB(6)" )
				( attribute "RELATIVE_PROPAGATION_DELAY_SCOPE" "G"
					( Parent
						( matchGroupRef "@baseboard_fab2_lib.baseboard_fab2(sch_1):\MG_DQ-DQS_NEAR_DIMM_NG_M_E_BYTE-ECC\" )
					)
					( Status sCSetFlattened )
					( Origin gBackEnd )
				)
				( attribute "RELATIVE_PROPAGATION_DELAY" "0.00 MIL,195.00 MIL"
					( Parent
						( matchGroupRef "@baseboard_fab2_lib.baseboard_fab2(sch_1):\MG_DQ-DQS_NEAR_DIMM_NG_M_E_BYTE-ECC\" )
					)
					( Units "uMatchProp" "ns" 1.000000)
					( Status sCSetFlattened )
					( Origin gBackEnd )
				)
				( attribute "RELATIVE_PROPAGATION_DELAY_SCOPE" "G"
					( Parent
						( matchGroupRef "@crescent_city_bb_fab1_lib.crescent_city_bb_fab1(sch_1):\MG_DQ_NEAR_DIMM_NG_M_E_BYTE-ECC\" )
					)
					( Origin gBackEnd )
				)
				( attribute "RELATIVE_PROPAGATION_DELAY" "-84.73 MIL,50.00 MIL"
					( Parent
						( matchGroupRef "@crescent_city_bb_fab1_lib.crescent_city_bb_fab1(sch_1):\MG_DQ_NEAR_DIMM_NG_M_E_BYTE-ECC\" )
					)
					( Units "uMatchProp" "ns" 1.000000)
					( Origin gBackEnd )
				)
			)
			( pinPair "@baseboard_fab2_lib.baseboard_fab2(sch_1):\PP4296\"
				( pinRef "@baseboard_fab2_lib.baseboard_fab2(sch_1):page27_i172:DDR4_ECC(7)" )
				( pinRef "@baseboard_fab2_lib.baseboard_fab2(sch_1):page51_i111:CB(6)" )
				( attribute "RELATIVE_PROPAGATION_DELAY_SCOPE" "G"
					( Parent
						( matchGroupRef "@baseboard_fab2_lib.baseboard_fab2(sch_1):\MG_DQ-DQS_FAR_DIMM_NG_M_E_BYTE-ECC\" )
					)
					( Status sCSetFlattened )
					( Origin gBackEnd )
				)
				( attribute "RELATIVE_PROPAGATION_DELAY" "0.00 MIL,195.00 MIL"
					( Parent
						( matchGroupRef "@baseboard_fab2_lib.baseboard_fab2(sch_1):\MG_DQ-DQS_FAR_DIMM_NG_M_E_BYTE-ECC\" )
					)
					( Units "uMatchProp" "ns" 1.000000)
					( Status sCSetFlattened )
					( Origin gBackEnd )
				)
				( attribute "RELATIVE_PROPAGATION_DELAY_SCOPE" "G"
					( Parent
						( matchGroupRef "@crescent_city_bb_fab1_lib.crescent_city_bb_fab1(sch_1):\MG_DQ_FAR_DIMM_NG_M_E_BYTE-ECC\" )
					)
					( Origin gBackEnd )
				)
				( attribute "RELATIVE_PROPAGATION_DELAY" "-88.37 MIL,50.00 MIL"
					( Parent
						( matchGroupRef "@crescent_city_bb_fab1_lib.crescent_city_bb_fab1(sch_1):\MG_DQ_FAR_DIMM_NG_M_E_BYTE-ECC\" )
					)
					( Units "uMatchProp" "ns" 1.000000)
					( Origin gBackEnd )
				)
			)
			( pinPair "@baseboard_fab2_lib.baseboard_fab2(sch_1):\PP4298\"
				( pinRef "@baseboard_fab2_lib.baseboard_fab2(sch_1):page52_i12:CB(7)" )
				( pinRef "@baseboard_fab2_lib.baseboard_fab2(sch_1):page27_i172:DDR4_ECC(7)" )
				( attribute "RELATIVE_PROPAGATION_DELAY_SCOPE" "G"
					( Parent
						( matchGroupRef "@baseboard_fab2_lib.baseboard_fab2(sch_1):\MG_DQ-DQS_NEAR_DIMM_NG_M_E_BYTE-ECC\" )
					)
					( Status sCSetFlattened )
					( Origin gBackEnd )
				)
				( attribute "RELATIVE_PROPAGATION_DELAY" "0.00 MIL,195.00 MIL"
					( Parent
						( matchGroupRef "@baseboard_fab2_lib.baseboard_fab2(sch_1):\MG_DQ-DQS_NEAR_DIMM_NG_M_E_BYTE-ECC\" )
					)
					( Units "uMatchProp" "ns" 1.000000)
					( Status sCSetFlattened )
					( Origin gBackEnd )
				)
				( attribute "RELATIVE_PROPAGATION_DELAY_SCOPE" "G"
					( Parent
						( matchGroupRef "@crescent_city_bb_fab1_lib.crescent_city_bb_fab1(sch_1):\MG_DQ_NEAR_DIMM_NG_M_E_BYTE-ECC\" )
					)
					( Origin gBackEnd )
				)
				( attribute "RELATIVE_PROPAGATION_DELAY" "-88.37 MIL,50.00 MIL"
					( Parent
						( matchGroupRef "@crescent_city_bb_fab1_lib.crescent_city_bb_fab1(sch_1):\MG_DQ_NEAR_DIMM_NG_M_E_BYTE-ECC\" )
					)
					( Units "uMatchProp" "ns" 1.000000)
					( Origin gBackEnd )
				)
			)
			( pinPair "@baseboard_fab2_lib.baseboard_fab2(sch_1):\PP4602\"
				( pinRef "@baseboard_fab2_lib.baseboard_fab2(sch_1):page26_i172:DDR3_DQ(37)" )
				( pinRef "@baseboard_fab2_lib.baseboard_fab2(sch_1):page49_i111:DQ(36)" )
				( attribute "RELATIVE_PROPAGATION_DELAY_SCOPE" "G"
					( Parent
						( matchGroupRef "@baseboard_fab2_lib.baseboard_fab2(sch_1):\MG_DQ-DQS_FAR_DIMM_NG_M_D_BYTE4\" )
					)
					( Status sCSetFlattened )
					( Origin gBackEnd )
				)
				( attribute "RELATIVE_PROPAGATION_DELAY" "0.00 MIL,195.00 MIL"
					( Parent
						( matchGroupRef "@baseboard_fab2_lib.baseboard_fab2(sch_1):\MG_DQ-DQS_FAR_DIMM_NG_M_D_BYTE4\" )
					)
					( Units "uMatchProp" "ns" 1.000000)
					( Status sCSetFlattened )
					( Origin gBackEnd )
				)
				( attribute "RELATIVE_PROPAGATION_DELAY_SCOPE" "G"
					( Parent
						( matchGroupRef "@baseboard_fab2_lib.baseboard_fab2(sch_1):\MG_DQ_FAR_DIMM_NG_M_D_BYTE4\" )
					)
					( Status sCSetFlattened )
					( Origin gBackEnd )
				)
				( attribute "RELATIVE_PROPAGATION_DELAY" "-50.00 MIL,50.00 MIL"
					( Parent
						( matchGroupRef "@baseboard_fab2_lib.baseboard_fab2(sch_1):\MG_DQ_FAR_DIMM_NG_M_D_BYTE4\" )
					)
					( Units "uMatchProp" "ns" 1.000000)
					( Status sCSetFlattened )
					( Origin gBackEnd )
				)
			)
			( pinPair "@baseboard_fab2_lib.baseboard_fab2(sch_1):\PP4604\"
				( pinRef "@baseboard_fab2_lib.baseboard_fab2(sch_1):page50_i158:DQ(37)" )
				( pinRef "@baseboard_fab2_lib.baseboard_fab2(sch_1):page26_i172:DDR3_DQ(37)" )
				( attribute "RELATIVE_PROPAGATION_DELAY_SCOPE" "G"
					( Parent
						( matchGroupRef "@baseboard_fab2_lib.baseboard_fab2(sch_1):\MG_DQ-DQS_NEAR_DIMM_NG_M_D_BYTE4\" )
					)
					( Status sCSetFlattened )
					( Origin gBackEnd )
				)
				( attribute "RELATIVE_PROPAGATION_DELAY" "0.00 MIL,195.00 MIL"
					( Parent
						( matchGroupRef "@baseboard_fab2_lib.baseboard_fab2(sch_1):\MG_DQ-DQS_NEAR_DIMM_NG_M_D_BYTE4\" )
					)
					( Units "uMatchProp" "ns" 1.000000)
					( Status sCSetFlattened )
					( Origin gBackEnd )
				)
				( attribute "RELATIVE_PROPAGATION_DELAY_SCOPE" "G"
					( Parent
						( matchGroupRef "@crescent_city_bb_fab1_lib.crescent_city_bb_fab1(sch_1):\MG_DQ_NEAR_DIMM_NG_M_D_BYTE4\" )
					)
					( Status sCSetFlattened )
					( Origin gBackEnd )
				)
				( attribute "RELATIVE_PROPAGATION_DELAY" "-50.00 MIL,50.00 MIL"
					( Parent
						( matchGroupRef "@crescent_city_bb_fab1_lib.crescent_city_bb_fab1(sch_1):\MG_DQ_NEAR_DIMM_NG_M_D_BYTE4\" )
					)
					( Units "uMatchProp" "ns" 1.000000)
					( Status sCSetFlattened )
					( Origin gBackEnd )
				)
			)
			( pinPair "@baseboard_fab2_lib.baseboard_fab2(sch_1):\PP4605\"
				( pinRef "@baseboard_fab2_lib.baseboard_fab2(sch_1):page26_i172:DDR3_DQ(38)" )
				( pinRef "@baseboard_fab2_lib.baseboard_fab2(sch_1):page49_i111:DQ(39)" )
				( attribute "RELATIVE_PROPAGATION_DELAY_SCOPE" "G"
					( Parent
						( matchGroupRef "@baseboard_fab2_lib.baseboard_fab2(sch_1):\MG_DQ-DQS_FAR_DIMM_NG_M_D_BYTE4\" )
					)
					( Status sCSetFlattened )
					( Origin gBackEnd )
				)
				( attribute "RELATIVE_PROPAGATION_DELAY" "0.00 MIL,195.00 MIL"
					( Parent
						( matchGroupRef "@baseboard_fab2_lib.baseboard_fab2(sch_1):\MG_DQ-DQS_FAR_DIMM_NG_M_D_BYTE4\" )
					)
					( Units "uMatchProp" "ns" 1.000000)
					( Status sCSetFlattened )
					( Origin gBackEnd )
				)
				( attribute "RELATIVE_PROPAGATION_DELAY_SCOPE" "G"
					( Parent
						( matchGroupRef "@baseboard_fab2_lib.baseboard_fab2(sch_1):\MG_DQ_FAR_DIMM_NG_M_D_BYTE4\" )
					)
					( Status sCSetFlattened )
					( Origin gBackEnd )
				)
				( attribute "RELATIVE_PROPAGATION_DELAY" "-50.00 MIL,50.00 MIL"
					( Parent
						( matchGroupRef "@baseboard_fab2_lib.baseboard_fab2(sch_1):\MG_DQ_FAR_DIMM_NG_M_D_BYTE4\" )
					)
					( Units "uMatchProp" "ns" 1.000000)
					( Status sCSetFlattened )
					( Origin gBackEnd )
				)
			)
			( pinPair "@baseboard_fab2_lib.baseboard_fab2(sch_1):\PP4607\"
				( pinRef "@baseboard_fab2_lib.baseboard_fab2(sch_1):page26_i172:DDR3_DQ(38)" )
				( pinRef "@baseboard_fab2_lib.baseboard_fab2(sch_1):page50_i158:DQ(38)" )
				( attribute "RELATIVE_PROPAGATION_DELAY_SCOPE" "G"
					( Parent
						( matchGroupRef "@baseboard_fab2_lib.baseboard_fab2(sch_1):\MG_DQ-DQS_NEAR_DIMM_NG_M_D_BYTE4\" )
					)
					( Status sCSetFlattened )
					( Origin gBackEnd )
				)
				( attribute "RELATIVE_PROPAGATION_DELAY" "0.00 MIL,195.00 MIL"
					( Parent
						( matchGroupRef "@baseboard_fab2_lib.baseboard_fab2(sch_1):\MG_DQ-DQS_NEAR_DIMM_NG_M_D_BYTE4\" )
					)
					( Units "uMatchProp" "ns" 1.000000)
					( Status sCSetFlattened )
					( Origin gBackEnd )
				)
				( attribute "RELATIVE_PROPAGATION_DELAY_SCOPE" "G"
					( Parent
						( matchGroupRef "@crescent_city_bb_fab1_lib.crescent_city_bb_fab1(sch_1):\MG_DQ_NEAR_DIMM_NG_M_D_BYTE4\" )
					)
					( Status sCSetFlattened )
					( Origin gBackEnd )
				)
				( attribute "RELATIVE_PROPAGATION_DELAY" "-50.00 MIL,50.00 MIL"
					( Parent
						( matchGroupRef "@crescent_city_bb_fab1_lib.crescent_city_bb_fab1(sch_1):\MG_DQ_NEAR_DIMM_NG_M_D_BYTE4\" )
					)
					( Units "uMatchProp" "ns" 1.000000)
					( Status sCSetFlattened )
					( Origin gBackEnd )
				)
			)
			( pinPair "@baseboard_fab2_lib.baseboard_fab2(sch_1):\PP4608\"
				( pinRef "@baseboard_fab2_lib.baseboard_fab2(sch_1):page26_i172:DDR3_DQ(39)" )
				( pinRef "@baseboard_fab2_lib.baseboard_fab2(sch_1):page49_i111:DQ(38)" )
				( attribute "RELATIVE_PROPAGATION_DELAY_SCOPE" "G"
					( Parent
						( matchGroupRef "@baseboard_fab2_lib.baseboard_fab2(sch_1):\MG_DQ-DQS_FAR_DIMM_NG_M_D_BYTE4\" )
					)
					( Status sCSetFlattened )
					( Origin gBackEnd )
				)
				( attribute "RELATIVE_PROPAGATION_DELAY" "0.00 MIL,195.00 MIL"
					( Parent
						( matchGroupRef "@baseboard_fab2_lib.baseboard_fab2(sch_1):\MG_DQ-DQS_FAR_DIMM_NG_M_D_BYTE4\" )
					)
					( Units "uMatchProp" "ns" 1.000000)
					( Status sCSetFlattened )
					( Origin gBackEnd )
				)
				( attribute "RELATIVE_PROPAGATION_DELAY_SCOPE" "G"
					( Parent
						( matchGroupRef "@baseboard_fab2_lib.baseboard_fab2(sch_1):\MG_DQ_FAR_DIMM_NG_M_D_BYTE4\" )
					)
					( Status sCSetFlattened )
					( Origin gBackEnd )
				)
				( attribute "RELATIVE_PROPAGATION_DELAY" "-50.00 MIL,50.00 MIL"
					( Parent
						( matchGroupRef "@baseboard_fab2_lib.baseboard_fab2(sch_1):\MG_DQ_FAR_DIMM_NG_M_D_BYTE4\" )
					)
					( Units "uMatchProp" "ns" 1.000000)
					( Status sCSetFlattened )
					( Origin gBackEnd )
				)
			)
			( pinPair "@baseboard_fab2_lib.baseboard_fab2(sch_1):\PP4610\"
				( pinRef "@baseboard_fab2_lib.baseboard_fab2(sch_1):page26_i172:DDR3_DQ(39)" )
				( pinRef "@baseboard_fab2_lib.baseboard_fab2(sch_1):page50_i158:DQ(39)" )
				( attribute "RELATIVE_PROPAGATION_DELAY_SCOPE" "G"
					( Parent
						( matchGroupRef "@baseboard_fab2_lib.baseboard_fab2(sch_1):\MG_DQ-DQS_NEAR_DIMM_NG_M_D_BYTE4\" )
					)
					( Status sCSetFlattened )
					( Origin gBackEnd )
				)
				( attribute "RELATIVE_PROPAGATION_DELAY" "0.00 MIL,195.00 MIL"
					( Parent
						( matchGroupRef "@baseboard_fab2_lib.baseboard_fab2(sch_1):\MG_DQ-DQS_NEAR_DIMM_NG_M_D_BYTE4\" )
					)
					( Units "uMatchProp" "ns" 1.000000)
					( Status sCSetFlattened )
					( Origin gBackEnd )
				)
				( attribute "RELATIVE_PROPAGATION_DELAY_SCOPE" "G"
					( Parent
						( matchGroupRef "@crescent_city_bb_fab1_lib.crescent_city_bb_fab1(sch_1):\MG_DQ_NEAR_DIMM_NG_M_D_BYTE4\" )
					)
					( Status sCSetFlattened )
					( Origin gBackEnd )
				)
				( attribute "RELATIVE_PROPAGATION_DELAY" "-50.00 MIL,50.00 MIL"
					( Parent
						( matchGroupRef "@crescent_city_bb_fab1_lib.crescent_city_bb_fab1(sch_1):\MG_DQ_NEAR_DIMM_NG_M_D_BYTE4\" )
					)
					( Units "uMatchProp" "ns" 1.000000)
					( Status sCSetFlattened )
					( Origin gBackEnd )
				)
			)
			( pinPair "@baseboard_fab2_lib.baseboard_fab2(sch_1):\PP4563\"
				( pinRef "@baseboard_fab2_lib.baseboard_fab2(sch_1):page26_i172:DDR3_DQ(40)" )
				( pinRef "@baseboard_fab2_lib.baseboard_fab2(sch_1):page49_i111:DQ(41)" )
				( attribute "RELATIVE_PROPAGATION_DELAY_SCOPE" "G"
					( Parent
						( matchGroupRef "@baseboard_fab2_lib.baseboard_fab2(sch_1):\MG_DQ-DQS_FAR_DIMM_NG_M_D_BYTE5\" )
					)
					( Status sCSetFlattened )
					( Origin gBackEnd )
				)
				( attribute "RELATIVE_PROPAGATION_DELAY" "0.00 MIL,195.00 MIL"
					( Parent
						( matchGroupRef "@baseboard_fab2_lib.baseboard_fab2(sch_1):\MG_DQ-DQS_FAR_DIMM_NG_M_D_BYTE5\" )
					)
					( Units "uMatchProp" "ns" 1.000000)
					( Status sCSetFlattened )
					( Origin gBackEnd )
				)
				( attribute "RELATIVE_PROPAGATION_DELAY_SCOPE" "G"
					( Parent
						( matchGroupRef "@crescent_city_bb_fab1_lib.crescent_city_bb_fab1(sch_1):\MG_DQ_FAR_DIMM_NG_M_D_BYTE5\" )
					)
					( Status sCSetFlattened )
					( Origin gBackEnd )
				)
				( attribute "RELATIVE_PROPAGATION_DELAY" "-50.00 MIL,50.00 MIL"
					( Parent
						( matchGroupRef "@crescent_city_bb_fab1_lib.crescent_city_bb_fab1(sch_1):\MG_DQ_FAR_DIMM_NG_M_D_BYTE5\" )
					)
					( Units "uMatchProp" "ns" 1.000000)
					( Status sCSetFlattened )
					( Origin gBackEnd )
				)
			)
			( pinPair "@baseboard_fab2_lib.baseboard_fab2(sch_1):\PP4565\"
				( pinRef "@baseboard_fab2_lib.baseboard_fab2(sch_1):page26_i172:DDR3_DQ(40)" )
				( pinRef "@baseboard_fab2_lib.baseboard_fab2(sch_1):page50_i158:DQ(40)" )
				( attribute "RELATIVE_PROPAGATION_DELAY_SCOPE" "G"
					( Parent
						( matchGroupRef "@baseboard_fab2_lib.baseboard_fab2(sch_1):\MG_DQ-DQS_NEAR_DIMM_NG_M_D_BYTE5\" )
					)
					( Status sCSetFlattened )
					( Origin gBackEnd )
				)
				( attribute "RELATIVE_PROPAGATION_DELAY" "0.00 MIL,195.00 MIL"
					( Parent
						( matchGroupRef "@baseboard_fab2_lib.baseboard_fab2(sch_1):\MG_DQ-DQS_NEAR_DIMM_NG_M_D_BYTE5\" )
					)
					( Units "uMatchProp" "ns" 1.000000)
					( Status sCSetFlattened )
					( Origin gBackEnd )
				)
				( attribute "RELATIVE_PROPAGATION_DELAY_SCOPE" "G"
					( Parent
						( matchGroupRef "@crescent_city_bb_fab1_lib.crescent_city_bb_fab1(sch_1):\MG_DQ_NEAR_DIMM_NG_M_D_BYTE5\" )
					)
					( Status sCSetFlattened )
					( Origin gBackEnd )
				)
				( attribute "RELATIVE_PROPAGATION_DELAY" "-50.00 MIL,50.00 MIL"
					( Parent
						( matchGroupRef "@crescent_city_bb_fab1_lib.crescent_city_bb_fab1(sch_1):\MG_DQ_NEAR_DIMM_NG_M_D_BYTE5\" )
					)
					( Units "uMatchProp" "ns" 1.000000)
					( Status sCSetFlattened )
					( Origin gBackEnd )
				)
			)
			( pinPair "@baseboard_fab2_lib.baseboard_fab2(sch_1):\PP4566\"
				( pinRef "@baseboard_fab2_lib.baseboard_fab2(sch_1):page26_i172:DDR3_DQ(41)" )
				( pinRef "@baseboard_fab2_lib.baseboard_fab2(sch_1):page49_i111:DQ(40)" )
				( attribute "RELATIVE_PROPAGATION_DELAY_SCOPE" "G"
					( Parent
						( matchGroupRef "@baseboard_fab2_lib.baseboard_fab2(sch_1):\MG_DQ-DQS_FAR_DIMM_NG_M_D_BYTE5\" )
					)
					( Status sCSetFlattened )
					( Origin gBackEnd )
				)
				( attribute "RELATIVE_PROPAGATION_DELAY" "0.00 MIL,195.00 MIL"
					( Parent
						( matchGroupRef "@baseboard_fab2_lib.baseboard_fab2(sch_1):\MG_DQ-DQS_FAR_DIMM_NG_M_D_BYTE5\" )
					)
					( Units "uMatchProp" "ns" 1.000000)
					( Status sCSetFlattened )
					( Origin gBackEnd )
				)
				( attribute "RELATIVE_PROPAGATION_DELAY_SCOPE" "G"
					( Parent
						( matchGroupRef "@crescent_city_bb_fab1_lib.crescent_city_bb_fab1(sch_1):\MG_DQ_FAR_DIMM_NG_M_D_BYTE5\" )
					)
					( Status sCSetFlattened )
					( Origin gBackEnd )
				)
				( attribute "RELATIVE_PROPAGATION_DELAY" "-50.00 MIL,50.00 MIL"
					( Parent
						( matchGroupRef "@crescent_city_bb_fab1_lib.crescent_city_bb_fab1(sch_1):\MG_DQ_FAR_DIMM_NG_M_D_BYTE5\" )
					)
					( Units "uMatchProp" "ns" 1.000000)
					( Status sCSetFlattened )
					( Origin gBackEnd )
				)
			)
			( pinPair "@baseboard_fab2_lib.baseboard_fab2(sch_1):\PP4568\"
				( pinRef "@baseboard_fab2_lib.baseboard_fab2(sch_1):page26_i172:DDR3_DQ(41)" )
				( pinRef "@baseboard_fab2_lib.baseboard_fab2(sch_1):page50_i158:DQ(41)" )
				( attribute "RELATIVE_PROPAGATION_DELAY_SCOPE" "G"
					( Parent
						( matchGroupRef "@baseboard_fab2_lib.baseboard_fab2(sch_1):\MG_DQ-DQS_NEAR_DIMM_NG_M_D_BYTE5\" )
					)
					( Status sCSetFlattened )
					( Origin gBackEnd )
				)
				( attribute "RELATIVE_PROPAGATION_DELAY" "0.00 MIL,195.00 MIL"
					( Parent
						( matchGroupRef "@baseboard_fab2_lib.baseboard_fab2(sch_1):\MG_DQ-DQS_NEAR_DIMM_NG_M_D_BYTE5\" )
					)
					( Units "uMatchProp" "ns" 1.000000)
					( Status sCSetFlattened )
					( Origin gBackEnd )
				)
				( attribute "RELATIVE_PROPAGATION_DELAY_SCOPE" "G"
					( Parent
						( matchGroupRef "@crescent_city_bb_fab1_lib.crescent_city_bb_fab1(sch_1):\MG_DQ_NEAR_DIMM_NG_M_D_BYTE5\" )
					)
					( Origin gBackEnd )
				)
				( attribute "RELATIVE_PROPAGATION_DELAY" "TARGET,TARGET"
					( Parent
						( matchGroupRef "@crescent_city_bb_fab1_lib.crescent_city_bb_fab1(sch_1):\MG_DQ_NEAR_DIMM_NG_M_D_BYTE5\" )
					)
					( Units "uMatchProp" "ns" 1.000000)
					( Origin gBackEnd )
				)
			)
			( pinPair "@baseboard_fab2_lib.baseboard_fab2(sch_1):\PP4569\"
				( pinRef "@baseboard_fab2_lib.baseboard_fab2(sch_1):page26_i172:DDR3_DQ(42)" )
				( pinRef "@baseboard_fab2_lib.baseboard_fab2(sch_1):page49_i111:DQ(43)" )
				( attribute "RELATIVE_PROPAGATION_DELAY_SCOPE" "G"
					( Parent
						( matchGroupRef "@baseboard_fab2_lib.baseboard_fab2(sch_1):\MG_DQ-DQS_FAR_DIMM_NG_M_D_BYTE5\" )
					)
					( Status sCSetFlattened )
					( Origin gBackEnd )
				)
				( attribute "RELATIVE_PROPAGATION_DELAY" "0.00 MIL,195.00 MIL"
					( Parent
						( matchGroupRef "@baseboard_fab2_lib.baseboard_fab2(sch_1):\MG_DQ-DQS_FAR_DIMM_NG_M_D_BYTE5\" )
					)
					( Units "uMatchProp" "ns" 1.000000)
					( Status sCSetFlattened )
					( Origin gBackEnd )
				)
				( attribute "RELATIVE_PROPAGATION_DELAY_SCOPE" "G"
					( Parent
						( matchGroupRef "@crescent_city_bb_fab1_lib.crescent_city_bb_fab1(sch_1):\MG_DQ_FAR_DIMM_NG_M_D_BYTE5\" )
					)
					( Status sCSetFlattened )
					( Origin gBackEnd )
				)
				( attribute "RELATIVE_PROPAGATION_DELAY" "-50.00 MIL,50.00 MIL"
					( Parent
						( matchGroupRef "@crescent_city_bb_fab1_lib.crescent_city_bb_fab1(sch_1):\MG_DQ_FAR_DIMM_NG_M_D_BYTE5\" )
					)
					( Units "uMatchProp" "ns" 1.000000)
					( Status sCSetFlattened )
					( Origin gBackEnd )
				)
			)
			( pinPair "@baseboard_fab2_lib.baseboard_fab2(sch_1):\PP4571\"
				( pinRef "@baseboard_fab2_lib.baseboard_fab2(sch_1):page26_i172:DDR3_DQ(42)" )
				( pinRef "@baseboard_fab2_lib.baseboard_fab2(sch_1):page50_i158:DQ(42)" )
				( attribute "RELATIVE_PROPAGATION_DELAY_SCOPE" "G"
					( Parent
						( matchGroupRef "@baseboard_fab2_lib.baseboard_fab2(sch_1):\MG_DQ-DQS_NEAR_DIMM_NG_M_D_BYTE5\" )
					)
					( Status sCSetFlattened )
					( Origin gBackEnd )
				)
				( attribute "RELATIVE_PROPAGATION_DELAY" "0.00 MIL,195.00 MIL"
					( Parent
						( matchGroupRef "@baseboard_fab2_lib.baseboard_fab2(sch_1):\MG_DQ-DQS_NEAR_DIMM_NG_M_D_BYTE5\" )
					)
					( Units "uMatchProp" "ns" 1.000000)
					( Status sCSetFlattened )
					( Origin gBackEnd )
				)
				( attribute "RELATIVE_PROPAGATION_DELAY_SCOPE" "G"
					( Parent
						( matchGroupRef "@crescent_city_bb_fab1_lib.crescent_city_bb_fab1(sch_1):\MG_DQ_NEAR_DIMM_NG_M_D_BYTE5\" )
					)
					( Status sCSetFlattened )
					( Origin gBackEnd )
				)
				( attribute "RELATIVE_PROPAGATION_DELAY" "-50.00 MIL,50.00 MIL"
					( Parent
						( matchGroupRef "@crescent_city_bb_fab1_lib.crescent_city_bb_fab1(sch_1):\MG_DQ_NEAR_DIMM_NG_M_D_BYTE5\" )
					)
					( Units "uMatchProp" "ns" 1.000000)
					( Status sCSetFlattened )
					( Origin gBackEnd )
				)
			)
			( pinPair "@baseboard_fab2_lib.baseboard_fab2(sch_1):\PP4572\"
				( pinRef "@baseboard_fab2_lib.baseboard_fab2(sch_1):page26_i172:DDR3_DQ(43)" )
				( pinRef "@baseboard_fab2_lib.baseboard_fab2(sch_1):page49_i111:DQ(42)" )
				( attribute "RELATIVE_PROPAGATION_DELAY_SCOPE" "G"
					( Parent
						( matchGroupRef "@baseboard_fab2_lib.baseboard_fab2(sch_1):\MG_DQ-DQS_FAR_DIMM_NG_M_D_BYTE5\" )
					)
					( Status sCSetFlattened )
					( Origin gBackEnd )
				)
				( attribute "RELATIVE_PROPAGATION_DELAY" "0.00 MIL,195.00 MIL"
					( Parent
						( matchGroupRef "@baseboard_fab2_lib.baseboard_fab2(sch_1):\MG_DQ-DQS_FAR_DIMM_NG_M_D_BYTE5\" )
					)
					( Units "uMatchProp" "ns" 1.000000)
					( Status sCSetFlattened )
					( Origin gBackEnd )
				)
				( attribute "RELATIVE_PROPAGATION_DELAY_SCOPE" "G"
					( Parent
						( matchGroupRef "@crescent_city_bb_fab1_lib.crescent_city_bb_fab1(sch_1):\MG_DQ_FAR_DIMM_NG_M_D_BYTE5\" )
					)
					( Status sCSetFlattened )
					( Origin gBackEnd )
				)
				( attribute "RELATIVE_PROPAGATION_DELAY" "-50.00 MIL,50.00 MIL"
					( Parent
						( matchGroupRef "@crescent_city_bb_fab1_lib.crescent_city_bb_fab1(sch_1):\MG_DQ_FAR_DIMM_NG_M_D_BYTE5\" )
					)
					( Units "uMatchProp" "ns" 1.000000)
					( Status sCSetFlattened )
					( Origin gBackEnd )
				)
			)
			( pinPair "@baseboard_fab2_lib.baseboard_fab2(sch_1):\PP4574\"
				( pinRef "@baseboard_fab2_lib.baseboard_fab2(sch_1):page26_i172:DDR3_DQ(43)" )
				( pinRef "@baseboard_fab2_lib.baseboard_fab2(sch_1):page50_i158:DQ(43)" )
				( attribute "RELATIVE_PROPAGATION_DELAY_SCOPE" "G"
					( Parent
						( matchGroupRef "@baseboard_fab2_lib.baseboard_fab2(sch_1):\MG_DQ-DQS_NEAR_DIMM_NG_M_D_BYTE5\" )
					)
					( Status sCSetFlattened )
					( Origin gBackEnd )
				)
				( attribute "RELATIVE_PROPAGATION_DELAY" "0.00 MIL,195.00 MIL"
					( Parent
						( matchGroupRef "@baseboard_fab2_lib.baseboard_fab2(sch_1):\MG_DQ-DQS_NEAR_DIMM_NG_M_D_BYTE5\" )
					)
					( Units "uMatchProp" "ns" 1.000000)
					( Status sCSetFlattened )
					( Origin gBackEnd )
				)
				( attribute "RELATIVE_PROPAGATION_DELAY_SCOPE" "G"
					( Parent
						( matchGroupRef "@crescent_city_bb_fab1_lib.crescent_city_bb_fab1(sch_1):\MG_DQ_NEAR_DIMM_NG_M_D_BYTE5\" )
					)
					( Status sCSetFlattened )
					( Origin gBackEnd )
				)
				( attribute "RELATIVE_PROPAGATION_DELAY" "-50.00 MIL,50.00 MIL"
					( Parent
						( matchGroupRef "@crescent_city_bb_fab1_lib.crescent_city_bb_fab1(sch_1):\MG_DQ_NEAR_DIMM_NG_M_D_BYTE5\" )
					)
					( Units "uMatchProp" "ns" 1.000000)
					( Status sCSetFlattened )
					( Origin gBackEnd )
				)
			)
			( pinPair "@baseboard_fab2_lib.baseboard_fab2(sch_1):\PP4575\"
				( pinRef "@baseboard_fab2_lib.baseboard_fab2(sch_1):page26_i172:DDR3_DQ(44)" )
				( pinRef "@baseboard_fab2_lib.baseboard_fab2(sch_1):page49_i111:DQ(45)" )
				( attribute "RELATIVE_PROPAGATION_DELAY_SCOPE" "G"
					( Parent
						( matchGroupRef "@baseboard_fab2_lib.baseboard_fab2(sch_1):\MG_DQ-DQS_FAR_DIMM_NG_M_D_BYTE5\" )
					)
					( Status sCSetFlattened )
					( Origin gBackEnd )
				)
				( attribute "RELATIVE_PROPAGATION_DELAY" "0.00 MIL,195.00 MIL"
					( Parent
						( matchGroupRef "@baseboard_fab2_lib.baseboard_fab2(sch_1):\MG_DQ-DQS_FAR_DIMM_NG_M_D_BYTE5\" )
					)
					( Units "uMatchProp" "ns" 1.000000)
					( Status sCSetFlattened )
					( Origin gBackEnd )
				)
				( attribute "RELATIVE_PROPAGATION_DELAY_SCOPE" "G"
					( Parent
						( matchGroupRef "@crescent_city_bb_fab1_lib.crescent_city_bb_fab1(sch_1):\MG_DQ_FAR_DIMM_NG_M_D_BYTE5\" )
					)
					( Status sCSetFlattened )
					( Origin gBackEnd )
				)
				( attribute "RELATIVE_PROPAGATION_DELAY" "-50.00 MIL,50.00 MIL"
					( Parent
						( matchGroupRef "@crescent_city_bb_fab1_lib.crescent_city_bb_fab1(sch_1):\MG_DQ_FAR_DIMM_NG_M_D_BYTE5\" )
					)
					( Units "uMatchProp" "ns" 1.000000)
					( Status sCSetFlattened )
					( Origin gBackEnd )
				)
			)
			( pinPair "@baseboard_fab2_lib.baseboard_fab2(sch_1):\PP4577\"
				( pinRef "@baseboard_fab2_lib.baseboard_fab2(sch_1):page26_i172:DDR3_DQ(44)" )
				( pinRef "@baseboard_fab2_lib.baseboard_fab2(sch_1):page50_i158:DQ(44)" )
				( attribute "RELATIVE_PROPAGATION_DELAY_SCOPE" "G"
					( Parent
						( matchGroupRef "@baseboard_fab2_lib.baseboard_fab2(sch_1):\MG_DQ-DQS_NEAR_DIMM_NG_M_D_BYTE5\" )
					)
					( Status sCSetFlattened )
					( Origin gBackEnd )
				)
				( attribute "RELATIVE_PROPAGATION_DELAY" "0.00 MIL,195.00 MIL"
					( Parent
						( matchGroupRef "@baseboard_fab2_lib.baseboard_fab2(sch_1):\MG_DQ-DQS_NEAR_DIMM_NG_M_D_BYTE5\" )
					)
					( Units "uMatchProp" "ns" 1.000000)
					( Status sCSetFlattened )
					( Origin gBackEnd )
				)
				( attribute "RELATIVE_PROPAGATION_DELAY_SCOPE" "G"
					( Parent
						( matchGroupRef "@crescent_city_bb_fab1_lib.crescent_city_bb_fab1(sch_1):\MG_DQ_NEAR_DIMM_NG_M_D_BYTE5\" )
					)
					( Status sCSetFlattened )
					( Origin gBackEnd )
				)
				( attribute "RELATIVE_PROPAGATION_DELAY" "-50.00 MIL,50.00 MIL"
					( Parent
						( matchGroupRef "@crescent_city_bb_fab1_lib.crescent_city_bb_fab1(sch_1):\MG_DQ_NEAR_DIMM_NG_M_D_BYTE5\" )
					)
					( Units "uMatchProp" "ns" 1.000000)
					( Status sCSetFlattened )
					( Origin gBackEnd )
				)
			)
			( pinPair "@baseboard_fab2_lib.baseboard_fab2(sch_1):\PP4578\"
				( pinRef "@baseboard_fab2_lib.baseboard_fab2(sch_1):page26_i172:DDR3_DQ(45)" )
				( pinRef "@baseboard_fab2_lib.baseboard_fab2(sch_1):page49_i111:DQ(44)" )
				( attribute "RELATIVE_PROPAGATION_DELAY_SCOPE" "G"
					( Parent
						( matchGroupRef "@baseboard_fab2_lib.baseboard_fab2(sch_1):\MG_DQ-DQS_FAR_DIMM_NG_M_D_BYTE5\" )
					)
					( Status sCSetFlattened )
					( Origin gBackEnd )
				)
				( attribute "RELATIVE_PROPAGATION_DELAY" "0.00 MIL,195.00 MIL"
					( Parent
						( matchGroupRef "@baseboard_fab2_lib.baseboard_fab2(sch_1):\MG_DQ-DQS_FAR_DIMM_NG_M_D_BYTE5\" )
					)
					( Units "uMatchProp" "ns" 1.000000)
					( Status sCSetFlattened )
					( Origin gBackEnd )
				)
				( attribute "RELATIVE_PROPAGATION_DELAY_SCOPE" "G"
					( Parent
						( matchGroupRef "@crescent_city_bb_fab1_lib.crescent_city_bb_fab1(sch_1):\MG_DQ_FAR_DIMM_NG_M_D_BYTE5\" )
					)
					( Status sCSetFlattened )
					( Origin gBackEnd )
				)
				( attribute "RELATIVE_PROPAGATION_DELAY" "-50.00 MIL,50.00 MIL"
					( Parent
						( matchGroupRef "@crescent_city_bb_fab1_lib.crescent_city_bb_fab1(sch_1):\MG_DQ_FAR_DIMM_NG_M_D_BYTE5\" )
					)
					( Units "uMatchProp" "ns" 1.000000)
					( Status sCSetFlattened )
					( Origin gBackEnd )
				)
			)
			( pinPair "@baseboard_fab2_lib.baseboard_fab2(sch_1):\PP4580\"
				( pinRef "@baseboard_fab2_lib.baseboard_fab2(sch_1):page26_i172:DDR3_DQ(45)" )
				( pinRef "@baseboard_fab2_lib.baseboard_fab2(sch_1):page50_i158:DQ(45)" )
				( attribute "RELATIVE_PROPAGATION_DELAY_SCOPE" "G"
					( Parent
						( matchGroupRef "@baseboard_fab2_lib.baseboard_fab2(sch_1):\MG_DQ-DQS_NEAR_DIMM_NG_M_D_BYTE5\" )
					)
					( Status sCSetFlattened )
					( Origin gBackEnd )
				)
				( attribute "RELATIVE_PROPAGATION_DELAY" "0.00 MIL,195.00 MIL"
					( Parent
						( matchGroupRef "@baseboard_fab2_lib.baseboard_fab2(sch_1):\MG_DQ-DQS_NEAR_DIMM_NG_M_D_BYTE5\" )
					)
					( Units "uMatchProp" "ns" 1.000000)
					( Status sCSetFlattened )
					( Origin gBackEnd )
				)
				( attribute "RELATIVE_PROPAGATION_DELAY_SCOPE" "G"
					( Parent
						( matchGroupRef "@crescent_city_bb_fab1_lib.crescent_city_bb_fab1(sch_1):\MG_DQ_NEAR_DIMM_NG_M_D_BYTE5\" )
					)
					( Status sCSetFlattened )
					( Origin gBackEnd )
				)
				( attribute "RELATIVE_PROPAGATION_DELAY" "-50.00 MIL,50.00 MIL"
					( Parent
						( matchGroupRef "@crescent_city_bb_fab1_lib.crescent_city_bb_fab1(sch_1):\MG_DQ_NEAR_DIMM_NG_M_D_BYTE5\" )
					)
					( Units "uMatchProp" "ns" 1.000000)
					( Status sCSetFlattened )
					( Origin gBackEnd )
				)
			)
			( pinPair "@baseboard_fab2_lib.baseboard_fab2(sch_1):\PP4581\"
				( pinRef "@baseboard_fab2_lib.baseboard_fab2(sch_1):page26_i172:DDR3_DQ(46)" )
				( pinRef "@baseboard_fab2_lib.baseboard_fab2(sch_1):page49_i111:DQ(47)" )
				( attribute "RELATIVE_PROPAGATION_DELAY_SCOPE" "G"
					( Parent
						( matchGroupRef "@baseboard_fab2_lib.baseboard_fab2(sch_1):\MG_DQ-DQS_FAR_DIMM_NG_M_D_BYTE5\" )
					)
					( Status sCSetFlattened )
					( Origin gBackEnd )
				)
				( attribute "RELATIVE_PROPAGATION_DELAY" "0.00 MIL,195.00 MIL"
					( Parent
						( matchGroupRef "@baseboard_fab2_lib.baseboard_fab2(sch_1):\MG_DQ-DQS_FAR_DIMM_NG_M_D_BYTE5\" )
					)
					( Units "uMatchProp" "ns" 1.000000)
					( Status sCSetFlattened )
					( Origin gBackEnd )
				)
				( attribute "RELATIVE_PROPAGATION_DELAY_SCOPE" "G"
					( Parent
						( matchGroupRef "@crescent_city_bb_fab1_lib.crescent_city_bb_fab1(sch_1):\MG_DQ_FAR_DIMM_NG_M_D_BYTE5\" )
					)
					( Origin gBackEnd )
				)
				( attribute "RELATIVE_PROPAGATION_DELAY" "TARGET,TARGET"
					( Parent
						( matchGroupRef "@crescent_city_bb_fab1_lib.crescent_city_bb_fab1(sch_1):\MG_DQ_FAR_DIMM_NG_M_D_BYTE5\" )
					)
					( Units "uMatchProp" "ns" 1.000000)
					( Origin gBackEnd )
				)
			)
			( pinPair "@baseboard_fab2_lib.baseboard_fab2(sch_1):\PP4583\"
				( pinRef "@baseboard_fab2_lib.baseboard_fab2(sch_1):page26_i172:DDR3_DQ(46)" )
				( pinRef "@baseboard_fab2_lib.baseboard_fab2(sch_1):page50_i158:DQ(46)" )
				( attribute "RELATIVE_PROPAGATION_DELAY_SCOPE" "G"
					( Parent
						( matchGroupRef "@baseboard_fab2_lib.baseboard_fab2(sch_1):\MG_DQ-DQS_NEAR_DIMM_NG_M_D_BYTE5\" )
					)
					( Status sCSetFlattened )
					( Origin gBackEnd )
				)
				( attribute "RELATIVE_PROPAGATION_DELAY" "0.00 MIL,195.00 MIL"
					( Parent
						( matchGroupRef "@baseboard_fab2_lib.baseboard_fab2(sch_1):\MG_DQ-DQS_NEAR_DIMM_NG_M_D_BYTE5\" )
					)
					( Units "uMatchProp" "ns" 1.000000)
					( Status sCSetFlattened )
					( Origin gBackEnd )
				)
				( attribute "RELATIVE_PROPAGATION_DELAY_SCOPE" "G"
					( Parent
						( matchGroupRef "@crescent_city_bb_fab1_lib.crescent_city_bb_fab1(sch_1):\MG_DQ_NEAR_DIMM_NG_M_D_BYTE5\" )
					)
					( Status sCSetFlattened )
					( Origin gBackEnd )
				)
				( attribute "RELATIVE_PROPAGATION_DELAY" "-50.00 MIL,50.00 MIL"
					( Parent
						( matchGroupRef "@crescent_city_bb_fab1_lib.crescent_city_bb_fab1(sch_1):\MG_DQ_NEAR_DIMM_NG_M_D_BYTE5\" )
					)
					( Units "uMatchProp" "ns" 1.000000)
					( Status sCSetFlattened )
					( Origin gBackEnd )
				)
			)
			( pinPair "@baseboard_fab2_lib.baseboard_fab2(sch_1):\PP4584\"
				( pinRef "@baseboard_fab2_lib.baseboard_fab2(sch_1):page26_i172:DDR3_DQ(47)" )
				( pinRef "@baseboard_fab2_lib.baseboard_fab2(sch_1):page49_i111:DQ(46)" )
				( attribute "RELATIVE_PROPAGATION_DELAY_SCOPE" "G"
					( Parent
						( matchGroupRef "@baseboard_fab2_lib.baseboard_fab2(sch_1):\MG_DQ-DQS_FAR_DIMM_NG_M_D_BYTE5\" )
					)
					( Status sCSetFlattened )
					( Origin gBackEnd )
				)
				( attribute "RELATIVE_PROPAGATION_DELAY" "0.00 MIL,195.00 MIL"
					( Parent
						( matchGroupRef "@baseboard_fab2_lib.baseboard_fab2(sch_1):\MG_DQ-DQS_FAR_DIMM_NG_M_D_BYTE5\" )
					)
					( Units "uMatchProp" "ns" 1.000000)
					( Status sCSetFlattened )
					( Origin gBackEnd )
				)
				( attribute "RELATIVE_PROPAGATION_DELAY_SCOPE" "G"
					( Parent
						( matchGroupRef "@crescent_city_bb_fab1_lib.crescent_city_bb_fab1(sch_1):\MG_DQ_FAR_DIMM_NG_M_D_BYTE5\" )
					)
					( Status sCSetFlattened )
					( Origin gBackEnd )
				)
				( attribute "RELATIVE_PROPAGATION_DELAY" "-50.00 MIL,50.00 MIL"
					( Parent
						( matchGroupRef "@crescent_city_bb_fab1_lib.crescent_city_bb_fab1(sch_1):\MG_DQ_FAR_DIMM_NG_M_D_BYTE5\" )
					)
					( Units "uMatchProp" "ns" 1.000000)
					( Status sCSetFlattened )
					( Origin gBackEnd )
				)
			)
			( pinPair "@baseboard_fab2_lib.baseboard_fab2(sch_1):\PP4586\"
				( pinRef "@baseboard_fab2_lib.baseboard_fab2(sch_1):page26_i172:DDR3_DQ(47)" )
				( pinRef "@baseboard_fab2_lib.baseboard_fab2(sch_1):page50_i158:DQ(47)" )
				( attribute "RELATIVE_PROPAGATION_DELAY_SCOPE" "G"
					( Parent
						( matchGroupRef "@baseboard_fab2_lib.baseboard_fab2(sch_1):\MG_DQ-DQS_NEAR_DIMM_NG_M_D_BYTE5\" )
					)
					( Status sCSetFlattened )
					( Origin gBackEnd )
				)
				( attribute "RELATIVE_PROPAGATION_DELAY" "0.00 MIL,195.00 MIL"
					( Parent
						( matchGroupRef "@baseboard_fab2_lib.baseboard_fab2(sch_1):\MG_DQ-DQS_NEAR_DIMM_NG_M_D_BYTE5\" )
					)
					( Units "uMatchProp" "ns" 1.000000)
					( Status sCSetFlattened )
					( Origin gBackEnd )
				)
				( attribute "RELATIVE_PROPAGATION_DELAY_SCOPE" "G"
					( Parent
						( matchGroupRef "@crescent_city_bb_fab1_lib.crescent_city_bb_fab1(sch_1):\MG_DQ_NEAR_DIMM_NG_M_D_BYTE5\" )
					)
					( Status sCSetFlattened )
					( Origin gBackEnd )
				)
				( attribute "RELATIVE_PROPAGATION_DELAY" "-50.00 MIL,50.00 MIL"
					( Parent
						( matchGroupRef "@crescent_city_bb_fab1_lib.crescent_city_bb_fab1(sch_1):\MG_DQ_NEAR_DIMM_NG_M_D_BYTE5\" )
					)
					( Units "uMatchProp" "ns" 1.000000)
					( Status sCSetFlattened )
					( Origin gBackEnd )
				)
			)
			( pinPair "@baseboard_fab2_lib.baseboard_fab2(sch_1):\PP4539\"
				( pinRef "@baseboard_fab2_lib.baseboard_fab2(sch_1):page26_i172:DDR3_DQ(48)" )
				( pinRef "@baseboard_fab2_lib.baseboard_fab2(sch_1):page49_i111:DQ(49)" )
				( attribute "RELATIVE_PROPAGATION_DELAY_SCOPE" "G"
					( Parent
						( matchGroupRef "@baseboard_fab2_lib.baseboard_fab2(sch_1):\MG_DQ-DQS_FAR_DIMM_NG_M_D_BYTE6\" )
					)
					( Status sCSetFlattened )
					( Origin gBackEnd )
				)
				( attribute "RELATIVE_PROPAGATION_DELAY" "0.00 MIL,195.00 MIL"
					( Parent
						( matchGroupRef "@baseboard_fab2_lib.baseboard_fab2(sch_1):\MG_DQ-DQS_FAR_DIMM_NG_M_D_BYTE6\" )
					)
					( Units "uMatchProp" "ns" 1.000000)
					( Status sCSetFlattened )
					( Origin gBackEnd )
				)
				( attribute "RELATIVE_PROPAGATION_DELAY_SCOPE" "G"
					( Parent
						( matchGroupRef "@crescent_city_bb_fab1_lib.crescent_city_bb_fab1(sch_1):\MG_DQ_FAR_DIMM_NG_M_D_BYTE6\" )
					)
					( Status sCSetFlattened )
					( Origin gBackEnd )
				)
				( attribute "RELATIVE_PROPAGATION_DELAY" "-50.00 MIL,50.00 MIL"
					( Parent
						( matchGroupRef "@crescent_city_bb_fab1_lib.crescent_city_bb_fab1(sch_1):\MG_DQ_FAR_DIMM_NG_M_D_BYTE6\" )
					)
					( Units "uMatchProp" "ns" 1.000000)
					( Status sCSetFlattened )
					( Origin gBackEnd )
				)
			)
			( pinPair "@baseboard_fab2_lib.baseboard_fab2(sch_1):\PP4541\"
				( pinRef "@baseboard_fab2_lib.baseboard_fab2(sch_1):page26_i172:DDR3_DQ(48)" )
				( pinRef "@baseboard_fab2_lib.baseboard_fab2(sch_1):page50_i158:DQ(48)" )
				( attribute "RELATIVE_PROPAGATION_DELAY_SCOPE" "G"
					( Parent
						( matchGroupRef "@baseboard_fab2_lib.baseboard_fab2(sch_1):\MG_DQ-DQS_NEAR_DIMM_NG_M_D_BYTE6\" )
					)
					( Status sCSetFlattened )
					( Origin gBackEnd )
				)
				( attribute "RELATIVE_PROPAGATION_DELAY" "0.00 MIL,195.00 MIL"
					( Parent
						( matchGroupRef "@baseboard_fab2_lib.baseboard_fab2(sch_1):\MG_DQ-DQS_NEAR_DIMM_NG_M_D_BYTE6\" )
					)
					( Units "uMatchProp" "ns" 1.000000)
					( Status sCSetFlattened )
					( Origin gBackEnd )
				)
				( attribute "RELATIVE_PROPAGATION_DELAY_SCOPE" "G"
					( Parent
						( matchGroupRef "@crescent_city_bb_fab1_lib.crescent_city_bb_fab1(sch_1):\MG_DQ_NEAR_DIMM_NG_M_D_BYTE6\" )
					)
					( Status sCSetFlattened )
					( Origin gBackEnd )
				)
				( attribute "RELATIVE_PROPAGATION_DELAY" "-50.00 MIL,50.00 MIL"
					( Parent
						( matchGroupRef "@crescent_city_bb_fab1_lib.crescent_city_bb_fab1(sch_1):\MG_DQ_NEAR_DIMM_NG_M_D_BYTE6\" )
					)
					( Units "uMatchProp" "ns" 1.000000)
					( Status sCSetFlattened )
					( Origin gBackEnd )
				)
			)
			( pinPair "@baseboard_fab2_lib.baseboard_fab2(sch_1):\PP4542\"
				( pinRef "@baseboard_fab2_lib.baseboard_fab2(sch_1):page26_i172:DDR3_DQ(49)" )
				( pinRef "@baseboard_fab2_lib.baseboard_fab2(sch_1):page49_i111:DQ(48)" )
				( attribute "RELATIVE_PROPAGATION_DELAY_SCOPE" "G"
					( Parent
						( matchGroupRef "@baseboard_fab2_lib.baseboard_fab2(sch_1):\MG_DQ-DQS_FAR_DIMM_NG_M_D_BYTE6\" )
					)
					( Status sCSetFlattened )
					( Origin gBackEnd )
				)
				( attribute "RELATIVE_PROPAGATION_DELAY" "0.00 MIL,195.00 MIL"
					( Parent
						( matchGroupRef "@baseboard_fab2_lib.baseboard_fab2(sch_1):\MG_DQ-DQS_FAR_DIMM_NG_M_D_BYTE6\" )
					)
					( Units "uMatchProp" "ns" 1.000000)
					( Status sCSetFlattened )
					( Origin gBackEnd )
				)
				( attribute "RELATIVE_PROPAGATION_DELAY_SCOPE" "G"
					( Parent
						( matchGroupRef "@crescent_city_bb_fab1_lib.crescent_city_bb_fab1(sch_1):\MG_DQ_FAR_DIMM_NG_M_D_BYTE6\" )
					)
					( Status sCSetFlattened )
					( Origin gBackEnd )
				)
				( attribute "RELATIVE_PROPAGATION_DELAY" "-50.00 MIL,50.00 MIL"
					( Parent
						( matchGroupRef "@crescent_city_bb_fab1_lib.crescent_city_bb_fab1(sch_1):\MG_DQ_FAR_DIMM_NG_M_D_BYTE6\" )
					)
					( Units "uMatchProp" "ns" 1.000000)
					( Status sCSetFlattened )
					( Origin gBackEnd )
				)
			)
			( pinPair "@baseboard_fab2_lib.baseboard_fab2(sch_1):\PP4544\"
				( pinRef "@baseboard_fab2_lib.baseboard_fab2(sch_1):page26_i172:DDR3_DQ(49)" )
				( pinRef "@baseboard_fab2_lib.baseboard_fab2(sch_1):page50_i158:DQ(49)" )
				( attribute "RELATIVE_PROPAGATION_DELAY_SCOPE" "G"
					( Parent
						( matchGroupRef "@baseboard_fab2_lib.baseboard_fab2(sch_1):\MG_DQ-DQS_NEAR_DIMM_NG_M_D_BYTE6\" )
					)
					( Status sCSetFlattened )
					( Origin gBackEnd )
				)
				( attribute "RELATIVE_PROPAGATION_DELAY" "0.00 MIL,195.00 MIL"
					( Parent
						( matchGroupRef "@baseboard_fab2_lib.baseboard_fab2(sch_1):\MG_DQ-DQS_NEAR_DIMM_NG_M_D_BYTE6\" )
					)
					( Units "uMatchProp" "ns" 1.000000)
					( Status sCSetFlattened )
					( Origin gBackEnd )
				)
				( attribute "RELATIVE_PROPAGATION_DELAY_SCOPE" "G"
					( Parent
						( matchGroupRef "@crescent_city_bb_fab1_lib.crescent_city_bb_fab1(sch_1):\MG_DQ_NEAR_DIMM_NG_M_D_BYTE6\" )
					)
					( Status sCSetFlattened )
					( Origin gBackEnd )
				)
				( attribute "RELATIVE_PROPAGATION_DELAY" "-50.00 MIL,50.00 MIL"
					( Parent
						( matchGroupRef "@crescent_city_bb_fab1_lib.crescent_city_bb_fab1(sch_1):\MG_DQ_NEAR_DIMM_NG_M_D_BYTE6\" )
					)
					( Units "uMatchProp" "ns" 1.000000)
					( Status sCSetFlattened )
					( Origin gBackEnd )
				)
			)
			( pinPair "@baseboard_fab2_lib.baseboard_fab2(sch_1):\PP4545\"
				( pinRef "@baseboard_fab2_lib.baseboard_fab2(sch_1):page26_i172:DDR3_DQ(50)" )
				( pinRef "@baseboard_fab2_lib.baseboard_fab2(sch_1):page49_i111:DQ(51)" )
				( attribute "RELATIVE_PROPAGATION_DELAY_SCOPE" "G"
					( Parent
						( matchGroupRef "@baseboard_fab2_lib.baseboard_fab2(sch_1):\MG_DQ-DQS_FAR_DIMM_NG_M_D_BYTE6\" )
					)
					( Status sCSetFlattened )
					( Origin gBackEnd )
				)
				( attribute "RELATIVE_PROPAGATION_DELAY" "0.00 MIL,195.00 MIL"
					( Parent
						( matchGroupRef "@baseboard_fab2_lib.baseboard_fab2(sch_1):\MG_DQ-DQS_FAR_DIMM_NG_M_D_BYTE6\" )
					)
					( Units "uMatchProp" "ns" 1.000000)
					( Status sCSetFlattened )
					( Origin gBackEnd )
				)
				( attribute "RELATIVE_PROPAGATION_DELAY_SCOPE" "G"
					( Parent
						( matchGroupRef "@crescent_city_bb_fab1_lib.crescent_city_bb_fab1(sch_1):\MG_DQ_FAR_DIMM_NG_M_D_BYTE6\" )
					)
					( Origin gBackEnd )
				)
				( attribute "RELATIVE_PROPAGATION_DELAY" "TARGET,TARGET"
					( Parent
						( matchGroupRef "@crescent_city_bb_fab1_lib.crescent_city_bb_fab1(sch_1):\MG_DQ_FAR_DIMM_NG_M_D_BYTE6\" )
					)
					( Units "uMatchProp" "ns" 1.000000)
					( Origin gBackEnd )
				)
			)
			( pinPair "@baseboard_fab2_lib.baseboard_fab2(sch_1):\PP4547\"
				( pinRef "@baseboard_fab2_lib.baseboard_fab2(sch_1):page50_i158:DQ(50)" )
				( pinRef "@baseboard_fab2_lib.baseboard_fab2(sch_1):page26_i172:DDR3_DQ(50)" )
				( attribute "RELATIVE_PROPAGATION_DELAY_SCOPE" "G"
					( Parent
						( matchGroupRef "@baseboard_fab2_lib.baseboard_fab2(sch_1):\MG_DQ-DQS_NEAR_DIMM_NG_M_D_BYTE6\" )
					)
					( Status sCSetFlattened )
					( Origin gBackEnd )
				)
				( attribute "RELATIVE_PROPAGATION_DELAY" "0.00 MIL,195.00 MIL"
					( Parent
						( matchGroupRef "@baseboard_fab2_lib.baseboard_fab2(sch_1):\MG_DQ-DQS_NEAR_DIMM_NG_M_D_BYTE6\" )
					)
					( Units "uMatchProp" "ns" 1.000000)
					( Status sCSetFlattened )
					( Origin gBackEnd )
				)
				( attribute "RELATIVE_PROPAGATION_DELAY_SCOPE" "G"
					( Parent
						( matchGroupRef "@crescent_city_bb_fab1_lib.crescent_city_bb_fab1(sch_1):\MG_DQ_NEAR_DIMM_NG_M_D_BYTE6\" )
					)
					( Status sCSetFlattened )
					( Origin gBackEnd )
				)
				( attribute "RELATIVE_PROPAGATION_DELAY" "-50.00 MIL,50.00 MIL"
					( Parent
						( matchGroupRef "@crescent_city_bb_fab1_lib.crescent_city_bb_fab1(sch_1):\MG_DQ_NEAR_DIMM_NG_M_D_BYTE6\" )
					)
					( Units "uMatchProp" "ns" 1.000000)
					( Status sCSetFlattened )
					( Origin gBackEnd )
				)
			)
			( pinPair "@baseboard_fab2_lib.baseboard_fab2(sch_1):\PP4548\"
				( pinRef "@baseboard_fab2_lib.baseboard_fab2(sch_1):page26_i172:DDR3_DQ(51)" )
				( pinRef "@baseboard_fab2_lib.baseboard_fab2(sch_1):page49_i111:DQ(50)" )
				( attribute "RELATIVE_PROPAGATION_DELAY_SCOPE" "G"
					( Parent
						( matchGroupRef "@baseboard_fab2_lib.baseboard_fab2(sch_1):\MG_DQ-DQS_FAR_DIMM_NG_M_D_BYTE6\" )
					)
					( Status sCSetFlattened )
					( Origin gBackEnd )
				)
				( attribute "RELATIVE_PROPAGATION_DELAY" "0.00 MIL,195.00 MIL"
					( Parent
						( matchGroupRef "@baseboard_fab2_lib.baseboard_fab2(sch_1):\MG_DQ-DQS_FAR_DIMM_NG_M_D_BYTE6\" )
					)
					( Units "uMatchProp" "ns" 1.000000)
					( Status sCSetFlattened )
					( Origin gBackEnd )
				)
				( attribute "RELATIVE_PROPAGATION_DELAY_SCOPE" "G"
					( Parent
						( matchGroupRef "@crescent_city_bb_fab1_lib.crescent_city_bb_fab1(sch_1):\MG_DQ_FAR_DIMM_NG_M_D_BYTE6\" )
					)
					( Status sCSetFlattened )
					( Origin gBackEnd )
				)
				( attribute "RELATIVE_PROPAGATION_DELAY" "-50.00 MIL,50.00 MIL"
					( Parent
						( matchGroupRef "@crescent_city_bb_fab1_lib.crescent_city_bb_fab1(sch_1):\MG_DQ_FAR_DIMM_NG_M_D_BYTE6\" )
					)
					( Units "uMatchProp" "ns" 1.000000)
					( Status sCSetFlattened )
					( Origin gBackEnd )
				)
			)
			( pinPair "@baseboard_fab2_lib.baseboard_fab2(sch_1):\PP4550\"
				( pinRef "@baseboard_fab2_lib.baseboard_fab2(sch_1):page50_i158:DQ(51)" )
				( pinRef "@baseboard_fab2_lib.baseboard_fab2(sch_1):page26_i172:DDR3_DQ(51)" )
				( attribute "RELATIVE_PROPAGATION_DELAY_SCOPE" "G"
					( Parent
						( matchGroupRef "@baseboard_fab2_lib.baseboard_fab2(sch_1):\MG_DQ-DQS_NEAR_DIMM_NG_M_D_BYTE6\" )
					)
					( Status sCSetFlattened )
					( Origin gBackEnd )
				)
				( attribute "RELATIVE_PROPAGATION_DELAY" "0.00 MIL,195.00 MIL"
					( Parent
						( matchGroupRef "@baseboard_fab2_lib.baseboard_fab2(sch_1):\MG_DQ-DQS_NEAR_DIMM_NG_M_D_BYTE6\" )
					)
					( Units "uMatchProp" "ns" 1.000000)
					( Status sCSetFlattened )
					( Origin gBackEnd )
				)
				( attribute "RELATIVE_PROPAGATION_DELAY_SCOPE" "G"
					( Parent
						( matchGroupRef "@crescent_city_bb_fab1_lib.crescent_city_bb_fab1(sch_1):\MG_DQ_NEAR_DIMM_NG_M_D_BYTE6\" )
					)
					( Origin gBackEnd )
				)
				( attribute "RELATIVE_PROPAGATION_DELAY" "TARGET,TARGET"
					( Parent
						( matchGroupRef "@crescent_city_bb_fab1_lib.crescent_city_bb_fab1(sch_1):\MG_DQ_NEAR_DIMM_NG_M_D_BYTE6\" )
					)
					( Units "uMatchProp" "ns" 1.000000)
					( Origin gBackEnd )
				)
			)
			( pinPair "@baseboard_fab2_lib.baseboard_fab2(sch_1):\PP4551\"
				( pinRef "@baseboard_fab2_lib.baseboard_fab2(sch_1):page26_i172:DDR3_DQ(52)" )
				( pinRef "@baseboard_fab2_lib.baseboard_fab2(sch_1):page49_i111:DQ(53)" )
				( attribute "RELATIVE_PROPAGATION_DELAY_SCOPE" "G"
					( Parent
						( matchGroupRef "@baseboard_fab2_lib.baseboard_fab2(sch_1):\MG_DQ-DQS_FAR_DIMM_NG_M_D_BYTE6\" )
					)
					( Status sCSetFlattened )
					( Origin gBackEnd )
				)
				( attribute "RELATIVE_PROPAGATION_DELAY" "0.00 MIL,195.00 MIL"
					( Parent
						( matchGroupRef "@baseboard_fab2_lib.baseboard_fab2(sch_1):\MG_DQ-DQS_FAR_DIMM_NG_M_D_BYTE6\" )
					)
					( Units "uMatchProp" "ns" 1.000000)
					( Status sCSetFlattened )
					( Origin gBackEnd )
				)
				( attribute "RELATIVE_PROPAGATION_DELAY_SCOPE" "G"
					( Parent
						( matchGroupRef "@crescent_city_bb_fab1_lib.crescent_city_bb_fab1(sch_1):\MG_DQ_FAR_DIMM_NG_M_D_BYTE6\" )
					)
					( Status sCSetFlattened )
					( Origin gBackEnd )
				)
				( attribute "RELATIVE_PROPAGATION_DELAY" "-50.00 MIL,50.00 MIL"
					( Parent
						( matchGroupRef "@crescent_city_bb_fab1_lib.crescent_city_bb_fab1(sch_1):\MG_DQ_FAR_DIMM_NG_M_D_BYTE6\" )
					)
					( Units "uMatchProp" "ns" 1.000000)
					( Status sCSetFlattened )
					( Origin gBackEnd )
				)
			)
			( pinPair "@baseboard_fab2_lib.baseboard_fab2(sch_1):\PP4553\"
				( pinRef "@baseboard_fab2_lib.baseboard_fab2(sch_1):page26_i172:DDR3_DQ(52)" )
				( pinRef "@baseboard_fab2_lib.baseboard_fab2(sch_1):page50_i158:DQ(52)" )
				( attribute "RELATIVE_PROPAGATION_DELAY_SCOPE" "G"
					( Parent
						( matchGroupRef "@baseboard_fab2_lib.baseboard_fab2(sch_1):\MG_DQ-DQS_NEAR_DIMM_NG_M_D_BYTE6\" )
					)
					( Status sCSetFlattened )
					( Origin gBackEnd )
				)
				( attribute "RELATIVE_PROPAGATION_DELAY" "0.00 MIL,195.00 MIL"
					( Parent
						( matchGroupRef "@baseboard_fab2_lib.baseboard_fab2(sch_1):\MG_DQ-DQS_NEAR_DIMM_NG_M_D_BYTE6\" )
					)
					( Units "uMatchProp" "ns" 1.000000)
					( Status sCSetFlattened )
					( Origin gBackEnd )
				)
				( attribute "RELATIVE_PROPAGATION_DELAY_SCOPE" "G"
					( Parent
						( matchGroupRef "@crescent_city_bb_fab1_lib.crescent_city_bb_fab1(sch_1):\MG_DQ_NEAR_DIMM_NG_M_D_BYTE6\" )
					)
					( Status sCSetFlattened )
					( Origin gBackEnd )
				)
				( attribute "RELATIVE_PROPAGATION_DELAY" "-50.00 MIL,50.00 MIL"
					( Parent
						( matchGroupRef "@crescent_city_bb_fab1_lib.crescent_city_bb_fab1(sch_1):\MG_DQ_NEAR_DIMM_NG_M_D_BYTE6\" )
					)
					( Units "uMatchProp" "ns" 1.000000)
					( Status sCSetFlattened )
					( Origin gBackEnd )
				)
			)
			( pinPair "@baseboard_fab2_lib.baseboard_fab2(sch_1):\PP4554\"
				( pinRef "@baseboard_fab2_lib.baseboard_fab2(sch_1):page26_i172:DDR3_DQ(53)" )
				( pinRef "@baseboard_fab2_lib.baseboard_fab2(sch_1):page49_i111:DQ(52)" )
				( attribute "RELATIVE_PROPAGATION_DELAY_SCOPE" "G"
					( Parent
						( matchGroupRef "@baseboard_fab2_lib.baseboard_fab2(sch_1):\MG_DQ-DQS_FAR_DIMM_NG_M_D_BYTE6\" )
					)
					( Status sCSetFlattened )
					( Origin gBackEnd )
				)
				( attribute "RELATIVE_PROPAGATION_DELAY" "0.00 MIL,195.00 MIL"
					( Parent
						( matchGroupRef "@baseboard_fab2_lib.baseboard_fab2(sch_1):\MG_DQ-DQS_FAR_DIMM_NG_M_D_BYTE6\" )
					)
					( Units "uMatchProp" "ns" 1.000000)
					( Status sCSetFlattened )
					( Origin gBackEnd )
				)
				( attribute "RELATIVE_PROPAGATION_DELAY_SCOPE" "G"
					( Parent
						( matchGroupRef "@crescent_city_bb_fab1_lib.crescent_city_bb_fab1(sch_1):\MG_DQ_FAR_DIMM_NG_M_D_BYTE6\" )
					)
					( Status sCSetFlattened )
					( Origin gBackEnd )
				)
				( attribute "RELATIVE_PROPAGATION_DELAY" "-50.00 MIL,50.00 MIL"
					( Parent
						( matchGroupRef "@crescent_city_bb_fab1_lib.crescent_city_bb_fab1(sch_1):\MG_DQ_FAR_DIMM_NG_M_D_BYTE6\" )
					)
					( Units "uMatchProp" "ns" 1.000000)
					( Status sCSetFlattened )
					( Origin gBackEnd )
				)
			)
			( pinPair "@baseboard_fab2_lib.baseboard_fab2(sch_1):\PP4556\"
				( pinRef "@baseboard_fab2_lib.baseboard_fab2(sch_1):page26_i172:DDR3_DQ(53)" )
				( pinRef "@baseboard_fab2_lib.baseboard_fab2(sch_1):page50_i158:DQ(53)" )
				( attribute "RELATIVE_PROPAGATION_DELAY_SCOPE" "G"
					( Parent
						( matchGroupRef "@baseboard_fab2_lib.baseboard_fab2(sch_1):\MG_DQ-DQS_NEAR_DIMM_NG_M_D_BYTE6\" )
					)
					( Status sCSetFlattened )
					( Origin gBackEnd )
				)
				( attribute "RELATIVE_PROPAGATION_DELAY" "0.00 MIL,195.00 MIL"
					( Parent
						( matchGroupRef "@baseboard_fab2_lib.baseboard_fab2(sch_1):\MG_DQ-DQS_NEAR_DIMM_NG_M_D_BYTE6\" )
					)
					( Units "uMatchProp" "ns" 1.000000)
					( Status sCSetFlattened )
					( Origin gBackEnd )
				)
				( attribute "RELATIVE_PROPAGATION_DELAY_SCOPE" "G"
					( Parent
						( matchGroupRef "@crescent_city_bb_fab1_lib.crescent_city_bb_fab1(sch_1):\MG_DQ_NEAR_DIMM_NG_M_D_BYTE6\" )
					)
					( Status sCSetFlattened )
					( Origin gBackEnd )
				)
				( attribute "RELATIVE_PROPAGATION_DELAY" "-50.00 MIL,50.00 MIL"
					( Parent
						( matchGroupRef "@crescent_city_bb_fab1_lib.crescent_city_bb_fab1(sch_1):\MG_DQ_NEAR_DIMM_NG_M_D_BYTE6\" )
					)
					( Units "uMatchProp" "ns" 1.000000)
					( Status sCSetFlattened )
					( Origin gBackEnd )
				)
			)
			( pinPair "@baseboard_fab2_lib.baseboard_fab2(sch_1):\PP4557\"
				( pinRef "@baseboard_fab2_lib.baseboard_fab2(sch_1):page26_i172:DDR3_DQ(54)" )
				( pinRef "@baseboard_fab2_lib.baseboard_fab2(sch_1):page49_i111:DQ(55)" )
				( attribute "RELATIVE_PROPAGATION_DELAY_SCOPE" "G"
					( Parent
						( matchGroupRef "@baseboard_fab2_lib.baseboard_fab2(sch_1):\MG_DQ-DQS_FAR_DIMM_NG_M_D_BYTE6\" )
					)
					( Status sCSetFlattened )
					( Origin gBackEnd )
				)
				( attribute "RELATIVE_PROPAGATION_DELAY" "0.00 MIL,195.00 MIL"
					( Parent
						( matchGroupRef "@baseboard_fab2_lib.baseboard_fab2(sch_1):\MG_DQ-DQS_FAR_DIMM_NG_M_D_BYTE6\" )
					)
					( Units "uMatchProp" "ns" 1.000000)
					( Status sCSetFlattened )
					( Origin gBackEnd )
				)
				( attribute "RELATIVE_PROPAGATION_DELAY_SCOPE" "G"
					( Parent
						( matchGroupRef "@crescent_city_bb_fab1_lib.crescent_city_bb_fab1(sch_1):\MG_DQ_FAR_DIMM_NG_M_D_BYTE6\" )
					)
					( Status sCSetFlattened )
					( Origin gBackEnd )
				)
				( attribute "RELATIVE_PROPAGATION_DELAY" "-50.00 MIL,50.00 MIL"
					( Parent
						( matchGroupRef "@crescent_city_bb_fab1_lib.crescent_city_bb_fab1(sch_1):\MG_DQ_FAR_DIMM_NG_M_D_BYTE6\" )
					)
					( Units "uMatchProp" "ns" 1.000000)
					( Status sCSetFlattened )
					( Origin gBackEnd )
				)
			)
			( pinPair "@baseboard_fab2_lib.baseboard_fab2(sch_1):\PP4559\"
				( pinRef "@baseboard_fab2_lib.baseboard_fab2(sch_1):page50_i158:DQ(54)" )
				( pinRef "@baseboard_fab2_lib.baseboard_fab2(sch_1):page26_i172:DDR3_DQ(54)" )
				( attribute "RELATIVE_PROPAGATION_DELAY_SCOPE" "G"
					( Parent
						( matchGroupRef "@baseboard_fab2_lib.baseboard_fab2(sch_1):\MG_DQ-DQS_NEAR_DIMM_NG_M_D_BYTE6\" )
					)
					( Status sCSetFlattened )
					( Origin gBackEnd )
				)
				( attribute "RELATIVE_PROPAGATION_DELAY" "0.00 MIL,195.00 MIL"
					( Parent
						( matchGroupRef "@baseboard_fab2_lib.baseboard_fab2(sch_1):\MG_DQ-DQS_NEAR_DIMM_NG_M_D_BYTE6\" )
					)
					( Units "uMatchProp" "ns" 1.000000)
					( Status sCSetFlattened )
					( Origin gBackEnd )
				)
				( attribute "RELATIVE_PROPAGATION_DELAY_SCOPE" "G"
					( Parent
						( matchGroupRef "@crescent_city_bb_fab1_lib.crescent_city_bb_fab1(sch_1):\MG_DQ_NEAR_DIMM_NG_M_D_BYTE6\" )
					)
					( Status sCSetFlattened )
					( Origin gBackEnd )
				)
				( attribute "RELATIVE_PROPAGATION_DELAY" "-50.00 MIL,50.00 MIL"
					( Parent
						( matchGroupRef "@crescent_city_bb_fab1_lib.crescent_city_bb_fab1(sch_1):\MG_DQ_NEAR_DIMM_NG_M_D_BYTE6\" )
					)
					( Units "uMatchProp" "ns" 1.000000)
					( Status sCSetFlattened )
					( Origin gBackEnd )
				)
			)
			( pinPair "@baseboard_fab2_lib.baseboard_fab2(sch_1):\PP4560\"
				( pinRef "@baseboard_fab2_lib.baseboard_fab2(sch_1):page26_i172:DDR3_DQ(55)" )
				( pinRef "@baseboard_fab2_lib.baseboard_fab2(sch_1):page49_i111:DQ(54)" )
				( attribute "RELATIVE_PROPAGATION_DELAY_SCOPE" "G"
					( Parent
						( matchGroupRef "@baseboard_fab2_lib.baseboard_fab2(sch_1):\MG_DQ-DQS_FAR_DIMM_NG_M_D_BYTE6\" )
					)
					( Status sCSetFlattened )
					( Origin gBackEnd )
				)
				( attribute "RELATIVE_PROPAGATION_DELAY" "0.00 MIL,195.00 MIL"
					( Parent
						( matchGroupRef "@baseboard_fab2_lib.baseboard_fab2(sch_1):\MG_DQ-DQS_FAR_DIMM_NG_M_D_BYTE6\" )
					)
					( Units "uMatchProp" "ns" 1.000000)
					( Status sCSetFlattened )
					( Origin gBackEnd )
				)
				( attribute "RELATIVE_PROPAGATION_DELAY_SCOPE" "G"
					( Parent
						( matchGroupRef "@crescent_city_bb_fab1_lib.crescent_city_bb_fab1(sch_1):\MG_DQ_FAR_DIMM_NG_M_D_BYTE6\" )
					)
					( Status sCSetFlattened )
					( Origin gBackEnd )
				)
				( attribute "RELATIVE_PROPAGATION_DELAY" "-50.00 MIL,50.00 MIL"
					( Parent
						( matchGroupRef "@crescent_city_bb_fab1_lib.crescent_city_bb_fab1(sch_1):\MG_DQ_FAR_DIMM_NG_M_D_BYTE6\" )
					)
					( Units "uMatchProp" "ns" 1.000000)
					( Status sCSetFlattened )
					( Origin gBackEnd )
				)
			)
			( pinPair "@baseboard_fab2_lib.baseboard_fab2(sch_1):\PP4562\"
				( pinRef "@baseboard_fab2_lib.baseboard_fab2(sch_1):page50_i158:DQ(55)" )
				( pinRef "@baseboard_fab2_lib.baseboard_fab2(sch_1):page26_i172:DDR3_DQ(55)" )
				( attribute "RELATIVE_PROPAGATION_DELAY_SCOPE" "G"
					( Parent
						( matchGroupRef "@baseboard_fab2_lib.baseboard_fab2(sch_1):\MG_DQ-DQS_NEAR_DIMM_NG_M_D_BYTE6\" )
					)
					( Status sCSetFlattened )
					( Origin gBackEnd )
				)
				( attribute "RELATIVE_PROPAGATION_DELAY" "0.00 MIL,195.00 MIL"
					( Parent
						( matchGroupRef "@baseboard_fab2_lib.baseboard_fab2(sch_1):\MG_DQ-DQS_NEAR_DIMM_NG_M_D_BYTE6\" )
					)
					( Units "uMatchProp" "ns" 1.000000)
					( Status sCSetFlattened )
					( Origin gBackEnd )
				)
				( attribute "RELATIVE_PROPAGATION_DELAY_SCOPE" "G"
					( Parent
						( matchGroupRef "@crescent_city_bb_fab1_lib.crescent_city_bb_fab1(sch_1):\MG_DQ_NEAR_DIMM_NG_M_D_BYTE6\" )
					)
					( Status sCSetFlattened )
					( Origin gBackEnd )
				)
				( attribute "RELATIVE_PROPAGATION_DELAY" "-50.00 MIL,50.00 MIL"
					( Parent
						( matchGroupRef "@crescent_city_bb_fab1_lib.crescent_city_bb_fab1(sch_1):\MG_DQ_NEAR_DIMM_NG_M_D_BYTE6\" )
					)
					( Units "uMatchProp" "ns" 1.000000)
					( Status sCSetFlattened )
					( Origin gBackEnd )
				)
			)
			( pinPair "@baseboard_fab2_lib.baseboard_fab2(sch_1):\PP4515\"
				( pinRef "@baseboard_fab2_lib.baseboard_fab2(sch_1):page26_i172:DDR3_DQ(56)" )
				( pinRef "@baseboard_fab2_lib.baseboard_fab2(sch_1):page49_i111:DQ(57)" )
				( attribute "RELATIVE_PROPAGATION_DELAY_SCOPE" "G"
					( Parent
						( matchGroupRef "@baseboard_fab2_lib.baseboard_fab2(sch_1):\MG_DQ-DQS_FAR_DIMM_NG_M_D_BYTE7\" )
					)
					( Status sCSetFlattened )
					( Origin gBackEnd )
				)
				( attribute "RELATIVE_PROPAGATION_DELAY" "0.00 MIL,195.00 MIL"
					( Parent
						( matchGroupRef "@baseboard_fab2_lib.baseboard_fab2(sch_1):\MG_DQ-DQS_FAR_DIMM_NG_M_D_BYTE7\" )
					)
					( Units "uMatchProp" "ns" 1.000000)
					( Status sCSetFlattened )
					( Origin gBackEnd )
				)
				( attribute "RELATIVE_PROPAGATION_DELAY_SCOPE" "G"
					( Parent
						( matchGroupRef "@crescent_city_bb_fab1_lib.crescent_city_bb_fab1(sch_1):\MG_DQ_FAR_DIMM_NG_M_D_BYTE7\" )
					)
					( Status sCSetFlattened )
					( Origin gBackEnd )
				)
				( attribute "RELATIVE_PROPAGATION_DELAY" "-50.00 MIL,50.00 MIL"
					( Parent
						( matchGroupRef "@crescent_city_bb_fab1_lib.crescent_city_bb_fab1(sch_1):\MG_DQ_FAR_DIMM_NG_M_D_BYTE7\" )
					)
					( Units "uMatchProp" "ns" 1.000000)
					( Status sCSetFlattened )
					( Origin gBackEnd )
				)
			)
			( pinPair "@baseboard_fab2_lib.baseboard_fab2(sch_1):\PP4517\"
				( pinRef "@baseboard_fab2_lib.baseboard_fab2(sch_1):page26_i172:DDR3_DQ(56)" )
				( pinRef "@baseboard_fab2_lib.baseboard_fab2(sch_1):page50_i158:DQ(56)" )
				( attribute "RELATIVE_PROPAGATION_DELAY_SCOPE" "G"
					( Parent
						( matchGroupRef "@baseboard_fab2_lib.baseboard_fab2(sch_1):\MG_DQ-DQS_NEAR_DIMM_NG_M_D_BYTE7\" )
					)
					( Status sCSetFlattened )
					( Origin gBackEnd )
				)
				( attribute "RELATIVE_PROPAGATION_DELAY" "0.00 MIL,195.00 MIL"
					( Parent
						( matchGroupRef "@baseboard_fab2_lib.baseboard_fab2(sch_1):\MG_DQ-DQS_NEAR_DIMM_NG_M_D_BYTE7\" )
					)
					( Units "uMatchProp" "ns" 1.000000)
					( Status sCSetFlattened )
					( Origin gBackEnd )
				)
				( attribute "RELATIVE_PROPAGATION_DELAY_SCOPE" "G"
					( Parent
						( matchGroupRef "@crescent_city_bb_fab1_lib.crescent_city_bb_fab1(sch_1):\MG_DQ_NEAR_DIMM_NG_M_D_BYTE7\" )
					)
					( Status sCSetFlattened )
					( Origin gBackEnd )
				)
				( attribute "RELATIVE_PROPAGATION_DELAY" "-50.00 MIL,50.00 MIL"
					( Parent
						( matchGroupRef "@crescent_city_bb_fab1_lib.crescent_city_bb_fab1(sch_1):\MG_DQ_NEAR_DIMM_NG_M_D_BYTE7\" )
					)
					( Units "uMatchProp" "ns" 1.000000)
					( Status sCSetFlattened )
					( Origin gBackEnd )
				)
			)
			( pinPair "@baseboard_fab2_lib.baseboard_fab2(sch_1):\PP4518\"
				( pinRef "@baseboard_fab2_lib.baseboard_fab2(sch_1):page26_i172:DDR3_DQ(57)" )
				( pinRef "@baseboard_fab2_lib.baseboard_fab2(sch_1):page49_i111:DQ(56)" )
				( attribute "RELATIVE_PROPAGATION_DELAY_SCOPE" "G"
					( Parent
						( matchGroupRef "@baseboard_fab2_lib.baseboard_fab2(sch_1):\MG_DQ-DQS_FAR_DIMM_NG_M_D_BYTE7\" )
					)
					( Status sCSetFlattened )
					( Origin gBackEnd )
				)
				( attribute "RELATIVE_PROPAGATION_DELAY" "0.00 MIL,195.00 MIL"
					( Parent
						( matchGroupRef "@baseboard_fab2_lib.baseboard_fab2(sch_1):\MG_DQ-DQS_FAR_DIMM_NG_M_D_BYTE7\" )
					)
					( Units "uMatchProp" "ns" 1.000000)
					( Status sCSetFlattened )
					( Origin gBackEnd )
				)
				( attribute "RELATIVE_PROPAGATION_DELAY_SCOPE" "G"
					( Parent
						( matchGroupRef "@crescent_city_bb_fab1_lib.crescent_city_bb_fab1(sch_1):\MG_DQ_FAR_DIMM_NG_M_D_BYTE7\" )
					)
					( Status sCSetFlattened )
					( Origin gBackEnd )
				)
				( attribute "RELATIVE_PROPAGATION_DELAY" "-50.00 MIL,50.00 MIL"
					( Parent
						( matchGroupRef "@crescent_city_bb_fab1_lib.crescent_city_bb_fab1(sch_1):\MG_DQ_FAR_DIMM_NG_M_D_BYTE7\" )
					)
					( Units "uMatchProp" "ns" 1.000000)
					( Status sCSetFlattened )
					( Origin gBackEnd )
				)
			)
			( pinPair "@baseboard_fab2_lib.baseboard_fab2(sch_1):\PP4520\"
				( pinRef "@baseboard_fab2_lib.baseboard_fab2(sch_1):page26_i172:DDR3_DQ(57)" )
				( pinRef "@baseboard_fab2_lib.baseboard_fab2(sch_1):page50_i158:DQ(57)" )
				( attribute "RELATIVE_PROPAGATION_DELAY_SCOPE" "G"
					( Parent
						( matchGroupRef "@baseboard_fab2_lib.baseboard_fab2(sch_1):\MG_DQ-DQS_NEAR_DIMM_NG_M_D_BYTE7\" )
					)
					( Status sCSetFlattened )
					( Origin gBackEnd )
				)
				( attribute "RELATIVE_PROPAGATION_DELAY" "0.00 MIL,195.00 MIL"
					( Parent
						( matchGroupRef "@baseboard_fab2_lib.baseboard_fab2(sch_1):\MG_DQ-DQS_NEAR_DIMM_NG_M_D_BYTE7\" )
					)
					( Units "uMatchProp" "ns" 1.000000)
					( Status sCSetFlattened )
					( Origin gBackEnd )
				)
				( attribute "RELATIVE_PROPAGATION_DELAY_SCOPE" "G"
					( Parent
						( matchGroupRef "@crescent_city_bb_fab1_lib.crescent_city_bb_fab1(sch_1):\MG_DQ_NEAR_DIMM_NG_M_D_BYTE7\" )
					)
					( Origin gBackEnd )
				)
				( attribute "RELATIVE_PROPAGATION_DELAY" "TARGET,TARGET"
					( Parent
						( matchGroupRef "@crescent_city_bb_fab1_lib.crescent_city_bb_fab1(sch_1):\MG_DQ_NEAR_DIMM_NG_M_D_BYTE7\" )
					)
					( Units "uMatchProp" "ns" 1.000000)
					( Origin gBackEnd )
				)
			)
			( pinPair "@baseboard_fab2_lib.baseboard_fab2(sch_1):\PP4521\"
				( pinRef "@baseboard_fab2_lib.baseboard_fab2(sch_1):page26_i172:DDR3_DQ(58)" )
				( pinRef "@baseboard_fab2_lib.baseboard_fab2(sch_1):page49_i111:DQ(59)" )
				( attribute "RELATIVE_PROPAGATION_DELAY_SCOPE" "G"
					( Parent
						( matchGroupRef "@baseboard_fab2_lib.baseboard_fab2(sch_1):\MG_DQ-DQS_FAR_DIMM_NG_M_D_BYTE7\" )
					)
					( Status sCSetFlattened )
					( Origin gBackEnd )
				)
				( attribute "RELATIVE_PROPAGATION_DELAY" "0.00 MIL,195.00 MIL"
					( Parent
						( matchGroupRef "@baseboard_fab2_lib.baseboard_fab2(sch_1):\MG_DQ-DQS_FAR_DIMM_NG_M_D_BYTE7\" )
					)
					( Units "uMatchProp" "ns" 1.000000)
					( Status sCSetFlattened )
					( Origin gBackEnd )
				)
				( attribute "RELATIVE_PROPAGATION_DELAY_SCOPE" "G"
					( Parent
						( matchGroupRef "@crescent_city_bb_fab1_lib.crescent_city_bb_fab1(sch_1):\MG_DQ_FAR_DIMM_NG_M_D_BYTE7\" )
					)
					( Origin gBackEnd )
				)
				( attribute "RELATIVE_PROPAGATION_DELAY" "TARGET,TARGET"
					( Parent
						( matchGroupRef "@crescent_city_bb_fab1_lib.crescent_city_bb_fab1(sch_1):\MG_DQ_FAR_DIMM_NG_M_D_BYTE7\" )
					)
					( Units "uMatchProp" "ns" 1.000000)
					( Origin gBackEnd )
				)
			)
			( pinPair "@baseboard_fab2_lib.baseboard_fab2(sch_1):\PP4522\"
				( pinRef "@baseboard_fab2_lib.baseboard_fab2(sch_1):page26_i172:DDR3_DQ(58)" )
				( pinRef "@baseboard_fab2_lib.baseboard_fab2(sch_1):page50_i158:DQ(58)" )
				( attribute "RELATIVE_PROPAGATION_DELAY_SCOPE" "G"
					( Parent
						( matchGroupRef "@baseboard_fab2_lib.baseboard_fab2(sch_1):\MG_DQ-DQS_NEAR_DIMM_NG_M_D_BYTE7\" )
					)
					( Status sCSetFlattened )
					( Origin gBackEnd )
				)
				( attribute "RELATIVE_PROPAGATION_DELAY" "0.00 MIL,195.00 MIL"
					( Parent
						( matchGroupRef "@baseboard_fab2_lib.baseboard_fab2(sch_1):\MG_DQ-DQS_NEAR_DIMM_NG_M_D_BYTE7\" )
					)
					( Units "uMatchProp" "ns" 1.000000)
					( Status sCSetFlattened )
					( Origin gBackEnd )
				)
				( attribute "RELATIVE_PROPAGATION_DELAY_SCOPE" "G"
					( Parent
						( matchGroupRef "@crescent_city_bb_fab1_lib.crescent_city_bb_fab1(sch_1):\MG_DQ_NEAR_DIMM_NG_M_D_BYTE7\" )
					)
					( Status sCSetFlattened )
					( Origin gBackEnd )
				)
				( attribute "RELATIVE_PROPAGATION_DELAY" "-50.00 MIL,50.00 MIL"
					( Parent
						( matchGroupRef "@crescent_city_bb_fab1_lib.crescent_city_bb_fab1(sch_1):\MG_DQ_NEAR_DIMM_NG_M_D_BYTE7\" )
					)
					( Units "uMatchProp" "ns" 1.000000)
					( Status sCSetFlattened )
					( Origin gBackEnd )
				)
			)
			( pinPair "@baseboard_fab2_lib.baseboard_fab2(sch_1):\PP4524\"
				( pinRef "@baseboard_fab2_lib.baseboard_fab2(sch_1):page26_i172:DDR3_DQ(59)" )
				( pinRef "@baseboard_fab2_lib.baseboard_fab2(sch_1):page49_i111:DQ(58)" )
				( attribute "RELATIVE_PROPAGATION_DELAY_SCOPE" "G"
					( Parent
						( matchGroupRef "@baseboard_fab2_lib.baseboard_fab2(sch_1):\MG_DQ-DQS_FAR_DIMM_NG_M_D_BYTE7\" )
					)
					( Status sCSetFlattened )
					( Origin gBackEnd )
				)
				( attribute "RELATIVE_PROPAGATION_DELAY" "0.00 MIL,195.00 MIL"
					( Parent
						( matchGroupRef "@baseboard_fab2_lib.baseboard_fab2(sch_1):\MG_DQ-DQS_FAR_DIMM_NG_M_D_BYTE7\" )
					)
					( Units "uMatchProp" "ns" 1.000000)
					( Status sCSetFlattened )
					( Origin gBackEnd )
				)
				( attribute "RELATIVE_PROPAGATION_DELAY_SCOPE" "G"
					( Parent
						( matchGroupRef "@crescent_city_bb_fab1_lib.crescent_city_bb_fab1(sch_1):\MG_DQ_FAR_DIMM_NG_M_D_BYTE7\" )
					)
					( Status sCSetFlattened )
					( Origin gBackEnd )
				)
				( attribute "RELATIVE_PROPAGATION_DELAY" "-50.00 MIL,50.00 MIL"
					( Parent
						( matchGroupRef "@crescent_city_bb_fab1_lib.crescent_city_bb_fab1(sch_1):\MG_DQ_FAR_DIMM_NG_M_D_BYTE7\" )
					)
					( Units "uMatchProp" "ns" 1.000000)
					( Status sCSetFlattened )
					( Origin gBackEnd )
				)
			)
			( pinPair "@baseboard_fab2_lib.baseboard_fab2(sch_1):\PP4525\"
				( pinRef "@baseboard_fab2_lib.baseboard_fab2(sch_1):page26_i172:DDR3_DQ(59)" )
				( pinRef "@baseboard_fab2_lib.baseboard_fab2(sch_1):page50_i158:DQ(59)" )
				( attribute "RELATIVE_PROPAGATION_DELAY_SCOPE" "G"
					( Parent
						( matchGroupRef "@baseboard_fab2_lib.baseboard_fab2(sch_1):\MG_DQ-DQS_NEAR_DIMM_NG_M_D_BYTE7\" )
					)
					( Status sCSetFlattened )
					( Origin gBackEnd )
				)
				( attribute "RELATIVE_PROPAGATION_DELAY" "0.00 MIL,195.00 MIL"
					( Parent
						( matchGroupRef "@baseboard_fab2_lib.baseboard_fab2(sch_1):\MG_DQ-DQS_NEAR_DIMM_NG_M_D_BYTE7\" )
					)
					( Units "uMatchProp" "ns" 1.000000)
					( Status sCSetFlattened )
					( Origin gBackEnd )
				)
				( attribute "RELATIVE_PROPAGATION_DELAY_SCOPE" "G"
					( Parent
						( matchGroupRef "@crescent_city_bb_fab1_lib.crescent_city_bb_fab1(sch_1):\MG_DQ_NEAR_DIMM_NG_M_D_BYTE7\" )
					)
					( Status sCSetFlattened )
					( Origin gBackEnd )
				)
				( attribute "RELATIVE_PROPAGATION_DELAY" "-50.00 MIL,50.00 MIL"
					( Parent
						( matchGroupRef "@crescent_city_bb_fab1_lib.crescent_city_bb_fab1(sch_1):\MG_DQ_NEAR_DIMM_NG_M_D_BYTE7\" )
					)
					( Units "uMatchProp" "ns" 1.000000)
					( Status sCSetFlattened )
					( Origin gBackEnd )
				)
			)
			( pinPair "@baseboard_fab2_lib.baseboard_fab2(sch_1):\PP4527\"
				( pinRef "@baseboard_fab2_lib.baseboard_fab2(sch_1):page26_i172:DDR3_DQ(60)" )
				( pinRef "@baseboard_fab2_lib.baseboard_fab2(sch_1):page49_i111:DQ(61)" )
				( attribute "RELATIVE_PROPAGATION_DELAY_SCOPE" "G"
					( Parent
						( matchGroupRef "@baseboard_fab2_lib.baseboard_fab2(sch_1):\MG_DQ-DQS_FAR_DIMM_NG_M_D_BYTE7\" )
					)
					( Status sCSetFlattened )
					( Origin gBackEnd )
				)
				( attribute "RELATIVE_PROPAGATION_DELAY" "0.00 MIL,195.00 MIL"
					( Parent
						( matchGroupRef "@baseboard_fab2_lib.baseboard_fab2(sch_1):\MG_DQ-DQS_FAR_DIMM_NG_M_D_BYTE7\" )
					)
					( Units "uMatchProp" "ns" 1.000000)
					( Status sCSetFlattened )
					( Origin gBackEnd )
				)
				( attribute "RELATIVE_PROPAGATION_DELAY_SCOPE" "G"
					( Parent
						( matchGroupRef "@crescent_city_bb_fab1_lib.crescent_city_bb_fab1(sch_1):\MG_DQ_FAR_DIMM_NG_M_D_BYTE7\" )
					)
					( Status sCSetFlattened )
					( Origin gBackEnd )
				)
				( attribute "RELATIVE_PROPAGATION_DELAY" "-50.00 MIL,50.00 MIL"
					( Parent
						( matchGroupRef "@crescent_city_bb_fab1_lib.crescent_city_bb_fab1(sch_1):\MG_DQ_FAR_DIMM_NG_M_D_BYTE7\" )
					)
					( Units "uMatchProp" "ns" 1.000000)
					( Status sCSetFlattened )
					( Origin gBackEnd )
				)
			)
			( pinPair "@baseboard_fab2_lib.baseboard_fab2(sch_1):\PP4529\"
				( pinRef "@baseboard_fab2_lib.baseboard_fab2(sch_1):page26_i172:DDR3_DQ(60)" )
				( pinRef "@baseboard_fab2_lib.baseboard_fab2(sch_1):page50_i158:DQ(60)" )
				( attribute "RELATIVE_PROPAGATION_DELAY_SCOPE" "G"
					( Parent
						( matchGroupRef "@baseboard_fab2_lib.baseboard_fab2(sch_1):\MG_DQ-DQS_NEAR_DIMM_NG_M_D_BYTE7\" )
					)
					( Status sCSetFlattened )
					( Origin gBackEnd )
				)
				( attribute "RELATIVE_PROPAGATION_DELAY" "0.00 MIL,195.00 MIL"
					( Parent
						( matchGroupRef "@baseboard_fab2_lib.baseboard_fab2(sch_1):\MG_DQ-DQS_NEAR_DIMM_NG_M_D_BYTE7\" )
					)
					( Units "uMatchProp" "ns" 1.000000)
					( Status sCSetFlattened )
					( Origin gBackEnd )
				)
				( attribute "RELATIVE_PROPAGATION_DELAY_SCOPE" "G"
					( Parent
						( matchGroupRef "@crescent_city_bb_fab1_lib.crescent_city_bb_fab1(sch_1):\MG_DQ_NEAR_DIMM_NG_M_D_BYTE7\" )
					)
					( Status sCSetFlattened )
					( Origin gBackEnd )
				)
				( attribute "RELATIVE_PROPAGATION_DELAY" "-50.00 MIL,50.00 MIL"
					( Parent
						( matchGroupRef "@crescent_city_bb_fab1_lib.crescent_city_bb_fab1(sch_1):\MG_DQ_NEAR_DIMM_NG_M_D_BYTE7\" )
					)
					( Units "uMatchProp" "ns" 1.000000)
					( Status sCSetFlattened )
					( Origin gBackEnd )
				)
			)
			( pinPair "@baseboard_fab2_lib.baseboard_fab2(sch_1):\PP4530\"
				( pinRef "@baseboard_fab2_lib.baseboard_fab2(sch_1):page26_i172:DDR3_DQ(61)" )
				( pinRef "@baseboard_fab2_lib.baseboard_fab2(sch_1):page49_i111:DQ(60)" )
				( attribute "RELATIVE_PROPAGATION_DELAY_SCOPE" "G"
					( Parent
						( matchGroupRef "@baseboard_fab2_lib.baseboard_fab2(sch_1):\MG_DQ-DQS_FAR_DIMM_NG_M_D_BYTE7\" )
					)
					( Status sCSetFlattened )
					( Origin gBackEnd )
				)
				( attribute "RELATIVE_PROPAGATION_DELAY" "0.00 MIL,195.00 MIL"
					( Parent
						( matchGroupRef "@baseboard_fab2_lib.baseboard_fab2(sch_1):\MG_DQ-DQS_FAR_DIMM_NG_M_D_BYTE7\" )
					)
					( Units "uMatchProp" "ns" 1.000000)
					( Status sCSetFlattened )
					( Origin gBackEnd )
				)
				( attribute "RELATIVE_PROPAGATION_DELAY_SCOPE" "G"
					( Parent
						( matchGroupRef "@crescent_city_bb_fab1_lib.crescent_city_bb_fab1(sch_1):\MG_DQ_FAR_DIMM_NG_M_D_BYTE7\" )
					)
					( Status sCSetFlattened )
					( Origin gBackEnd )
				)
				( attribute "RELATIVE_PROPAGATION_DELAY" "-50.00 MIL,50.00 MIL"
					( Parent
						( matchGroupRef "@crescent_city_bb_fab1_lib.crescent_city_bb_fab1(sch_1):\MG_DQ_FAR_DIMM_NG_M_D_BYTE7\" )
					)
					( Units "uMatchProp" "ns" 1.000000)
					( Status sCSetFlattened )
					( Origin gBackEnd )
				)
			)
			( pinPair "@baseboard_fab2_lib.baseboard_fab2(sch_1):\PP4532\"
				( pinRef "@baseboard_fab2_lib.baseboard_fab2(sch_1):page26_i172:DDR3_DQ(61)" )
				( pinRef "@baseboard_fab2_lib.baseboard_fab2(sch_1):page50_i158:DQ(61)" )
				( attribute "RELATIVE_PROPAGATION_DELAY_SCOPE" "G"
					( Parent
						( matchGroupRef "@baseboard_fab2_lib.baseboard_fab2(sch_1):\MG_DQ-DQS_NEAR_DIMM_NG_M_D_BYTE7\" )
					)
					( Status sCSetFlattened )
					( Origin gBackEnd )
				)
				( attribute "RELATIVE_PROPAGATION_DELAY" "0.00 MIL,195.00 MIL"
					( Parent
						( matchGroupRef "@baseboard_fab2_lib.baseboard_fab2(sch_1):\MG_DQ-DQS_NEAR_DIMM_NG_M_D_BYTE7\" )
					)
					( Units "uMatchProp" "ns" 1.000000)
					( Status sCSetFlattened )
					( Origin gBackEnd )
				)
				( attribute "RELATIVE_PROPAGATION_DELAY_SCOPE" "G"
					( Parent
						( matchGroupRef "@crescent_city_bb_fab1_lib.crescent_city_bb_fab1(sch_1):\MG_DQ_NEAR_DIMM_NG_M_D_BYTE7\" )
					)
					( Status sCSetFlattened )
					( Origin gBackEnd )
				)
				( attribute "RELATIVE_PROPAGATION_DELAY" "-50.00 MIL,50.00 MIL"
					( Parent
						( matchGroupRef "@crescent_city_bb_fab1_lib.crescent_city_bb_fab1(sch_1):\MG_DQ_NEAR_DIMM_NG_M_D_BYTE7\" )
					)
					( Units "uMatchProp" "ns" 1.000000)
					( Status sCSetFlattened )
					( Origin gBackEnd )
				)
			)
			( pinPair "@baseboard_fab2_lib.baseboard_fab2(sch_1):\PP4533\"
				( pinRef "@baseboard_fab2_lib.baseboard_fab2(sch_1):page26_i172:DDR3_DQ(62)" )
				( pinRef "@baseboard_fab2_lib.baseboard_fab2(sch_1):page49_i111:DQ(63)" )
				( attribute "RELATIVE_PROPAGATION_DELAY_SCOPE" "G"
					( Parent
						( matchGroupRef "@baseboard_fab2_lib.baseboard_fab2(sch_1):\MG_DQ-DQS_FAR_DIMM_NG_M_D_BYTE7\" )
					)
					( Status sCSetFlattened )
					( Origin gBackEnd )
				)
				( attribute "RELATIVE_PROPAGATION_DELAY" "0.00 MIL,195.00 MIL"
					( Parent
						( matchGroupRef "@baseboard_fab2_lib.baseboard_fab2(sch_1):\MG_DQ-DQS_FAR_DIMM_NG_M_D_BYTE7\" )
					)
					( Units "uMatchProp" "ns" 1.000000)
					( Status sCSetFlattened )
					( Origin gBackEnd )
				)
				( attribute "RELATIVE_PROPAGATION_DELAY_SCOPE" "G"
					( Parent
						( matchGroupRef "@crescent_city_bb_fab1_lib.crescent_city_bb_fab1(sch_1):\MG_DQ_FAR_DIMM_NG_M_D_BYTE7\" )
					)
					( Status sCSetFlattened )
					( Origin gBackEnd )
				)
				( attribute "RELATIVE_PROPAGATION_DELAY" "-50.00 MIL,50.00 MIL"
					( Parent
						( matchGroupRef "@crescent_city_bb_fab1_lib.crescent_city_bb_fab1(sch_1):\MG_DQ_FAR_DIMM_NG_M_D_BYTE7\" )
					)
					( Units "uMatchProp" "ns" 1.000000)
					( Status sCSetFlattened )
					( Origin gBackEnd )
				)
			)
			( pinPair "@baseboard_fab2_lib.baseboard_fab2(sch_1):\PP4535\"
				( pinRef "@baseboard_fab2_lib.baseboard_fab2(sch_1):page26_i172:DDR3_DQ(62)" )
				( pinRef "@baseboard_fab2_lib.baseboard_fab2(sch_1):page50_i158:DQ(62)" )
				( attribute "RELATIVE_PROPAGATION_DELAY_SCOPE" "G"
					( Parent
						( matchGroupRef "@baseboard_fab2_lib.baseboard_fab2(sch_1):\MG_DQ-DQS_NEAR_DIMM_NG_M_D_BYTE7\" )
					)
					( Status sCSetFlattened )
					( Origin gBackEnd )
				)
				( attribute "RELATIVE_PROPAGATION_DELAY" "0.00 MIL,195.00 MIL"
					( Parent
						( matchGroupRef "@baseboard_fab2_lib.baseboard_fab2(sch_1):\MG_DQ-DQS_NEAR_DIMM_NG_M_D_BYTE7\" )
					)
					( Units "uMatchProp" "ns" 1.000000)
					( Status sCSetFlattened )
					( Origin gBackEnd )
				)
				( attribute "RELATIVE_PROPAGATION_DELAY_SCOPE" "G"
					( Parent
						( matchGroupRef "@crescent_city_bb_fab1_lib.crescent_city_bb_fab1(sch_1):\MG_DQ_NEAR_DIMM_NG_M_D_BYTE7\" )
					)
					( Status sCSetFlattened )
					( Origin gBackEnd )
				)
				( attribute "RELATIVE_PROPAGATION_DELAY" "-50.00 MIL,50.00 MIL"
					( Parent
						( matchGroupRef "@crescent_city_bb_fab1_lib.crescent_city_bb_fab1(sch_1):\MG_DQ_NEAR_DIMM_NG_M_D_BYTE7\" )
					)
					( Units "uMatchProp" "ns" 1.000000)
					( Status sCSetFlattened )
					( Origin gBackEnd )
				)
			)
			( pinPair "@baseboard_fab2_lib.baseboard_fab2(sch_1):\PP4536\"
				( pinRef "@baseboard_fab2_lib.baseboard_fab2(sch_1):page26_i172:DDR3_DQ(63)" )
				( pinRef "@baseboard_fab2_lib.baseboard_fab2(sch_1):page49_i111:DQ(62)" )
				( attribute "RELATIVE_PROPAGATION_DELAY_SCOPE" "G"
					( Parent
						( matchGroupRef "@baseboard_fab2_lib.baseboard_fab2(sch_1):\MG_DQ-DQS_FAR_DIMM_NG_M_D_BYTE7\" )
					)
					( Status sCSetFlattened )
					( Origin gBackEnd )
				)
				( attribute "RELATIVE_PROPAGATION_DELAY" "0.00 MIL,195.00 MIL"
					( Parent
						( matchGroupRef "@baseboard_fab2_lib.baseboard_fab2(sch_1):\MG_DQ-DQS_FAR_DIMM_NG_M_D_BYTE7\" )
					)
					( Units "uMatchProp" "ns" 1.000000)
					( Status sCSetFlattened )
					( Origin gBackEnd )
				)
				( attribute "RELATIVE_PROPAGATION_DELAY_SCOPE" "G"
					( Parent
						( matchGroupRef "@crescent_city_bb_fab1_lib.crescent_city_bb_fab1(sch_1):\MG_DQ_FAR_DIMM_NG_M_D_BYTE7\" )
					)
					( Status sCSetFlattened )
					( Origin gBackEnd )
				)
				( attribute "RELATIVE_PROPAGATION_DELAY" "-50.00 MIL,50.00 MIL"
					( Parent
						( matchGroupRef "@crescent_city_bb_fab1_lib.crescent_city_bb_fab1(sch_1):\MG_DQ_FAR_DIMM_NG_M_D_BYTE7\" )
					)
					( Units "uMatchProp" "ns" 1.000000)
					( Status sCSetFlattened )
					( Origin gBackEnd )
				)
			)
			( pinPair "@baseboard_fab2_lib.baseboard_fab2(sch_1):\PP4538\"
				( pinRef "@baseboard_fab2_lib.baseboard_fab2(sch_1):page26_i172:DDR3_DQ(63)" )
				( pinRef "@baseboard_fab2_lib.baseboard_fab2(sch_1):page50_i158:DQ(63)" )
				( attribute "RELATIVE_PROPAGATION_DELAY_SCOPE" "G"
					( Parent
						( matchGroupRef "@baseboard_fab2_lib.baseboard_fab2(sch_1):\MG_DQ-DQS_NEAR_DIMM_NG_M_D_BYTE7\" )
					)
					( Status sCSetFlattened )
					( Origin gBackEnd )
				)
				( attribute "RELATIVE_PROPAGATION_DELAY" "0.00 MIL,195.00 MIL"
					( Parent
						( matchGroupRef "@baseboard_fab2_lib.baseboard_fab2(sch_1):\MG_DQ-DQS_NEAR_DIMM_NG_M_D_BYTE7\" )
					)
					( Units "uMatchProp" "ns" 1.000000)
					( Status sCSetFlattened )
					( Origin gBackEnd )
				)
				( attribute "RELATIVE_PROPAGATION_DELAY_SCOPE" "G"
					( Parent
						( matchGroupRef "@crescent_city_bb_fab1_lib.crescent_city_bb_fab1(sch_1):\MG_DQ_NEAR_DIMM_NG_M_D_BYTE7\" )
					)
					( Status sCSetFlattened )
					( Origin gBackEnd )
				)
				( attribute "RELATIVE_PROPAGATION_DELAY" "-50.00 MIL,50.00 MIL"
					( Parent
						( matchGroupRef "@crescent_city_bb_fab1_lib.crescent_city_bb_fab1(sch_1):\MG_DQ_NEAR_DIMM_NG_M_D_BYTE7\" )
					)
					( Units "uMatchProp" "ns" 1.000000)
					( Status sCSetFlattened )
					( Origin gBackEnd )
				)
			)
			( pinPair "@baseboard_fab2_lib.baseboard_fab2(sch_1):\PP4467\"
				( pinRef "@baseboard_fab2_lib.baseboard_fab2(sch_1):page27_i172:DDR4_DQ(0)" )
				( pinRef "@baseboard_fab2_lib.baseboard_fab2(sch_1):page51_i111:DQ(1)" )
				( attribute "RELATIVE_PROPAGATION_DELAY_SCOPE" "G"
					( Parent
						( matchGroupRef "@baseboard_fab2_lib.baseboard_fab2(sch_1):\MG_DQ-DQS_FAR_DIMM_NG_M_E_BYTE0\" )
					)
					( Status sCSetFlattened )
					( Origin gBackEnd )
				)
				( attribute "RELATIVE_PROPAGATION_DELAY" "0.00 MIL,195.00 MIL"
					( Parent
						( matchGroupRef "@baseboard_fab2_lib.baseboard_fab2(sch_1):\MG_DQ-DQS_FAR_DIMM_NG_M_E_BYTE0\" )
					)
					( Units "uMatchProp" "ns" 1.000000)
					( Status sCSetFlattened )
					( Origin gBackEnd )
				)
				( attribute "RELATIVE_PROPAGATION_DELAY_SCOPE" "G"
					( Parent
						( matchGroupRef "@crescent_city_bb_fab1_lib.crescent_city_bb_fab1(sch_1):\MG_DQ_FAR_DIMM_NG_M_E_BYTE0\" )
					)
					( Status sCSetFlattened )
					( Origin gBackEnd )
				)
				( attribute "RELATIVE_PROPAGATION_DELAY" "-50.00 MIL,50.00 MIL"
					( Parent
						( matchGroupRef "@crescent_city_bb_fab1_lib.crescent_city_bb_fab1(sch_1):\MG_DQ_FAR_DIMM_NG_M_E_BYTE0\" )
					)
					( Units "uMatchProp" "ns" 1.000000)
					( Status sCSetFlattened )
					( Origin gBackEnd )
				)
			)
			( pinPair "@baseboard_fab2_lib.baseboard_fab2(sch_1):\PP4469\"
				( pinRef "@baseboard_fab2_lib.baseboard_fab2(sch_1):page27_i172:DDR4_DQ(0)" )
				( pinRef "@baseboard_fab2_lib.baseboard_fab2(sch_1):page52_i12:DQ(0)" )
				( attribute "RELATIVE_PROPAGATION_DELAY_SCOPE" "G"
					( Parent
						( matchGroupRef "@baseboard_fab2_lib.baseboard_fab2(sch_1):\MG_DQ-DQS_NEAR_DIMM_NG_M_E_BYTE0\" )
					)
					( Status sCSetFlattened )
					( Origin gBackEnd )
				)
				( attribute "RELATIVE_PROPAGATION_DELAY" "0.00 MIL,195.00 MIL"
					( Parent
						( matchGroupRef "@baseboard_fab2_lib.baseboard_fab2(sch_1):\MG_DQ-DQS_NEAR_DIMM_NG_M_E_BYTE0\" )
					)
					( Units "uMatchProp" "ns" 1.000000)
					( Status sCSetFlattened )
					( Origin gBackEnd )
				)
				( attribute "RELATIVE_PROPAGATION_DELAY_SCOPE" "G"
					( Parent
						( matchGroupRef "@crescent_city_bb_fab1_lib.crescent_city_bb_fab1(sch_1):\MG_DQ_NEAR_DIMM_NG_M_E_BYTE0\" )
					)
					( Status sCSetFlattened )
					( Origin gBackEnd )
				)
				( attribute "RELATIVE_PROPAGATION_DELAY" "-50.00 MIL,50.00 MIL"
					( Parent
						( matchGroupRef "@crescent_city_bb_fab1_lib.crescent_city_bb_fab1(sch_1):\MG_DQ_NEAR_DIMM_NG_M_E_BYTE0\" )
					)
					( Units "uMatchProp" "ns" 1.000000)
					( Status sCSetFlattened )
					( Origin gBackEnd )
				)
			)
			( pinPair "@baseboard_fab2_lib.baseboard_fab2(sch_1):\PP4470\"
				( pinRef "@baseboard_fab2_lib.baseboard_fab2(sch_1):page27_i172:DDR4_DQ(1)" )
				( pinRef "@baseboard_fab2_lib.baseboard_fab2(sch_1):page51_i111:DQ(0)" )
				( attribute "RELATIVE_PROPAGATION_DELAY_SCOPE" "G"
					( Parent
						( matchGroupRef "@baseboard_fab2_lib.baseboard_fab2(sch_1):\MG_DQ-DQS_FAR_DIMM_NG_M_E_BYTE0\" )
					)
					( Status sCSetFlattened )
					( Origin gBackEnd )
				)
				( attribute "RELATIVE_PROPAGATION_DELAY" "0.00 MIL,195.00 MIL"
					( Parent
						( matchGroupRef "@baseboard_fab2_lib.baseboard_fab2(sch_1):\MG_DQ-DQS_FAR_DIMM_NG_M_E_BYTE0\" )
					)
					( Units "uMatchProp" "ns" 1.000000)
					( Status sCSetFlattened )
					( Origin gBackEnd )
				)
				( attribute "RELATIVE_PROPAGATION_DELAY_SCOPE" "G"
					( Parent
						( matchGroupRef "@crescent_city_bb_fab1_lib.crescent_city_bb_fab1(sch_1):\MG_DQ_FAR_DIMM_NG_M_E_BYTE0\" )
					)
					( Status sCSetFlattened )
					( Origin gBackEnd )
				)
				( attribute "RELATIVE_PROPAGATION_DELAY" "-50.00 MIL,50.00 MIL"
					( Parent
						( matchGroupRef "@crescent_city_bb_fab1_lib.crescent_city_bb_fab1(sch_1):\MG_DQ_FAR_DIMM_NG_M_E_BYTE0\" )
					)
					( Units "uMatchProp" "ns" 1.000000)
					( Status sCSetFlattened )
					( Origin gBackEnd )
				)
			)
			( pinPair "@baseboard_fab2_lib.baseboard_fab2(sch_1):\PP4472\"
				( pinRef "@baseboard_fab2_lib.baseboard_fab2(sch_1):page27_i172:DDR4_DQ(1)" )
				( pinRef "@baseboard_fab2_lib.baseboard_fab2(sch_1):page52_i12:DQ(1)" )
				( attribute "RELATIVE_PROPAGATION_DELAY_SCOPE" "G"
					( Parent
						( matchGroupRef "@baseboard_fab2_lib.baseboard_fab2(sch_1):\MG_DQ-DQS_NEAR_DIMM_NG_M_E_BYTE0\" )
					)
					( Status sCSetFlattened )
					( Origin gBackEnd )
				)
				( attribute "RELATIVE_PROPAGATION_DELAY" "0.00 MIL,195.00 MIL"
					( Parent
						( matchGroupRef "@baseboard_fab2_lib.baseboard_fab2(sch_1):\MG_DQ-DQS_NEAR_DIMM_NG_M_E_BYTE0\" )
					)
					( Units "uMatchProp" "ns" 1.000000)
					( Status sCSetFlattened )
					( Origin gBackEnd )
				)
				( attribute "RELATIVE_PROPAGATION_DELAY_SCOPE" "G"
					( Parent
						( matchGroupRef "@crescent_city_bb_fab1_lib.crescent_city_bb_fab1(sch_1):\MG_DQ_NEAR_DIMM_NG_M_E_BYTE0\" )
					)
					( Status sCSetFlattened )
					( Origin gBackEnd )
				)
				( attribute "RELATIVE_PROPAGATION_DELAY" "-50.00 MIL,50.00 MIL"
					( Parent
						( matchGroupRef "@crescent_city_bb_fab1_lib.crescent_city_bb_fab1(sch_1):\MG_DQ_NEAR_DIMM_NG_M_E_BYTE0\" )
					)
					( Units "uMatchProp" "ns" 1.000000)
					( Status sCSetFlattened )
					( Origin gBackEnd )
				)
			)
			( pinPair "@baseboard_fab2_lib.baseboard_fab2(sch_1):\PP4473\"
				( pinRef "@baseboard_fab2_lib.baseboard_fab2(sch_1):page27_i172:DDR4_DQ(2)" )
				( pinRef "@baseboard_fab2_lib.baseboard_fab2(sch_1):page51_i111:DQ(3)" )
				( attribute "RELATIVE_PROPAGATION_DELAY_SCOPE" "G"
					( Parent
						( matchGroupRef "@baseboard_fab2_lib.baseboard_fab2(sch_1):\MG_DQ-DQS_FAR_DIMM_NG_M_E_BYTE0\" )
					)
					( Status sCSetFlattened )
					( Origin gBackEnd )
				)
				( attribute "RELATIVE_PROPAGATION_DELAY" "0.00 MIL,195.00 MIL"
					( Parent
						( matchGroupRef "@baseboard_fab2_lib.baseboard_fab2(sch_1):\MG_DQ-DQS_FAR_DIMM_NG_M_E_BYTE0\" )
					)
					( Units "uMatchProp" "ns" 1.000000)
					( Status sCSetFlattened )
					( Origin gBackEnd )
				)
				( attribute "RELATIVE_PROPAGATION_DELAY_SCOPE" "G"
					( Parent
						( matchGroupRef "@crescent_city_bb_fab1_lib.crescent_city_bb_fab1(sch_1):\MG_DQ_FAR_DIMM_NG_M_E_BYTE0\" )
					)
					( Status sCSetFlattened )
					( Origin gBackEnd )
				)
				( attribute "RELATIVE_PROPAGATION_DELAY" "-50.00 MIL,50.00 MIL"
					( Parent
						( matchGroupRef "@crescent_city_bb_fab1_lib.crescent_city_bb_fab1(sch_1):\MG_DQ_FAR_DIMM_NG_M_E_BYTE0\" )
					)
					( Units "uMatchProp" "ns" 1.000000)
					( Status sCSetFlattened )
					( Origin gBackEnd )
				)
			)
			( pinPair "@baseboard_fab2_lib.baseboard_fab2(sch_1):\PP4475\"
				( pinRef "@baseboard_fab2_lib.baseboard_fab2(sch_1):page27_i172:DDR4_DQ(2)" )
				( pinRef "@baseboard_fab2_lib.baseboard_fab2(sch_1):page52_i12:DQ(2)" )
				( attribute "RELATIVE_PROPAGATION_DELAY_SCOPE" "G"
					( Parent
						( matchGroupRef "@baseboard_fab2_lib.baseboard_fab2(sch_1):\MG_DQ-DQS_NEAR_DIMM_NG_M_E_BYTE0\" )
					)
					( Status sCSetFlattened )
					( Origin gBackEnd )
				)
				( attribute "RELATIVE_PROPAGATION_DELAY" "0.00 MIL,195.00 MIL"
					( Parent
						( matchGroupRef "@baseboard_fab2_lib.baseboard_fab2(sch_1):\MG_DQ-DQS_NEAR_DIMM_NG_M_E_BYTE0\" )
					)
					( Units "uMatchProp" "ns" 1.000000)
					( Status sCSetFlattened )
					( Origin gBackEnd )
				)
				( attribute "RELATIVE_PROPAGATION_DELAY_SCOPE" "G"
					( Parent
						( matchGroupRef "@crescent_city_bb_fab1_lib.crescent_city_bb_fab1(sch_1):\MG_DQ_NEAR_DIMM_NG_M_E_BYTE0\" )
					)
					( Status sCSetFlattened )
					( Origin gBackEnd )
				)
				( attribute "RELATIVE_PROPAGATION_DELAY" "-50.00 MIL,50.00 MIL"
					( Parent
						( matchGroupRef "@crescent_city_bb_fab1_lib.crescent_city_bb_fab1(sch_1):\MG_DQ_NEAR_DIMM_NG_M_E_BYTE0\" )
					)
					( Units "uMatchProp" "ns" 1.000000)
					( Status sCSetFlattened )
					( Origin gBackEnd )
				)
			)
			( pinPair "@baseboard_fab2_lib.baseboard_fab2(sch_1):\PP4476\"
				( pinRef "@baseboard_fab2_lib.baseboard_fab2(sch_1):page27_i172:DDR4_DQ(3)" )
				( pinRef "@baseboard_fab2_lib.baseboard_fab2(sch_1):page51_i111:DQ(2)" )
				( attribute "RELATIVE_PROPAGATION_DELAY_SCOPE" "G"
					( Parent
						( matchGroupRef "@baseboard_fab2_lib.baseboard_fab2(sch_1):\MG_DQ-DQS_FAR_DIMM_NG_M_E_BYTE0\" )
					)
					( Status sCSetFlattened )
					( Origin gBackEnd )
				)
				( attribute "RELATIVE_PROPAGATION_DELAY" "0.00 MIL,195.00 MIL"
					( Parent
						( matchGroupRef "@baseboard_fab2_lib.baseboard_fab2(sch_1):\MG_DQ-DQS_FAR_DIMM_NG_M_E_BYTE0\" )
					)
					( Units "uMatchProp" "ns" 1.000000)
					( Status sCSetFlattened )
					( Origin gBackEnd )
				)
				( attribute "RELATIVE_PROPAGATION_DELAY_SCOPE" "G"
					( Parent
						( matchGroupRef "@crescent_city_bb_fab1_lib.crescent_city_bb_fab1(sch_1):\MG_DQ_FAR_DIMM_NG_M_E_BYTE0\" )
					)
					( Status sCSetFlattened )
					( Origin gBackEnd )
				)
				( attribute "RELATIVE_PROPAGATION_DELAY" "-50.00 MIL,50.00 MIL"
					( Parent
						( matchGroupRef "@crescent_city_bb_fab1_lib.crescent_city_bb_fab1(sch_1):\MG_DQ_FAR_DIMM_NG_M_E_BYTE0\" )
					)
					( Units "uMatchProp" "ns" 1.000000)
					( Status sCSetFlattened )
					( Origin gBackEnd )
				)
			)
			( pinPair "@baseboard_fab2_lib.baseboard_fab2(sch_1):\PP4478\"
				( pinRef "@baseboard_fab2_lib.baseboard_fab2(sch_1):page52_i12:DQ(3)" )
				( pinRef "@baseboard_fab2_lib.baseboard_fab2(sch_1):page27_i172:DDR4_DQ(3)" )
				( attribute "RELATIVE_PROPAGATION_DELAY_SCOPE" "G"
					( Parent
						( matchGroupRef "@baseboard_fab2_lib.baseboard_fab2(sch_1):\MG_DQ-DQS_NEAR_DIMM_NG_M_E_BYTE0\" )
					)
					( Status sCSetFlattened )
					( Origin gBackEnd )
				)
				( attribute "RELATIVE_PROPAGATION_DELAY" "0.00 MIL,195.00 MIL"
					( Parent
						( matchGroupRef "@baseboard_fab2_lib.baseboard_fab2(sch_1):\MG_DQ-DQS_NEAR_DIMM_NG_M_E_BYTE0\" )
					)
					( Units "uMatchProp" "ns" 1.000000)
					( Status sCSetFlattened )
					( Origin gBackEnd )
				)
				( attribute "RELATIVE_PROPAGATION_DELAY_SCOPE" "G"
					( Parent
						( matchGroupRef "@crescent_city_bb_fab1_lib.crescent_city_bb_fab1(sch_1):\MG_DQ_NEAR_DIMM_NG_M_E_BYTE0\" )
					)
					( Status sCSetFlattened )
					( Origin gBackEnd )
				)
				( attribute "RELATIVE_PROPAGATION_DELAY" "-50.00 MIL,50.00 MIL"
					( Parent
						( matchGroupRef "@crescent_city_bb_fab1_lib.crescent_city_bb_fab1(sch_1):\MG_DQ_NEAR_DIMM_NG_M_E_BYTE0\" )
					)
					( Units "uMatchProp" "ns" 1.000000)
					( Status sCSetFlattened )
					( Origin gBackEnd )
				)
			)
			( pinPair "@baseboard_fab2_lib.baseboard_fab2(sch_1):\PP4479\"
				( pinRef "@baseboard_fab2_lib.baseboard_fab2(sch_1):page27_i172:DDR4_DQ(4)" )
				( pinRef "@baseboard_fab2_lib.baseboard_fab2(sch_1):page51_i111:DQ(5)" )
				( attribute "RELATIVE_PROPAGATION_DELAY_SCOPE" "G"
					( Parent
						( matchGroupRef "@baseboard_fab2_lib.baseboard_fab2(sch_1):\MG_DQ-DQS_FAR_DIMM_NG_M_E_BYTE0\" )
					)
					( Status sCSetFlattened )
					( Origin gBackEnd )
				)
				( attribute "RELATIVE_PROPAGATION_DELAY" "0.00 MIL,195.00 MIL"
					( Parent
						( matchGroupRef "@baseboard_fab2_lib.baseboard_fab2(sch_1):\MG_DQ-DQS_FAR_DIMM_NG_M_E_BYTE0\" )
					)
					( Units "uMatchProp" "ns" 1.000000)
					( Status sCSetFlattened )
					( Origin gBackEnd )
				)
				( attribute "RELATIVE_PROPAGATION_DELAY_SCOPE" "G"
					( Parent
						( matchGroupRef "@crescent_city_bb_fab1_lib.crescent_city_bb_fab1(sch_1):\MG_DQ_FAR_DIMM_NG_M_E_BYTE0\" )
					)
					( Origin gBackEnd )
				)
				( attribute "RELATIVE_PROPAGATION_DELAY" "TARGET,TARGET"
					( Parent
						( matchGroupRef "@crescent_city_bb_fab1_lib.crescent_city_bb_fab1(sch_1):\MG_DQ_FAR_DIMM_NG_M_E_BYTE0\" )
					)
					( Units "uMatchProp" "ns" 1.000000)
					( Origin gBackEnd )
				)
			)
			( pinPair "@baseboard_fab2_lib.baseboard_fab2(sch_1):\PP4481\"
				( pinRef "@baseboard_fab2_lib.baseboard_fab2(sch_1):page27_i172:DDR4_DQ(4)" )
				( pinRef "@baseboard_fab2_lib.baseboard_fab2(sch_1):page52_i12:DQ(4)" )
				( attribute "RELATIVE_PROPAGATION_DELAY_SCOPE" "G"
					( Parent
						( matchGroupRef "@baseboard_fab2_lib.baseboard_fab2(sch_1):\MG_DQ-DQS_NEAR_DIMM_NG_M_E_BYTE0\" )
					)
					( Status sCSetFlattened )
					( Origin gBackEnd )
				)
				( attribute "RELATIVE_PROPAGATION_DELAY" "0.00 MIL,195.00 MIL"
					( Parent
						( matchGroupRef "@baseboard_fab2_lib.baseboard_fab2(sch_1):\MG_DQ-DQS_NEAR_DIMM_NG_M_E_BYTE0\" )
					)
					( Units "uMatchProp" "ns" 1.000000)
					( Status sCSetFlattened )
					( Origin gBackEnd )
				)
				( attribute "RELATIVE_PROPAGATION_DELAY_SCOPE" "G"
					( Parent
						( matchGroupRef "@crescent_city_bb_fab1_lib.crescent_city_bb_fab1(sch_1):\MG_DQ_NEAR_DIMM_NG_M_E_BYTE0\" )
					)
					( Origin gBackEnd )
				)
				( attribute "RELATIVE_PROPAGATION_DELAY" "TARGET,TARGET"
					( Parent
						( matchGroupRef "@crescent_city_bb_fab1_lib.crescent_city_bb_fab1(sch_1):\MG_DQ_NEAR_DIMM_NG_M_E_BYTE0\" )
					)
					( Units "uMatchProp" "ns" 1.000000)
					( Origin gBackEnd )
				)
			)
			( pinPair "@baseboard_fab2_lib.baseboard_fab2(sch_1):\PP4482\"
				( pinRef "@baseboard_fab2_lib.baseboard_fab2(sch_1):page27_i172:DDR4_DQ(5)" )
				( pinRef "@baseboard_fab2_lib.baseboard_fab2(sch_1):page51_i111:DQ(4)" )
				( attribute "RELATIVE_PROPAGATION_DELAY_SCOPE" "G"
					( Parent
						( matchGroupRef "@baseboard_fab2_lib.baseboard_fab2(sch_1):\MG_DQ-DQS_FAR_DIMM_NG_M_E_BYTE0\" )
					)
					( Status sCSetFlattened )
					( Origin gBackEnd )
				)
				( attribute "RELATIVE_PROPAGATION_DELAY" "0.00 MIL,195.00 MIL"
					( Parent
						( matchGroupRef "@baseboard_fab2_lib.baseboard_fab2(sch_1):\MG_DQ-DQS_FAR_DIMM_NG_M_E_BYTE0\" )
					)
					( Units "uMatchProp" "ns" 1.000000)
					( Status sCSetFlattened )
					( Origin gBackEnd )
				)
				( attribute "RELATIVE_PROPAGATION_DELAY_SCOPE" "G"
					( Parent
						( matchGroupRef "@crescent_city_bb_fab1_lib.crescent_city_bb_fab1(sch_1):\MG_DQ_FAR_DIMM_NG_M_E_BYTE0\" )
					)
					( Status sCSetFlattened )
					( Origin gBackEnd )
				)
				( attribute "RELATIVE_PROPAGATION_DELAY" "-50.00 MIL,50.00 MIL"
					( Parent
						( matchGroupRef "@crescent_city_bb_fab1_lib.crescent_city_bb_fab1(sch_1):\MG_DQ_FAR_DIMM_NG_M_E_BYTE0\" )
					)
					( Units "uMatchProp" "ns" 1.000000)
					( Status sCSetFlattened )
					( Origin gBackEnd )
				)
			)
			( pinPair "@baseboard_fab2_lib.baseboard_fab2(sch_1):\PP4484\"
				( pinRef "@baseboard_fab2_lib.baseboard_fab2(sch_1):page27_i172:DDR4_DQ(5)" )
				( pinRef "@baseboard_fab2_lib.baseboard_fab2(sch_1):page52_i12:DQ(5)" )
				( attribute "RELATIVE_PROPAGATION_DELAY_SCOPE" "G"
					( Parent
						( matchGroupRef "@baseboard_fab2_lib.baseboard_fab2(sch_1):\MG_DQ-DQS_NEAR_DIMM_NG_M_E_BYTE0\" )
					)
					( Status sCSetFlattened )
					( Origin gBackEnd )
				)
				( attribute "RELATIVE_PROPAGATION_DELAY" "0.00 MIL,195.00 MIL"
					( Parent
						( matchGroupRef "@baseboard_fab2_lib.baseboard_fab2(sch_1):\MG_DQ-DQS_NEAR_DIMM_NG_M_E_BYTE0\" )
					)
					( Units "uMatchProp" "ns" 1.000000)
					( Status sCSetFlattened )
					( Origin gBackEnd )
				)
				( attribute "RELATIVE_PROPAGATION_DELAY_SCOPE" "G"
					( Parent
						( matchGroupRef "@crescent_city_bb_fab1_lib.crescent_city_bb_fab1(sch_1):\MG_DQ_NEAR_DIMM_NG_M_E_BYTE0\" )
					)
					( Status sCSetFlattened )
					( Origin gBackEnd )
				)
				( attribute "RELATIVE_PROPAGATION_DELAY" "-50.00 MIL,50.00 MIL"
					( Parent
						( matchGroupRef "@crescent_city_bb_fab1_lib.crescent_city_bb_fab1(sch_1):\MG_DQ_NEAR_DIMM_NG_M_E_BYTE0\" )
					)
					( Units "uMatchProp" "ns" 1.000000)
					( Status sCSetFlattened )
					( Origin gBackEnd )
				)
			)
			( pinPair "@baseboard_fab2_lib.baseboard_fab2(sch_1):\PP4485\"
				( pinRef "@baseboard_fab2_lib.baseboard_fab2(sch_1):page27_i172:DDR4_DQ(6)" )
				( pinRef "@baseboard_fab2_lib.baseboard_fab2(sch_1):page51_i111:DQ(7)" )
				( attribute "RELATIVE_PROPAGATION_DELAY_SCOPE" "G"
					( Parent
						( matchGroupRef "@baseboard_fab2_lib.baseboard_fab2(sch_1):\MG_DQ-DQS_FAR_DIMM_NG_M_E_BYTE0\" )
					)
					( Status sCSetFlattened )
					( Origin gBackEnd )
				)
				( attribute "RELATIVE_PROPAGATION_DELAY" "0.00 MIL,195.00 MIL"
					( Parent
						( matchGroupRef "@baseboard_fab2_lib.baseboard_fab2(sch_1):\MG_DQ-DQS_FAR_DIMM_NG_M_E_BYTE0\" )
					)
					( Units "uMatchProp" "ns" 1.000000)
					( Status sCSetFlattened )
					( Origin gBackEnd )
				)
				( attribute "RELATIVE_PROPAGATION_DELAY_SCOPE" "G"
					( Parent
						( matchGroupRef "@crescent_city_bb_fab1_lib.crescent_city_bb_fab1(sch_1):\MG_DQ_FAR_DIMM_NG_M_E_BYTE0\" )
					)
					( Status sCSetFlattened )
					( Origin gBackEnd )
				)
				( attribute "RELATIVE_PROPAGATION_DELAY" "-50.00 MIL,50.00 MIL"
					( Parent
						( matchGroupRef "@crescent_city_bb_fab1_lib.crescent_city_bb_fab1(sch_1):\MG_DQ_FAR_DIMM_NG_M_E_BYTE0\" )
					)
					( Units "uMatchProp" "ns" 1.000000)
					( Status sCSetFlattened )
					( Origin gBackEnd )
				)
			)
			( pinPair "@baseboard_fab2_lib.baseboard_fab2(sch_1):\PP4487\"
				( pinRef "@baseboard_fab2_lib.baseboard_fab2(sch_1):page27_i172:DDR4_DQ(6)" )
				( pinRef "@baseboard_fab2_lib.baseboard_fab2(sch_1):page52_i12:DQ(6)" )
				( attribute "RELATIVE_PROPAGATION_DELAY_SCOPE" "G"
					( Parent
						( matchGroupRef "@baseboard_fab2_lib.baseboard_fab2(sch_1):\MG_DQ-DQS_NEAR_DIMM_NG_M_E_BYTE0\" )
					)
					( Status sCSetFlattened )
					( Origin gBackEnd )
				)
				( attribute "RELATIVE_PROPAGATION_DELAY" "0.00 MIL,195.00 MIL"
					( Parent
						( matchGroupRef "@baseboard_fab2_lib.baseboard_fab2(sch_1):\MG_DQ-DQS_NEAR_DIMM_NG_M_E_BYTE0\" )
					)
					( Units "uMatchProp" "ns" 1.000000)
					( Status sCSetFlattened )
					( Origin gBackEnd )
				)
				( attribute "RELATIVE_PROPAGATION_DELAY_SCOPE" "G"
					( Parent
						( matchGroupRef "@crescent_city_bb_fab1_lib.crescent_city_bb_fab1(sch_1):\MG_DQ_NEAR_DIMM_NG_M_E_BYTE0\" )
					)
					( Status sCSetFlattened )
					( Origin gBackEnd )
				)
				( attribute "RELATIVE_PROPAGATION_DELAY" "-50.00 MIL,50.00 MIL"
					( Parent
						( matchGroupRef "@crescent_city_bb_fab1_lib.crescent_city_bb_fab1(sch_1):\MG_DQ_NEAR_DIMM_NG_M_E_BYTE0\" )
					)
					( Units "uMatchProp" "ns" 1.000000)
					( Status sCSetFlattened )
					( Origin gBackEnd )
				)
			)
			( pinPair "@baseboard_fab2_lib.baseboard_fab2(sch_1):\PP4488\"
				( pinRef "@baseboard_fab2_lib.baseboard_fab2(sch_1):page27_i172:DDR4_DQ(7)" )
				( pinRef "@baseboard_fab2_lib.baseboard_fab2(sch_1):page51_i111:DQ(6)" )
				( attribute "RELATIVE_PROPAGATION_DELAY_SCOPE" "G"
					( Parent
						( matchGroupRef "@baseboard_fab2_lib.baseboard_fab2(sch_1):\MG_DQ-DQS_FAR_DIMM_NG_M_E_BYTE0\" )
					)
					( Status sCSetFlattened )
					( Origin gBackEnd )
				)
				( attribute "RELATIVE_PROPAGATION_DELAY" "0.00 MIL,195.00 MIL"
					( Parent
						( matchGroupRef "@baseboard_fab2_lib.baseboard_fab2(sch_1):\MG_DQ-DQS_FAR_DIMM_NG_M_E_BYTE0\" )
					)
					( Units "uMatchProp" "ns" 1.000000)
					( Status sCSetFlattened )
					( Origin gBackEnd )
				)
				( attribute "RELATIVE_PROPAGATION_DELAY_SCOPE" "G"
					( Parent
						( matchGroupRef "@crescent_city_bb_fab1_lib.crescent_city_bb_fab1(sch_1):\MG_DQ_FAR_DIMM_NG_M_E_BYTE0\" )
					)
					( Status sCSetFlattened )
					( Origin gBackEnd )
				)
				( attribute "RELATIVE_PROPAGATION_DELAY" "-50.00 MIL,50.00 MIL"
					( Parent
						( matchGroupRef "@crescent_city_bb_fab1_lib.crescent_city_bb_fab1(sch_1):\MG_DQ_FAR_DIMM_NG_M_E_BYTE0\" )
					)
					( Units "uMatchProp" "ns" 1.000000)
					( Status sCSetFlattened )
					( Origin gBackEnd )
				)
			)
			( pinPair "@baseboard_fab2_lib.baseboard_fab2(sch_1):\PP4490\"
				( pinRef "@baseboard_fab2_lib.baseboard_fab2(sch_1):page27_i172:DDR4_DQ(7)" )
				( pinRef "@baseboard_fab2_lib.baseboard_fab2(sch_1):page52_i12:DQ(7)" )
				( attribute "RELATIVE_PROPAGATION_DELAY_SCOPE" "G"
					( Parent
						( matchGroupRef "@baseboard_fab2_lib.baseboard_fab2(sch_1):\MG_DQ-DQS_NEAR_DIMM_NG_M_E_BYTE0\" )
					)
					( Status sCSetFlattened )
					( Origin gBackEnd )
				)
				( attribute "RELATIVE_PROPAGATION_DELAY" "0.00 MIL,195.00 MIL"
					( Parent
						( matchGroupRef "@baseboard_fab2_lib.baseboard_fab2(sch_1):\MG_DQ-DQS_NEAR_DIMM_NG_M_E_BYTE0\" )
					)
					( Units "uMatchProp" "ns" 1.000000)
					( Status sCSetFlattened )
					( Origin gBackEnd )
				)
				( attribute "RELATIVE_PROPAGATION_DELAY_SCOPE" "G"
					( Parent
						( matchGroupRef "@crescent_city_bb_fab1_lib.crescent_city_bb_fab1(sch_1):\MG_DQ_NEAR_DIMM_NG_M_E_BYTE0\" )
					)
					( Status sCSetFlattened )
					( Origin gBackEnd )
				)
				( attribute "RELATIVE_PROPAGATION_DELAY" "-50.00 MIL,50.00 MIL"
					( Parent
						( matchGroupRef "@crescent_city_bb_fab1_lib.crescent_city_bb_fab1(sch_1):\MG_DQ_NEAR_DIMM_NG_M_E_BYTE0\" )
					)
					( Units "uMatchProp" "ns" 1.000000)
					( Status sCSetFlattened )
					( Origin gBackEnd )
				)
			)
			( pinPair "@baseboard_fab2_lib.baseboard_fab2(sch_1):\PP4443\"
				( pinRef "@baseboard_fab2_lib.baseboard_fab2(sch_1):page27_i172:DDR4_DQ(8)" )
				( pinRef "@baseboard_fab2_lib.baseboard_fab2(sch_1):page51_i111:DQ(9)" )
				( attribute "RELATIVE_PROPAGATION_DELAY_SCOPE" "G"
					( Parent
						( matchGroupRef "@baseboard_fab2_lib.baseboard_fab2(sch_1):\MG_DQ-DQS_FAR_DIMM_NG_M_E_BYTE1\" )
					)
					( Status sCSetFlattened )
					( Origin gBackEnd )
				)
				( attribute "RELATIVE_PROPAGATION_DELAY" "0.00 MIL,195.00 MIL"
					( Parent
						( matchGroupRef "@baseboard_fab2_lib.baseboard_fab2(sch_1):\MG_DQ-DQS_FAR_DIMM_NG_M_E_BYTE1\" )
					)
					( Units "uMatchProp" "ns" 1.000000)
					( Status sCSetFlattened )
					( Origin gBackEnd )
				)
				( attribute "RELATIVE_PROPAGATION_DELAY_SCOPE" "G"
					( Parent
						( matchGroupRef "@baseboard_fab2_lib.baseboard_fab2(sch_1):\MG_DQ_FAR_DIMM_NG_M_E_BYTE1\" )
					)
					( Status sCSetFlattened )
					( Origin gBackEnd )
				)
				( attribute "RELATIVE_PROPAGATION_DELAY" "-50.00 MIL,50.00 MIL"
					( Parent
						( matchGroupRef "@baseboard_fab2_lib.baseboard_fab2(sch_1):\MG_DQ_FAR_DIMM_NG_M_E_BYTE1\" )
					)
					( Units "uMatchProp" "ns" 1.000000)
					( Status sCSetFlattened )
					( Origin gBackEnd )
				)
			)
			( pinPair "@baseboard_fab2_lib.baseboard_fab2(sch_1):\PP4445\"
				( pinRef "@baseboard_fab2_lib.baseboard_fab2(sch_1):page52_i12:DQ(8)" )
				( pinRef "@baseboard_fab2_lib.baseboard_fab2(sch_1):page27_i172:DDR4_DQ(8)" )
				( attribute "RELATIVE_PROPAGATION_DELAY_SCOPE" "G"
					( Parent
						( matchGroupRef "@baseboard_fab2_lib.baseboard_fab2(sch_1):\MG_DQ-DQS_NEAR_DIMM_NG_M_E_BYTE1\" )
					)
					( Status sCSetFlattened )
					( Origin gBackEnd )
				)
				( attribute "RELATIVE_PROPAGATION_DELAY" "0.00 MIL,195.00 MIL"
					( Parent
						( matchGroupRef "@baseboard_fab2_lib.baseboard_fab2(sch_1):\MG_DQ-DQS_NEAR_DIMM_NG_M_E_BYTE1\" )
					)
					( Units "uMatchProp" "ns" 1.000000)
					( Status sCSetFlattened )
					( Origin gBackEnd )
				)
				( attribute "RELATIVE_PROPAGATION_DELAY_SCOPE" "G"
					( Parent
						( matchGroupRef "@baseboard_fab2_lib.baseboard_fab2(sch_1):\MG_DQ_NEAR_DIMM_NG_M_E_BYTE1\" )
					)
					( Status sCSetFlattened )
					( Origin gBackEnd )
				)
				( attribute "RELATIVE_PROPAGATION_DELAY" "-50.00 MIL,50.00 MIL"
					( Parent
						( matchGroupRef "@baseboard_fab2_lib.baseboard_fab2(sch_1):\MG_DQ_NEAR_DIMM_NG_M_E_BYTE1\" )
					)
					( Units "uMatchProp" "ns" 1.000000)
					( Status sCSetFlattened )
					( Origin gBackEnd )
				)
			)
			( pinPair "@baseboard_fab2_lib.baseboard_fab2(sch_1):\PP4446\"
				( pinRef "@baseboard_fab2_lib.baseboard_fab2(sch_1):page27_i172:DDR4_DQ(9)" )
				( pinRef "@baseboard_fab2_lib.baseboard_fab2(sch_1):page51_i111:DQ(8)" )
				( attribute "RELATIVE_PROPAGATION_DELAY_SCOPE" "G"
					( Parent
						( matchGroupRef "@baseboard_fab2_lib.baseboard_fab2(sch_1):\MG_DQ-DQS_FAR_DIMM_NG_M_E_BYTE1\" )
					)
					( Status sCSetFlattened )
					( Origin gBackEnd )
				)
				( attribute "RELATIVE_PROPAGATION_DELAY" "0.00 MIL,195.00 MIL"
					( Parent
						( matchGroupRef "@baseboard_fab2_lib.baseboard_fab2(sch_1):\MG_DQ-DQS_FAR_DIMM_NG_M_E_BYTE1\" )
					)
					( Units "uMatchProp" "ns" 1.000000)
					( Status sCSetFlattened )
					( Origin gBackEnd )
				)
				( attribute "RELATIVE_PROPAGATION_DELAY_SCOPE" "G"
					( Parent
						( matchGroupRef "@baseboard_fab2_lib.baseboard_fab2(sch_1):\MG_DQ_FAR_DIMM_NG_M_E_BYTE1\" )
					)
					( Status sCSetFlattened )
					( Origin gBackEnd )
				)
				( attribute "RELATIVE_PROPAGATION_DELAY" "-50.00 MIL,50.00 MIL"
					( Parent
						( matchGroupRef "@baseboard_fab2_lib.baseboard_fab2(sch_1):\MG_DQ_FAR_DIMM_NG_M_E_BYTE1\" )
					)
					( Units "uMatchProp" "ns" 1.000000)
					( Status sCSetFlattened )
					( Origin gBackEnd )
				)
			)
			( pinPair "@baseboard_fab2_lib.baseboard_fab2(sch_1):\PP4448\"
				( pinRef "@baseboard_fab2_lib.baseboard_fab2(sch_1):page52_i12:DQ(9)" )
				( pinRef "@baseboard_fab2_lib.baseboard_fab2(sch_1):page27_i172:DDR4_DQ(9)" )
				( attribute "RELATIVE_PROPAGATION_DELAY_SCOPE" "G"
					( Parent
						( matchGroupRef "@baseboard_fab2_lib.baseboard_fab2(sch_1):\MG_DQ-DQS_NEAR_DIMM_NG_M_E_BYTE1\" )
					)
					( Status sCSetFlattened )
					( Origin gBackEnd )
				)
				( attribute "RELATIVE_PROPAGATION_DELAY" "0.00 MIL,195.00 MIL"
					( Parent
						( matchGroupRef "@baseboard_fab2_lib.baseboard_fab2(sch_1):\MG_DQ-DQS_NEAR_DIMM_NG_M_E_BYTE1\" )
					)
					( Units "uMatchProp" "ns" 1.000000)
					( Status sCSetFlattened )
					( Origin gBackEnd )
				)
				( attribute "RELATIVE_PROPAGATION_DELAY_SCOPE" "G"
					( Parent
						( matchGroupRef "@baseboard_fab2_lib.baseboard_fab2(sch_1):\MG_DQ_NEAR_DIMM_NG_M_E_BYTE1\" )
					)
					( Status sCSetFlattened )
					( Origin gBackEnd )
				)
				( attribute "RELATIVE_PROPAGATION_DELAY" "-50.00 MIL,50.00 MIL"
					( Parent
						( matchGroupRef "@baseboard_fab2_lib.baseboard_fab2(sch_1):\MG_DQ_NEAR_DIMM_NG_M_E_BYTE1\" )
					)
					( Units "uMatchProp" "ns" 1.000000)
					( Status sCSetFlattened )
					( Origin gBackEnd )
				)
			)
			( pinPair "@baseboard_fab2_lib.baseboard_fab2(sch_1):\PP4449\"
				( pinRef "@baseboard_fab2_lib.baseboard_fab2(sch_1):page27_i172:DDR4_DQ(10)" )
				( pinRef "@baseboard_fab2_lib.baseboard_fab2(sch_1):page51_i111:DQ(11)" )
				( attribute "RELATIVE_PROPAGATION_DELAY_SCOPE" "G"
					( Parent
						( matchGroupRef "@baseboard_fab2_lib.baseboard_fab2(sch_1):\MG_DQ-DQS_FAR_DIMM_NG_M_E_BYTE1\" )
					)
					( Status sCSetFlattened )
					( Origin gBackEnd )
				)
				( attribute "RELATIVE_PROPAGATION_DELAY" "0.00 MIL,195.00 MIL"
					( Parent
						( matchGroupRef "@baseboard_fab2_lib.baseboard_fab2(sch_1):\MG_DQ-DQS_FAR_DIMM_NG_M_E_BYTE1\" )
					)
					( Units "uMatchProp" "ns" 1.000000)
					( Status sCSetFlattened )
					( Origin gBackEnd )
				)
				( attribute "RELATIVE_PROPAGATION_DELAY_SCOPE" "G"
					( Parent
						( matchGroupRef "@baseboard_fab2_lib.baseboard_fab2(sch_1):\MG_DQ_FAR_DIMM_NG_M_E_BYTE1\" )
					)
					( Status sCSetFlattened )
					( Origin gBackEnd )
				)
				( attribute "RELATIVE_PROPAGATION_DELAY" "-50.00 MIL,50.00 MIL"
					( Parent
						( matchGroupRef "@baseboard_fab2_lib.baseboard_fab2(sch_1):\MG_DQ_FAR_DIMM_NG_M_E_BYTE1\" )
					)
					( Units "uMatchProp" "ns" 1.000000)
					( Status sCSetFlattened )
					( Origin gBackEnd )
				)
			)
			( pinPair "@baseboard_fab2_lib.baseboard_fab2(sch_1):\PP4451\"
				( pinRef "@baseboard_fab2_lib.baseboard_fab2(sch_1):page52_i12:DQ(10)" )
				( pinRef "@baseboard_fab2_lib.baseboard_fab2(sch_1):page27_i172:DDR4_DQ(10)" )
				( attribute "RELATIVE_PROPAGATION_DELAY_SCOPE" "G"
					( Parent
						( matchGroupRef "@baseboard_fab2_lib.baseboard_fab2(sch_1):\MG_DQ-DQS_NEAR_DIMM_NG_M_E_BYTE1\" )
					)
					( Status sCSetFlattened )
					( Origin gBackEnd )
				)
				( attribute "RELATIVE_PROPAGATION_DELAY" "0.00 MIL,195.00 MIL"
					( Parent
						( matchGroupRef "@baseboard_fab2_lib.baseboard_fab2(sch_1):\MG_DQ-DQS_NEAR_DIMM_NG_M_E_BYTE1\" )
					)
					( Units "uMatchProp" "ns" 1.000000)
					( Status sCSetFlattened )
					( Origin gBackEnd )
				)
				( attribute "RELATIVE_PROPAGATION_DELAY_SCOPE" "G"
					( Parent
						( matchGroupRef "@baseboard_fab2_lib.baseboard_fab2(sch_1):\MG_DQ_NEAR_DIMM_NG_M_E_BYTE1\" )
					)
					( Status sCSetFlattened )
					( Origin gBackEnd )
				)
				( attribute "RELATIVE_PROPAGATION_DELAY" "-50.00 MIL,50.00 MIL"
					( Parent
						( matchGroupRef "@baseboard_fab2_lib.baseboard_fab2(sch_1):\MG_DQ_NEAR_DIMM_NG_M_E_BYTE1\" )
					)
					( Units "uMatchProp" "ns" 1.000000)
					( Status sCSetFlattened )
					( Origin gBackEnd )
				)
			)
			( pinPair "@baseboard_fab2_lib.baseboard_fab2(sch_1):\PP4452\"
				( pinRef "@baseboard_fab2_lib.baseboard_fab2(sch_1):page27_i172:DDR4_DQ(11)" )
				( pinRef "@baseboard_fab2_lib.baseboard_fab2(sch_1):page51_i111:DQ(10)" )
				( attribute "RELATIVE_PROPAGATION_DELAY_SCOPE" "G"
					( Parent
						( matchGroupRef "@baseboard_fab2_lib.baseboard_fab2(sch_1):\MG_DQ-DQS_FAR_DIMM_NG_M_E_BYTE1\" )
					)
					( Status sCSetFlattened )
					( Origin gBackEnd )
				)
				( attribute "RELATIVE_PROPAGATION_DELAY" "0.00 MIL,195.00 MIL"
					( Parent
						( matchGroupRef "@baseboard_fab2_lib.baseboard_fab2(sch_1):\MG_DQ-DQS_FAR_DIMM_NG_M_E_BYTE1\" )
					)
					( Units "uMatchProp" "ns" 1.000000)
					( Status sCSetFlattened )
					( Origin gBackEnd )
				)
				( attribute "RELATIVE_PROPAGATION_DELAY_SCOPE" "G"
					( Parent
						( matchGroupRef "@baseboard_fab2_lib.baseboard_fab2(sch_1):\MG_DQ_FAR_DIMM_NG_M_E_BYTE1\" )
					)
					( Status sCSetFlattened )
					( Origin gBackEnd )
				)
				( attribute "RELATIVE_PROPAGATION_DELAY" "-50.00 MIL,50.00 MIL"
					( Parent
						( matchGroupRef "@baseboard_fab2_lib.baseboard_fab2(sch_1):\MG_DQ_FAR_DIMM_NG_M_E_BYTE1\" )
					)
					( Units "uMatchProp" "ns" 1.000000)
					( Status sCSetFlattened )
					( Origin gBackEnd )
				)
			)
			( pinPair "@baseboard_fab2_lib.baseboard_fab2(sch_1):\PP4454\"
				( pinRef "@baseboard_fab2_lib.baseboard_fab2(sch_1):page52_i12:DQ(11)" )
				( pinRef "@baseboard_fab2_lib.baseboard_fab2(sch_1):page27_i172:DDR4_DQ(11)" )
				( attribute "RELATIVE_PROPAGATION_DELAY_SCOPE" "G"
					( Parent
						( matchGroupRef "@baseboard_fab2_lib.baseboard_fab2(sch_1):\MG_DQ-DQS_NEAR_DIMM_NG_M_E_BYTE1\" )
					)
					( Status sCSetFlattened )
					( Origin gBackEnd )
				)
				( attribute "RELATIVE_PROPAGATION_DELAY" "0.00 MIL,195.00 MIL"
					( Parent
						( matchGroupRef "@baseboard_fab2_lib.baseboard_fab2(sch_1):\MG_DQ-DQS_NEAR_DIMM_NG_M_E_BYTE1\" )
					)
					( Units "uMatchProp" "ns" 1.000000)
					( Status sCSetFlattened )
					( Origin gBackEnd )
				)
				( attribute "RELATIVE_PROPAGATION_DELAY_SCOPE" "G"
					( Parent
						( matchGroupRef "@baseboard_fab2_lib.baseboard_fab2(sch_1):\MG_DQ_NEAR_DIMM_NG_M_E_BYTE1\" )
					)
					( Status sCSetFlattened )
					( Origin gBackEnd )
				)
				( attribute "RELATIVE_PROPAGATION_DELAY" "-50.00 MIL,50.00 MIL"
					( Parent
						( matchGroupRef "@baseboard_fab2_lib.baseboard_fab2(sch_1):\MG_DQ_NEAR_DIMM_NG_M_E_BYTE1\" )
					)
					( Units "uMatchProp" "ns" 1.000000)
					( Status sCSetFlattened )
					( Origin gBackEnd )
				)
			)
			( pinPair "@baseboard_fab2_lib.baseboard_fab2(sch_1):\PP4455\"
				( pinRef "@baseboard_fab2_lib.baseboard_fab2(sch_1):page27_i172:DDR4_DQ(12)" )
				( pinRef "@baseboard_fab2_lib.baseboard_fab2(sch_1):page51_i111:DQ(13)" )
				( attribute "RELATIVE_PROPAGATION_DELAY_SCOPE" "G"
					( Parent
						( matchGroupRef "@baseboard_fab2_lib.baseboard_fab2(sch_1):\MG_DQ-DQS_FAR_DIMM_NG_M_E_BYTE1\" )
					)
					( Status sCSetFlattened )
					( Origin gBackEnd )
				)
				( attribute "RELATIVE_PROPAGATION_DELAY" "0.00 MIL,195.00 MIL"
					( Parent
						( matchGroupRef "@baseboard_fab2_lib.baseboard_fab2(sch_1):\MG_DQ-DQS_FAR_DIMM_NG_M_E_BYTE1\" )
					)
					( Units "uMatchProp" "ns" 1.000000)
					( Status sCSetFlattened )
					( Origin gBackEnd )
				)
				( attribute "RELATIVE_PROPAGATION_DELAY_SCOPE" "G"
					( Parent
						( matchGroupRef "@baseboard_fab2_lib.baseboard_fab2(sch_1):\MG_DQ_FAR_DIMM_NG_M_E_BYTE1\" )
					)
					( Status sCSetFlattened )
					( Origin gBackEnd )
				)
				( attribute "RELATIVE_PROPAGATION_DELAY" "-50.00 MIL,50.00 MIL"
					( Parent
						( matchGroupRef "@baseboard_fab2_lib.baseboard_fab2(sch_1):\MG_DQ_FAR_DIMM_NG_M_E_BYTE1\" )
					)
					( Units "uMatchProp" "ns" 1.000000)
					( Status sCSetFlattened )
					( Origin gBackEnd )
				)
			)
			( pinPair "@baseboard_fab2_lib.baseboard_fab2(sch_1):\PP4457\"
				( pinRef "@baseboard_fab2_lib.baseboard_fab2(sch_1):page52_i12:DQ(12)" )
				( pinRef "@baseboard_fab2_lib.baseboard_fab2(sch_1):page27_i172:DDR4_DQ(12)" )
				( attribute "RELATIVE_PROPAGATION_DELAY_SCOPE" "G"
					( Parent
						( matchGroupRef "@baseboard_fab2_lib.baseboard_fab2(sch_1):\MG_DQ-DQS_NEAR_DIMM_NG_M_E_BYTE1\" )
					)
					( Status sCSetFlattened )
					( Origin gBackEnd )
				)
				( attribute "RELATIVE_PROPAGATION_DELAY" "0.00 MIL,195.00 MIL"
					( Parent
						( matchGroupRef "@baseboard_fab2_lib.baseboard_fab2(sch_1):\MG_DQ-DQS_NEAR_DIMM_NG_M_E_BYTE1\" )
					)
					( Units "uMatchProp" "ns" 1.000000)
					( Status sCSetFlattened )
					( Origin gBackEnd )
				)
				( attribute "RELATIVE_PROPAGATION_DELAY_SCOPE" "G"
					( Parent
						( matchGroupRef "@baseboard_fab2_lib.baseboard_fab2(sch_1):\MG_DQ_NEAR_DIMM_NG_M_E_BYTE1\" )
					)
					( Status sCSetFlattened )
					( Origin gBackEnd )
				)
				( attribute "RELATIVE_PROPAGATION_DELAY" "-50.00 MIL,50.00 MIL"
					( Parent
						( matchGroupRef "@baseboard_fab2_lib.baseboard_fab2(sch_1):\MG_DQ_NEAR_DIMM_NG_M_E_BYTE1\" )
					)
					( Units "uMatchProp" "ns" 1.000000)
					( Status sCSetFlattened )
					( Origin gBackEnd )
				)
			)
			( pinPair "@baseboard_fab2_lib.baseboard_fab2(sch_1):\PP4458\"
				( pinRef "@baseboard_fab2_lib.baseboard_fab2(sch_1):page27_i172:DDR4_DQ(13)" )
				( pinRef "@baseboard_fab2_lib.baseboard_fab2(sch_1):page51_i111:DQ(12)" )
				( attribute "RELATIVE_PROPAGATION_DELAY_SCOPE" "G"
					( Parent
						( matchGroupRef "@baseboard_fab2_lib.baseboard_fab2(sch_1):\MG_DQ-DQS_FAR_DIMM_NG_M_E_BYTE1\" )
					)
					( Status sCSetFlattened )
					( Origin gBackEnd )
				)
				( attribute "RELATIVE_PROPAGATION_DELAY" "0.00 MIL,195.00 MIL"
					( Parent
						( matchGroupRef "@baseboard_fab2_lib.baseboard_fab2(sch_1):\MG_DQ-DQS_FAR_DIMM_NG_M_E_BYTE1\" )
					)
					( Units "uMatchProp" "ns" 1.000000)
					( Status sCSetFlattened )
					( Origin gBackEnd )
				)
				( attribute "RELATIVE_PROPAGATION_DELAY_SCOPE" "G"
					( Parent
						( matchGroupRef "@baseboard_fab2_lib.baseboard_fab2(sch_1):\MG_DQ_FAR_DIMM_NG_M_E_BYTE1\" )
					)
					( Status sCSetFlattened )
					( Origin gBackEnd )
				)
				( attribute "RELATIVE_PROPAGATION_DELAY" "-50.00 MIL,50.00 MIL"
					( Parent
						( matchGroupRef "@baseboard_fab2_lib.baseboard_fab2(sch_1):\MG_DQ_FAR_DIMM_NG_M_E_BYTE1\" )
					)
					( Units "uMatchProp" "ns" 1.000000)
					( Status sCSetFlattened )
					( Origin gBackEnd )
				)
			)
			( pinPair "@baseboard_fab2_lib.baseboard_fab2(sch_1):\PP4460\"
				( pinRef "@baseboard_fab2_lib.baseboard_fab2(sch_1):page52_i12:DQ(13)" )
				( pinRef "@baseboard_fab2_lib.baseboard_fab2(sch_1):page27_i172:DDR4_DQ(13)" )
				( attribute "RELATIVE_PROPAGATION_DELAY_SCOPE" "G"
					( Parent
						( matchGroupRef "@baseboard_fab2_lib.baseboard_fab2(sch_1):\MG_DQ-DQS_NEAR_DIMM_NG_M_E_BYTE1\" )
					)
					( Status sCSetFlattened )
					( Origin gBackEnd )
				)
				( attribute "RELATIVE_PROPAGATION_DELAY" "0.00 MIL,195.00 MIL"
					( Parent
						( matchGroupRef "@baseboard_fab2_lib.baseboard_fab2(sch_1):\MG_DQ-DQS_NEAR_DIMM_NG_M_E_BYTE1\" )
					)
					( Units "uMatchProp" "ns" 1.000000)
					( Status sCSetFlattened )
					( Origin gBackEnd )
				)
				( attribute "RELATIVE_PROPAGATION_DELAY_SCOPE" "G"
					( Parent
						( matchGroupRef "@baseboard_fab2_lib.baseboard_fab2(sch_1):\MG_DQ_NEAR_DIMM_NG_M_E_BYTE1\" )
					)
					( Status sCSetFlattened )
					( Origin gBackEnd )
				)
				( attribute "RELATIVE_PROPAGATION_DELAY" "-50.00 MIL,50.00 MIL"
					( Parent
						( matchGroupRef "@baseboard_fab2_lib.baseboard_fab2(sch_1):\MG_DQ_NEAR_DIMM_NG_M_E_BYTE1\" )
					)
					( Units "uMatchProp" "ns" 1.000000)
					( Status sCSetFlattened )
					( Origin gBackEnd )
				)
			)
			( pinPair "@baseboard_fab2_lib.baseboard_fab2(sch_1):\PP4461\"
				( pinRef "@baseboard_fab2_lib.baseboard_fab2(sch_1):page27_i172:DDR4_DQ(14)" )
				( pinRef "@baseboard_fab2_lib.baseboard_fab2(sch_1):page51_i111:DQ(15)" )
				( attribute "RELATIVE_PROPAGATION_DELAY_SCOPE" "G"
					( Parent
						( matchGroupRef "@baseboard_fab2_lib.baseboard_fab2(sch_1):\MG_DQ-DQS_FAR_DIMM_NG_M_E_BYTE1\" )
					)
					( Status sCSetFlattened )
					( Origin gBackEnd )
				)
				( attribute "RELATIVE_PROPAGATION_DELAY" "0.00 MIL,195.00 MIL"
					( Parent
						( matchGroupRef "@baseboard_fab2_lib.baseboard_fab2(sch_1):\MG_DQ-DQS_FAR_DIMM_NG_M_E_BYTE1\" )
					)
					( Units "uMatchProp" "ns" 1.000000)
					( Status sCSetFlattened )
					( Origin gBackEnd )
				)
				( attribute "RELATIVE_PROPAGATION_DELAY_SCOPE" "G"
					( Parent
						( matchGroupRef "@baseboard_fab2_lib.baseboard_fab2(sch_1):\MG_DQ_FAR_DIMM_NG_M_E_BYTE1\" )
					)
					( Status sCSetFlattened )
					( Origin gBackEnd )
				)
				( attribute "RELATIVE_PROPAGATION_DELAY" "-50.00 MIL,50.00 MIL"
					( Parent
						( matchGroupRef "@baseboard_fab2_lib.baseboard_fab2(sch_1):\MG_DQ_FAR_DIMM_NG_M_E_BYTE1\" )
					)
					( Units "uMatchProp" "ns" 1.000000)
					( Status sCSetFlattened )
					( Origin gBackEnd )
				)
			)
			( pinPair "@baseboard_fab2_lib.baseboard_fab2(sch_1):\PP4463\"
				( pinRef "@baseboard_fab2_lib.baseboard_fab2(sch_1):page52_i12:DQ(14)" )
				( pinRef "@baseboard_fab2_lib.baseboard_fab2(sch_1):page27_i172:DDR4_DQ(14)" )
				( attribute "RELATIVE_PROPAGATION_DELAY_SCOPE" "G"
					( Parent
						( matchGroupRef "@baseboard_fab2_lib.baseboard_fab2(sch_1):\MG_DQ-DQS_NEAR_DIMM_NG_M_E_BYTE1\" )
					)
					( Status sCSetFlattened )
					( Origin gBackEnd )
				)
				( attribute "RELATIVE_PROPAGATION_DELAY" "0.00 MIL,195.00 MIL"
					( Parent
						( matchGroupRef "@baseboard_fab2_lib.baseboard_fab2(sch_1):\MG_DQ-DQS_NEAR_DIMM_NG_M_E_BYTE1\" )
					)
					( Units "uMatchProp" "ns" 1.000000)
					( Status sCSetFlattened )
					( Origin gBackEnd )
				)
				( attribute "RELATIVE_PROPAGATION_DELAY_SCOPE" "G"
					( Parent
						( matchGroupRef "@baseboard_fab2_lib.baseboard_fab2(sch_1):\MG_DQ_NEAR_DIMM_NG_M_E_BYTE1\" )
					)
					( Status sCSetFlattened )
					( Origin gBackEnd )
				)
				( attribute "RELATIVE_PROPAGATION_DELAY" "-50.00 MIL,50.00 MIL"
					( Parent
						( matchGroupRef "@baseboard_fab2_lib.baseboard_fab2(sch_1):\MG_DQ_NEAR_DIMM_NG_M_E_BYTE1\" )
					)
					( Units "uMatchProp" "ns" 1.000000)
					( Status sCSetFlattened )
					( Origin gBackEnd )
				)
			)
			( pinPair "@baseboard_fab2_lib.baseboard_fab2(sch_1):\PP4464\"
				( pinRef "@baseboard_fab2_lib.baseboard_fab2(sch_1):page27_i172:DDR4_DQ(15)" )
				( pinRef "@baseboard_fab2_lib.baseboard_fab2(sch_1):page51_i111:DQ(14)" )
				( attribute "RELATIVE_PROPAGATION_DELAY_SCOPE" "G"
					( Parent
						( matchGroupRef "@baseboard_fab2_lib.baseboard_fab2(sch_1):\MG_DQ-DQS_FAR_DIMM_NG_M_E_BYTE1\" )
					)
					( Status sCSetFlattened )
					( Origin gBackEnd )
				)
				( attribute "RELATIVE_PROPAGATION_DELAY" "0.00 MIL,195.00 MIL"
					( Parent
						( matchGroupRef "@baseboard_fab2_lib.baseboard_fab2(sch_1):\MG_DQ-DQS_FAR_DIMM_NG_M_E_BYTE1\" )
					)
					( Units "uMatchProp" "ns" 1.000000)
					( Status sCSetFlattened )
					( Origin gBackEnd )
				)
				( attribute "RELATIVE_PROPAGATION_DELAY_SCOPE" "G"
					( Parent
						( matchGroupRef "@baseboard_fab2_lib.baseboard_fab2(sch_1):\MG_DQ_FAR_DIMM_NG_M_E_BYTE1\" )
					)
					( Status sCSetFlattened )
					( Origin gBackEnd )
				)
				( attribute "RELATIVE_PROPAGATION_DELAY" "-50.00 MIL,50.00 MIL"
					( Parent
						( matchGroupRef "@baseboard_fab2_lib.baseboard_fab2(sch_1):\MG_DQ_FAR_DIMM_NG_M_E_BYTE1\" )
					)
					( Units "uMatchProp" "ns" 1.000000)
					( Status sCSetFlattened )
					( Origin gBackEnd )
				)
			)
			( pinPair "@baseboard_fab2_lib.baseboard_fab2(sch_1):\PP4466\"
				( pinRef "@baseboard_fab2_lib.baseboard_fab2(sch_1):page52_i12:DQ(15)" )
				( pinRef "@baseboard_fab2_lib.baseboard_fab2(sch_1):page27_i172:DDR4_DQ(15)" )
				( attribute "RELATIVE_PROPAGATION_DELAY_SCOPE" "G"
					( Parent
						( matchGroupRef "@baseboard_fab2_lib.baseboard_fab2(sch_1):\MG_DQ-DQS_NEAR_DIMM_NG_M_E_BYTE1\" )
					)
					( Status sCSetFlattened )
					( Origin gBackEnd )
				)
				( attribute "RELATIVE_PROPAGATION_DELAY" "0.00 MIL,195.00 MIL"
					( Parent
						( matchGroupRef "@baseboard_fab2_lib.baseboard_fab2(sch_1):\MG_DQ-DQS_NEAR_DIMM_NG_M_E_BYTE1\" )
					)
					( Units "uMatchProp" "ns" 1.000000)
					( Status sCSetFlattened )
					( Origin gBackEnd )
				)
				( attribute "RELATIVE_PROPAGATION_DELAY_SCOPE" "G"
					( Parent
						( matchGroupRef "@baseboard_fab2_lib.baseboard_fab2(sch_1):\MG_DQ_NEAR_DIMM_NG_M_E_BYTE1\" )
					)
					( Status sCSetFlattened )
					( Origin gBackEnd )
				)
				( attribute "RELATIVE_PROPAGATION_DELAY" "-50.00 MIL,50.00 MIL"
					( Parent
						( matchGroupRef "@baseboard_fab2_lib.baseboard_fab2(sch_1):\MG_DQ_NEAR_DIMM_NG_M_E_BYTE1\" )
					)
					( Units "uMatchProp" "ns" 1.000000)
					( Status sCSetFlattened )
					( Origin gBackEnd )
				)
			)
			( pinPair "@baseboard_fab2_lib.baseboard_fab2(sch_1):\PP4419\"
				( pinRef "@baseboard_fab2_lib.baseboard_fab2(sch_1):page27_i172:DDR4_DQ(16)" )
				( pinRef "@baseboard_fab2_lib.baseboard_fab2(sch_1):page51_i111:DQ(17)" )
				( attribute "RELATIVE_PROPAGATION_DELAY_SCOPE" "G"
					( Parent
						( matchGroupRef "@baseboard_fab2_lib.baseboard_fab2(sch_1):\MG_DQ-DQS_FAR_DIMM_NG_M_E_BYTE2\" )
					)
					( Status sCSetFlattened )
					( Origin gBackEnd )
				)
				( attribute "RELATIVE_PROPAGATION_DELAY" "0.00 MIL,195.00 MIL"
					( Parent
						( matchGroupRef "@baseboard_fab2_lib.baseboard_fab2(sch_1):\MG_DQ-DQS_FAR_DIMM_NG_M_E_BYTE2\" )
					)
					( Units "uMatchProp" "ns" 1.000000)
					( Status sCSetFlattened )
					( Origin gBackEnd )
				)
				( attribute "RELATIVE_PROPAGATION_DELAY_SCOPE" "G"
					( Parent
						( matchGroupRef "@crescent_city_bb_fab1_lib.crescent_city_bb_fab1(sch_1):\MG_DQ_FAR_DIMM_NG_M_E_BYTE2\" )
					)
					( Status sCSetFlattened )
					( Origin gBackEnd )
				)
				( attribute "RELATIVE_PROPAGATION_DELAY" "-50.00 MIL,50.00 MIL"
					( Parent
						( matchGroupRef "@crescent_city_bb_fab1_lib.crescent_city_bb_fab1(sch_1):\MG_DQ_FAR_DIMM_NG_M_E_BYTE2\" )
					)
					( Units "uMatchProp" "ns" 1.000000)
					( Status sCSetFlattened )
					( Origin gBackEnd )
				)
			)
			( pinPair "@baseboard_fab2_lib.baseboard_fab2(sch_1):\PP4421\"
				( pinRef "@baseboard_fab2_lib.baseboard_fab2(sch_1):page52_i12:DQ(16)" )
				( pinRef "@baseboard_fab2_lib.baseboard_fab2(sch_1):page27_i172:DDR4_DQ(16)" )
				( attribute "RELATIVE_PROPAGATION_DELAY_SCOPE" "G"
					( Parent
						( matchGroupRef "@baseboard_fab2_lib.baseboard_fab2(sch_1):\MG_DQ-DQS_NEAR_DIMM_NG_M_E_BYTE2\" )
					)
					( Status sCSetFlattened )
					( Origin gBackEnd )
				)
				( attribute "RELATIVE_PROPAGATION_DELAY" "0.00 MIL,195.00 MIL"
					( Parent
						( matchGroupRef "@baseboard_fab2_lib.baseboard_fab2(sch_1):\MG_DQ-DQS_NEAR_DIMM_NG_M_E_BYTE2\" )
					)
					( Units "uMatchProp" "ns" 1.000000)
					( Status sCSetFlattened )
					( Origin gBackEnd )
				)
				( attribute "RELATIVE_PROPAGATION_DELAY_SCOPE" "G"
					( Parent
						( matchGroupRef "@crescent_city_bb_fab1_lib.crescent_city_bb_fab1(sch_1):\MG_DQ_NEAR_DIMM_NG_M_E_BYTE2\" )
					)
					( Status sCSetFlattened )
					( Origin gBackEnd )
				)
				( attribute "RELATIVE_PROPAGATION_DELAY" "-50.00 MIL,50.00 MIL"
					( Parent
						( matchGroupRef "@crescent_city_bb_fab1_lib.crescent_city_bb_fab1(sch_1):\MG_DQ_NEAR_DIMM_NG_M_E_BYTE2\" )
					)
					( Units "uMatchProp" "ns" 1.000000)
					( Status sCSetFlattened )
					( Origin gBackEnd )
				)
			)
			( pinPair "@baseboard_fab2_lib.baseboard_fab2(sch_1):\PP4422\"
				( pinRef "@baseboard_fab2_lib.baseboard_fab2(sch_1):page27_i172:DDR4_DQ(17)" )
				( pinRef "@baseboard_fab2_lib.baseboard_fab2(sch_1):page51_i111:DQ(16)" )
				( attribute "RELATIVE_PROPAGATION_DELAY_SCOPE" "G"
					( Parent
						( matchGroupRef "@baseboard_fab2_lib.baseboard_fab2(sch_1):\MG_DQ-DQS_FAR_DIMM_NG_M_E_BYTE2\" )
					)
					( Status sCSetFlattened )
					( Origin gBackEnd )
				)
				( attribute "RELATIVE_PROPAGATION_DELAY" "0.00 MIL,195.00 MIL"
					( Parent
						( matchGroupRef "@baseboard_fab2_lib.baseboard_fab2(sch_1):\MG_DQ-DQS_FAR_DIMM_NG_M_E_BYTE2\" )
					)
					( Units "uMatchProp" "ns" 1.000000)
					( Status sCSetFlattened )
					( Origin gBackEnd )
				)
				( attribute "RELATIVE_PROPAGATION_DELAY_SCOPE" "G"
					( Parent
						( matchGroupRef "@crescent_city_bb_fab1_lib.crescent_city_bb_fab1(sch_1):\MG_DQ_FAR_DIMM_NG_M_E_BYTE2\" )
					)
					( Status sCSetFlattened )
					( Origin gBackEnd )
				)
				( attribute "RELATIVE_PROPAGATION_DELAY" "-50.00 MIL,50.00 MIL"
					( Parent
						( matchGroupRef "@crescent_city_bb_fab1_lib.crescent_city_bb_fab1(sch_1):\MG_DQ_FAR_DIMM_NG_M_E_BYTE2\" )
					)
					( Units "uMatchProp" "ns" 1.000000)
					( Status sCSetFlattened )
					( Origin gBackEnd )
				)
			)
			( pinPair "@baseboard_fab2_lib.baseboard_fab2(sch_1):\PP4424\"
				( pinRef "@baseboard_fab2_lib.baseboard_fab2(sch_1):page52_i12:DQ(17)" )
				( pinRef "@baseboard_fab2_lib.baseboard_fab2(sch_1):page27_i172:DDR4_DQ(17)" )
				( attribute "RELATIVE_PROPAGATION_DELAY_SCOPE" "G"
					( Parent
						( matchGroupRef "@baseboard_fab2_lib.baseboard_fab2(sch_1):\MG_DQ-DQS_NEAR_DIMM_NG_M_E_BYTE2\" )
					)
					( Status sCSetFlattened )
					( Origin gBackEnd )
				)
				( attribute "RELATIVE_PROPAGATION_DELAY" "0.00 MIL,195.00 MIL"
					( Parent
						( matchGroupRef "@baseboard_fab2_lib.baseboard_fab2(sch_1):\MG_DQ-DQS_NEAR_DIMM_NG_M_E_BYTE2\" )
					)
					( Units "uMatchProp" "ns" 1.000000)
					( Status sCSetFlattened )
					( Origin gBackEnd )
				)
				( attribute "RELATIVE_PROPAGATION_DELAY_SCOPE" "G"
					( Parent
						( matchGroupRef "@crescent_city_bb_fab1_lib.crescent_city_bb_fab1(sch_1):\MG_DQ_NEAR_DIMM_NG_M_E_BYTE2\" )
					)
					( Status sCSetFlattened )
					( Origin gBackEnd )
				)
				( attribute "RELATIVE_PROPAGATION_DELAY" "-50.00 MIL,50.00 MIL"
					( Parent
						( matchGroupRef "@crescent_city_bb_fab1_lib.crescent_city_bb_fab1(sch_1):\MG_DQ_NEAR_DIMM_NG_M_E_BYTE2\" )
					)
					( Units "uMatchProp" "ns" 1.000000)
					( Status sCSetFlattened )
					( Origin gBackEnd )
				)
			)
			( pinPair "@baseboard_fab2_lib.baseboard_fab2(sch_1):\PP4425\"
				( pinRef "@baseboard_fab2_lib.baseboard_fab2(sch_1):page27_i172:DDR4_DQ(18)" )
				( pinRef "@baseboard_fab2_lib.baseboard_fab2(sch_1):page51_i111:DQ(19)" )
				( attribute "RELATIVE_PROPAGATION_DELAY_SCOPE" "G"
					( Parent
						( matchGroupRef "@baseboard_fab2_lib.baseboard_fab2(sch_1):\MG_DQ-DQS_FAR_DIMM_NG_M_E_BYTE2\" )
					)
					( Status sCSetFlattened )
					( Origin gBackEnd )
				)
				( attribute "RELATIVE_PROPAGATION_DELAY" "0.00 MIL,195.00 MIL"
					( Parent
						( matchGroupRef "@baseboard_fab2_lib.baseboard_fab2(sch_1):\MG_DQ-DQS_FAR_DIMM_NG_M_E_BYTE2\" )
					)
					( Units "uMatchProp" "ns" 1.000000)
					( Status sCSetFlattened )
					( Origin gBackEnd )
				)
				( attribute "RELATIVE_PROPAGATION_DELAY_SCOPE" "G"
					( Parent
						( matchGroupRef "@crescent_city_bb_fab1_lib.crescent_city_bb_fab1(sch_1):\MG_DQ_FAR_DIMM_NG_M_E_BYTE2\" )
					)
					( Status sCSetFlattened )
					( Origin gBackEnd )
				)
				( attribute "RELATIVE_PROPAGATION_DELAY" "-50.00 MIL,50.00 MIL"
					( Parent
						( matchGroupRef "@crescent_city_bb_fab1_lib.crescent_city_bb_fab1(sch_1):\MG_DQ_FAR_DIMM_NG_M_E_BYTE2\" )
					)
					( Units "uMatchProp" "ns" 1.000000)
					( Status sCSetFlattened )
					( Origin gBackEnd )
				)
			)
			( pinPair "@baseboard_fab2_lib.baseboard_fab2(sch_1):\PP4427\"
				( pinRef "@baseboard_fab2_lib.baseboard_fab2(sch_1):page52_i12:DQ(18)" )
				( pinRef "@baseboard_fab2_lib.baseboard_fab2(sch_1):page27_i172:DDR4_DQ(18)" )
				( attribute "RELATIVE_PROPAGATION_DELAY_SCOPE" "G"
					( Parent
						( matchGroupRef "@baseboard_fab2_lib.baseboard_fab2(sch_1):\MG_DQ-DQS_NEAR_DIMM_NG_M_E_BYTE2\" )
					)
					( Status sCSetFlattened )
					( Origin gBackEnd )
				)
				( attribute "RELATIVE_PROPAGATION_DELAY" "0.00 MIL,195.00 MIL"
					( Parent
						( matchGroupRef "@baseboard_fab2_lib.baseboard_fab2(sch_1):\MG_DQ-DQS_NEAR_DIMM_NG_M_E_BYTE2\" )
					)
					( Units "uMatchProp" "ns" 1.000000)
					( Status sCSetFlattened )
					( Origin gBackEnd )
				)
				( attribute "RELATIVE_PROPAGATION_DELAY_SCOPE" "G"
					( Parent
						( matchGroupRef "@crescent_city_bb_fab1_lib.crescent_city_bb_fab1(sch_1):\MG_DQ_NEAR_DIMM_NG_M_E_BYTE2\" )
					)
					( Status sCSetFlattened )
					( Origin gBackEnd )
				)
				( attribute "RELATIVE_PROPAGATION_DELAY" "-50.00 MIL,50.00 MIL"
					( Parent
						( matchGroupRef "@crescent_city_bb_fab1_lib.crescent_city_bb_fab1(sch_1):\MG_DQ_NEAR_DIMM_NG_M_E_BYTE2\" )
					)
					( Units "uMatchProp" "ns" 1.000000)
					( Status sCSetFlattened )
					( Origin gBackEnd )
				)
			)
			( pinPair "@baseboard_fab2_lib.baseboard_fab2(sch_1):\PP4428\"
				( pinRef "@baseboard_fab2_lib.baseboard_fab2(sch_1):page27_i172:DDR4_DQ(19)" )
				( pinRef "@baseboard_fab2_lib.baseboard_fab2(sch_1):page51_i111:DQ(18)" )
				( attribute "RELATIVE_PROPAGATION_DELAY_SCOPE" "G"
					( Parent
						( matchGroupRef "@baseboard_fab2_lib.baseboard_fab2(sch_1):\MG_DQ-DQS_FAR_DIMM_NG_M_E_BYTE2\" )
					)
					( Status sCSetFlattened )
					( Origin gBackEnd )
				)
				( attribute "RELATIVE_PROPAGATION_DELAY" "0.00 MIL,195.00 MIL"
					( Parent
						( matchGroupRef "@baseboard_fab2_lib.baseboard_fab2(sch_1):\MG_DQ-DQS_FAR_DIMM_NG_M_E_BYTE2\" )
					)
					( Units "uMatchProp" "ns" 1.000000)
					( Status sCSetFlattened )
					( Origin gBackEnd )
				)
				( attribute "RELATIVE_PROPAGATION_DELAY_SCOPE" "G"
					( Parent
						( matchGroupRef "@crescent_city_bb_fab1_lib.crescent_city_bb_fab1(sch_1):\MG_DQ_FAR_DIMM_NG_M_E_BYTE2\" )
					)
					( Status sCSetFlattened )
					( Origin gBackEnd )
				)
				( attribute "RELATIVE_PROPAGATION_DELAY" "-50.00 MIL,50.00 MIL"
					( Parent
						( matchGroupRef "@crescent_city_bb_fab1_lib.crescent_city_bb_fab1(sch_1):\MG_DQ_FAR_DIMM_NG_M_E_BYTE2\" )
					)
					( Units "uMatchProp" "ns" 1.000000)
					( Status sCSetFlattened )
					( Origin gBackEnd )
				)
			)
			( pinPair "@baseboard_fab2_lib.baseboard_fab2(sch_1):\PP4430\"
				( pinRef "@baseboard_fab2_lib.baseboard_fab2(sch_1):page52_i12:DQ(19)" )
				( pinRef "@baseboard_fab2_lib.baseboard_fab2(sch_1):page27_i172:DDR4_DQ(19)" )
				( attribute "RELATIVE_PROPAGATION_DELAY_SCOPE" "G"
					( Parent
						( matchGroupRef "@baseboard_fab2_lib.baseboard_fab2(sch_1):\MG_DQ-DQS_NEAR_DIMM_NG_M_E_BYTE2\" )
					)
					( Status sCSetFlattened )
					( Origin gBackEnd )
				)
				( attribute "RELATIVE_PROPAGATION_DELAY" "0.00 MIL,195.00 MIL"
					( Parent
						( matchGroupRef "@baseboard_fab2_lib.baseboard_fab2(sch_1):\MG_DQ-DQS_NEAR_DIMM_NG_M_E_BYTE2\" )
					)
					( Units "uMatchProp" "ns" 1.000000)
					( Status sCSetFlattened )
					( Origin gBackEnd )
				)
				( attribute "RELATIVE_PROPAGATION_DELAY_SCOPE" "G"
					( Parent
						( matchGroupRef "@crescent_city_bb_fab1_lib.crescent_city_bb_fab1(sch_1):\MG_DQ_NEAR_DIMM_NG_M_E_BYTE2\" )
					)
					( Origin gBackEnd )
				)
				( attribute "RELATIVE_PROPAGATION_DELAY" "TARGET,TARGET"
					( Parent
						( matchGroupRef "@crescent_city_bb_fab1_lib.crescent_city_bb_fab1(sch_1):\MG_DQ_NEAR_DIMM_NG_M_E_BYTE2\" )
					)
					( Units "uMatchProp" "ns" 1.000000)
					( Origin gBackEnd )
				)
			)
			( pinPair "@baseboard_fab2_lib.baseboard_fab2(sch_1):\PP4431\"
				( pinRef "@baseboard_fab2_lib.baseboard_fab2(sch_1):page27_i172:DDR4_DQ(20)" )
				( pinRef "@baseboard_fab2_lib.baseboard_fab2(sch_1):page51_i111:DQ(21)" )
				( attribute "RELATIVE_PROPAGATION_DELAY_SCOPE" "G"
					( Parent
						( matchGroupRef "@baseboard_fab2_lib.baseboard_fab2(sch_1):\MG_DQ-DQS_FAR_DIMM_NG_M_E_BYTE2\" )
					)
					( Status sCSetFlattened )
					( Origin gBackEnd )
				)
				( attribute "RELATIVE_PROPAGATION_DELAY" "0.00 MIL,195.00 MIL"
					( Parent
						( matchGroupRef "@baseboard_fab2_lib.baseboard_fab2(sch_1):\MG_DQ-DQS_FAR_DIMM_NG_M_E_BYTE2\" )
					)
					( Units "uMatchProp" "ns" 1.000000)
					( Status sCSetFlattened )
					( Origin gBackEnd )
				)
				( attribute "RELATIVE_PROPAGATION_DELAY_SCOPE" "G"
					( Parent
						( matchGroupRef "@crescent_city_bb_fab1_lib.crescent_city_bb_fab1(sch_1):\MG_DQ_FAR_DIMM_NG_M_E_BYTE2\" )
					)
					( Status sCSetFlattened )
					( Origin gBackEnd )
				)
				( attribute "RELATIVE_PROPAGATION_DELAY" "-50.00 MIL,50.00 MIL"
					( Parent
						( matchGroupRef "@crescent_city_bb_fab1_lib.crescent_city_bb_fab1(sch_1):\MG_DQ_FAR_DIMM_NG_M_E_BYTE2\" )
					)
					( Units "uMatchProp" "ns" 1.000000)
					( Status sCSetFlattened )
					( Origin gBackEnd )
				)
			)
			( pinPair "@baseboard_fab2_lib.baseboard_fab2(sch_1):\PP4433\"
				( pinRef "@baseboard_fab2_lib.baseboard_fab2(sch_1):page52_i12:DQ(20)" )
				( pinRef "@baseboard_fab2_lib.baseboard_fab2(sch_1):page27_i172:DDR4_DQ(20)" )
				( attribute "RELATIVE_PROPAGATION_DELAY_SCOPE" "G"
					( Parent
						( matchGroupRef "@baseboard_fab2_lib.baseboard_fab2(sch_1):\MG_DQ-DQS_NEAR_DIMM_NG_M_E_BYTE2\" )
					)
					( Status sCSetFlattened )
					( Origin gBackEnd )
				)
				( attribute "RELATIVE_PROPAGATION_DELAY" "0.00 MIL,195.00 MIL"
					( Parent
						( matchGroupRef "@baseboard_fab2_lib.baseboard_fab2(sch_1):\MG_DQ-DQS_NEAR_DIMM_NG_M_E_BYTE2\" )
					)
					( Units "uMatchProp" "ns" 1.000000)
					( Status sCSetFlattened )
					( Origin gBackEnd )
				)
				( attribute "RELATIVE_PROPAGATION_DELAY_SCOPE" "G"
					( Parent
						( matchGroupRef "@crescent_city_bb_fab1_lib.crescent_city_bb_fab1(sch_1):\MG_DQ_NEAR_DIMM_NG_M_E_BYTE2\" )
					)
					( Status sCSetFlattened )
					( Origin gBackEnd )
				)
				( attribute "RELATIVE_PROPAGATION_DELAY" "-50.00 MIL,50.00 MIL"
					( Parent
						( matchGroupRef "@crescent_city_bb_fab1_lib.crescent_city_bb_fab1(sch_1):\MG_DQ_NEAR_DIMM_NG_M_E_BYTE2\" )
					)
					( Units "uMatchProp" "ns" 1.000000)
					( Status sCSetFlattened )
					( Origin gBackEnd )
				)
			)
			( pinPair "@baseboard_fab2_lib.baseboard_fab2(sch_1):\PP4434\"
				( pinRef "@baseboard_fab2_lib.baseboard_fab2(sch_1):page27_i172:DDR4_DQ(21)" )
				( pinRef "@baseboard_fab2_lib.baseboard_fab2(sch_1):page51_i111:DQ(20)" )
				( attribute "RELATIVE_PROPAGATION_DELAY_SCOPE" "G"
					( Parent
						( matchGroupRef "@baseboard_fab2_lib.baseboard_fab2(sch_1):\MG_DQ-DQS_FAR_DIMM_NG_M_E_BYTE2\" )
					)
					( Status sCSetFlattened )
					( Origin gBackEnd )
				)
				( attribute "RELATIVE_PROPAGATION_DELAY" "0.00 MIL,195.00 MIL"
					( Parent
						( matchGroupRef "@baseboard_fab2_lib.baseboard_fab2(sch_1):\MG_DQ-DQS_FAR_DIMM_NG_M_E_BYTE2\" )
					)
					( Units "uMatchProp" "ns" 1.000000)
					( Status sCSetFlattened )
					( Origin gBackEnd )
				)
				( attribute "RELATIVE_PROPAGATION_DELAY_SCOPE" "G"
					( Parent
						( matchGroupRef "@crescent_city_bb_fab1_lib.crescent_city_bb_fab1(sch_1):\MG_DQ_FAR_DIMM_NG_M_E_BYTE2\" )
					)
					( Status sCSetFlattened )
					( Origin gBackEnd )
				)
				( attribute "RELATIVE_PROPAGATION_DELAY" "-50.00 MIL,50.00 MIL"
					( Parent
						( matchGroupRef "@crescent_city_bb_fab1_lib.crescent_city_bb_fab1(sch_1):\MG_DQ_FAR_DIMM_NG_M_E_BYTE2\" )
					)
					( Units "uMatchProp" "ns" 1.000000)
					( Status sCSetFlattened )
					( Origin gBackEnd )
				)
			)
			( pinPair "@baseboard_fab2_lib.baseboard_fab2(sch_1):\PP4436\"
				( pinRef "@baseboard_fab2_lib.baseboard_fab2(sch_1):page52_i12:DQ(21)" )
				( pinRef "@baseboard_fab2_lib.baseboard_fab2(sch_1):page27_i172:DDR4_DQ(21)" )
				( attribute "RELATIVE_PROPAGATION_DELAY_SCOPE" "G"
					( Parent
						( matchGroupRef "@baseboard_fab2_lib.baseboard_fab2(sch_1):\MG_DQ-DQS_NEAR_DIMM_NG_M_E_BYTE2\" )
					)
					( Status sCSetFlattened )
					( Origin gBackEnd )
				)
				( attribute "RELATIVE_PROPAGATION_DELAY" "0.00 MIL,195.00 MIL"
					( Parent
						( matchGroupRef "@baseboard_fab2_lib.baseboard_fab2(sch_1):\MG_DQ-DQS_NEAR_DIMM_NG_M_E_BYTE2\" )
					)
					( Units "uMatchProp" "ns" 1.000000)
					( Status sCSetFlattened )
					( Origin gBackEnd )
				)
				( attribute "RELATIVE_PROPAGATION_DELAY_SCOPE" "G"
					( Parent
						( matchGroupRef "@crescent_city_bb_fab1_lib.crescent_city_bb_fab1(sch_1):\MG_DQ_NEAR_DIMM_NG_M_E_BYTE2\" )
					)
					( Status sCSetFlattened )
					( Origin gBackEnd )
				)
				( attribute "RELATIVE_PROPAGATION_DELAY" "-50.00 MIL,50.00 MIL"
					( Parent
						( matchGroupRef "@crescent_city_bb_fab1_lib.crescent_city_bb_fab1(sch_1):\MG_DQ_NEAR_DIMM_NG_M_E_BYTE2\" )
					)
					( Units "uMatchProp" "ns" 1.000000)
					( Status sCSetFlattened )
					( Origin gBackEnd )
				)
			)
			( pinPair "@baseboard_fab2_lib.baseboard_fab2(sch_1):\PP4437\"
				( pinRef "@baseboard_fab2_lib.baseboard_fab2(sch_1):page27_i172:DDR4_DQ(22)" )
				( pinRef "@baseboard_fab2_lib.baseboard_fab2(sch_1):page51_i111:DQ(23)" )
				( attribute "RELATIVE_PROPAGATION_DELAY_SCOPE" "G"
					( Parent
						( matchGroupRef "@baseboard_fab2_lib.baseboard_fab2(sch_1):\MG_DQ-DQS_FAR_DIMM_NG_M_E_BYTE2\" )
					)
					( Status sCSetFlattened )
					( Origin gBackEnd )
				)
				( attribute "RELATIVE_PROPAGATION_DELAY" "0.00 MIL,195.00 MIL"
					( Parent
						( matchGroupRef "@baseboard_fab2_lib.baseboard_fab2(sch_1):\MG_DQ-DQS_FAR_DIMM_NG_M_E_BYTE2\" )
					)
					( Units "uMatchProp" "ns" 1.000000)
					( Status sCSetFlattened )
					( Origin gBackEnd )
				)
				( attribute "RELATIVE_PROPAGATION_DELAY_SCOPE" "G"
					( Parent
						( matchGroupRef "@crescent_city_bb_fab1_lib.crescent_city_bb_fab1(sch_1):\MG_DQ_FAR_DIMM_NG_M_E_BYTE2\" )
					)
					( Origin gBackEnd )
				)
				( attribute "RELATIVE_PROPAGATION_DELAY" "TARGET,TARGET"
					( Parent
						( matchGroupRef "@crescent_city_bb_fab1_lib.crescent_city_bb_fab1(sch_1):\MG_DQ_FAR_DIMM_NG_M_E_BYTE2\" )
					)
					( Units "uMatchProp" "ns" 1.000000)
					( Origin gBackEnd )
				)
			)
			( pinPair "@baseboard_fab2_lib.baseboard_fab2(sch_1):\PP4439\"
				( pinRef "@baseboard_fab2_lib.baseboard_fab2(sch_1):page52_i12:DQ(22)" )
				( pinRef "@baseboard_fab2_lib.baseboard_fab2(sch_1):page27_i172:DDR4_DQ(22)" )
				( attribute "RELATIVE_PROPAGATION_DELAY_SCOPE" "G"
					( Parent
						( matchGroupRef "@baseboard_fab2_lib.baseboard_fab2(sch_1):\MG_DQ-DQS_NEAR_DIMM_NG_M_E_BYTE2\" )
					)
					( Status sCSetFlattened )
					( Origin gBackEnd )
				)
				( attribute "RELATIVE_PROPAGATION_DELAY" "0.00 MIL,195.00 MIL"
					( Parent
						( matchGroupRef "@baseboard_fab2_lib.baseboard_fab2(sch_1):\MG_DQ-DQS_NEAR_DIMM_NG_M_E_BYTE2\" )
					)
					( Units "uMatchProp" "ns" 1.000000)
					( Status sCSetFlattened )
					( Origin gBackEnd )
				)
				( attribute "RELATIVE_PROPAGATION_DELAY_SCOPE" "G"
					( Parent
						( matchGroupRef "@crescent_city_bb_fab1_lib.crescent_city_bb_fab1(sch_1):\MG_DQ_NEAR_DIMM_NG_M_E_BYTE2\" )
					)
					( Status sCSetFlattened )
					( Origin gBackEnd )
				)
				( attribute "RELATIVE_PROPAGATION_DELAY" "-50.00 MIL,50.00 MIL"
					( Parent
						( matchGroupRef "@crescent_city_bb_fab1_lib.crescent_city_bb_fab1(sch_1):\MG_DQ_NEAR_DIMM_NG_M_E_BYTE2\" )
					)
					( Units "uMatchProp" "ns" 1.000000)
					( Status sCSetFlattened )
					( Origin gBackEnd )
				)
			)
			( pinPair "@baseboard_fab2_lib.baseboard_fab2(sch_1):\PP4440\"
				( pinRef "@baseboard_fab2_lib.baseboard_fab2(sch_1):page27_i172:DDR4_DQ(23)" )
				( pinRef "@baseboard_fab2_lib.baseboard_fab2(sch_1):page51_i111:DQ(22)" )
				( attribute "RELATIVE_PROPAGATION_DELAY_SCOPE" "G"
					( Parent
						( matchGroupRef "@baseboard_fab2_lib.baseboard_fab2(sch_1):\MG_DQ-DQS_FAR_DIMM_NG_M_E_BYTE2\" )
					)
					( Status sCSetFlattened )
					( Origin gBackEnd )
				)
				( attribute "RELATIVE_PROPAGATION_DELAY" "0.00 MIL,195.00 MIL"
					( Parent
						( matchGroupRef "@baseboard_fab2_lib.baseboard_fab2(sch_1):\MG_DQ-DQS_FAR_DIMM_NG_M_E_BYTE2\" )
					)
					( Units "uMatchProp" "ns" 1.000000)
					( Status sCSetFlattened )
					( Origin gBackEnd )
				)
				( attribute "RELATIVE_PROPAGATION_DELAY_SCOPE" "G"
					( Parent
						( matchGroupRef "@crescent_city_bb_fab1_lib.crescent_city_bb_fab1(sch_1):\MG_DQ_FAR_DIMM_NG_M_E_BYTE2\" )
					)
					( Status sCSetFlattened )
					( Origin gBackEnd )
				)
				( attribute "RELATIVE_PROPAGATION_DELAY" "-50.00 MIL,50.00 MIL"
					( Parent
						( matchGroupRef "@crescent_city_bb_fab1_lib.crescent_city_bb_fab1(sch_1):\MG_DQ_FAR_DIMM_NG_M_E_BYTE2\" )
					)
					( Units "uMatchProp" "ns" 1.000000)
					( Status sCSetFlattened )
					( Origin gBackEnd )
				)
			)
			( pinPair "@baseboard_fab2_lib.baseboard_fab2(sch_1):\PP4442\"
				( pinRef "@baseboard_fab2_lib.baseboard_fab2(sch_1):page52_i12:DQ(23)" )
				( pinRef "@baseboard_fab2_lib.baseboard_fab2(sch_1):page27_i172:DDR4_DQ(23)" )
				( attribute "RELATIVE_PROPAGATION_DELAY_SCOPE" "G"
					( Parent
						( matchGroupRef "@baseboard_fab2_lib.baseboard_fab2(sch_1):\MG_DQ-DQS_NEAR_DIMM_NG_M_E_BYTE2\" )
					)
					( Status sCSetFlattened )
					( Origin gBackEnd )
				)
				( attribute "RELATIVE_PROPAGATION_DELAY" "0.00 MIL,195.00 MIL"
					( Parent
						( matchGroupRef "@baseboard_fab2_lib.baseboard_fab2(sch_1):\MG_DQ-DQS_NEAR_DIMM_NG_M_E_BYTE2\" )
					)
					( Units "uMatchProp" "ns" 1.000000)
					( Status sCSetFlattened )
					( Origin gBackEnd )
				)
				( attribute "RELATIVE_PROPAGATION_DELAY_SCOPE" "G"
					( Parent
						( matchGroupRef "@crescent_city_bb_fab1_lib.crescent_city_bb_fab1(sch_1):\MG_DQ_NEAR_DIMM_NG_M_E_BYTE2\" )
					)
					( Status sCSetFlattened )
					( Origin gBackEnd )
				)
				( attribute "RELATIVE_PROPAGATION_DELAY" "-50.00 MIL,50.00 MIL"
					( Parent
						( matchGroupRef "@crescent_city_bb_fab1_lib.crescent_city_bb_fab1(sch_1):\MG_DQ_NEAR_DIMM_NG_M_E_BYTE2\" )
					)
					( Units "uMatchProp" "ns" 1.000000)
					( Status sCSetFlattened )
					( Origin gBackEnd )
				)
			)
			( pinPair "@baseboard_fab2_lib.baseboard_fab2(sch_1):\PP4299\"
				( pinRef "@baseboard_fab2_lib.baseboard_fab2(sch_1):page27_i172:DDR4_DQ(24)" )
				( pinRef "@baseboard_fab2_lib.baseboard_fab2(sch_1):page51_i111:DQ(25)" )
				( attribute "RELATIVE_PROPAGATION_DELAY_SCOPE" "G"
					( Parent
						( matchGroupRef "@baseboard_fab2_lib.baseboard_fab2(sch_1):\MG_DQ-DQS_FAR_DIMM_NG_M_E_BYTE3\" )
					)
					( Status sCSetFlattened )
					( Origin gBackEnd )
				)
				( attribute "RELATIVE_PROPAGATION_DELAY" "0.00 MIL,195.00 MIL"
					( Parent
						( matchGroupRef "@baseboard_fab2_lib.baseboard_fab2(sch_1):\MG_DQ-DQS_FAR_DIMM_NG_M_E_BYTE3\" )
					)
					( Units "uMatchProp" "ns" 1.000000)
					( Status sCSetFlattened )
					( Origin gBackEnd )
				)
				( attribute "RELATIVE_PROPAGATION_DELAY_SCOPE" "G"
					( Parent
						( matchGroupRef "@crescent_city_bb_fab1_lib.crescent_city_bb_fab1(sch_1):\MG_DQ_FAR_DIMM_NG_M_E_BYTE3\" )
					)
					( Origin gBackEnd )
				)
				( attribute "RELATIVE_PROPAGATION_DELAY" "-64.27 MIL,50.00 MIL"
					( Parent
						( matchGroupRef "@crescent_city_bb_fab1_lib.crescent_city_bb_fab1(sch_1):\MG_DQ_FAR_DIMM_NG_M_E_BYTE3\" )
					)
					( Units "uMatchProp" "ns" 1.000000)
					( Origin gBackEnd )
				)
			)
			( pinPair "@baseboard_fab2_lib.baseboard_fab2(sch_1):\PP4301\"
				( pinRef "@baseboard_fab2_lib.baseboard_fab2(sch_1):page52_i12:DQ(24)" )
				( pinRef "@baseboard_fab2_lib.baseboard_fab2(sch_1):page27_i172:DDR4_DQ(24)" )
				( attribute "RELATIVE_PROPAGATION_DELAY_SCOPE" "G"
					( Parent
						( matchGroupRef "@baseboard_fab2_lib.baseboard_fab2(sch_1):\MG_DQ-DQS_NEAR_DIMM_NG_M_E_BYTE3\" )
					)
					( Status sCSetFlattened )
					( Origin gBackEnd )
				)
				( attribute "RELATIVE_PROPAGATION_DELAY" "0.00 MIL,195.00 MIL"
					( Parent
						( matchGroupRef "@baseboard_fab2_lib.baseboard_fab2(sch_1):\MG_DQ-DQS_NEAR_DIMM_NG_M_E_BYTE3\" )
					)
					( Units "uMatchProp" "ns" 1.000000)
					( Status sCSetFlattened )
					( Origin gBackEnd )
				)
				( attribute "RELATIVE_PROPAGATION_DELAY_SCOPE" "G"
					( Parent
						( matchGroupRef "@crescent_city_bb_fab1_lib.crescent_city_bb_fab1(sch_1):\MG_DQ_NEAR_DIMM_NG_M_E_BYTE3\" )
					)
					( Origin gBackEnd )
				)
				( attribute "RELATIVE_PROPAGATION_DELAY" "-64.27 MIL,50.00 MIL"
					( Parent
						( matchGroupRef "@crescent_city_bb_fab1_lib.crescent_city_bb_fab1(sch_1):\MG_DQ_NEAR_DIMM_NG_M_E_BYTE3\" )
					)
					( Units "uMatchProp" "ns" 1.000000)
					( Origin gBackEnd )
				)
			)
			( pinPair "@baseboard_fab2_lib.baseboard_fab2(sch_1):\PP4302\"
				( pinRef "@baseboard_fab2_lib.baseboard_fab2(sch_1):page27_i172:DDR4_DQ(25)" )
				( pinRef "@baseboard_fab2_lib.baseboard_fab2(sch_1):page51_i111:DQ(24)" )
				( attribute "RELATIVE_PROPAGATION_DELAY_SCOPE" "G"
					( Parent
						( matchGroupRef "@baseboard_fab2_lib.baseboard_fab2(sch_1):\MG_DQ-DQS_FAR_DIMM_NG_M_E_BYTE3\" )
					)
					( Status sCSetFlattened )
					( Origin gBackEnd )
				)
				( attribute "RELATIVE_PROPAGATION_DELAY" "0.00 MIL,195.00 MIL"
					( Parent
						( matchGroupRef "@baseboard_fab2_lib.baseboard_fab2(sch_1):\MG_DQ-DQS_FAR_DIMM_NG_M_E_BYTE3\" )
					)
					( Units "uMatchProp" "ns" 1.000000)
					( Status sCSetFlattened )
					( Origin gBackEnd )
				)
				( attribute "RELATIVE_PROPAGATION_DELAY_SCOPE" "G"
					( Parent
						( matchGroupRef "@crescent_city_bb_fab1_lib.crescent_city_bb_fab1(sch_1):\MG_DQ_FAR_DIMM_NG_M_E_BYTE3\" )
					)
					( Origin gBackEnd )
				)
				( attribute "RELATIVE_PROPAGATION_DELAY" "-67.43 MIL,50.00 MIL"
					( Parent
						( matchGroupRef "@crescent_city_bb_fab1_lib.crescent_city_bb_fab1(sch_1):\MG_DQ_FAR_DIMM_NG_M_E_BYTE3\" )
					)
					( Units "uMatchProp" "ns" 1.000000)
					( Origin gBackEnd )
				)
			)
			( pinPair "@baseboard_fab2_lib.baseboard_fab2(sch_1):\PP4304\"
				( pinRef "@baseboard_fab2_lib.baseboard_fab2(sch_1):page52_i12:DQ(25)" )
				( pinRef "@baseboard_fab2_lib.baseboard_fab2(sch_1):page27_i172:DDR4_DQ(25)" )
				( attribute "RELATIVE_PROPAGATION_DELAY_SCOPE" "G"
					( Parent
						( matchGroupRef "@baseboard_fab2_lib.baseboard_fab2(sch_1):\MG_DQ-DQS_NEAR_DIMM_NG_M_E_BYTE3\" )
					)
					( Status sCSetFlattened )
					( Origin gBackEnd )
				)
				( attribute "RELATIVE_PROPAGATION_DELAY" "0.00 MIL,195.00 MIL"
					( Parent
						( matchGroupRef "@baseboard_fab2_lib.baseboard_fab2(sch_1):\MG_DQ-DQS_NEAR_DIMM_NG_M_E_BYTE3\" )
					)
					( Units "uMatchProp" "ns" 1.000000)
					( Status sCSetFlattened )
					( Origin gBackEnd )
				)
				( attribute "RELATIVE_PROPAGATION_DELAY_SCOPE" "G"
					( Parent
						( matchGroupRef "@crescent_city_bb_fab1_lib.crescent_city_bb_fab1(sch_1):\MG_DQ_NEAR_DIMM_NG_M_E_BYTE3\" )
					)
					( Origin gBackEnd )
				)
				( attribute "RELATIVE_PROPAGATION_DELAY" "-67.43 MIL,50.00 MIL"
					( Parent
						( matchGroupRef "@crescent_city_bb_fab1_lib.crescent_city_bb_fab1(sch_1):\MG_DQ_NEAR_DIMM_NG_M_E_BYTE3\" )
					)
					( Units "uMatchProp" "ns" 1.000000)
					( Origin gBackEnd )
				)
			)
			( pinPair "@baseboard_fab2_lib.baseboard_fab2(sch_1):\PP4305\"
				( pinRef "@baseboard_fab2_lib.baseboard_fab2(sch_1):page27_i172:DDR4_DQ(26)" )
				( pinRef "@baseboard_fab2_lib.baseboard_fab2(sch_1):page51_i111:DQ(27)" )
				( attribute "RELATIVE_PROPAGATION_DELAY_SCOPE" "G"
					( Parent
						( matchGroupRef "@baseboard_fab2_lib.baseboard_fab2(sch_1):\MG_DQ-DQS_FAR_DIMM_NG_M_E_BYTE3\" )
					)
					( Status sCSetFlattened )
					( Origin gBackEnd )
				)
				( attribute "RELATIVE_PROPAGATION_DELAY" "0.00 MIL,195.00 MIL"
					( Parent
						( matchGroupRef "@baseboard_fab2_lib.baseboard_fab2(sch_1):\MG_DQ-DQS_FAR_DIMM_NG_M_E_BYTE3\" )
					)
					( Units "uMatchProp" "ns" 1.000000)
					( Status sCSetFlattened )
					( Origin gBackEnd )
				)
				( attribute "RELATIVE_PROPAGATION_DELAY_SCOPE" "G"
					( Parent
						( matchGroupRef "@crescent_city_bb_fab1_lib.crescent_city_bb_fab1(sch_1):\MG_DQ_FAR_DIMM_NG_M_E_BYTE3\" )
					)
					( Origin gBackEnd )
				)
				( attribute "RELATIVE_PROPAGATION_DELAY" "-75.65 MIL,50.00 MIL"
					( Parent
						( matchGroupRef "@crescent_city_bb_fab1_lib.crescent_city_bb_fab1(sch_1):\MG_DQ_FAR_DIMM_NG_M_E_BYTE3\" )
					)
					( Units "uMatchProp" "ns" 1.000000)
					( Origin gBackEnd )
				)
			)
			( pinPair "@baseboard_fab2_lib.baseboard_fab2(sch_1):\PP4307\"
				( pinRef "@baseboard_fab2_lib.baseboard_fab2(sch_1):page52_i12:DQ(26)" )
				( pinRef "@baseboard_fab2_lib.baseboard_fab2(sch_1):page27_i172:DDR4_DQ(26)" )
				( attribute "RELATIVE_PROPAGATION_DELAY_SCOPE" "G"
					( Parent
						( matchGroupRef "@baseboard_fab2_lib.baseboard_fab2(sch_1):\MG_DQ-DQS_NEAR_DIMM_NG_M_E_BYTE3\" )
					)
					( Status sCSetFlattened )
					( Origin gBackEnd )
				)
				( attribute "RELATIVE_PROPAGATION_DELAY" "0.00 MIL,195.00 MIL"
					( Parent
						( matchGroupRef "@baseboard_fab2_lib.baseboard_fab2(sch_1):\MG_DQ-DQS_NEAR_DIMM_NG_M_E_BYTE3\" )
					)
					( Units "uMatchProp" "ns" 1.000000)
					( Status sCSetFlattened )
					( Origin gBackEnd )
				)
				( attribute "RELATIVE_PROPAGATION_DELAY_SCOPE" "G"
					( Parent
						( matchGroupRef "@crescent_city_bb_fab1_lib.crescent_city_bb_fab1(sch_1):\MG_DQ_NEAR_DIMM_NG_M_E_BYTE3\" )
					)
					( Origin gBackEnd )
				)
				( attribute "RELATIVE_PROPAGATION_DELAY" "-75.65 MIL,50.00 MIL"
					( Parent
						( matchGroupRef "@crescent_city_bb_fab1_lib.crescent_city_bb_fab1(sch_1):\MG_DQ_NEAR_DIMM_NG_M_E_BYTE3\" )
					)
					( Units "uMatchProp" "ns" 1.000000)
					( Origin gBackEnd )
				)
			)
			( pinPair "@baseboard_fab2_lib.baseboard_fab2(sch_1):\PP4308\"
				( pinRef "@baseboard_fab2_lib.baseboard_fab2(sch_1):page27_i172:DDR4_DQ(27)" )
				( pinRef "@baseboard_fab2_lib.baseboard_fab2(sch_1):page51_i111:DQ(26)" )
				( attribute "RELATIVE_PROPAGATION_DELAY_SCOPE" "G"
					( Parent
						( matchGroupRef "@baseboard_fab2_lib.baseboard_fab2(sch_1):\MG_DQ-DQS_FAR_DIMM_NG_M_E_BYTE3\" )
					)
					( Status sCSetFlattened )
					( Origin gBackEnd )
				)
				( attribute "RELATIVE_PROPAGATION_DELAY" "0.00 MIL,195.00 MIL"
					( Parent
						( matchGroupRef "@baseboard_fab2_lib.baseboard_fab2(sch_1):\MG_DQ-DQS_FAR_DIMM_NG_M_E_BYTE3\" )
					)
					( Units "uMatchProp" "ns" 1.000000)
					( Status sCSetFlattened )
					( Origin gBackEnd )
				)
				( attribute "RELATIVE_PROPAGATION_DELAY_SCOPE" "G"
					( Parent
						( matchGroupRef "@crescent_city_bb_fab1_lib.crescent_city_bb_fab1(sch_1):\MG_DQ_FAR_DIMM_NG_M_E_BYTE3\" )
					)
					( Origin gBackEnd )
				)
				( attribute "RELATIVE_PROPAGATION_DELAY" "-57.85 MIL,50.00 MIL"
					( Parent
						( matchGroupRef "@crescent_city_bb_fab1_lib.crescent_city_bb_fab1(sch_1):\MG_DQ_FAR_DIMM_NG_M_E_BYTE3\" )
					)
					( Units "uMatchProp" "ns" 1.000000)
					( Origin gBackEnd )
				)
			)
			( pinPair "@baseboard_fab2_lib.baseboard_fab2(sch_1):\PP4310\"
				( pinRef "@baseboard_fab2_lib.baseboard_fab2(sch_1):page52_i12:DQ(27)" )
				( pinRef "@baseboard_fab2_lib.baseboard_fab2(sch_1):page27_i172:DDR4_DQ(27)" )
				( attribute "RELATIVE_PROPAGATION_DELAY_SCOPE" "G"
					( Parent
						( matchGroupRef "@baseboard_fab2_lib.baseboard_fab2(sch_1):\MG_DQ-DQS_NEAR_DIMM_NG_M_E_BYTE3\" )
					)
					( Status sCSetFlattened )
					( Origin gBackEnd )
				)
				( attribute "RELATIVE_PROPAGATION_DELAY" "0.00 MIL,195.00 MIL"
					( Parent
						( matchGroupRef "@baseboard_fab2_lib.baseboard_fab2(sch_1):\MG_DQ-DQS_NEAR_DIMM_NG_M_E_BYTE3\" )
					)
					( Units "uMatchProp" "ns" 1.000000)
					( Status sCSetFlattened )
					( Origin gBackEnd )
				)
				( attribute "RELATIVE_PROPAGATION_DELAY_SCOPE" "G"
					( Parent
						( matchGroupRef "@crescent_city_bb_fab1_lib.crescent_city_bb_fab1(sch_1):\MG_DQ_NEAR_DIMM_NG_M_E_BYTE3\" )
					)
					( Origin gBackEnd )
				)
				( attribute "RELATIVE_PROPAGATION_DELAY" "-57.85 MIL,50.00 MIL"
					( Parent
						( matchGroupRef "@crescent_city_bb_fab1_lib.crescent_city_bb_fab1(sch_1):\MG_DQ_NEAR_DIMM_NG_M_E_BYTE3\" )
					)
					( Units "uMatchProp" "ns" 1.000000)
					( Origin gBackEnd )
				)
			)
			( pinPair "@baseboard_fab2_lib.baseboard_fab2(sch_1):\PP4311\"
				( pinRef "@baseboard_fab2_lib.baseboard_fab2(sch_1):page27_i172:DDR4_DQ(28)" )
				( pinRef "@baseboard_fab2_lib.baseboard_fab2(sch_1):page51_i111:DQ(29)" )
				( attribute "RELATIVE_PROPAGATION_DELAY_SCOPE" "G"
					( Parent
						( matchGroupRef "@baseboard_fab2_lib.baseboard_fab2(sch_1):\MG_DQ-DQS_FAR_DIMM_NG_M_E_BYTE3\" )
					)
					( Status sCSetFlattened )
					( Origin gBackEnd )
				)
				( attribute "RELATIVE_PROPAGATION_DELAY" "0.00 MIL,195.00 MIL"
					( Parent
						( matchGroupRef "@baseboard_fab2_lib.baseboard_fab2(sch_1):\MG_DQ-DQS_FAR_DIMM_NG_M_E_BYTE3\" )
					)
					( Units "uMatchProp" "ns" 1.000000)
					( Status sCSetFlattened )
					( Origin gBackEnd )
				)
				( attribute "RELATIVE_PROPAGATION_DELAY_SCOPE" "G"
					( Parent
						( matchGroupRef "@crescent_city_bb_fab1_lib.crescent_city_bb_fab1(sch_1):\MG_DQ_FAR_DIMM_NG_M_E_BYTE3\" )
					)
					( Origin gBackEnd )
				)
				( attribute "RELATIVE_PROPAGATION_DELAY" "TARGET,TARGET"
					( Parent
						( matchGroupRef "@crescent_city_bb_fab1_lib.crescent_city_bb_fab1(sch_1):\MG_DQ_FAR_DIMM_NG_M_E_BYTE3\" )
					)
					( Units "uMatchProp" "ns" 1.000000)
					( Origin gBackEnd )
				)
			)
			( pinPair "@baseboard_fab2_lib.baseboard_fab2(sch_1):\PP4313\"
				( pinRef "@baseboard_fab2_lib.baseboard_fab2(sch_1):page52_i12:DQ(28)" )
				( pinRef "@baseboard_fab2_lib.baseboard_fab2(sch_1):page27_i172:DDR4_DQ(28)" )
				( attribute "RELATIVE_PROPAGATION_DELAY_SCOPE" "G"
					( Parent
						( matchGroupRef "@baseboard_fab2_lib.baseboard_fab2(sch_1):\MG_DQ-DQS_NEAR_DIMM_NG_M_E_BYTE3\" )
					)
					( Status sCSetFlattened )
					( Origin gBackEnd )
				)
				( attribute "RELATIVE_PROPAGATION_DELAY" "0.00 MIL,195.00 MIL"
					( Parent
						( matchGroupRef "@baseboard_fab2_lib.baseboard_fab2(sch_1):\MG_DQ-DQS_NEAR_DIMM_NG_M_E_BYTE3\" )
					)
					( Units "uMatchProp" "ns" 1.000000)
					( Status sCSetFlattened )
					( Origin gBackEnd )
				)
				( attribute "RELATIVE_PROPAGATION_DELAY_SCOPE" "G"
					( Parent
						( matchGroupRef "@crescent_city_bb_fab1_lib.crescent_city_bb_fab1(sch_1):\MG_DQ_NEAR_DIMM_NG_M_E_BYTE3\" )
					)
					( Status sCSetFlattened )
					( Origin gBackEnd )
				)
				( attribute "RELATIVE_PROPAGATION_DELAY" "-50.00 MIL,50.00 MIL"
					( Parent
						( matchGroupRef "@crescent_city_bb_fab1_lib.crescent_city_bb_fab1(sch_1):\MG_DQ_NEAR_DIMM_NG_M_E_BYTE3\" )
					)
					( Units "uMatchProp" "ns" 1.000000)
					( Status sCSetFlattened )
					( Origin gBackEnd )
				)
			)
			( pinPair "@baseboard_fab2_lib.baseboard_fab2(sch_1):\PP4314\"
				( pinRef "@baseboard_fab2_lib.baseboard_fab2(sch_1):page27_i172:DDR4_DQ(29)" )
				( pinRef "@baseboard_fab2_lib.baseboard_fab2(sch_1):page51_i111:DQ(28)" )
				( attribute "RELATIVE_PROPAGATION_DELAY_SCOPE" "G"
					( Parent
						( matchGroupRef "@baseboard_fab2_lib.baseboard_fab2(sch_1):\MG_DQ-DQS_FAR_DIMM_NG_M_E_BYTE3\" )
					)
					( Status sCSetFlattened )
					( Origin gBackEnd )
				)
				( attribute "RELATIVE_PROPAGATION_DELAY" "0.00 MIL,195.00 MIL"
					( Parent
						( matchGroupRef "@baseboard_fab2_lib.baseboard_fab2(sch_1):\MG_DQ-DQS_FAR_DIMM_NG_M_E_BYTE3\" )
					)
					( Units "uMatchProp" "ns" 1.000000)
					( Status sCSetFlattened )
					( Origin gBackEnd )
				)
				( attribute "RELATIVE_PROPAGATION_DELAY_SCOPE" "G"
					( Parent
						( matchGroupRef "@crescent_city_bb_fab1_lib.crescent_city_bb_fab1(sch_1):\MG_DQ_FAR_DIMM_NG_M_E_BYTE3\" )
					)
					( Origin gBackEnd )
				)
				( attribute "RELATIVE_PROPAGATION_DELAY" "-61.41 MIL,50.00 MIL"
					( Parent
						( matchGroupRef "@crescent_city_bb_fab1_lib.crescent_city_bb_fab1(sch_1):\MG_DQ_FAR_DIMM_NG_M_E_BYTE3\" )
					)
					( Units "uMatchProp" "ns" 1.000000)
					( Origin gBackEnd )
				)
			)
			( pinPair "@baseboard_fab2_lib.baseboard_fab2(sch_1):\PP4316\"
				( pinRef "@baseboard_fab2_lib.baseboard_fab2(sch_1):page52_i12:DQ(29)" )
				( pinRef "@baseboard_fab2_lib.baseboard_fab2(sch_1):page27_i172:DDR4_DQ(29)" )
				( attribute "RELATIVE_PROPAGATION_DELAY_SCOPE" "G"
					( Parent
						( matchGroupRef "@baseboard_fab2_lib.baseboard_fab2(sch_1):\MG_DQ-DQS_NEAR_DIMM_NG_M_E_BYTE3\" )
					)
					( Status sCSetFlattened )
					( Origin gBackEnd )
				)
				( attribute "RELATIVE_PROPAGATION_DELAY" "0.00 MIL,195.00 MIL"
					( Parent
						( matchGroupRef "@baseboard_fab2_lib.baseboard_fab2(sch_1):\MG_DQ-DQS_NEAR_DIMM_NG_M_E_BYTE3\" )
					)
					( Units "uMatchProp" "ns" 1.000000)
					( Status sCSetFlattened )
					( Origin gBackEnd )
				)
				( attribute "RELATIVE_PROPAGATION_DELAY_SCOPE" "G"
					( Parent
						( matchGroupRef "@crescent_city_bb_fab1_lib.crescent_city_bb_fab1(sch_1):\MG_DQ_NEAR_DIMM_NG_M_E_BYTE3\" )
					)
					( Origin gBackEnd )
				)
				( attribute "RELATIVE_PROPAGATION_DELAY" "-61.41 MIL,50.00 MIL"
					( Parent
						( matchGroupRef "@crescent_city_bb_fab1_lib.crescent_city_bb_fab1(sch_1):\MG_DQ_NEAR_DIMM_NG_M_E_BYTE3\" )
					)
					( Units "uMatchProp" "ns" 1.000000)
					( Origin gBackEnd )
				)
			)
			( pinPair "@baseboard_fab2_lib.baseboard_fab2(sch_1):\PP4317\"
				( pinRef "@baseboard_fab2_lib.baseboard_fab2(sch_1):page27_i172:DDR4_DQ(30)" )
				( pinRef "@baseboard_fab2_lib.baseboard_fab2(sch_1):page51_i111:DQ(31)" )
				( attribute "RELATIVE_PROPAGATION_DELAY_SCOPE" "G"
					( Parent
						( matchGroupRef "@baseboard_fab2_lib.baseboard_fab2(sch_1):\MG_DQ-DQS_FAR_DIMM_NG_M_E_BYTE3\" )
					)
					( Status sCSetFlattened )
					( Origin gBackEnd )
				)
				( attribute "RELATIVE_PROPAGATION_DELAY" "0.00 MIL,195.00 MIL"
					( Parent
						( matchGroupRef "@baseboard_fab2_lib.baseboard_fab2(sch_1):\MG_DQ-DQS_FAR_DIMM_NG_M_E_BYTE3\" )
					)
					( Units "uMatchProp" "ns" 1.000000)
					( Status sCSetFlattened )
					( Origin gBackEnd )
				)
				( attribute "RELATIVE_PROPAGATION_DELAY_SCOPE" "G"
					( Parent
						( matchGroupRef "@crescent_city_bb_fab1_lib.crescent_city_bb_fab1(sch_1):\MG_DQ_FAR_DIMM_NG_M_E_BYTE3\" )
					)
					( Origin gBackEnd )
				)
				( attribute "RELATIVE_PROPAGATION_DELAY" "-70.54 MIL,50.00 MIL"
					( Parent
						( matchGroupRef "@crescent_city_bb_fab1_lib.crescent_city_bb_fab1(sch_1):\MG_DQ_FAR_DIMM_NG_M_E_BYTE3\" )
					)
					( Units "uMatchProp" "ns" 1.000000)
					( Origin gBackEnd )
				)
			)
			( pinPair "@baseboard_fab2_lib.baseboard_fab2(sch_1):\PP4319\"
				( pinRef "@baseboard_fab2_lib.baseboard_fab2(sch_1):page52_i12:DQ(30)" )
				( pinRef "@baseboard_fab2_lib.baseboard_fab2(sch_1):page27_i172:DDR4_DQ(30)" )
				( attribute "RELATIVE_PROPAGATION_DELAY_SCOPE" "G"
					( Parent
						( matchGroupRef "@baseboard_fab2_lib.baseboard_fab2(sch_1):\MG_DQ-DQS_NEAR_DIMM_NG_M_E_BYTE3\" )
					)
					( Status sCSetFlattened )
					( Origin gBackEnd )
				)
				( attribute "RELATIVE_PROPAGATION_DELAY" "0.00 MIL,195.00 MIL"
					( Parent
						( matchGroupRef "@baseboard_fab2_lib.baseboard_fab2(sch_1):\MG_DQ-DQS_NEAR_DIMM_NG_M_E_BYTE3\" )
					)
					( Units "uMatchProp" "ns" 1.000000)
					( Status sCSetFlattened )
					( Origin gBackEnd )
				)
				( attribute "RELATIVE_PROPAGATION_DELAY_SCOPE" "G"
					( Parent
						( matchGroupRef "@crescent_city_bb_fab1_lib.crescent_city_bb_fab1(sch_1):\MG_DQ_NEAR_DIMM_NG_M_E_BYTE3\" )
					)
					( Origin gBackEnd )
				)
				( attribute "RELATIVE_PROPAGATION_DELAY" "-70.54 MIL,50.00 MIL"
					( Parent
						( matchGroupRef "@crescent_city_bb_fab1_lib.crescent_city_bb_fab1(sch_1):\MG_DQ_NEAR_DIMM_NG_M_E_BYTE3\" )
					)
					( Units "uMatchProp" "ns" 1.000000)
					( Origin gBackEnd )
				)
			)
			( pinPair "@baseboard_fab2_lib.baseboard_fab2(sch_1):\PP4320\"
				( pinRef "@baseboard_fab2_lib.baseboard_fab2(sch_1):page27_i172:DDR4_DQ(31)" )
				( pinRef "@baseboard_fab2_lib.baseboard_fab2(sch_1):page51_i111:DQ(30)" )
				( attribute "RELATIVE_PROPAGATION_DELAY_SCOPE" "G"
					( Parent
						( matchGroupRef "@baseboard_fab2_lib.baseboard_fab2(sch_1):\MG_DQ-DQS_FAR_DIMM_NG_M_E_BYTE3\" )
					)
					( Status sCSetFlattened )
					( Origin gBackEnd )
				)
				( attribute "RELATIVE_PROPAGATION_DELAY" "0.00 MIL,195.00 MIL"
					( Parent
						( matchGroupRef "@baseboard_fab2_lib.baseboard_fab2(sch_1):\MG_DQ-DQS_FAR_DIMM_NG_M_E_BYTE3\" )
					)
					( Units "uMatchProp" "ns" 1.000000)
					( Status sCSetFlattened )
					( Origin gBackEnd )
				)
				( attribute "RELATIVE_PROPAGATION_DELAY_SCOPE" "G"
					( Parent
						( matchGroupRef "@crescent_city_bb_fab1_lib.crescent_city_bb_fab1(sch_1):\MG_DQ_FAR_DIMM_NG_M_E_BYTE3\" )
					)
					( Origin gBackEnd )
				)
				( attribute "RELATIVE_PROPAGATION_DELAY" "-72.73 MIL,50.00 MIL"
					( Parent
						( matchGroupRef "@crescent_city_bb_fab1_lib.crescent_city_bb_fab1(sch_1):\MG_DQ_FAR_DIMM_NG_M_E_BYTE3\" )
					)
					( Units "uMatchProp" "ns" 1.000000)
					( Origin gBackEnd )
				)
			)
			( pinPair "@baseboard_fab2_lib.baseboard_fab2(sch_1):\PP4322\"
				( pinRef "@baseboard_fab2_lib.baseboard_fab2(sch_1):page52_i12:DQ(31)" )
				( pinRef "@baseboard_fab2_lib.baseboard_fab2(sch_1):page27_i172:DDR4_DQ(31)" )
				( attribute "RELATIVE_PROPAGATION_DELAY_SCOPE" "G"
					( Parent
						( matchGroupRef "@baseboard_fab2_lib.baseboard_fab2(sch_1):\MG_DQ-DQS_NEAR_DIMM_NG_M_E_BYTE3\" )
					)
					( Status sCSetFlattened )
					( Origin gBackEnd )
				)
				( attribute "RELATIVE_PROPAGATION_DELAY" "0.00 MIL,195.00 MIL"
					( Parent
						( matchGroupRef "@baseboard_fab2_lib.baseboard_fab2(sch_1):\MG_DQ-DQS_NEAR_DIMM_NG_M_E_BYTE3\" )
					)
					( Units "uMatchProp" "ns" 1.000000)
					( Status sCSetFlattened )
					( Origin gBackEnd )
				)
				( attribute "RELATIVE_PROPAGATION_DELAY_SCOPE" "G"
					( Parent
						( matchGroupRef "@crescent_city_bb_fab1_lib.crescent_city_bb_fab1(sch_1):\MG_DQ_NEAR_DIMM_NG_M_E_BYTE3\" )
					)
					( Origin gBackEnd )
				)
				( attribute "RELATIVE_PROPAGATION_DELAY" "-72.73 MIL,50.00 MIL"
					( Parent
						( matchGroupRef "@crescent_city_bb_fab1_lib.crescent_city_bb_fab1(sch_1):\MG_DQ_NEAR_DIMM_NG_M_E_BYTE3\" )
					)
					( Units "uMatchProp" "ns" 1.000000)
					( Origin gBackEnd )
				)
			)
			( pinPair "@baseboard_fab2_lib.baseboard_fab2(sch_1):\PP4395\"
				( pinRef "@baseboard_fab2_lib.baseboard_fab2(sch_1):page27_i172:DDR4_DQ(32)" )
				( pinRef "@baseboard_fab2_lib.baseboard_fab2(sch_1):page51_i111:DQ(33)" )
				( attribute "RELATIVE_PROPAGATION_DELAY_SCOPE" "G"
					( Parent
						( matchGroupRef "@baseboard_fab2_lib.baseboard_fab2(sch_1):\MG_DQ-DQS_FAR_DIMM_NG_M_E_BYTE4\" )
					)
					( Status sCSetFlattened )
					( Origin gBackEnd )
				)
				( attribute "RELATIVE_PROPAGATION_DELAY" "0.00 MIL,195.00 MIL"
					( Parent
						( matchGroupRef "@baseboard_fab2_lib.baseboard_fab2(sch_1):\MG_DQ-DQS_FAR_DIMM_NG_M_E_BYTE4\" )
					)
					( Units "uMatchProp" "ns" 1.000000)
					( Status sCSetFlattened )
					( Origin gBackEnd )
				)
				( attribute "RELATIVE_PROPAGATION_DELAY_SCOPE" "G"
					( Parent
						( matchGroupRef "@crescent_city_bb_fab1_lib.crescent_city_bb_fab1(sch_1):\MG_DQ_FAR_DIMM_NG_M_E_BYTE4\" )
					)
					( Status sCSetFlattened )
					( Origin gBackEnd )
				)
				( attribute "RELATIVE_PROPAGATION_DELAY" "-50.00 MIL,50.00 MIL"
					( Parent
						( matchGroupRef "@crescent_city_bb_fab1_lib.crescent_city_bb_fab1(sch_1):\MG_DQ_FAR_DIMM_NG_M_E_BYTE4\" )
					)
					( Units "uMatchProp" "ns" 1.000000)
					( Status sCSetFlattened )
					( Origin gBackEnd )
				)
			)
			( pinPair "@baseboard_fab2_lib.baseboard_fab2(sch_1):\PP4396\"
				( pinRef "@baseboard_fab2_lib.baseboard_fab2(sch_1):page27_i172:DDR4_DQ(32)" )
				( pinRef "@baseboard_fab2_lib.baseboard_fab2(sch_1):page52_i12:DQ(32)" )
				( attribute "RELATIVE_PROPAGATION_DELAY_SCOPE" "G"
					( Parent
						( matchGroupRef "@baseboard_fab2_lib.baseboard_fab2(sch_1):\MG_DQ-DQS_NEAR_DIMM_NG_M_E_BYTE4\" )
					)
					( Status sCSetFlattened )
					( Origin gBackEnd )
				)
				( attribute "RELATIVE_PROPAGATION_DELAY" "0.00 MIL,195.00 MIL"
					( Parent
						( matchGroupRef "@baseboard_fab2_lib.baseboard_fab2(sch_1):\MG_DQ-DQS_NEAR_DIMM_NG_M_E_BYTE4\" )
					)
					( Units "uMatchProp" "ns" 1.000000)
					( Status sCSetFlattened )
					( Origin gBackEnd )
				)
				( attribute "RELATIVE_PROPAGATION_DELAY_SCOPE" "G"
					( Parent
						( matchGroupRef "@crescent_city_bb_fab1_lib.crescent_city_bb_fab1(sch_1):\MG_DQ_NEAR_DIMM_NG_M_E_BYTE4\" )
					)
					( Status sCSetFlattened )
					( Origin gBackEnd )
				)
				( attribute "RELATIVE_PROPAGATION_DELAY" "-50.00 MIL,50.00 MIL"
					( Parent
						( matchGroupRef "@crescent_city_bb_fab1_lib.crescent_city_bb_fab1(sch_1):\MG_DQ_NEAR_DIMM_NG_M_E_BYTE4\" )
					)
					( Units "uMatchProp" "ns" 1.000000)
					( Status sCSetFlattened )
					( Origin gBackEnd )
				)
			)
			( pinPair "@baseboard_fab2_lib.baseboard_fab2(sch_1):\PP4398\"
				( pinRef "@baseboard_fab2_lib.baseboard_fab2(sch_1):page27_i172:DDR4_DQ(33)" )
				( pinRef "@baseboard_fab2_lib.baseboard_fab2(sch_1):page51_i111:DQ(32)" )
				( attribute "RELATIVE_PROPAGATION_DELAY_SCOPE" "G"
					( Parent
						( matchGroupRef "@baseboard_fab2_lib.baseboard_fab2(sch_1):\MG_DQ-DQS_FAR_DIMM_NG_M_E_BYTE4\" )
					)
					( Status sCSetFlattened )
					( Origin gBackEnd )
				)
				( attribute "RELATIVE_PROPAGATION_DELAY" "0.00 MIL,195.00 MIL"
					( Parent
						( matchGroupRef "@baseboard_fab2_lib.baseboard_fab2(sch_1):\MG_DQ-DQS_FAR_DIMM_NG_M_E_BYTE4\" )
					)
					( Units "uMatchProp" "ns" 1.000000)
					( Status sCSetFlattened )
					( Origin gBackEnd )
				)
				( attribute "RELATIVE_PROPAGATION_DELAY_SCOPE" "G"
					( Parent
						( matchGroupRef "@crescent_city_bb_fab1_lib.crescent_city_bb_fab1(sch_1):\MG_DQ_FAR_DIMM_NG_M_E_BYTE4\" )
					)
					( Status sCSetFlattened )
					( Origin gBackEnd )
				)
				( attribute "RELATIVE_PROPAGATION_DELAY" "-50.00 MIL,50.00 MIL"
					( Parent
						( matchGroupRef "@crescent_city_bb_fab1_lib.crescent_city_bb_fab1(sch_1):\MG_DQ_FAR_DIMM_NG_M_E_BYTE4\" )
					)
					( Units "uMatchProp" "ns" 1.000000)
					( Status sCSetFlattened )
					( Origin gBackEnd )
				)
			)
			( pinPair "@baseboard_fab2_lib.baseboard_fab2(sch_1):\PP4399\"
				( pinRef "@baseboard_fab2_lib.baseboard_fab2(sch_1):page27_i172:DDR4_DQ(33)" )
				( pinRef "@baseboard_fab2_lib.baseboard_fab2(sch_1):page52_i12:DQ(33)" )
				( attribute "RELATIVE_PROPAGATION_DELAY_SCOPE" "G"
					( Parent
						( matchGroupRef "@baseboard_fab2_lib.baseboard_fab2(sch_1):\MG_DQ-DQS_NEAR_DIMM_NG_M_E_BYTE4\" )
					)
					( Status sCSetFlattened )
					( Origin gBackEnd )
				)
				( attribute "RELATIVE_PROPAGATION_DELAY" "0.00 MIL,195.00 MIL"
					( Parent
						( matchGroupRef "@baseboard_fab2_lib.baseboard_fab2(sch_1):\MG_DQ-DQS_NEAR_DIMM_NG_M_E_BYTE4\" )
					)
					( Units "uMatchProp" "ns" 1.000000)
					( Status sCSetFlattened )
					( Origin gBackEnd )
				)
				( attribute "RELATIVE_PROPAGATION_DELAY_SCOPE" "G"
					( Parent
						( matchGroupRef "@crescent_city_bb_fab1_lib.crescent_city_bb_fab1(sch_1):\MG_DQ_NEAR_DIMM_NG_M_E_BYTE4\" )
					)
					( Status sCSetFlattened )
					( Origin gBackEnd )
				)
				( attribute "RELATIVE_PROPAGATION_DELAY" "-50.00 MIL,50.00 MIL"
					( Parent
						( matchGroupRef "@crescent_city_bb_fab1_lib.crescent_city_bb_fab1(sch_1):\MG_DQ_NEAR_DIMM_NG_M_E_BYTE4\" )
					)
					( Units "uMatchProp" "ns" 1.000000)
					( Status sCSetFlattened )
					( Origin gBackEnd )
				)
			)
			( pinPair "@baseboard_fab2_lib.baseboard_fab2(sch_1):\PP4401\"
				( pinRef "@baseboard_fab2_lib.baseboard_fab2(sch_1):page27_i172:DDR4_DQ(34)" )
				( pinRef "@baseboard_fab2_lib.baseboard_fab2(sch_1):page51_i111:DQ(35)" )
				( attribute "RELATIVE_PROPAGATION_DELAY_SCOPE" "G"
					( Parent
						( matchGroupRef "@baseboard_fab2_lib.baseboard_fab2(sch_1):\MG_DQ-DQS_FAR_DIMM_NG_M_E_BYTE4\" )
					)
					( Status sCSetFlattened )
					( Origin gBackEnd )
				)
				( attribute "RELATIVE_PROPAGATION_DELAY" "0.00 MIL,195.00 MIL"
					( Parent
						( matchGroupRef "@baseboard_fab2_lib.baseboard_fab2(sch_1):\MG_DQ-DQS_FAR_DIMM_NG_M_E_BYTE4\" )
					)
					( Units "uMatchProp" "ns" 1.000000)
					( Status sCSetFlattened )
					( Origin gBackEnd )
				)
				( attribute "RELATIVE_PROPAGATION_DELAY_SCOPE" "G"
					( Parent
						( matchGroupRef "@crescent_city_bb_fab1_lib.crescent_city_bb_fab1(sch_1):\MG_DQ_FAR_DIMM_NG_M_E_BYTE4\" )
					)
					( Status sCSetFlattened )
					( Origin gBackEnd )
				)
				( attribute "RELATIVE_PROPAGATION_DELAY" "-50.00 MIL,50.00 MIL"
					( Parent
						( matchGroupRef "@crescent_city_bb_fab1_lib.crescent_city_bb_fab1(sch_1):\MG_DQ_FAR_DIMM_NG_M_E_BYTE4\" )
					)
					( Units "uMatchProp" "ns" 1.000000)
					( Status sCSetFlattened )
					( Origin gBackEnd )
				)
			)
			( pinPair "@baseboard_fab2_lib.baseboard_fab2(sch_1):\PP4403\"
				( pinRef "@baseboard_fab2_lib.baseboard_fab2(sch_1):page27_i172:DDR4_DQ(34)" )
				( pinRef "@baseboard_fab2_lib.baseboard_fab2(sch_1):page52_i12:DQ(34)" )
				( attribute "RELATIVE_PROPAGATION_DELAY_SCOPE" "G"
					( Parent
						( matchGroupRef "@baseboard_fab2_lib.baseboard_fab2(sch_1):\MG_DQ-DQS_NEAR_DIMM_NG_M_E_BYTE4\" )
					)
					( Status sCSetFlattened )
					( Origin gBackEnd )
				)
				( attribute "RELATIVE_PROPAGATION_DELAY" "0.00 MIL,195.00 MIL"
					( Parent
						( matchGroupRef "@baseboard_fab2_lib.baseboard_fab2(sch_1):\MG_DQ-DQS_NEAR_DIMM_NG_M_E_BYTE4\" )
					)
					( Units "uMatchProp" "ns" 1.000000)
					( Status sCSetFlattened )
					( Origin gBackEnd )
				)
				( attribute "RELATIVE_PROPAGATION_DELAY_SCOPE" "G"
					( Parent
						( matchGroupRef "@crescent_city_bb_fab1_lib.crescent_city_bb_fab1(sch_1):\MG_DQ_NEAR_DIMM_NG_M_E_BYTE4\" )
					)
					( Status sCSetFlattened )
					( Origin gBackEnd )
				)
				( attribute "RELATIVE_PROPAGATION_DELAY" "-50.00 MIL,50.00 MIL"
					( Parent
						( matchGroupRef "@crescent_city_bb_fab1_lib.crescent_city_bb_fab1(sch_1):\MG_DQ_NEAR_DIMM_NG_M_E_BYTE4\" )
					)
					( Units "uMatchProp" "ns" 1.000000)
					( Status sCSetFlattened )
					( Origin gBackEnd )
				)
			)
			( pinPair "@baseboard_fab2_lib.baseboard_fab2(sch_1):\PP4404\"
				( pinRef "@baseboard_fab2_lib.baseboard_fab2(sch_1):page27_i172:DDR4_DQ(35)" )
				( pinRef "@baseboard_fab2_lib.baseboard_fab2(sch_1):page51_i111:DQ(34)" )
				( attribute "RELATIVE_PROPAGATION_DELAY_SCOPE" "G"
					( Parent
						( matchGroupRef "@baseboard_fab2_lib.baseboard_fab2(sch_1):\MG_DQ-DQS_FAR_DIMM_NG_M_E_BYTE4\" )
					)
					( Status sCSetFlattened )
					( Origin gBackEnd )
				)
				( attribute "RELATIVE_PROPAGATION_DELAY" "0.00 MIL,195.00 MIL"
					( Parent
						( matchGroupRef "@baseboard_fab2_lib.baseboard_fab2(sch_1):\MG_DQ-DQS_FAR_DIMM_NG_M_E_BYTE4\" )
					)
					( Units "uMatchProp" "ns" 1.000000)
					( Status sCSetFlattened )
					( Origin gBackEnd )
				)
				( attribute "RELATIVE_PROPAGATION_DELAY_SCOPE" "G"
					( Parent
						( matchGroupRef "@crescent_city_bb_fab1_lib.crescent_city_bb_fab1(sch_1):\MG_DQ_FAR_DIMM_NG_M_E_BYTE4\" )
					)
					( Status sCSetFlattened )
					( Origin gBackEnd )
				)
				( attribute "RELATIVE_PROPAGATION_DELAY" "-50.00 MIL,50.00 MIL"
					( Parent
						( matchGroupRef "@crescent_city_bb_fab1_lib.crescent_city_bb_fab1(sch_1):\MG_DQ_FAR_DIMM_NG_M_E_BYTE4\" )
					)
					( Units "uMatchProp" "ns" 1.000000)
					( Status sCSetFlattened )
					( Origin gBackEnd )
				)
			)
			( pinPair "@baseboard_fab2_lib.baseboard_fab2(sch_1):\PP4406\"
				( pinRef "@baseboard_fab2_lib.baseboard_fab2(sch_1):page27_i172:DDR4_DQ(35)" )
				( pinRef "@baseboard_fab2_lib.baseboard_fab2(sch_1):page52_i12:DQ(35)" )
				( attribute "RELATIVE_PROPAGATION_DELAY_SCOPE" "G"
					( Parent
						( matchGroupRef "@baseboard_fab2_lib.baseboard_fab2(sch_1):\MG_DQ-DQS_NEAR_DIMM_NG_M_E_BYTE4\" )
					)
					( Status sCSetFlattened )
					( Origin gBackEnd )
				)
				( attribute "RELATIVE_PROPAGATION_DELAY" "0.00 MIL,195.00 MIL"
					( Parent
						( matchGroupRef "@baseboard_fab2_lib.baseboard_fab2(sch_1):\MG_DQ-DQS_NEAR_DIMM_NG_M_E_BYTE4\" )
					)
					( Units "uMatchProp" "ns" 1.000000)
					( Status sCSetFlattened )
					( Origin gBackEnd )
				)
				( attribute "RELATIVE_PROPAGATION_DELAY_SCOPE" "G"
					( Parent
						( matchGroupRef "@crescent_city_bb_fab1_lib.crescent_city_bb_fab1(sch_1):\MG_DQ_NEAR_DIMM_NG_M_E_BYTE4\" )
					)
					( Origin gBackEnd )
				)
				( attribute "RELATIVE_PROPAGATION_DELAY" "TARGET,TARGET"
					( Parent
						( matchGroupRef "@crescent_city_bb_fab1_lib.crescent_city_bb_fab1(sch_1):\MG_DQ_NEAR_DIMM_NG_M_E_BYTE4\" )
					)
					( Units "uMatchProp" "ns" 1.000000)
					( Origin gBackEnd )
				)
			)
			( pinPair "@baseboard_fab2_lib.baseboard_fab2(sch_1):\PP4407\"
				( pinRef "@baseboard_fab2_lib.baseboard_fab2(sch_1):page27_i172:DDR4_DQ(36)" )
				( pinRef "@baseboard_fab2_lib.baseboard_fab2(sch_1):page51_i111:DQ(37)" )
				( attribute "RELATIVE_PROPAGATION_DELAY_SCOPE" "G"
					( Parent
						( matchGroupRef "@baseboard_fab2_lib.baseboard_fab2(sch_1):\MG_DQ-DQS_FAR_DIMM_NG_M_E_BYTE4\" )
					)
					( Status sCSetFlattened )
					( Origin gBackEnd )
				)
				( attribute "RELATIVE_PROPAGATION_DELAY" "0.00 MIL,195.00 MIL"
					( Parent
						( matchGroupRef "@baseboard_fab2_lib.baseboard_fab2(sch_1):\MG_DQ-DQS_FAR_DIMM_NG_M_E_BYTE4\" )
					)
					( Units "uMatchProp" "ns" 1.000000)
					( Status sCSetFlattened )
					( Origin gBackEnd )
				)
				( attribute "RELATIVE_PROPAGATION_DELAY_SCOPE" "G"
					( Parent
						( matchGroupRef "@crescent_city_bb_fab1_lib.crescent_city_bb_fab1(sch_1):\MG_DQ_FAR_DIMM_NG_M_E_BYTE4\" )
					)
					( Status sCSetFlattened )
					( Origin gBackEnd )
				)
				( attribute "RELATIVE_PROPAGATION_DELAY" "-50.00 MIL,50.00 MIL"
					( Parent
						( matchGroupRef "@crescent_city_bb_fab1_lib.crescent_city_bb_fab1(sch_1):\MG_DQ_FAR_DIMM_NG_M_E_BYTE4\" )
					)
					( Units "uMatchProp" "ns" 1.000000)
					( Status sCSetFlattened )
					( Origin gBackEnd )
				)
			)
			( pinPair "@baseboard_fab2_lib.baseboard_fab2(sch_1):\PP4408\"
				( pinRef "@baseboard_fab2_lib.baseboard_fab2(sch_1):page27_i172:DDR4_DQ(36)" )
				( pinRef "@baseboard_fab2_lib.baseboard_fab2(sch_1):page52_i12:DQ(36)" )
				( attribute "RELATIVE_PROPAGATION_DELAY_SCOPE" "G"
					( Parent
						( matchGroupRef "@baseboard_fab2_lib.baseboard_fab2(sch_1):\MG_DQ-DQS_NEAR_DIMM_NG_M_E_BYTE4\" )
					)
					( Status sCSetFlattened )
					( Origin gBackEnd )
				)
				( attribute "RELATIVE_PROPAGATION_DELAY" "0.00 MIL,195.00 MIL"
					( Parent
						( matchGroupRef "@baseboard_fab2_lib.baseboard_fab2(sch_1):\MG_DQ-DQS_NEAR_DIMM_NG_M_E_BYTE4\" )
					)
					( Units "uMatchProp" "ns" 1.000000)
					( Status sCSetFlattened )
					( Origin gBackEnd )
				)
				( attribute "RELATIVE_PROPAGATION_DELAY_SCOPE" "G"
					( Parent
						( matchGroupRef "@crescent_city_bb_fab1_lib.crescent_city_bb_fab1(sch_1):\MG_DQ_NEAR_DIMM_NG_M_E_BYTE4\" )
					)
					( Status sCSetFlattened )
					( Origin gBackEnd )
				)
				( attribute "RELATIVE_PROPAGATION_DELAY" "-50.00 MIL,50.00 MIL"
					( Parent
						( matchGroupRef "@crescent_city_bb_fab1_lib.crescent_city_bb_fab1(sch_1):\MG_DQ_NEAR_DIMM_NG_M_E_BYTE4\" )
					)
					( Units "uMatchProp" "ns" 1.000000)
					( Status sCSetFlattened )
					( Origin gBackEnd )
				)
			)
			( pinPair "@baseboard_fab2_lib.baseboard_fab2(sch_1):\PP4410\"
				( pinRef "@baseboard_fab2_lib.baseboard_fab2(sch_1):page27_i172:DDR4_DQ(37)" )
				( pinRef "@baseboard_fab2_lib.baseboard_fab2(sch_1):page51_i111:DQ(36)" )
				( attribute "RELATIVE_PROPAGATION_DELAY_SCOPE" "G"
					( Parent
						( matchGroupRef "@baseboard_fab2_lib.baseboard_fab2(sch_1):\MG_DQ-DQS_FAR_DIMM_NG_M_E_BYTE4\" )
					)
					( Status sCSetFlattened )
					( Origin gBackEnd )
				)
				( attribute "RELATIVE_PROPAGATION_DELAY" "0.00 MIL,195.00 MIL"
					( Parent
						( matchGroupRef "@baseboard_fab2_lib.baseboard_fab2(sch_1):\MG_DQ-DQS_FAR_DIMM_NG_M_E_BYTE4\" )
					)
					( Units "uMatchProp" "ns" 1.000000)
					( Status sCSetFlattened )
					( Origin gBackEnd )
				)
				( attribute "RELATIVE_PROPAGATION_DELAY_SCOPE" "G"
					( Parent
						( matchGroupRef "@crescent_city_bb_fab1_lib.crescent_city_bb_fab1(sch_1):\MG_DQ_FAR_DIMM_NG_M_E_BYTE4\" )
					)
					( Status sCSetFlattened )
					( Origin gBackEnd )
				)
				( attribute "RELATIVE_PROPAGATION_DELAY" "-50.00 MIL,50.00 MIL"
					( Parent
						( matchGroupRef "@crescent_city_bb_fab1_lib.crescent_city_bb_fab1(sch_1):\MG_DQ_FAR_DIMM_NG_M_E_BYTE4\" )
					)
					( Units "uMatchProp" "ns" 1.000000)
					( Status sCSetFlattened )
					( Origin gBackEnd )
				)
			)
			( pinPair "@baseboard_fab2_lib.baseboard_fab2(sch_1):\PP4411\"
				( pinRef "@baseboard_fab2_lib.baseboard_fab2(sch_1):page27_i172:DDR4_DQ(37)" )
				( pinRef "@baseboard_fab2_lib.baseboard_fab2(sch_1):page52_i12:DQ(37)" )
				( attribute "RELATIVE_PROPAGATION_DELAY_SCOPE" "G"
					( Parent
						( matchGroupRef "@baseboard_fab2_lib.baseboard_fab2(sch_1):\MG_DQ-DQS_NEAR_DIMM_NG_M_E_BYTE4\" )
					)
					( Status sCSetFlattened )
					( Origin gBackEnd )
				)
				( attribute "RELATIVE_PROPAGATION_DELAY" "0.00 MIL,195.00 MIL"
					( Parent
						( matchGroupRef "@baseboard_fab2_lib.baseboard_fab2(sch_1):\MG_DQ-DQS_NEAR_DIMM_NG_M_E_BYTE4\" )
					)
					( Units "uMatchProp" "ns" 1.000000)
					( Status sCSetFlattened )
					( Origin gBackEnd )
				)
				( attribute "RELATIVE_PROPAGATION_DELAY_SCOPE" "G"
					( Parent
						( matchGroupRef "@crescent_city_bb_fab1_lib.crescent_city_bb_fab1(sch_1):\MG_DQ_NEAR_DIMM_NG_M_E_BYTE4\" )
					)
					( Status sCSetFlattened )
					( Origin gBackEnd )
				)
				( attribute "RELATIVE_PROPAGATION_DELAY" "-50.00 MIL,50.00 MIL"
					( Parent
						( matchGroupRef "@crescent_city_bb_fab1_lib.crescent_city_bb_fab1(sch_1):\MG_DQ_NEAR_DIMM_NG_M_E_BYTE4\" )
					)
					( Units "uMatchProp" "ns" 1.000000)
					( Status sCSetFlattened )
					( Origin gBackEnd )
				)
			)
			( pinPair "@baseboard_fab2_lib.baseboard_fab2(sch_1):\PP4413\"
				( pinRef "@baseboard_fab2_lib.baseboard_fab2(sch_1):page27_i172:DDR4_DQ(38)" )
				( pinRef "@baseboard_fab2_lib.baseboard_fab2(sch_1):page51_i111:DQ(39)" )
				( attribute "RELATIVE_PROPAGATION_DELAY_SCOPE" "G"
					( Parent
						( matchGroupRef "@baseboard_fab2_lib.baseboard_fab2(sch_1):\MG_DQ-DQS_FAR_DIMM_NG_M_E_BYTE4\" )
					)
					( Status sCSetFlattened )
					( Origin gBackEnd )
				)
				( attribute "RELATIVE_PROPAGATION_DELAY" "0.00 MIL,195.00 MIL"
					( Parent
						( matchGroupRef "@baseboard_fab2_lib.baseboard_fab2(sch_1):\MG_DQ-DQS_FAR_DIMM_NG_M_E_BYTE4\" )
					)
					( Units "uMatchProp" "ns" 1.000000)
					( Status sCSetFlattened )
					( Origin gBackEnd )
				)
				( attribute "RELATIVE_PROPAGATION_DELAY_SCOPE" "G"
					( Parent
						( matchGroupRef "@crescent_city_bb_fab1_lib.crescent_city_bb_fab1(sch_1):\MG_DQ_FAR_DIMM_NG_M_E_BYTE4\" )
					)
					( Origin gBackEnd )
				)
				( attribute "RELATIVE_PROPAGATION_DELAY" "TARGET,TARGET"
					( Parent
						( matchGroupRef "@crescent_city_bb_fab1_lib.crescent_city_bb_fab1(sch_1):\MG_DQ_FAR_DIMM_NG_M_E_BYTE4\" )
					)
					( Units "uMatchProp" "ns" 1.000000)
					( Origin gBackEnd )
				)
			)
			( pinPair "@baseboard_fab2_lib.baseboard_fab2(sch_1):\PP4415\"
				( pinRef "@baseboard_fab2_lib.baseboard_fab2(sch_1):page27_i172:DDR4_DQ(38)" )
				( pinRef "@baseboard_fab2_lib.baseboard_fab2(sch_1):page52_i12:DQ(38)" )
				( attribute "RELATIVE_PROPAGATION_DELAY_SCOPE" "G"
					( Parent
						( matchGroupRef "@baseboard_fab2_lib.baseboard_fab2(sch_1):\MG_DQ-DQS_NEAR_DIMM_NG_M_E_BYTE4\" )
					)
					( Status sCSetFlattened )
					( Origin gBackEnd )
				)
				( attribute "RELATIVE_PROPAGATION_DELAY" "0.00 MIL,195.00 MIL"
					( Parent
						( matchGroupRef "@baseboard_fab2_lib.baseboard_fab2(sch_1):\MG_DQ-DQS_NEAR_DIMM_NG_M_E_BYTE4\" )
					)
					( Units "uMatchProp" "ns" 1.000000)
					( Status sCSetFlattened )
					( Origin gBackEnd )
				)
				( attribute "RELATIVE_PROPAGATION_DELAY_SCOPE" "G"
					( Parent
						( matchGroupRef "@crescent_city_bb_fab1_lib.crescent_city_bb_fab1(sch_1):\MG_DQ_NEAR_DIMM_NG_M_E_BYTE4\" )
					)
					( Status sCSetFlattened )
					( Origin gBackEnd )
				)
				( attribute "RELATIVE_PROPAGATION_DELAY" "-50.00 MIL,50.00 MIL"
					( Parent
						( matchGroupRef "@crescent_city_bb_fab1_lib.crescent_city_bb_fab1(sch_1):\MG_DQ_NEAR_DIMM_NG_M_E_BYTE4\" )
					)
					( Units "uMatchProp" "ns" 1.000000)
					( Status sCSetFlattened )
					( Origin gBackEnd )
				)
			)
			( pinPair "@baseboard_fab2_lib.baseboard_fab2(sch_1):\PP4416\"
				( pinRef "@baseboard_fab2_lib.baseboard_fab2(sch_1):page27_i172:DDR4_DQ(39)" )
				( pinRef "@baseboard_fab2_lib.baseboard_fab2(sch_1):page51_i111:DQ(38)" )
				( attribute "RELATIVE_PROPAGATION_DELAY_SCOPE" "G"
					( Parent
						( matchGroupRef "@baseboard_fab2_lib.baseboard_fab2(sch_1):\MG_DQ-DQS_FAR_DIMM_NG_M_E_BYTE4\" )
					)
					( Status sCSetFlattened )
					( Origin gBackEnd )
				)
				( attribute "RELATIVE_PROPAGATION_DELAY" "0.00 MIL,195.00 MIL"
					( Parent
						( matchGroupRef "@baseboard_fab2_lib.baseboard_fab2(sch_1):\MG_DQ-DQS_FAR_DIMM_NG_M_E_BYTE4\" )
					)
					( Units "uMatchProp" "ns" 1.000000)
					( Status sCSetFlattened )
					( Origin gBackEnd )
				)
				( attribute "RELATIVE_PROPAGATION_DELAY_SCOPE" "G"
					( Parent
						( matchGroupRef "@crescent_city_bb_fab1_lib.crescent_city_bb_fab1(sch_1):\MG_DQ_FAR_DIMM_NG_M_E_BYTE4\" )
					)
					( Status sCSetFlattened )
					( Origin gBackEnd )
				)
				( attribute "RELATIVE_PROPAGATION_DELAY" "-50.00 MIL,50.00 MIL"
					( Parent
						( matchGroupRef "@crescent_city_bb_fab1_lib.crescent_city_bb_fab1(sch_1):\MG_DQ_FAR_DIMM_NG_M_E_BYTE4\" )
					)
					( Units "uMatchProp" "ns" 1.000000)
					( Status sCSetFlattened )
					( Origin gBackEnd )
				)
			)
			( pinPair "@baseboard_fab2_lib.baseboard_fab2(sch_1):\PP4418\"
				( pinRef "@baseboard_fab2_lib.baseboard_fab2(sch_1):page27_i172:DDR4_DQ(39)" )
				( pinRef "@baseboard_fab2_lib.baseboard_fab2(sch_1):page52_i12:DQ(39)" )
				( attribute "RELATIVE_PROPAGATION_DELAY_SCOPE" "G"
					( Parent
						( matchGroupRef "@baseboard_fab2_lib.baseboard_fab2(sch_1):\MG_DQ-DQS_NEAR_DIMM_NG_M_E_BYTE4\" )
					)
					( Status sCSetFlattened )
					( Origin gBackEnd )
				)
				( attribute "RELATIVE_PROPAGATION_DELAY" "0.00 MIL,195.00 MIL"
					( Parent
						( matchGroupRef "@baseboard_fab2_lib.baseboard_fab2(sch_1):\MG_DQ-DQS_NEAR_DIMM_NG_M_E_BYTE4\" )
					)
					( Units "uMatchProp" "ns" 1.000000)
					( Status sCSetFlattened )
					( Origin gBackEnd )
				)
				( attribute "RELATIVE_PROPAGATION_DELAY_SCOPE" "G"
					( Parent
						( matchGroupRef "@crescent_city_bb_fab1_lib.crescent_city_bb_fab1(sch_1):\MG_DQ_NEAR_DIMM_NG_M_E_BYTE4\" )
					)
					( Status sCSetFlattened )
					( Origin gBackEnd )
				)
				( attribute "RELATIVE_PROPAGATION_DELAY" "-50.00 MIL,50.00 MIL"
					( Parent
						( matchGroupRef "@crescent_city_bb_fab1_lib.crescent_city_bb_fab1(sch_1):\MG_DQ_NEAR_DIMM_NG_M_E_BYTE4\" )
					)
					( Units "uMatchProp" "ns" 1.000000)
					( Status sCSetFlattened )
					( Origin gBackEnd )
				)
			)
			( pinPair "@baseboard_fab2_lib.baseboard_fab2(sch_1):\PP4371\"
				( pinRef "@baseboard_fab2_lib.baseboard_fab2(sch_1):page27_i172:DDR4_DQ(40)" )
				( pinRef "@baseboard_fab2_lib.baseboard_fab2(sch_1):page51_i111:DQ(41)" )
				( attribute "RELATIVE_PROPAGATION_DELAY_SCOPE" "G"
					( Parent
						( matchGroupRef "@baseboard_fab2_lib.baseboard_fab2(sch_1):\MG_DQ-DQS_FAR_DIMM_NG_M_E_BYTE5\" )
					)
					( Status sCSetFlattened )
					( Origin gBackEnd )
				)
				( attribute "RELATIVE_PROPAGATION_DELAY" "0.00 MIL,195.00 MIL"
					( Parent
						( matchGroupRef "@baseboard_fab2_lib.baseboard_fab2(sch_1):\MG_DQ-DQS_FAR_DIMM_NG_M_E_BYTE5\" )
					)
					( Units "uMatchProp" "ns" 1.000000)
					( Status sCSetFlattened )
					( Origin gBackEnd )
				)
				( attribute "RELATIVE_PROPAGATION_DELAY_SCOPE" "G"
					( Parent
						( matchGroupRef "@baseboard_fab2_lib.baseboard_fab2(sch_1):\MG_DQ_FAR_DIMM_NG_M_E_BYTE5\" )
					)
					( Status sCSetFlattened )
					( Origin gBackEnd )
				)
				( attribute "RELATIVE_PROPAGATION_DELAY" "-50.00 MIL,50.00 MIL"
					( Parent
						( matchGroupRef "@baseboard_fab2_lib.baseboard_fab2(sch_1):\MG_DQ_FAR_DIMM_NG_M_E_BYTE5\" )
					)
					( Units "uMatchProp" "ns" 1.000000)
					( Status sCSetFlattened )
					( Origin gBackEnd )
				)
			)
			( pinPair "@baseboard_fab2_lib.baseboard_fab2(sch_1):\PP4373\"
				( pinRef "@baseboard_fab2_lib.baseboard_fab2(sch_1):page52_i12:DQ(40)" )
				( pinRef "@baseboard_fab2_lib.baseboard_fab2(sch_1):page27_i172:DDR4_DQ(40)" )
				( attribute "RELATIVE_PROPAGATION_DELAY_SCOPE" "G"
					( Parent
						( matchGroupRef "@baseboard_fab2_lib.baseboard_fab2(sch_1):\MG_DQ-DQS_NEAR_DIMM_NG_M_E_BYTE5\" )
					)
					( Status sCSetFlattened )
					( Origin gBackEnd )
				)
				( attribute "RELATIVE_PROPAGATION_DELAY" "0.00 MIL,195.00 MIL"
					( Parent
						( matchGroupRef "@baseboard_fab2_lib.baseboard_fab2(sch_1):\MG_DQ-DQS_NEAR_DIMM_NG_M_E_BYTE5\" )
					)
					( Units "uMatchProp" "ns" 1.000000)
					( Status sCSetFlattened )
					( Origin gBackEnd )
				)
				( attribute "RELATIVE_PROPAGATION_DELAY_SCOPE" "G"
					( Parent
						( matchGroupRef "@baseboard_fab2_lib.baseboard_fab2(sch_1):\MG_DQ_NEAR_DIMM_NG_M_E_BYTE5\" )
					)
					( Status sCSetFlattened )
					( Origin gBackEnd )
				)
				( attribute "RELATIVE_PROPAGATION_DELAY" "-50.00 MIL,50.00 MIL"
					( Parent
						( matchGroupRef "@baseboard_fab2_lib.baseboard_fab2(sch_1):\MG_DQ_NEAR_DIMM_NG_M_E_BYTE5\" )
					)
					( Units "uMatchProp" "ns" 1.000000)
					( Status sCSetFlattened )
					( Origin gBackEnd )
				)
			)
			( pinPair "@baseboard_fab2_lib.baseboard_fab2(sch_1):\PP4374\"
				( pinRef "@baseboard_fab2_lib.baseboard_fab2(sch_1):page27_i172:DDR4_DQ(41)" )
				( pinRef "@baseboard_fab2_lib.baseboard_fab2(sch_1):page51_i111:DQ(40)" )
				( attribute "RELATIVE_PROPAGATION_DELAY_SCOPE" "G"
					( Parent
						( matchGroupRef "@baseboard_fab2_lib.baseboard_fab2(sch_1):\MG_DQ-DQS_FAR_DIMM_NG_M_E_BYTE5\" )
					)
					( Status sCSetFlattened )
					( Origin gBackEnd )
				)
				( attribute "RELATIVE_PROPAGATION_DELAY" "0.00 MIL,195.00 MIL"
					( Parent
						( matchGroupRef "@baseboard_fab2_lib.baseboard_fab2(sch_1):\MG_DQ-DQS_FAR_DIMM_NG_M_E_BYTE5\" )
					)
					( Units "uMatchProp" "ns" 1.000000)
					( Status sCSetFlattened )
					( Origin gBackEnd )
				)
				( attribute "RELATIVE_PROPAGATION_DELAY_SCOPE" "G"
					( Parent
						( matchGroupRef "@baseboard_fab2_lib.baseboard_fab2(sch_1):\MG_DQ_FAR_DIMM_NG_M_E_BYTE5\" )
					)
					( Status sCSetFlattened )
					( Origin gBackEnd )
				)
				( attribute "RELATIVE_PROPAGATION_DELAY" "-50.00 MIL,50.00 MIL"
					( Parent
						( matchGroupRef "@baseboard_fab2_lib.baseboard_fab2(sch_1):\MG_DQ_FAR_DIMM_NG_M_E_BYTE5\" )
					)
					( Units "uMatchProp" "ns" 1.000000)
					( Status sCSetFlattened )
					( Origin gBackEnd )
				)
			)
			( pinPair "@baseboard_fab2_lib.baseboard_fab2(sch_1):\PP4376\"
				( pinRef "@baseboard_fab2_lib.baseboard_fab2(sch_1):page52_i12:DQ(41)" )
				( pinRef "@baseboard_fab2_lib.baseboard_fab2(sch_1):page27_i172:DDR4_DQ(41)" )
				( attribute "RELATIVE_PROPAGATION_DELAY_SCOPE" "G"
					( Parent
						( matchGroupRef "@baseboard_fab2_lib.baseboard_fab2(sch_1):\MG_DQ-DQS_NEAR_DIMM_NG_M_E_BYTE5\" )
					)
					( Status sCSetFlattened )
					( Origin gBackEnd )
				)
				( attribute "RELATIVE_PROPAGATION_DELAY" "0.00 MIL,195.00 MIL"
					( Parent
						( matchGroupRef "@baseboard_fab2_lib.baseboard_fab2(sch_1):\MG_DQ-DQS_NEAR_DIMM_NG_M_E_BYTE5\" )
					)
					( Units "uMatchProp" "ns" 1.000000)
					( Status sCSetFlattened )
					( Origin gBackEnd )
				)
				( attribute "RELATIVE_PROPAGATION_DELAY_SCOPE" "G"
					( Parent
						( matchGroupRef "@baseboard_fab2_lib.baseboard_fab2(sch_1):\MG_DQ_NEAR_DIMM_NG_M_E_BYTE5\" )
					)
					( Status sCSetFlattened )
					( Origin gBackEnd )
				)
				( attribute "RELATIVE_PROPAGATION_DELAY" "-50.00 MIL,50.00 MIL"
					( Parent
						( matchGroupRef "@baseboard_fab2_lib.baseboard_fab2(sch_1):\MG_DQ_NEAR_DIMM_NG_M_E_BYTE5\" )
					)
					( Units "uMatchProp" "ns" 1.000000)
					( Status sCSetFlattened )
					( Origin gBackEnd )
				)
			)
			( pinPair "@baseboard_fab2_lib.baseboard_fab2(sch_1):\PP4377\"
				( pinRef "@baseboard_fab2_lib.baseboard_fab2(sch_1):page27_i172:DDR4_DQ(42)" )
				( pinRef "@baseboard_fab2_lib.baseboard_fab2(sch_1):page51_i111:DQ(43)" )
				( attribute "RELATIVE_PROPAGATION_DELAY_SCOPE" "G"
					( Parent
						( matchGroupRef "@baseboard_fab2_lib.baseboard_fab2(sch_1):\MG_DQ-DQS_FAR_DIMM_NG_M_E_BYTE5\" )
					)
					( Status sCSetFlattened )
					( Origin gBackEnd )
				)
				( attribute "RELATIVE_PROPAGATION_DELAY" "0.00 MIL,195.00 MIL"
					( Parent
						( matchGroupRef "@baseboard_fab2_lib.baseboard_fab2(sch_1):\MG_DQ-DQS_FAR_DIMM_NG_M_E_BYTE5\" )
					)
					( Units "uMatchProp" "ns" 1.000000)
					( Status sCSetFlattened )
					( Origin gBackEnd )
				)
				( attribute "RELATIVE_PROPAGATION_DELAY_SCOPE" "G"
					( Parent
						( matchGroupRef "@baseboard_fab2_lib.baseboard_fab2(sch_1):\MG_DQ_FAR_DIMM_NG_M_E_BYTE5\" )
					)
					( Status sCSetFlattened )
					( Origin gBackEnd )
				)
				( attribute "RELATIVE_PROPAGATION_DELAY" "-50.00 MIL,50.00 MIL"
					( Parent
						( matchGroupRef "@baseboard_fab2_lib.baseboard_fab2(sch_1):\MG_DQ_FAR_DIMM_NG_M_E_BYTE5\" )
					)
					( Units "uMatchProp" "ns" 1.000000)
					( Status sCSetFlattened )
					( Origin gBackEnd )
				)
			)
			( pinPair "@baseboard_fab2_lib.baseboard_fab2(sch_1):\PP4379\"
				( pinRef "@baseboard_fab2_lib.baseboard_fab2(sch_1):page52_i12:DQ(42)" )
				( pinRef "@baseboard_fab2_lib.baseboard_fab2(sch_1):page27_i172:DDR4_DQ(42)" )
				( attribute "RELATIVE_PROPAGATION_DELAY_SCOPE" "G"
					( Parent
						( matchGroupRef "@baseboard_fab2_lib.baseboard_fab2(sch_1):\MG_DQ-DQS_NEAR_DIMM_NG_M_E_BYTE5\" )
					)
					( Status sCSetFlattened )
					( Origin gBackEnd )
				)
				( attribute "RELATIVE_PROPAGATION_DELAY" "0.00 MIL,195.00 MIL"
					( Parent
						( matchGroupRef "@baseboard_fab2_lib.baseboard_fab2(sch_1):\MG_DQ-DQS_NEAR_DIMM_NG_M_E_BYTE5\" )
					)
					( Units "uMatchProp" "ns" 1.000000)
					( Status sCSetFlattened )
					( Origin gBackEnd )
				)
				( attribute "RELATIVE_PROPAGATION_DELAY_SCOPE" "G"
					( Parent
						( matchGroupRef "@baseboard_fab2_lib.baseboard_fab2(sch_1):\MG_DQ_NEAR_DIMM_NG_M_E_BYTE5\" )
					)
					( Status sCSetFlattened )
					( Origin gBackEnd )
				)
				( attribute "RELATIVE_PROPAGATION_DELAY" "-50.00 MIL,50.00 MIL"
					( Parent
						( matchGroupRef "@baseboard_fab2_lib.baseboard_fab2(sch_1):\MG_DQ_NEAR_DIMM_NG_M_E_BYTE5\" )
					)
					( Units "uMatchProp" "ns" 1.000000)
					( Status sCSetFlattened )
					( Origin gBackEnd )
				)
			)
			( pinPair "@baseboard_fab2_lib.baseboard_fab2(sch_1):\PP4380\"
				( pinRef "@baseboard_fab2_lib.baseboard_fab2(sch_1):page27_i172:DDR4_DQ(43)" )
				( pinRef "@baseboard_fab2_lib.baseboard_fab2(sch_1):page51_i111:DQ(42)" )
				( attribute "RELATIVE_PROPAGATION_DELAY_SCOPE" "G"
					( Parent
						( matchGroupRef "@baseboard_fab2_lib.baseboard_fab2(sch_1):\MG_DQ-DQS_FAR_DIMM_NG_M_E_BYTE5\" )
					)
					( Status sCSetFlattened )
					( Origin gBackEnd )
				)
				( attribute "RELATIVE_PROPAGATION_DELAY" "0.00 MIL,195.00 MIL"
					( Parent
						( matchGroupRef "@baseboard_fab2_lib.baseboard_fab2(sch_1):\MG_DQ-DQS_FAR_DIMM_NG_M_E_BYTE5\" )
					)
					( Units "uMatchProp" "ns" 1.000000)
					( Status sCSetFlattened )
					( Origin gBackEnd )
				)
				( attribute "RELATIVE_PROPAGATION_DELAY_SCOPE" "G"
					( Parent
						( matchGroupRef "@baseboard_fab2_lib.baseboard_fab2(sch_1):\MG_DQ_FAR_DIMM_NG_M_E_BYTE5\" )
					)
					( Status sCSetFlattened )
					( Origin gBackEnd )
				)
				( attribute "RELATIVE_PROPAGATION_DELAY" "-50.00 MIL,50.00 MIL"
					( Parent
						( matchGroupRef "@baseboard_fab2_lib.baseboard_fab2(sch_1):\MG_DQ_FAR_DIMM_NG_M_E_BYTE5\" )
					)
					( Units "uMatchProp" "ns" 1.000000)
					( Status sCSetFlattened )
					( Origin gBackEnd )
				)
			)
			( pinPair "@baseboard_fab2_lib.baseboard_fab2(sch_1):\PP4382\"
				( pinRef "@baseboard_fab2_lib.baseboard_fab2(sch_1):page52_i12:DQ(43)" )
				( pinRef "@baseboard_fab2_lib.baseboard_fab2(sch_1):page27_i172:DDR4_DQ(43)" )
				( attribute "RELATIVE_PROPAGATION_DELAY_SCOPE" "G"
					( Parent
						( matchGroupRef "@baseboard_fab2_lib.baseboard_fab2(sch_1):\MG_DQ-DQS_NEAR_DIMM_NG_M_E_BYTE5\" )
					)
					( Status sCSetFlattened )
					( Origin gBackEnd )
				)
				( attribute "RELATIVE_PROPAGATION_DELAY" "0.00 MIL,195.00 MIL"
					( Parent
						( matchGroupRef "@baseboard_fab2_lib.baseboard_fab2(sch_1):\MG_DQ-DQS_NEAR_DIMM_NG_M_E_BYTE5\" )
					)
					( Units "uMatchProp" "ns" 1.000000)
					( Status sCSetFlattened )
					( Origin gBackEnd )
				)
				( attribute "RELATIVE_PROPAGATION_DELAY_SCOPE" "G"
					( Parent
						( matchGroupRef "@baseboard_fab2_lib.baseboard_fab2(sch_1):\MG_DQ_NEAR_DIMM_NG_M_E_BYTE5\" )
					)
					( Status sCSetFlattened )
					( Origin gBackEnd )
				)
				( attribute "RELATIVE_PROPAGATION_DELAY" "-50.00 MIL,50.00 MIL"
					( Parent
						( matchGroupRef "@baseboard_fab2_lib.baseboard_fab2(sch_1):\MG_DQ_NEAR_DIMM_NG_M_E_BYTE5\" )
					)
					( Units "uMatchProp" "ns" 1.000000)
					( Status sCSetFlattened )
					( Origin gBackEnd )
				)
			)
			( pinPair "@baseboard_fab2_lib.baseboard_fab2(sch_1):\PP4383\"
				( pinRef "@baseboard_fab2_lib.baseboard_fab2(sch_1):page27_i172:DDR4_DQ(44)" )
				( pinRef "@baseboard_fab2_lib.baseboard_fab2(sch_1):page51_i111:DQ(45)" )
				( attribute "RELATIVE_PROPAGATION_DELAY_SCOPE" "G"
					( Parent
						( matchGroupRef "@baseboard_fab2_lib.baseboard_fab2(sch_1):\MG_DQ-DQS_FAR_DIMM_NG_M_E_BYTE5\" )
					)
					( Status sCSetFlattened )
					( Origin gBackEnd )
				)
				( attribute "RELATIVE_PROPAGATION_DELAY" "0.00 MIL,195.00 MIL"
					( Parent
						( matchGroupRef "@baseboard_fab2_lib.baseboard_fab2(sch_1):\MG_DQ-DQS_FAR_DIMM_NG_M_E_BYTE5\" )
					)
					( Units "uMatchProp" "ns" 1.000000)
					( Status sCSetFlattened )
					( Origin gBackEnd )
				)
				( attribute "RELATIVE_PROPAGATION_DELAY_SCOPE" "G"
					( Parent
						( matchGroupRef "@baseboard_fab2_lib.baseboard_fab2(sch_1):\MG_DQ_FAR_DIMM_NG_M_E_BYTE5\" )
					)
					( Status sCSetFlattened )
					( Origin gBackEnd )
				)
				( attribute "RELATIVE_PROPAGATION_DELAY" "-50.00 MIL,50.00 MIL"
					( Parent
						( matchGroupRef "@baseboard_fab2_lib.baseboard_fab2(sch_1):\MG_DQ_FAR_DIMM_NG_M_E_BYTE5\" )
					)
					( Units "uMatchProp" "ns" 1.000000)
					( Status sCSetFlattened )
					( Origin gBackEnd )
				)
			)
			( pinPair "@baseboard_fab2_lib.baseboard_fab2(sch_1):\PP4385\"
				( pinRef "@baseboard_fab2_lib.baseboard_fab2(sch_1):page52_i12:DQ(44)" )
				( pinRef "@baseboard_fab2_lib.baseboard_fab2(sch_1):page27_i172:DDR4_DQ(44)" )
				( attribute "RELATIVE_PROPAGATION_DELAY_SCOPE" "G"
					( Parent
						( matchGroupRef "@baseboard_fab2_lib.baseboard_fab2(sch_1):\MG_DQ-DQS_NEAR_DIMM_NG_M_E_BYTE5\" )
					)
					( Status sCSetFlattened )
					( Origin gBackEnd )
				)
				( attribute "RELATIVE_PROPAGATION_DELAY" "0.00 MIL,195.00 MIL"
					( Parent
						( matchGroupRef "@baseboard_fab2_lib.baseboard_fab2(sch_1):\MG_DQ-DQS_NEAR_DIMM_NG_M_E_BYTE5\" )
					)
					( Units "uMatchProp" "ns" 1.000000)
					( Status sCSetFlattened )
					( Origin gBackEnd )
				)
				( attribute "RELATIVE_PROPAGATION_DELAY_SCOPE" "G"
					( Parent
						( matchGroupRef "@baseboard_fab2_lib.baseboard_fab2(sch_1):\MG_DQ_NEAR_DIMM_NG_M_E_BYTE5\" )
					)
					( Status sCSetFlattened )
					( Origin gBackEnd )
				)
				( attribute "RELATIVE_PROPAGATION_DELAY" "-50.00 MIL,50.00 MIL"
					( Parent
						( matchGroupRef "@baseboard_fab2_lib.baseboard_fab2(sch_1):\MG_DQ_NEAR_DIMM_NG_M_E_BYTE5\" )
					)
					( Units "uMatchProp" "ns" 1.000000)
					( Status sCSetFlattened )
					( Origin gBackEnd )
				)
			)
			( pinPair "@baseboard_fab2_lib.baseboard_fab2(sch_1):\PP4386\"
				( pinRef "@baseboard_fab2_lib.baseboard_fab2(sch_1):page27_i172:DDR4_DQ(45)" )
				( pinRef "@baseboard_fab2_lib.baseboard_fab2(sch_1):page51_i111:DQ(44)" )
				( attribute "RELATIVE_PROPAGATION_DELAY_SCOPE" "G"
					( Parent
						( matchGroupRef "@baseboard_fab2_lib.baseboard_fab2(sch_1):\MG_DQ-DQS_FAR_DIMM_NG_M_E_BYTE5\" )
					)
					( Status sCSetFlattened )
					( Origin gBackEnd )
				)
				( attribute "RELATIVE_PROPAGATION_DELAY" "0.00 MIL,195.00 MIL"
					( Parent
						( matchGroupRef "@baseboard_fab2_lib.baseboard_fab2(sch_1):\MG_DQ-DQS_FAR_DIMM_NG_M_E_BYTE5\" )
					)
					( Units "uMatchProp" "ns" 1.000000)
					( Status sCSetFlattened )
					( Origin gBackEnd )
				)
				( attribute "RELATIVE_PROPAGATION_DELAY_SCOPE" "G"
					( Parent
						( matchGroupRef "@baseboard_fab2_lib.baseboard_fab2(sch_1):\MG_DQ_FAR_DIMM_NG_M_E_BYTE5\" )
					)
					( Status sCSetFlattened )
					( Origin gBackEnd )
				)
				( attribute "RELATIVE_PROPAGATION_DELAY" "-50.00 MIL,50.00 MIL"
					( Parent
						( matchGroupRef "@baseboard_fab2_lib.baseboard_fab2(sch_1):\MG_DQ_FAR_DIMM_NG_M_E_BYTE5\" )
					)
					( Units "uMatchProp" "ns" 1.000000)
					( Status sCSetFlattened )
					( Origin gBackEnd )
				)
			)
			( pinPair "@baseboard_fab2_lib.baseboard_fab2(sch_1):\PP4388\"
				( pinRef "@baseboard_fab2_lib.baseboard_fab2(sch_1):page52_i12:DQ(45)" )
				( pinRef "@baseboard_fab2_lib.baseboard_fab2(sch_1):page27_i172:DDR4_DQ(45)" )
				( attribute "RELATIVE_PROPAGATION_DELAY_SCOPE" "G"
					( Parent
						( matchGroupRef "@baseboard_fab2_lib.baseboard_fab2(sch_1):\MG_DQ-DQS_NEAR_DIMM_NG_M_E_BYTE5\" )
					)
					( Status sCSetFlattened )
					( Origin gBackEnd )
				)
				( attribute "RELATIVE_PROPAGATION_DELAY" "0.00 MIL,195.00 MIL"
					( Parent
						( matchGroupRef "@baseboard_fab2_lib.baseboard_fab2(sch_1):\MG_DQ-DQS_NEAR_DIMM_NG_M_E_BYTE5\" )
					)
					( Units "uMatchProp" "ns" 1.000000)
					( Status sCSetFlattened )
					( Origin gBackEnd )
				)
				( attribute "RELATIVE_PROPAGATION_DELAY_SCOPE" "G"
					( Parent
						( matchGroupRef "@baseboard_fab2_lib.baseboard_fab2(sch_1):\MG_DQ_NEAR_DIMM_NG_M_E_BYTE5\" )
					)
					( Status sCSetFlattened )
					( Origin gBackEnd )
				)
				( attribute "RELATIVE_PROPAGATION_DELAY" "-50.00 MIL,50.00 MIL"
					( Parent
						( matchGroupRef "@baseboard_fab2_lib.baseboard_fab2(sch_1):\MG_DQ_NEAR_DIMM_NG_M_E_BYTE5\" )
					)
					( Units "uMatchProp" "ns" 1.000000)
					( Status sCSetFlattened )
					( Origin gBackEnd )
				)
			)
			( pinPair "@baseboard_fab2_lib.baseboard_fab2(sch_1):\PP4389\"
				( pinRef "@baseboard_fab2_lib.baseboard_fab2(sch_1):page27_i172:DDR4_DQ(46)" )
				( pinRef "@baseboard_fab2_lib.baseboard_fab2(sch_1):page51_i111:DQ(47)" )
				( attribute "RELATIVE_PROPAGATION_DELAY_SCOPE" "G"
					( Parent
						( matchGroupRef "@baseboard_fab2_lib.baseboard_fab2(sch_1):\MG_DQ-DQS_FAR_DIMM_NG_M_E_BYTE5\" )
					)
					( Status sCSetFlattened )
					( Origin gBackEnd )
				)
				( attribute "RELATIVE_PROPAGATION_DELAY" "0.00 MIL,195.00 MIL"
					( Parent
						( matchGroupRef "@baseboard_fab2_lib.baseboard_fab2(sch_1):\MG_DQ-DQS_FAR_DIMM_NG_M_E_BYTE5\" )
					)
					( Units "uMatchProp" "ns" 1.000000)
					( Status sCSetFlattened )
					( Origin gBackEnd )
				)
				( attribute "RELATIVE_PROPAGATION_DELAY_SCOPE" "G"
					( Parent
						( matchGroupRef "@baseboard_fab2_lib.baseboard_fab2(sch_1):\MG_DQ_FAR_DIMM_NG_M_E_BYTE5\" )
					)
					( Status sCSetFlattened )
					( Origin gBackEnd )
				)
				( attribute "RELATIVE_PROPAGATION_DELAY" "-50.00 MIL,50.00 MIL"
					( Parent
						( matchGroupRef "@baseboard_fab2_lib.baseboard_fab2(sch_1):\MG_DQ_FAR_DIMM_NG_M_E_BYTE5\" )
					)
					( Units "uMatchProp" "ns" 1.000000)
					( Status sCSetFlattened )
					( Origin gBackEnd )
				)
			)
			( pinPair "@baseboard_fab2_lib.baseboard_fab2(sch_1):\PP4391\"
				( pinRef "@baseboard_fab2_lib.baseboard_fab2(sch_1):page52_i12:DQ(46)" )
				( pinRef "@baseboard_fab2_lib.baseboard_fab2(sch_1):page27_i172:DDR4_DQ(46)" )
				( attribute "RELATIVE_PROPAGATION_DELAY_SCOPE" "G"
					( Parent
						( matchGroupRef "@baseboard_fab2_lib.baseboard_fab2(sch_1):\MG_DQ-DQS_NEAR_DIMM_NG_M_E_BYTE5\" )
					)
					( Status sCSetFlattened )
					( Origin gBackEnd )
				)
				( attribute "RELATIVE_PROPAGATION_DELAY" "0.00 MIL,195.00 MIL"
					( Parent
						( matchGroupRef "@baseboard_fab2_lib.baseboard_fab2(sch_1):\MG_DQ-DQS_NEAR_DIMM_NG_M_E_BYTE5\" )
					)
					( Units "uMatchProp" "ns" 1.000000)
					( Status sCSetFlattened )
					( Origin gBackEnd )
				)
				( attribute "RELATIVE_PROPAGATION_DELAY_SCOPE" "G"
					( Parent
						( matchGroupRef "@baseboard_fab2_lib.baseboard_fab2(sch_1):\MG_DQ_NEAR_DIMM_NG_M_E_BYTE5\" )
					)
					( Status sCSetFlattened )
					( Origin gBackEnd )
				)
				( attribute "RELATIVE_PROPAGATION_DELAY" "-50.00 MIL,50.00 MIL"
					( Parent
						( matchGroupRef "@baseboard_fab2_lib.baseboard_fab2(sch_1):\MG_DQ_NEAR_DIMM_NG_M_E_BYTE5\" )
					)
					( Units "uMatchProp" "ns" 1.000000)
					( Status sCSetFlattened )
					( Origin gBackEnd )
				)
			)
			( pinPair "@baseboard_fab2_lib.baseboard_fab2(sch_1):\PP4392\"
				( pinRef "@baseboard_fab2_lib.baseboard_fab2(sch_1):page27_i172:DDR4_DQ(47)" )
				( pinRef "@baseboard_fab2_lib.baseboard_fab2(sch_1):page51_i111:DQ(46)" )
				( attribute "RELATIVE_PROPAGATION_DELAY_SCOPE" "G"
					( Parent
						( matchGroupRef "@baseboard_fab2_lib.baseboard_fab2(sch_1):\MG_DQ-DQS_FAR_DIMM_NG_M_E_BYTE5\" )
					)
					( Status sCSetFlattened )
					( Origin gBackEnd )
				)
				( attribute "RELATIVE_PROPAGATION_DELAY" "0.00 MIL,195.00 MIL"
					( Parent
						( matchGroupRef "@baseboard_fab2_lib.baseboard_fab2(sch_1):\MG_DQ-DQS_FAR_DIMM_NG_M_E_BYTE5\" )
					)
					( Units "uMatchProp" "ns" 1.000000)
					( Status sCSetFlattened )
					( Origin gBackEnd )
				)
				( attribute "RELATIVE_PROPAGATION_DELAY_SCOPE" "G"
					( Parent
						( matchGroupRef "@baseboard_fab2_lib.baseboard_fab2(sch_1):\MG_DQ_FAR_DIMM_NG_M_E_BYTE5\" )
					)
					( Status sCSetFlattened )
					( Origin gBackEnd )
				)
				( attribute "RELATIVE_PROPAGATION_DELAY" "-50.00 MIL,50.00 MIL"
					( Parent
						( matchGroupRef "@baseboard_fab2_lib.baseboard_fab2(sch_1):\MG_DQ_FAR_DIMM_NG_M_E_BYTE5\" )
					)
					( Units "uMatchProp" "ns" 1.000000)
					( Status sCSetFlattened )
					( Origin gBackEnd )
				)
			)
			( pinPair "@baseboard_fab2_lib.baseboard_fab2(sch_1):\PP4394\"
				( pinRef "@baseboard_fab2_lib.baseboard_fab2(sch_1):page52_i12:DQ(47)" )
				( pinRef "@baseboard_fab2_lib.baseboard_fab2(sch_1):page27_i172:DDR4_DQ(47)" )
				( attribute "RELATIVE_PROPAGATION_DELAY_SCOPE" "G"
					( Parent
						( matchGroupRef "@baseboard_fab2_lib.baseboard_fab2(sch_1):\MG_DQ-DQS_NEAR_DIMM_NG_M_E_BYTE5\" )
					)
					( Status sCSetFlattened )
					( Origin gBackEnd )
				)
				( attribute "RELATIVE_PROPAGATION_DELAY" "0.00 MIL,195.00 MIL"
					( Parent
						( matchGroupRef "@baseboard_fab2_lib.baseboard_fab2(sch_1):\MG_DQ-DQS_NEAR_DIMM_NG_M_E_BYTE5\" )
					)
					( Units "uMatchProp" "ns" 1.000000)
					( Status sCSetFlattened )
					( Origin gBackEnd )
				)
				( attribute "RELATIVE_PROPAGATION_DELAY_SCOPE" "G"
					( Parent
						( matchGroupRef "@baseboard_fab2_lib.baseboard_fab2(sch_1):\MG_DQ_NEAR_DIMM_NG_M_E_BYTE5\" )
					)
					( Status sCSetFlattened )
					( Origin gBackEnd )
				)
				( attribute "RELATIVE_PROPAGATION_DELAY" "-50.00 MIL,50.00 MIL"
					( Parent
						( matchGroupRef "@baseboard_fab2_lib.baseboard_fab2(sch_1):\MG_DQ_NEAR_DIMM_NG_M_E_BYTE5\" )
					)
					( Units "uMatchProp" "ns" 1.000000)
					( Status sCSetFlattened )
					( Origin gBackEnd )
				)
			)
			( pinPair "@baseboard_fab2_lib.baseboard_fab2(sch_1):\PP4347\"
				( pinRef "@baseboard_fab2_lib.baseboard_fab2(sch_1):page27_i172:DDR4_DQ(48)" )
				( pinRef "@baseboard_fab2_lib.baseboard_fab2(sch_1):page51_i111:DQ(49)" )
				( attribute "RELATIVE_PROPAGATION_DELAY_SCOPE" "G"
					( Parent
						( matchGroupRef "@baseboard_fab2_lib.baseboard_fab2(sch_1):\MG_DQ-DQS_FAR_DIMM_NG_M_E_BYTE6\" )
					)
					( Status sCSetFlattened )
					( Origin gBackEnd )
				)
				( attribute "RELATIVE_PROPAGATION_DELAY" "0.00 MIL,195.00 MIL"
					( Parent
						( matchGroupRef "@baseboard_fab2_lib.baseboard_fab2(sch_1):\MG_DQ-DQS_FAR_DIMM_NG_M_E_BYTE6\" )
					)
					( Units "uMatchProp" "ns" 1.000000)
					( Status sCSetFlattened )
					( Origin gBackEnd )
				)
				( attribute "RELATIVE_PROPAGATION_DELAY_SCOPE" "G"
					( Parent
						( matchGroupRef "@baseboard_fab2_lib.baseboard_fab2(sch_1):\MG_DQ_FAR_DIMM_NG_M_E_BYTE6\" )
					)
					( Status sCSetFlattened )
					( Origin gBackEnd )
				)
				( attribute "RELATIVE_PROPAGATION_DELAY" "-50.00 MIL,50.00 MIL"
					( Parent
						( matchGroupRef "@baseboard_fab2_lib.baseboard_fab2(sch_1):\MG_DQ_FAR_DIMM_NG_M_E_BYTE6\" )
					)
					( Units "uMatchProp" "ns" 1.000000)
					( Status sCSetFlattened )
					( Origin gBackEnd )
				)
			)
			( pinPair "@baseboard_fab2_lib.baseboard_fab2(sch_1):\PP4349\"
				( pinRef "@baseboard_fab2_lib.baseboard_fab2(sch_1):page27_i172:DDR4_DQ(48)" )
				( pinRef "@baseboard_fab2_lib.baseboard_fab2(sch_1):page52_i12:DQ(48)" )
				( attribute "RELATIVE_PROPAGATION_DELAY_SCOPE" "G"
					( Parent
						( matchGroupRef "@baseboard_fab2_lib.baseboard_fab2(sch_1):\MG_DQ-DQS_NEAR_DIMM_NG_M_E_BYTE6\" )
					)
					( Status sCSetFlattened )
					( Origin gBackEnd )
				)
				( attribute "RELATIVE_PROPAGATION_DELAY" "0.00 MIL,195.00 MIL"
					( Parent
						( matchGroupRef "@baseboard_fab2_lib.baseboard_fab2(sch_1):\MG_DQ-DQS_NEAR_DIMM_NG_M_E_BYTE6\" )
					)
					( Units "uMatchProp" "ns" 1.000000)
					( Status sCSetFlattened )
					( Origin gBackEnd )
				)
				( attribute "RELATIVE_PROPAGATION_DELAY_SCOPE" "G"
					( Parent
						( matchGroupRef "@baseboard_fab2_lib.baseboard_fab2(sch_1):\MG_DQ_NEAR_DIMM_NG_M_E_BYTE6\" )
					)
					( Status sCSetFlattened )
					( Origin gBackEnd )
				)
				( attribute "RELATIVE_PROPAGATION_DELAY" "-50.00 MIL,50.00 MIL"
					( Parent
						( matchGroupRef "@baseboard_fab2_lib.baseboard_fab2(sch_1):\MG_DQ_NEAR_DIMM_NG_M_E_BYTE6\" )
					)
					( Units "uMatchProp" "ns" 1.000000)
					( Status sCSetFlattened )
					( Origin gBackEnd )
				)
			)
			( pinPair "@baseboard_fab2_lib.baseboard_fab2(sch_1):\PP4350\"
				( pinRef "@baseboard_fab2_lib.baseboard_fab2(sch_1):page27_i172:DDR4_DQ(49)" )
				( pinRef "@baseboard_fab2_lib.baseboard_fab2(sch_1):page51_i111:DQ(48)" )
				( attribute "RELATIVE_PROPAGATION_DELAY_SCOPE" "G"
					( Parent
						( matchGroupRef "@baseboard_fab2_lib.baseboard_fab2(sch_1):\MG_DQ-DQS_FAR_DIMM_NG_M_E_BYTE6\" )
					)
					( Status sCSetFlattened )
					( Origin gBackEnd )
				)
				( attribute "RELATIVE_PROPAGATION_DELAY" "0.00 MIL,195.00 MIL"
					( Parent
						( matchGroupRef "@baseboard_fab2_lib.baseboard_fab2(sch_1):\MG_DQ-DQS_FAR_DIMM_NG_M_E_BYTE6\" )
					)
					( Units "uMatchProp" "ns" 1.000000)
					( Status sCSetFlattened )
					( Origin gBackEnd )
				)
				( attribute "RELATIVE_PROPAGATION_DELAY_SCOPE" "G"
					( Parent
						( matchGroupRef "@baseboard_fab2_lib.baseboard_fab2(sch_1):\MG_DQ_FAR_DIMM_NG_M_E_BYTE6\" )
					)
					( Status sCSetFlattened )
					( Origin gBackEnd )
				)
				( attribute "RELATIVE_PROPAGATION_DELAY" "-50.00 MIL,50.00 MIL"
					( Parent
						( matchGroupRef "@baseboard_fab2_lib.baseboard_fab2(sch_1):\MG_DQ_FAR_DIMM_NG_M_E_BYTE6\" )
					)
					( Units "uMatchProp" "ns" 1.000000)
					( Status sCSetFlattened )
					( Origin gBackEnd )
				)
			)
			( pinPair "@baseboard_fab2_lib.baseboard_fab2(sch_1):\PP4352\"
				( pinRef "@baseboard_fab2_lib.baseboard_fab2(sch_1):page27_i172:DDR4_DQ(49)" )
				( pinRef "@baseboard_fab2_lib.baseboard_fab2(sch_1):page52_i12:DQ(49)" )
				( attribute "RELATIVE_PROPAGATION_DELAY_SCOPE" "G"
					( Parent
						( matchGroupRef "@baseboard_fab2_lib.baseboard_fab2(sch_1):\MG_DQ-DQS_NEAR_DIMM_NG_M_E_BYTE6\" )
					)
					( Status sCSetFlattened )
					( Origin gBackEnd )
				)
				( attribute "RELATIVE_PROPAGATION_DELAY" "0.00 MIL,195.00 MIL"
					( Parent
						( matchGroupRef "@baseboard_fab2_lib.baseboard_fab2(sch_1):\MG_DQ-DQS_NEAR_DIMM_NG_M_E_BYTE6\" )
					)
					( Units "uMatchProp" "ns" 1.000000)
					( Status sCSetFlattened )
					( Origin gBackEnd )
				)
				( attribute "RELATIVE_PROPAGATION_DELAY_SCOPE" "G"
					( Parent
						( matchGroupRef "@baseboard_fab2_lib.baseboard_fab2(sch_1):\MG_DQ_NEAR_DIMM_NG_M_E_BYTE6\" )
					)
					( Status sCSetFlattened )
					( Origin gBackEnd )
				)
				( attribute "RELATIVE_PROPAGATION_DELAY" "-50.00 MIL,50.00 MIL"
					( Parent
						( matchGroupRef "@baseboard_fab2_lib.baseboard_fab2(sch_1):\MG_DQ_NEAR_DIMM_NG_M_E_BYTE6\" )
					)
					( Units "uMatchProp" "ns" 1.000000)
					( Status sCSetFlattened )
					( Origin gBackEnd )
				)
			)
			( pinPair "@baseboard_fab2_lib.baseboard_fab2(sch_1):\PP4353\"
				( pinRef "@baseboard_fab2_lib.baseboard_fab2(sch_1):page27_i172:DDR4_DQ(50)" )
				( pinRef "@baseboard_fab2_lib.baseboard_fab2(sch_1):page51_i111:DQ(51)" )
				( attribute "RELATIVE_PROPAGATION_DELAY_SCOPE" "G"
					( Parent
						( matchGroupRef "@baseboard_fab2_lib.baseboard_fab2(sch_1):\MG_DQ-DQS_FAR_DIMM_NG_M_E_BYTE6\" )
					)
					( Status sCSetFlattened )
					( Origin gBackEnd )
				)
				( attribute "RELATIVE_PROPAGATION_DELAY" "0.00 MIL,195.00 MIL"
					( Parent
						( matchGroupRef "@baseboard_fab2_lib.baseboard_fab2(sch_1):\MG_DQ-DQS_FAR_DIMM_NG_M_E_BYTE6\" )
					)
					( Units "uMatchProp" "ns" 1.000000)
					( Status sCSetFlattened )
					( Origin gBackEnd )
				)
				( attribute "RELATIVE_PROPAGATION_DELAY_SCOPE" "G"
					( Parent
						( matchGroupRef "@baseboard_fab2_lib.baseboard_fab2(sch_1):\MG_DQ_FAR_DIMM_NG_M_E_BYTE6\" )
					)
					( Status sCSetFlattened )
					( Origin gBackEnd )
				)
				( attribute "RELATIVE_PROPAGATION_DELAY" "-50.00 MIL,50.00 MIL"
					( Parent
						( matchGroupRef "@baseboard_fab2_lib.baseboard_fab2(sch_1):\MG_DQ_FAR_DIMM_NG_M_E_BYTE6\" )
					)
					( Units "uMatchProp" "ns" 1.000000)
					( Status sCSetFlattened )
					( Origin gBackEnd )
				)
			)
			( pinPair "@baseboard_fab2_lib.baseboard_fab2(sch_1):\PP4355\"
				( pinRef "@baseboard_fab2_lib.baseboard_fab2(sch_1):page27_i172:DDR4_DQ(50)" )
				( pinRef "@baseboard_fab2_lib.baseboard_fab2(sch_1):page52_i12:DQ(50)" )
				( attribute "RELATIVE_PROPAGATION_DELAY_SCOPE" "G"
					( Parent
						( matchGroupRef "@baseboard_fab2_lib.baseboard_fab2(sch_1):\MG_DQ-DQS_NEAR_DIMM_NG_M_E_BYTE6\" )
					)
					( Status sCSetFlattened )
					( Origin gBackEnd )
				)
				( attribute "RELATIVE_PROPAGATION_DELAY" "0.00 MIL,195.00 MIL"
					( Parent
						( matchGroupRef "@baseboard_fab2_lib.baseboard_fab2(sch_1):\MG_DQ-DQS_NEAR_DIMM_NG_M_E_BYTE6\" )
					)
					( Units "uMatchProp" "ns" 1.000000)
					( Status sCSetFlattened )
					( Origin gBackEnd )
				)
				( attribute "RELATIVE_PROPAGATION_DELAY_SCOPE" "G"
					( Parent
						( matchGroupRef "@baseboard_fab2_lib.baseboard_fab2(sch_1):\MG_DQ_NEAR_DIMM_NG_M_E_BYTE6\" )
					)
					( Status sCSetFlattened )
					( Origin gBackEnd )
				)
				( attribute "RELATIVE_PROPAGATION_DELAY" "-50.00 MIL,50.00 MIL"
					( Parent
						( matchGroupRef "@baseboard_fab2_lib.baseboard_fab2(sch_1):\MG_DQ_NEAR_DIMM_NG_M_E_BYTE6\" )
					)
					( Units "uMatchProp" "ns" 1.000000)
					( Status sCSetFlattened )
					( Origin gBackEnd )
				)
			)
			( pinPair "@baseboard_fab2_lib.baseboard_fab2(sch_1):\PP4356\"
				( pinRef "@baseboard_fab2_lib.baseboard_fab2(sch_1):page27_i172:DDR4_DQ(51)" )
				( pinRef "@baseboard_fab2_lib.baseboard_fab2(sch_1):page51_i111:DQ(50)" )
				( attribute "RELATIVE_PROPAGATION_DELAY_SCOPE" "G"
					( Parent
						( matchGroupRef "@baseboard_fab2_lib.baseboard_fab2(sch_1):\MG_DQ-DQS_FAR_DIMM_NG_M_E_BYTE6\" )
					)
					( Status sCSetFlattened )
					( Origin gBackEnd )
				)
				( attribute "RELATIVE_PROPAGATION_DELAY" "0.00 MIL,195.00 MIL"
					( Parent
						( matchGroupRef "@baseboard_fab2_lib.baseboard_fab2(sch_1):\MG_DQ-DQS_FAR_DIMM_NG_M_E_BYTE6\" )
					)
					( Units "uMatchProp" "ns" 1.000000)
					( Status sCSetFlattened )
					( Origin gBackEnd )
				)
				( attribute "RELATIVE_PROPAGATION_DELAY_SCOPE" "G"
					( Parent
						( matchGroupRef "@baseboard_fab2_lib.baseboard_fab2(sch_1):\MG_DQ_FAR_DIMM_NG_M_E_BYTE6\" )
					)
					( Status sCSetFlattened )
					( Origin gBackEnd )
				)
				( attribute "RELATIVE_PROPAGATION_DELAY" "-50.00 MIL,50.00 MIL"
					( Parent
						( matchGroupRef "@baseboard_fab2_lib.baseboard_fab2(sch_1):\MG_DQ_FAR_DIMM_NG_M_E_BYTE6\" )
					)
					( Units "uMatchProp" "ns" 1.000000)
					( Status sCSetFlattened )
					( Origin gBackEnd )
				)
			)
			( pinPair "@baseboard_fab2_lib.baseboard_fab2(sch_1):\PP4358\"
				( pinRef "@baseboard_fab2_lib.baseboard_fab2(sch_1):page27_i172:DDR4_DQ(51)" )
				( pinRef "@baseboard_fab2_lib.baseboard_fab2(sch_1):page52_i12:DQ(51)" )
				( attribute "RELATIVE_PROPAGATION_DELAY_SCOPE" "G"
					( Parent
						( matchGroupRef "@baseboard_fab2_lib.baseboard_fab2(sch_1):\MG_DQ-DQS_NEAR_DIMM_NG_M_E_BYTE6\" )
					)
					( Status sCSetFlattened )
					( Origin gBackEnd )
				)
				( attribute "RELATIVE_PROPAGATION_DELAY" "0.00 MIL,195.00 MIL"
					( Parent
						( matchGroupRef "@baseboard_fab2_lib.baseboard_fab2(sch_1):\MG_DQ-DQS_NEAR_DIMM_NG_M_E_BYTE6\" )
					)
					( Units "uMatchProp" "ns" 1.000000)
					( Status sCSetFlattened )
					( Origin gBackEnd )
				)
				( attribute "RELATIVE_PROPAGATION_DELAY_SCOPE" "G"
					( Parent
						( matchGroupRef "@baseboard_fab2_lib.baseboard_fab2(sch_1):\MG_DQ_NEAR_DIMM_NG_M_E_BYTE6\" )
					)
					( Status sCSetFlattened )
					( Origin gBackEnd )
				)
				( attribute "RELATIVE_PROPAGATION_DELAY" "-50.00 MIL,50.00 MIL"
					( Parent
						( matchGroupRef "@baseboard_fab2_lib.baseboard_fab2(sch_1):\MG_DQ_NEAR_DIMM_NG_M_E_BYTE6\" )
					)
					( Units "uMatchProp" "ns" 1.000000)
					( Status sCSetFlattened )
					( Origin gBackEnd )
				)
			)
			( pinPair "@baseboard_fab2_lib.baseboard_fab2(sch_1):\PP4359\"
				( pinRef "@baseboard_fab2_lib.baseboard_fab2(sch_1):page27_i172:DDR4_DQ(52)" )
				( pinRef "@baseboard_fab2_lib.baseboard_fab2(sch_1):page51_i111:DQ(53)" )
				( attribute "RELATIVE_PROPAGATION_DELAY_SCOPE" "G"
					( Parent
						( matchGroupRef "@baseboard_fab2_lib.baseboard_fab2(sch_1):\MG_DQ-DQS_FAR_DIMM_NG_M_E_BYTE6\" )
					)
					( Status sCSetFlattened )
					( Origin gBackEnd )
				)
				( attribute "RELATIVE_PROPAGATION_DELAY" "0.00 MIL,195.00 MIL"
					( Parent
						( matchGroupRef "@baseboard_fab2_lib.baseboard_fab2(sch_1):\MG_DQ-DQS_FAR_DIMM_NG_M_E_BYTE6\" )
					)
					( Units "uMatchProp" "ns" 1.000000)
					( Status sCSetFlattened )
					( Origin gBackEnd )
				)
				( attribute "RELATIVE_PROPAGATION_DELAY_SCOPE" "G"
					( Parent
						( matchGroupRef "@baseboard_fab2_lib.baseboard_fab2(sch_1):\MG_DQ_FAR_DIMM_NG_M_E_BYTE6\" )
					)
					( Status sCSetFlattened )
					( Origin gBackEnd )
				)
				( attribute "RELATIVE_PROPAGATION_DELAY" "-50.00 MIL,50.00 MIL"
					( Parent
						( matchGroupRef "@baseboard_fab2_lib.baseboard_fab2(sch_1):\MG_DQ_FAR_DIMM_NG_M_E_BYTE6\" )
					)
					( Units "uMatchProp" "ns" 1.000000)
					( Status sCSetFlattened )
					( Origin gBackEnd )
				)
			)
			( pinPair "@baseboard_fab2_lib.baseboard_fab2(sch_1):\PP4361\"
				( pinRef "@baseboard_fab2_lib.baseboard_fab2(sch_1):page27_i172:DDR4_DQ(52)" )
				( pinRef "@baseboard_fab2_lib.baseboard_fab2(sch_1):page52_i12:DQ(52)" )
				( attribute "RELATIVE_PROPAGATION_DELAY_SCOPE" "G"
					( Parent
						( matchGroupRef "@baseboard_fab2_lib.baseboard_fab2(sch_1):\MG_DQ-DQS_NEAR_DIMM_NG_M_E_BYTE6\" )
					)
					( Status sCSetFlattened )
					( Origin gBackEnd )
				)
				( attribute "RELATIVE_PROPAGATION_DELAY" "0.00 MIL,195.00 MIL"
					( Parent
						( matchGroupRef "@baseboard_fab2_lib.baseboard_fab2(sch_1):\MG_DQ-DQS_NEAR_DIMM_NG_M_E_BYTE6\" )
					)
					( Units "uMatchProp" "ns" 1.000000)
					( Status sCSetFlattened )
					( Origin gBackEnd )
				)
				( attribute "RELATIVE_PROPAGATION_DELAY_SCOPE" "G"
					( Parent
						( matchGroupRef "@baseboard_fab2_lib.baseboard_fab2(sch_1):\MG_DQ_NEAR_DIMM_NG_M_E_BYTE6\" )
					)
					( Status sCSetFlattened )
					( Origin gBackEnd )
				)
				( attribute "RELATIVE_PROPAGATION_DELAY" "-50.00 MIL,50.00 MIL"
					( Parent
						( matchGroupRef "@baseboard_fab2_lib.baseboard_fab2(sch_1):\MG_DQ_NEAR_DIMM_NG_M_E_BYTE6\" )
					)
					( Units "uMatchProp" "ns" 1.000000)
					( Status sCSetFlattened )
					( Origin gBackEnd )
				)
			)
			( pinPair "@baseboard_fab2_lib.baseboard_fab2(sch_1):\PP4362\"
				( pinRef "@baseboard_fab2_lib.baseboard_fab2(sch_1):page27_i172:DDR4_DQ(53)" )
				( pinRef "@baseboard_fab2_lib.baseboard_fab2(sch_1):page51_i111:DQ(52)" )
				( attribute "RELATIVE_PROPAGATION_DELAY_SCOPE" "G"
					( Parent
						( matchGroupRef "@baseboard_fab2_lib.baseboard_fab2(sch_1):\MG_DQ-DQS_FAR_DIMM_NG_M_E_BYTE6\" )
					)
					( Status sCSetFlattened )
					( Origin gBackEnd )
				)
				( attribute "RELATIVE_PROPAGATION_DELAY" "0.00 MIL,195.00 MIL"
					( Parent
						( matchGroupRef "@baseboard_fab2_lib.baseboard_fab2(sch_1):\MG_DQ-DQS_FAR_DIMM_NG_M_E_BYTE6\" )
					)
					( Units "uMatchProp" "ns" 1.000000)
					( Status sCSetFlattened )
					( Origin gBackEnd )
				)
				( attribute "RELATIVE_PROPAGATION_DELAY_SCOPE" "G"
					( Parent
						( matchGroupRef "@baseboard_fab2_lib.baseboard_fab2(sch_1):\MG_DQ_FAR_DIMM_NG_M_E_BYTE6\" )
					)
					( Status sCSetFlattened )
					( Origin gBackEnd )
				)
				( attribute "RELATIVE_PROPAGATION_DELAY" "-50.00 MIL,50.00 MIL"
					( Parent
						( matchGroupRef "@baseboard_fab2_lib.baseboard_fab2(sch_1):\MG_DQ_FAR_DIMM_NG_M_E_BYTE6\" )
					)
					( Units "uMatchProp" "ns" 1.000000)
					( Status sCSetFlattened )
					( Origin gBackEnd )
				)
			)
			( pinPair "@baseboard_fab2_lib.baseboard_fab2(sch_1):\PP4364\"
				( pinRef "@baseboard_fab2_lib.baseboard_fab2(sch_1):page27_i172:DDR4_DQ(53)" )
				( pinRef "@baseboard_fab2_lib.baseboard_fab2(sch_1):page52_i12:DQ(53)" )
				( attribute "RELATIVE_PROPAGATION_DELAY_SCOPE" "G"
					( Parent
						( matchGroupRef "@baseboard_fab2_lib.baseboard_fab2(sch_1):\MG_DQ-DQS_NEAR_DIMM_NG_M_E_BYTE6\" )
					)
					( Status sCSetFlattened )
					( Origin gBackEnd )
				)
				( attribute "RELATIVE_PROPAGATION_DELAY" "0.00 MIL,195.00 MIL"
					( Parent
						( matchGroupRef "@baseboard_fab2_lib.baseboard_fab2(sch_1):\MG_DQ-DQS_NEAR_DIMM_NG_M_E_BYTE6\" )
					)
					( Units "uMatchProp" "ns" 1.000000)
					( Status sCSetFlattened )
					( Origin gBackEnd )
				)
				( attribute "RELATIVE_PROPAGATION_DELAY_SCOPE" "G"
					( Parent
						( matchGroupRef "@baseboard_fab2_lib.baseboard_fab2(sch_1):\MG_DQ_NEAR_DIMM_NG_M_E_BYTE6\" )
					)
					( Status sCSetFlattened )
					( Origin gBackEnd )
				)
				( attribute "RELATIVE_PROPAGATION_DELAY" "-50.00 MIL,50.00 MIL"
					( Parent
						( matchGroupRef "@baseboard_fab2_lib.baseboard_fab2(sch_1):\MG_DQ_NEAR_DIMM_NG_M_E_BYTE6\" )
					)
					( Units "uMatchProp" "ns" 1.000000)
					( Status sCSetFlattened )
					( Origin gBackEnd )
				)
			)
			( pinPair "@baseboard_fab2_lib.baseboard_fab2(sch_1):\PP4365\"
				( pinRef "@baseboard_fab2_lib.baseboard_fab2(sch_1):page27_i172:DDR4_DQ(54)" )
				( pinRef "@baseboard_fab2_lib.baseboard_fab2(sch_1):page51_i111:DQ(55)" )
				( attribute "RELATIVE_PROPAGATION_DELAY_SCOPE" "G"
					( Parent
						( matchGroupRef "@baseboard_fab2_lib.baseboard_fab2(sch_1):\MG_DQ-DQS_FAR_DIMM_NG_M_E_BYTE6\" )
					)
					( Status sCSetFlattened )
					( Origin gBackEnd )
				)
				( attribute "RELATIVE_PROPAGATION_DELAY" "0.00 MIL,195.00 MIL"
					( Parent
						( matchGroupRef "@baseboard_fab2_lib.baseboard_fab2(sch_1):\MG_DQ-DQS_FAR_DIMM_NG_M_E_BYTE6\" )
					)
					( Units "uMatchProp" "ns" 1.000000)
					( Status sCSetFlattened )
					( Origin gBackEnd )
				)
				( attribute "RELATIVE_PROPAGATION_DELAY_SCOPE" "G"
					( Parent
						( matchGroupRef "@baseboard_fab2_lib.baseboard_fab2(sch_1):\MG_DQ_FAR_DIMM_NG_M_E_BYTE6\" )
					)
					( Status sCSetFlattened )
					( Origin gBackEnd )
				)
				( attribute "RELATIVE_PROPAGATION_DELAY" "-50.00 MIL,50.00 MIL"
					( Parent
						( matchGroupRef "@baseboard_fab2_lib.baseboard_fab2(sch_1):\MG_DQ_FAR_DIMM_NG_M_E_BYTE6\" )
					)
					( Units "uMatchProp" "ns" 1.000000)
					( Status sCSetFlattened )
					( Origin gBackEnd )
				)
			)
			( pinPair "@baseboard_fab2_lib.baseboard_fab2(sch_1):\PP4367\"
				( pinRef "@baseboard_fab2_lib.baseboard_fab2(sch_1):page27_i172:DDR4_DQ(54)" )
				( pinRef "@baseboard_fab2_lib.baseboard_fab2(sch_1):page52_i12:DQ(54)" )
				( attribute "RELATIVE_PROPAGATION_DELAY_SCOPE" "G"
					( Parent
						( matchGroupRef "@baseboard_fab2_lib.baseboard_fab2(sch_1):\MG_DQ-DQS_NEAR_DIMM_NG_M_E_BYTE6\" )
					)
					( Status sCSetFlattened )
					( Origin gBackEnd )
				)
				( attribute "RELATIVE_PROPAGATION_DELAY" "0.00 MIL,195.00 MIL"
					( Parent
						( matchGroupRef "@baseboard_fab2_lib.baseboard_fab2(sch_1):\MG_DQ-DQS_NEAR_DIMM_NG_M_E_BYTE6\" )
					)
					( Units "uMatchProp" "ns" 1.000000)
					( Status sCSetFlattened )
					( Origin gBackEnd )
				)
				( attribute "RELATIVE_PROPAGATION_DELAY_SCOPE" "G"
					( Parent
						( matchGroupRef "@baseboard_fab2_lib.baseboard_fab2(sch_1):\MG_DQ_NEAR_DIMM_NG_M_E_BYTE6\" )
					)
					( Status sCSetFlattened )
					( Origin gBackEnd )
				)
				( attribute "RELATIVE_PROPAGATION_DELAY" "-50.00 MIL,50.00 MIL"
					( Parent
						( matchGroupRef "@baseboard_fab2_lib.baseboard_fab2(sch_1):\MG_DQ_NEAR_DIMM_NG_M_E_BYTE6\" )
					)
					( Units "uMatchProp" "ns" 1.000000)
					( Status sCSetFlattened )
					( Origin gBackEnd )
				)
			)
			( pinPair "@baseboard_fab2_lib.baseboard_fab2(sch_1):\PP4368\"
				( pinRef "@baseboard_fab2_lib.baseboard_fab2(sch_1):page27_i172:DDR4_DQ(55)" )
				( pinRef "@baseboard_fab2_lib.baseboard_fab2(sch_1):page51_i111:DQ(54)" )
				( attribute "RELATIVE_PROPAGATION_DELAY_SCOPE" "G"
					( Parent
						( matchGroupRef "@baseboard_fab2_lib.baseboard_fab2(sch_1):\MG_DQ-DQS_FAR_DIMM_NG_M_E_BYTE6\" )
					)
					( Status sCSetFlattened )
					( Origin gBackEnd )
				)
				( attribute "RELATIVE_PROPAGATION_DELAY" "0.00 MIL,195.00 MIL"
					( Parent
						( matchGroupRef "@baseboard_fab2_lib.baseboard_fab2(sch_1):\MG_DQ-DQS_FAR_DIMM_NG_M_E_BYTE6\" )
					)
					( Units "uMatchProp" "ns" 1.000000)
					( Status sCSetFlattened )
					( Origin gBackEnd )
				)
				( attribute "RELATIVE_PROPAGATION_DELAY_SCOPE" "G"
					( Parent
						( matchGroupRef "@baseboard_fab2_lib.baseboard_fab2(sch_1):\MG_DQ_FAR_DIMM_NG_M_E_BYTE6\" )
					)
					( Status sCSetFlattened )
					( Origin gBackEnd )
				)
				( attribute "RELATIVE_PROPAGATION_DELAY" "-50.00 MIL,50.00 MIL"
					( Parent
						( matchGroupRef "@baseboard_fab2_lib.baseboard_fab2(sch_1):\MG_DQ_FAR_DIMM_NG_M_E_BYTE6\" )
					)
					( Units "uMatchProp" "ns" 1.000000)
					( Status sCSetFlattened )
					( Origin gBackEnd )
				)
			)
			( pinPair "@baseboard_fab2_lib.baseboard_fab2(sch_1):\PP4370\"
				( pinRef "@baseboard_fab2_lib.baseboard_fab2(sch_1):page52_i12:DQ(55)" )
				( pinRef "@baseboard_fab2_lib.baseboard_fab2(sch_1):page27_i172:DDR4_DQ(55)" )
				( attribute "RELATIVE_PROPAGATION_DELAY_SCOPE" "G"
					( Parent
						( matchGroupRef "@baseboard_fab2_lib.baseboard_fab2(sch_1):\MG_DQ-DQS_NEAR_DIMM_NG_M_E_BYTE6\" )
					)
					( Status sCSetFlattened )
					( Origin gBackEnd )
				)
				( attribute "RELATIVE_PROPAGATION_DELAY" "0.00 MIL,195.00 MIL"
					( Parent
						( matchGroupRef "@baseboard_fab2_lib.baseboard_fab2(sch_1):\MG_DQ-DQS_NEAR_DIMM_NG_M_E_BYTE6\" )
					)
					( Units "uMatchProp" "ns" 1.000000)
					( Status sCSetFlattened )
					( Origin gBackEnd )
				)
				( attribute "RELATIVE_PROPAGATION_DELAY_SCOPE" "G"
					( Parent
						( matchGroupRef "@baseboard_fab2_lib.baseboard_fab2(sch_1):\MG_DQ_NEAR_DIMM_NG_M_E_BYTE6\" )
					)
					( Status sCSetFlattened )
					( Origin gBackEnd )
				)
				( attribute "RELATIVE_PROPAGATION_DELAY" "-50.00 MIL,50.00 MIL"
					( Parent
						( matchGroupRef "@baseboard_fab2_lib.baseboard_fab2(sch_1):\MG_DQ_NEAR_DIMM_NG_M_E_BYTE6\" )
					)
					( Units "uMatchProp" "ns" 1.000000)
					( Status sCSetFlattened )
					( Origin gBackEnd )
				)
			)
			( pinPair "@baseboard_fab2_lib.baseboard_fab2(sch_1):\PP4323\"
				( pinRef "@baseboard_fab2_lib.baseboard_fab2(sch_1):page27_i172:DDR4_DQ(56)" )
				( pinRef "@baseboard_fab2_lib.baseboard_fab2(sch_1):page51_i111:DQ(57)" )
				( attribute "RELATIVE_PROPAGATION_DELAY_SCOPE" "G"
					( Parent
						( matchGroupRef "@baseboard_fab2_lib.baseboard_fab2(sch_1):\MG_DQ-DQS_FAR_DIMM_NG_M_E_BYTE7\" )
					)
					( Status sCSetFlattened )
					( Origin gBackEnd )
				)
				( attribute "RELATIVE_PROPAGATION_DELAY" "0.00 MIL,195.00 MIL"
					( Parent
						( matchGroupRef "@baseboard_fab2_lib.baseboard_fab2(sch_1):\MG_DQ-DQS_FAR_DIMM_NG_M_E_BYTE7\" )
					)
					( Units "uMatchProp" "ns" 1.000000)
					( Status sCSetFlattened )
					( Origin gBackEnd )
				)
				( attribute "RELATIVE_PROPAGATION_DELAY_SCOPE" "G"
					( Parent
						( matchGroupRef "@baseboard_fab2_lib.baseboard_fab2(sch_1):\MG_DQ_FAR_DIMM_NG_M_E_BYTE7\" )
					)
					( Status sCSetFlattened )
					( Origin gBackEnd )
				)
				( attribute "RELATIVE_PROPAGATION_DELAY" "-50.00 MIL,50.00 MIL"
					( Parent
						( matchGroupRef "@baseboard_fab2_lib.baseboard_fab2(sch_1):\MG_DQ_FAR_DIMM_NG_M_E_BYTE7\" )
					)
					( Units "uMatchProp" "ns" 1.000000)
					( Status sCSetFlattened )
					( Origin gBackEnd )
				)
			)
			( pinPair "@baseboard_fab2_lib.baseboard_fab2(sch_1):\PP4325\"
				( pinRef "@baseboard_fab2_lib.baseboard_fab2(sch_1):page52_i12:DQ(56)" )
				( pinRef "@baseboard_fab2_lib.baseboard_fab2(sch_1):page27_i172:DDR4_DQ(56)" )
				( attribute "RELATIVE_PROPAGATION_DELAY_SCOPE" "G"
					( Parent
						( matchGroupRef "@baseboard_fab2_lib.baseboard_fab2(sch_1):\MG_DQ-DQS_NEAR_DIMM_NG_M_E_BYTE7\" )
					)
					( Status sCSetFlattened )
					( Origin gBackEnd )
				)
				( attribute "RELATIVE_PROPAGATION_DELAY" "0.00 MIL,195.00 MIL"
					( Parent
						( matchGroupRef "@baseboard_fab2_lib.baseboard_fab2(sch_1):\MG_DQ-DQS_NEAR_DIMM_NG_M_E_BYTE7\" )
					)
					( Units "uMatchProp" "ns" 1.000000)
					( Status sCSetFlattened )
					( Origin gBackEnd )
				)
				( attribute "RELATIVE_PROPAGATION_DELAY_SCOPE" "G"
					( Parent
						( matchGroupRef "@baseboard_fab2_lib.baseboard_fab2(sch_1):\MG_DQ_NEAR_DIMM_NG_M_E_BYTE7\" )
					)
					( Status sCSetFlattened )
					( Origin gBackEnd )
				)
				( attribute "RELATIVE_PROPAGATION_DELAY" "-50.00 MIL,50.00 MIL"
					( Parent
						( matchGroupRef "@baseboard_fab2_lib.baseboard_fab2(sch_1):\MG_DQ_NEAR_DIMM_NG_M_E_BYTE7\" )
					)
					( Units "uMatchProp" "ns" 1.000000)
					( Status sCSetFlattened )
					( Origin gBackEnd )
				)
			)
			( pinPair "@baseboard_fab2_lib.baseboard_fab2(sch_1):\PP4326\"
				( pinRef "@baseboard_fab2_lib.baseboard_fab2(sch_1):page27_i172:DDR4_DQ(57)" )
				( pinRef "@baseboard_fab2_lib.baseboard_fab2(sch_1):page51_i111:DQ(56)" )
				( attribute "RELATIVE_PROPAGATION_DELAY_SCOPE" "G"
					( Parent
						( matchGroupRef "@baseboard_fab2_lib.baseboard_fab2(sch_1):\MG_DQ-DQS_FAR_DIMM_NG_M_E_BYTE7\" )
					)
					( Status sCSetFlattened )
					( Origin gBackEnd )
				)
				( attribute "RELATIVE_PROPAGATION_DELAY" "0.00 MIL,195.00 MIL"
					( Parent
						( matchGroupRef "@baseboard_fab2_lib.baseboard_fab2(sch_1):\MG_DQ-DQS_FAR_DIMM_NG_M_E_BYTE7\" )
					)
					( Units "uMatchProp" "ns" 1.000000)
					( Status sCSetFlattened )
					( Origin gBackEnd )
				)
				( attribute "RELATIVE_PROPAGATION_DELAY_SCOPE" "G"
					( Parent
						( matchGroupRef "@baseboard_fab2_lib.baseboard_fab2(sch_1):\MG_DQ_FAR_DIMM_NG_M_E_BYTE7\" )
					)
					( Status sCSetFlattened )
					( Origin gBackEnd )
				)
				( attribute "RELATIVE_PROPAGATION_DELAY" "-50.00 MIL,50.00 MIL"
					( Parent
						( matchGroupRef "@baseboard_fab2_lib.baseboard_fab2(sch_1):\MG_DQ_FAR_DIMM_NG_M_E_BYTE7\" )
					)
					( Units "uMatchProp" "ns" 1.000000)
					( Status sCSetFlattened )
					( Origin gBackEnd )
				)
			)
			( pinPair "@baseboard_fab2_lib.baseboard_fab2(sch_1):\PP4328\"
				( pinRef "@baseboard_fab2_lib.baseboard_fab2(sch_1):page52_i12:DQ(57)" )
				( pinRef "@baseboard_fab2_lib.baseboard_fab2(sch_1):page27_i172:DDR4_DQ(57)" )
				( attribute "RELATIVE_PROPAGATION_DELAY_SCOPE" "G"
					( Parent
						( matchGroupRef "@baseboard_fab2_lib.baseboard_fab2(sch_1):\MG_DQ-DQS_NEAR_DIMM_NG_M_E_BYTE7\" )
					)
					( Status sCSetFlattened )
					( Origin gBackEnd )
				)
				( attribute "RELATIVE_PROPAGATION_DELAY" "0.00 MIL,195.00 MIL"
					( Parent
						( matchGroupRef "@baseboard_fab2_lib.baseboard_fab2(sch_1):\MG_DQ-DQS_NEAR_DIMM_NG_M_E_BYTE7\" )
					)
					( Units "uMatchProp" "ns" 1.000000)
					( Status sCSetFlattened )
					( Origin gBackEnd )
				)
				( attribute "RELATIVE_PROPAGATION_DELAY_SCOPE" "G"
					( Parent
						( matchGroupRef "@baseboard_fab2_lib.baseboard_fab2(sch_1):\MG_DQ_NEAR_DIMM_NG_M_E_BYTE7\" )
					)
					( Status sCSetFlattened )
					( Origin gBackEnd )
				)
				( attribute "RELATIVE_PROPAGATION_DELAY" "-50.00 MIL,50.00 MIL"
					( Parent
						( matchGroupRef "@baseboard_fab2_lib.baseboard_fab2(sch_1):\MG_DQ_NEAR_DIMM_NG_M_E_BYTE7\" )
					)
					( Units "uMatchProp" "ns" 1.000000)
					( Status sCSetFlattened )
					( Origin gBackEnd )
				)
			)
			( pinPair "@baseboard_fab2_lib.baseboard_fab2(sch_1):\PP4329\"
				( pinRef "@baseboard_fab2_lib.baseboard_fab2(sch_1):page27_i172:DDR4_DQ(58)" )
				( pinRef "@baseboard_fab2_lib.baseboard_fab2(sch_1):page51_i111:DQ(59)" )
				( attribute "RELATIVE_PROPAGATION_DELAY_SCOPE" "G"
					( Parent
						( matchGroupRef "@baseboard_fab2_lib.baseboard_fab2(sch_1):\MG_DQ-DQS_FAR_DIMM_NG_M_E_BYTE7\" )
					)
					( Status sCSetFlattened )
					( Origin gBackEnd )
				)
				( attribute "RELATIVE_PROPAGATION_DELAY" "0.00 MIL,195.00 MIL"
					( Parent
						( matchGroupRef "@baseboard_fab2_lib.baseboard_fab2(sch_1):\MG_DQ-DQS_FAR_DIMM_NG_M_E_BYTE7\" )
					)
					( Units "uMatchProp" "ns" 1.000000)
					( Status sCSetFlattened )
					( Origin gBackEnd )
				)
				( attribute "RELATIVE_PROPAGATION_DELAY_SCOPE" "G"
					( Parent
						( matchGroupRef "@baseboard_fab2_lib.baseboard_fab2(sch_1):\MG_DQ_FAR_DIMM_NG_M_E_BYTE7\" )
					)
					( Status sCSetFlattened )
					( Origin gBackEnd )
				)
				( attribute "RELATIVE_PROPAGATION_DELAY" "-50.00 MIL,50.00 MIL"
					( Parent
						( matchGroupRef "@baseboard_fab2_lib.baseboard_fab2(sch_1):\MG_DQ_FAR_DIMM_NG_M_E_BYTE7\" )
					)
					( Units "uMatchProp" "ns" 1.000000)
					( Status sCSetFlattened )
					( Origin gBackEnd )
				)
			)
			( pinPair "@baseboard_fab2_lib.baseboard_fab2(sch_1):\PP4331\"
				( pinRef "@baseboard_fab2_lib.baseboard_fab2(sch_1):page52_i12:DQ(58)" )
				( pinRef "@baseboard_fab2_lib.baseboard_fab2(sch_1):page27_i172:DDR4_DQ(58)" )
				( attribute "RELATIVE_PROPAGATION_DELAY_SCOPE" "G"
					( Parent
						( matchGroupRef "@baseboard_fab2_lib.baseboard_fab2(sch_1):\MG_DQ-DQS_NEAR_DIMM_NG_M_E_BYTE7\" )
					)
					( Status sCSetFlattened )
					( Origin gBackEnd )
				)
				( attribute "RELATIVE_PROPAGATION_DELAY" "0.00 MIL,195.00 MIL"
					( Parent
						( matchGroupRef "@baseboard_fab2_lib.baseboard_fab2(sch_1):\MG_DQ-DQS_NEAR_DIMM_NG_M_E_BYTE7\" )
					)
					( Units "uMatchProp" "ns" 1.000000)
					( Status sCSetFlattened )
					( Origin gBackEnd )
				)
				( attribute "RELATIVE_PROPAGATION_DELAY_SCOPE" "G"
					( Parent
						( matchGroupRef "@baseboard_fab2_lib.baseboard_fab2(sch_1):\MG_DQ_NEAR_DIMM_NG_M_E_BYTE7\" )
					)
					( Status sCSetFlattened )
					( Origin gBackEnd )
				)
				( attribute "RELATIVE_PROPAGATION_DELAY" "-50.00 MIL,50.00 MIL"
					( Parent
						( matchGroupRef "@baseboard_fab2_lib.baseboard_fab2(sch_1):\MG_DQ_NEAR_DIMM_NG_M_E_BYTE7\" )
					)
					( Units "uMatchProp" "ns" 1.000000)
					( Status sCSetFlattened )
					( Origin gBackEnd )
				)
			)
			( pinPair "@baseboard_fab2_lib.baseboard_fab2(sch_1):\PP4332\"
				( pinRef "@baseboard_fab2_lib.baseboard_fab2(sch_1):page27_i172:DDR4_DQ(59)" )
				( pinRef "@baseboard_fab2_lib.baseboard_fab2(sch_1):page51_i111:DQ(58)" )
				( attribute "RELATIVE_PROPAGATION_DELAY_SCOPE" "G"
					( Parent
						( matchGroupRef "@baseboard_fab2_lib.baseboard_fab2(sch_1):\MG_DQ-DQS_FAR_DIMM_NG_M_E_BYTE7\" )
					)
					( Status sCSetFlattened )
					( Origin gBackEnd )
				)
				( attribute "RELATIVE_PROPAGATION_DELAY" "0.00 MIL,195.00 MIL"
					( Parent
						( matchGroupRef "@baseboard_fab2_lib.baseboard_fab2(sch_1):\MG_DQ-DQS_FAR_DIMM_NG_M_E_BYTE7\" )
					)
					( Units "uMatchProp" "ns" 1.000000)
					( Status sCSetFlattened )
					( Origin gBackEnd )
				)
				( attribute "RELATIVE_PROPAGATION_DELAY_SCOPE" "G"
					( Parent
						( matchGroupRef "@baseboard_fab2_lib.baseboard_fab2(sch_1):\MG_DQ_FAR_DIMM_NG_M_E_BYTE7\" )
					)
					( Status sCSetFlattened )
					( Origin gBackEnd )
				)
				( attribute "RELATIVE_PROPAGATION_DELAY" "-50.00 MIL,50.00 MIL"
					( Parent
						( matchGroupRef "@baseboard_fab2_lib.baseboard_fab2(sch_1):\MG_DQ_FAR_DIMM_NG_M_E_BYTE7\" )
					)
					( Units "uMatchProp" "ns" 1.000000)
					( Status sCSetFlattened )
					( Origin gBackEnd )
				)
			)
			( pinPair "@baseboard_fab2_lib.baseboard_fab2(sch_1):\PP4334\"
				( pinRef "@baseboard_fab2_lib.baseboard_fab2(sch_1):page52_i12:DQ(59)" )
				( pinRef "@baseboard_fab2_lib.baseboard_fab2(sch_1):page27_i172:DDR4_DQ(59)" )
				( attribute "RELATIVE_PROPAGATION_DELAY_SCOPE" "G"
					( Parent
						( matchGroupRef "@baseboard_fab2_lib.baseboard_fab2(sch_1):\MG_DQ-DQS_NEAR_DIMM_NG_M_E_BYTE7\" )
					)
					( Status sCSetFlattened )
					( Origin gBackEnd )
				)
				( attribute "RELATIVE_PROPAGATION_DELAY" "0.00 MIL,195.00 MIL"
					( Parent
						( matchGroupRef "@baseboard_fab2_lib.baseboard_fab2(sch_1):\MG_DQ-DQS_NEAR_DIMM_NG_M_E_BYTE7\" )
					)
					( Units "uMatchProp" "ns" 1.000000)
					( Status sCSetFlattened )
					( Origin gBackEnd )
				)
				( attribute "RELATIVE_PROPAGATION_DELAY_SCOPE" "G"
					( Parent
						( matchGroupRef "@baseboard_fab2_lib.baseboard_fab2(sch_1):\MG_DQ_NEAR_DIMM_NG_M_E_BYTE7\" )
					)
					( Status sCSetFlattened )
					( Origin gBackEnd )
				)
				( attribute "RELATIVE_PROPAGATION_DELAY" "-50.00 MIL,50.00 MIL"
					( Parent
						( matchGroupRef "@baseboard_fab2_lib.baseboard_fab2(sch_1):\MG_DQ_NEAR_DIMM_NG_M_E_BYTE7\" )
					)
					( Units "uMatchProp" "ns" 1.000000)
					( Status sCSetFlattened )
					( Origin gBackEnd )
				)
			)
			( pinPair "@baseboard_fab2_lib.baseboard_fab2(sch_1):\PP4335\"
				( pinRef "@baseboard_fab2_lib.baseboard_fab2(sch_1):page27_i172:DDR4_DQ(60)" )
				( pinRef "@baseboard_fab2_lib.baseboard_fab2(sch_1):page51_i111:DQ(61)" )
				( attribute "RELATIVE_PROPAGATION_DELAY_SCOPE" "G"
					( Parent
						( matchGroupRef "@baseboard_fab2_lib.baseboard_fab2(sch_1):\MG_DQ-DQS_FAR_DIMM_NG_M_E_BYTE7\" )
					)
					( Status sCSetFlattened )
					( Origin gBackEnd )
				)
				( attribute "RELATIVE_PROPAGATION_DELAY" "0.00 MIL,195.00 MIL"
					( Parent
						( matchGroupRef "@baseboard_fab2_lib.baseboard_fab2(sch_1):\MG_DQ-DQS_FAR_DIMM_NG_M_E_BYTE7\" )
					)
					( Units "uMatchProp" "ns" 1.000000)
					( Status sCSetFlattened )
					( Origin gBackEnd )
				)
				( attribute "RELATIVE_PROPAGATION_DELAY_SCOPE" "G"
					( Parent
						( matchGroupRef "@baseboard_fab2_lib.baseboard_fab2(sch_1):\MG_DQ_FAR_DIMM_NG_M_E_BYTE7\" )
					)
					( Status sCSetFlattened )
					( Origin gBackEnd )
				)
				( attribute "RELATIVE_PROPAGATION_DELAY" "-50.00 MIL,50.00 MIL"
					( Parent
						( matchGroupRef "@baseboard_fab2_lib.baseboard_fab2(sch_1):\MG_DQ_FAR_DIMM_NG_M_E_BYTE7\" )
					)
					( Units "uMatchProp" "ns" 1.000000)
					( Status sCSetFlattened )
					( Origin gBackEnd )
				)
			)
			( pinPair "@baseboard_fab2_lib.baseboard_fab2(sch_1):\PP4337\"
				( pinRef "@baseboard_fab2_lib.baseboard_fab2(sch_1):page52_i12:DQ(60)" )
				( pinRef "@baseboard_fab2_lib.baseboard_fab2(sch_1):page27_i172:DDR4_DQ(60)" )
				( attribute "RELATIVE_PROPAGATION_DELAY_SCOPE" "G"
					( Parent
						( matchGroupRef "@baseboard_fab2_lib.baseboard_fab2(sch_1):\MG_DQ-DQS_NEAR_DIMM_NG_M_E_BYTE7\" )
					)
					( Status sCSetFlattened )
					( Origin gBackEnd )
				)
				( attribute "RELATIVE_PROPAGATION_DELAY" "0.00 MIL,195.00 MIL"
					( Parent
						( matchGroupRef "@baseboard_fab2_lib.baseboard_fab2(sch_1):\MG_DQ-DQS_NEAR_DIMM_NG_M_E_BYTE7\" )
					)
					( Units "uMatchProp" "ns" 1.000000)
					( Status sCSetFlattened )
					( Origin gBackEnd )
				)
				( attribute "RELATIVE_PROPAGATION_DELAY_SCOPE" "G"
					( Parent
						( matchGroupRef "@baseboard_fab2_lib.baseboard_fab2(sch_1):\MG_DQ_NEAR_DIMM_NG_M_E_BYTE7\" )
					)
					( Status sCSetFlattened )
					( Origin gBackEnd )
				)
				( attribute "RELATIVE_PROPAGATION_DELAY" "-50.00 MIL,50.00 MIL"
					( Parent
						( matchGroupRef "@baseboard_fab2_lib.baseboard_fab2(sch_1):\MG_DQ_NEAR_DIMM_NG_M_E_BYTE7\" )
					)
					( Units "uMatchProp" "ns" 1.000000)
					( Status sCSetFlattened )
					( Origin gBackEnd )
				)
			)
			( pinPair "@baseboard_fab2_lib.baseboard_fab2(sch_1):\PP4338\"
				( pinRef "@baseboard_fab2_lib.baseboard_fab2(sch_1):page27_i172:DDR4_DQ(61)" )
				( pinRef "@baseboard_fab2_lib.baseboard_fab2(sch_1):page51_i111:DQ(60)" )
				( attribute "RELATIVE_PROPAGATION_DELAY_SCOPE" "G"
					( Parent
						( matchGroupRef "@baseboard_fab2_lib.baseboard_fab2(sch_1):\MG_DQ-DQS_FAR_DIMM_NG_M_E_BYTE7\" )
					)
					( Status sCSetFlattened )
					( Origin gBackEnd )
				)
				( attribute "RELATIVE_PROPAGATION_DELAY" "0.00 MIL,195.00 MIL"
					( Parent
						( matchGroupRef "@baseboard_fab2_lib.baseboard_fab2(sch_1):\MG_DQ-DQS_FAR_DIMM_NG_M_E_BYTE7\" )
					)
					( Units "uMatchProp" "ns" 1.000000)
					( Status sCSetFlattened )
					( Origin gBackEnd )
				)
				( attribute "RELATIVE_PROPAGATION_DELAY_SCOPE" "G"
					( Parent
						( matchGroupRef "@baseboard_fab2_lib.baseboard_fab2(sch_1):\MG_DQ_FAR_DIMM_NG_M_E_BYTE7\" )
					)
					( Status sCSetFlattened )
					( Origin gBackEnd )
				)
				( attribute "RELATIVE_PROPAGATION_DELAY" "-50.00 MIL,50.00 MIL"
					( Parent
						( matchGroupRef "@baseboard_fab2_lib.baseboard_fab2(sch_1):\MG_DQ_FAR_DIMM_NG_M_E_BYTE7\" )
					)
					( Units "uMatchProp" "ns" 1.000000)
					( Status sCSetFlattened )
					( Origin gBackEnd )
				)
			)
			( pinPair "@baseboard_fab2_lib.baseboard_fab2(sch_1):\PP4340\"
				( pinRef "@baseboard_fab2_lib.baseboard_fab2(sch_1):page52_i12:DQ(61)" )
				( pinRef "@baseboard_fab2_lib.baseboard_fab2(sch_1):page27_i172:DDR4_DQ(61)" )
				( attribute "RELATIVE_PROPAGATION_DELAY_SCOPE" "G"
					( Parent
						( matchGroupRef "@baseboard_fab2_lib.baseboard_fab2(sch_1):\MG_DQ-DQS_NEAR_DIMM_NG_M_E_BYTE7\" )
					)
					( Status sCSetFlattened )
					( Origin gBackEnd )
				)
				( attribute "RELATIVE_PROPAGATION_DELAY" "0.00 MIL,195.00 MIL"
					( Parent
						( matchGroupRef "@baseboard_fab2_lib.baseboard_fab2(sch_1):\MG_DQ-DQS_NEAR_DIMM_NG_M_E_BYTE7\" )
					)
					( Units "uMatchProp" "ns" 1.000000)
					( Status sCSetFlattened )
					( Origin gBackEnd )
				)
				( attribute "RELATIVE_PROPAGATION_DELAY_SCOPE" "G"
					( Parent
						( matchGroupRef "@baseboard_fab2_lib.baseboard_fab2(sch_1):\MG_DQ_NEAR_DIMM_NG_M_E_BYTE7\" )
					)
					( Status sCSetFlattened )
					( Origin gBackEnd )
				)
				( attribute "RELATIVE_PROPAGATION_DELAY" "-50.00 MIL,50.00 MIL"
					( Parent
						( matchGroupRef "@baseboard_fab2_lib.baseboard_fab2(sch_1):\MG_DQ_NEAR_DIMM_NG_M_E_BYTE7\" )
					)
					( Units "uMatchProp" "ns" 1.000000)
					( Status sCSetFlattened )
					( Origin gBackEnd )
				)
			)
			( pinPair "@baseboard_fab2_lib.baseboard_fab2(sch_1):\PP4341\"
				( pinRef "@baseboard_fab2_lib.baseboard_fab2(sch_1):page27_i172:DDR4_DQ(62)" )
				( pinRef "@baseboard_fab2_lib.baseboard_fab2(sch_1):page51_i111:DQ(63)" )
				( attribute "RELATIVE_PROPAGATION_DELAY_SCOPE" "G"
					( Parent
						( matchGroupRef "@baseboard_fab2_lib.baseboard_fab2(sch_1):\MG_DQ-DQS_FAR_DIMM_NG_M_E_BYTE7\" )
					)
					( Status sCSetFlattened )
					( Origin gBackEnd )
				)
				( attribute "RELATIVE_PROPAGATION_DELAY" "0.00 MIL,195.00 MIL"
					( Parent
						( matchGroupRef "@baseboard_fab2_lib.baseboard_fab2(sch_1):\MG_DQ-DQS_FAR_DIMM_NG_M_E_BYTE7\" )
					)
					( Units "uMatchProp" "ns" 1.000000)
					( Status sCSetFlattened )
					( Origin gBackEnd )
				)
				( attribute "RELATIVE_PROPAGATION_DELAY_SCOPE" "G"
					( Parent
						( matchGroupRef "@baseboard_fab2_lib.baseboard_fab2(sch_1):\MG_DQ_FAR_DIMM_NG_M_E_BYTE7\" )
					)
					( Status sCSetFlattened )
					( Origin gBackEnd )
				)
				( attribute "RELATIVE_PROPAGATION_DELAY" "-50.00 MIL,50.00 MIL"
					( Parent
						( matchGroupRef "@baseboard_fab2_lib.baseboard_fab2(sch_1):\MG_DQ_FAR_DIMM_NG_M_E_BYTE7\" )
					)
					( Units "uMatchProp" "ns" 1.000000)
					( Status sCSetFlattened )
					( Origin gBackEnd )
				)
			)
			( pinPair "@baseboard_fab2_lib.baseboard_fab2(sch_1):\PP4343\"
				( pinRef "@baseboard_fab2_lib.baseboard_fab2(sch_1):page52_i12:DQ(62)" )
				( pinRef "@baseboard_fab2_lib.baseboard_fab2(sch_1):page27_i172:DDR4_DQ(62)" )
				( attribute "RELATIVE_PROPAGATION_DELAY_SCOPE" "G"
					( Parent
						( matchGroupRef "@baseboard_fab2_lib.baseboard_fab2(sch_1):\MG_DQ-DQS_NEAR_DIMM_NG_M_E_BYTE7\" )
					)
					( Status sCSetFlattened )
					( Origin gBackEnd )
				)
				( attribute "RELATIVE_PROPAGATION_DELAY" "0.00 MIL,195.00 MIL"
					( Parent
						( matchGroupRef "@baseboard_fab2_lib.baseboard_fab2(sch_1):\MG_DQ-DQS_NEAR_DIMM_NG_M_E_BYTE7\" )
					)
					( Units "uMatchProp" "ns" 1.000000)
					( Status sCSetFlattened )
					( Origin gBackEnd )
				)
				( attribute "RELATIVE_PROPAGATION_DELAY_SCOPE" "G"
					( Parent
						( matchGroupRef "@baseboard_fab2_lib.baseboard_fab2(sch_1):\MG_DQ_NEAR_DIMM_NG_M_E_BYTE7\" )
					)
					( Status sCSetFlattened )
					( Origin gBackEnd )
				)
				( attribute "RELATIVE_PROPAGATION_DELAY" "-50.00 MIL,50.00 MIL"
					( Parent
						( matchGroupRef "@baseboard_fab2_lib.baseboard_fab2(sch_1):\MG_DQ_NEAR_DIMM_NG_M_E_BYTE7\" )
					)
					( Units "uMatchProp" "ns" 1.000000)
					( Status sCSetFlattened )
					( Origin gBackEnd )
				)
			)
			( pinPair "@baseboard_fab2_lib.baseboard_fab2(sch_1):\PP4344\"
				( pinRef "@baseboard_fab2_lib.baseboard_fab2(sch_1):page27_i172:DDR4_DQ(63)" )
				( pinRef "@baseboard_fab2_lib.baseboard_fab2(sch_1):page51_i111:DQ(62)" )
				( attribute "RELATIVE_PROPAGATION_DELAY_SCOPE" "G"
					( Parent
						( matchGroupRef "@baseboard_fab2_lib.baseboard_fab2(sch_1):\MG_DQ-DQS_FAR_DIMM_NG_M_E_BYTE7\" )
					)
					( Status sCSetFlattened )
					( Origin gBackEnd )
				)
				( attribute "RELATIVE_PROPAGATION_DELAY" "0.00 MIL,195.00 MIL"
					( Parent
						( matchGroupRef "@baseboard_fab2_lib.baseboard_fab2(sch_1):\MG_DQ-DQS_FAR_DIMM_NG_M_E_BYTE7\" )
					)
					( Units "uMatchProp" "ns" 1.000000)
					( Status sCSetFlattened )
					( Origin gBackEnd )
				)
				( attribute "RELATIVE_PROPAGATION_DELAY_SCOPE" "G"
					( Parent
						( matchGroupRef "@baseboard_fab2_lib.baseboard_fab2(sch_1):\MG_DQ_FAR_DIMM_NG_M_E_BYTE7\" )
					)
					( Status sCSetFlattened )
					( Origin gBackEnd )
				)
				( attribute "RELATIVE_PROPAGATION_DELAY" "-50.00 MIL,50.00 MIL"
					( Parent
						( matchGroupRef "@baseboard_fab2_lib.baseboard_fab2(sch_1):\MG_DQ_FAR_DIMM_NG_M_E_BYTE7\" )
					)
					( Units "uMatchProp" "ns" 1.000000)
					( Status sCSetFlattened )
					( Origin gBackEnd )
				)
			)
			( pinPair "@baseboard_fab2_lib.baseboard_fab2(sch_1):\PP4346\"
				( pinRef "@baseboard_fab2_lib.baseboard_fab2(sch_1):page52_i12:DQ(63)" )
				( pinRef "@baseboard_fab2_lib.baseboard_fab2(sch_1):page27_i172:DDR4_DQ(63)" )
				( attribute "RELATIVE_PROPAGATION_DELAY_SCOPE" "G"
					( Parent
						( matchGroupRef "@baseboard_fab2_lib.baseboard_fab2(sch_1):\MG_DQ-DQS_NEAR_DIMM_NG_M_E_BYTE7\" )
					)
					( Status sCSetFlattened )
					( Origin gBackEnd )
				)
				( attribute "RELATIVE_PROPAGATION_DELAY" "0.00 MIL,195.00 MIL"
					( Parent
						( matchGroupRef "@baseboard_fab2_lib.baseboard_fab2(sch_1):\MG_DQ-DQS_NEAR_DIMM_NG_M_E_BYTE7\" )
					)
					( Units "uMatchProp" "ns" 1.000000)
					( Status sCSetFlattened )
					( Origin gBackEnd )
				)
				( attribute "RELATIVE_PROPAGATION_DELAY_SCOPE" "G"
					( Parent
						( matchGroupRef "@baseboard_fab2_lib.baseboard_fab2(sch_1):\MG_DQ_NEAR_DIMM_NG_M_E_BYTE7\" )
					)
					( Status sCSetFlattened )
					( Origin gBackEnd )
				)
				( attribute "RELATIVE_PROPAGATION_DELAY" "-50.00 MIL,50.00 MIL"
					( Parent
						( matchGroupRef "@baseboard_fab2_lib.baseboard_fab2(sch_1):\MG_DQ_NEAR_DIMM_NG_M_E_BYTE7\" )
					)
					( Units "uMatchProp" "ns" 1.000000)
					( Status sCSetFlattened )
					( Origin gBackEnd )
				)
			)
			( pinPair "@baseboard_fab2_lib.baseboard_fab2(sch_1):\PP4251\"
				( pinRef "@baseboard_fab2_lib.baseboard_fab2(sch_1):page28_i172:DDR5_DQ(0)" )
				( pinRef "@baseboard_fab2_lib.baseboard_fab2(sch_1):page53_i111:DQ(1)" )
				( attribute "RELATIVE_PROPAGATION_DELAY_SCOPE" "G"
					( Parent
						( matchGroupRef "@baseboard_fab2_lib.baseboard_fab2(sch_1):\MG_DQ-DQS_FAR_DIMM_NG_M_F_BYTE0\" )
					)
					( Status sCSetFlattened )
					( Origin gBackEnd )
				)
				( attribute "RELATIVE_PROPAGATION_DELAY" "0.00 MIL,195.00 MIL"
					( Parent
						( matchGroupRef "@baseboard_fab2_lib.baseboard_fab2(sch_1):\MG_DQ-DQS_FAR_DIMM_NG_M_F_BYTE0\" )
					)
					( Units "uMatchProp" "ns" 1.000000)
					( Status sCSetFlattened )
					( Origin gBackEnd )
				)
				( attribute "RELATIVE_PROPAGATION_DELAY_SCOPE" "G"
					( Parent
						( matchGroupRef "@crescent_city_bb_fab1_lib.crescent_city_bb_fab1(sch_1):\MG_DQ_FAR_DIMM_NG_M_F_BYTE0\" )
					)
					( Status sCSetFlattened )
					( Origin gBackEnd )
				)
				( attribute "RELATIVE_PROPAGATION_DELAY" "-50.00 MIL,50.00 MIL"
					( Parent
						( matchGroupRef "@crescent_city_bb_fab1_lib.crescent_city_bb_fab1(sch_1):\MG_DQ_FAR_DIMM_NG_M_F_BYTE0\" )
					)
					( Units "uMatchProp" "ns" 1.000000)
					( Status sCSetFlattened )
					( Origin gBackEnd )
				)
			)
			( pinPair "@baseboard_fab2_lib.baseboard_fab2(sch_1):\PP4253\"
				( pinRef "@baseboard_fab2_lib.baseboard_fab2(sch_1):page54_i111:DQ(0)" )
				( pinRef "@baseboard_fab2_lib.baseboard_fab2(sch_1):page28_i172:DDR5_DQ(0)" )
				( attribute "RELATIVE_PROPAGATION_DELAY_SCOPE" "G"
					( Parent
						( matchGroupRef "@baseboard_fab2_lib.baseboard_fab2(sch_1):\MG_DQ-DQS_NEAR_DIMM_NG_M_F_BYTE0\" )
					)
					( Status sCSetFlattened )
					( Origin gBackEnd )
				)
				( attribute "RELATIVE_PROPAGATION_DELAY" "0.00 MIL,195.00 MIL"
					( Parent
						( matchGroupRef "@baseboard_fab2_lib.baseboard_fab2(sch_1):\MG_DQ-DQS_NEAR_DIMM_NG_M_F_BYTE0\" )
					)
					( Units "uMatchProp" "ns" 1.000000)
					( Status sCSetFlattened )
					( Origin gBackEnd )
				)
				( attribute "RELATIVE_PROPAGATION_DELAY_SCOPE" "G"
					( Parent
						( matchGroupRef "@baseboard_fab2_lib.baseboard_fab2(sch_1):\MG_DQ_NEAR_DIMM_NG_M_F_BYTE0\" )
					)
					( Status sCSetFlattened )
					( Origin gBackEnd )
				)
				( attribute "RELATIVE_PROPAGATION_DELAY" "-50.00 MIL,50.00 MIL"
					( Parent
						( matchGroupRef "@baseboard_fab2_lib.baseboard_fab2(sch_1):\MG_DQ_NEAR_DIMM_NG_M_F_BYTE0\" )
					)
					( Units "uMatchProp" "ns" 1.000000)
					( Status sCSetFlattened )
					( Origin gBackEnd )
				)
			)
			( pinPair "@baseboard_fab2_lib.baseboard_fab2(sch_1):\PP4254\"
				( pinRef "@baseboard_fab2_lib.baseboard_fab2(sch_1):page28_i172:DDR5_DQ(1)" )
				( pinRef "@baseboard_fab2_lib.baseboard_fab2(sch_1):page53_i111:DQ(0)" )
				( attribute "RELATIVE_PROPAGATION_DELAY_SCOPE" "G"
					( Parent
						( matchGroupRef "@baseboard_fab2_lib.baseboard_fab2(sch_1):\MG_DQ-DQS_FAR_DIMM_NG_M_F_BYTE0\" )
					)
					( Status sCSetFlattened )
					( Origin gBackEnd )
				)
				( attribute "RELATIVE_PROPAGATION_DELAY" "0.00 MIL,195.00 MIL"
					( Parent
						( matchGroupRef "@baseboard_fab2_lib.baseboard_fab2(sch_1):\MG_DQ-DQS_FAR_DIMM_NG_M_F_BYTE0\" )
					)
					( Units "uMatchProp" "ns" 1.000000)
					( Status sCSetFlattened )
					( Origin gBackEnd )
				)
				( attribute "RELATIVE_PROPAGATION_DELAY_SCOPE" "G"
					( Parent
						( matchGroupRef "@crescent_city_bb_fab1_lib.crescent_city_bb_fab1(sch_1):\MG_DQ_FAR_DIMM_NG_M_F_BYTE0\" )
					)
					( Status sCSetFlattened )
					( Origin gBackEnd )
				)
				( attribute "RELATIVE_PROPAGATION_DELAY" "-50.00 MIL,50.00 MIL"
					( Parent
						( matchGroupRef "@crescent_city_bb_fab1_lib.crescent_city_bb_fab1(sch_1):\MG_DQ_FAR_DIMM_NG_M_F_BYTE0\" )
					)
					( Units "uMatchProp" "ns" 1.000000)
					( Status sCSetFlattened )
					( Origin gBackEnd )
				)
			)
			( pinPair "@baseboard_fab2_lib.baseboard_fab2(sch_1):\PP4256\"
				( pinRef "@baseboard_fab2_lib.baseboard_fab2(sch_1):page54_i111:DQ(1)" )
				( pinRef "@baseboard_fab2_lib.baseboard_fab2(sch_1):page28_i172:DDR5_DQ(1)" )
				( attribute "RELATIVE_PROPAGATION_DELAY_SCOPE" "G"
					( Parent
						( matchGroupRef "@baseboard_fab2_lib.baseboard_fab2(sch_1):\MG_DQ-DQS_NEAR_DIMM_NG_M_F_BYTE0\" )
					)
					( Status sCSetFlattened )
					( Origin gBackEnd )
				)
				( attribute "RELATIVE_PROPAGATION_DELAY" "0.00 MIL,195.00 MIL"
					( Parent
						( matchGroupRef "@baseboard_fab2_lib.baseboard_fab2(sch_1):\MG_DQ-DQS_NEAR_DIMM_NG_M_F_BYTE0\" )
					)
					( Units "uMatchProp" "ns" 1.000000)
					( Status sCSetFlattened )
					( Origin gBackEnd )
				)
				( attribute "RELATIVE_PROPAGATION_DELAY_SCOPE" "G"
					( Parent
						( matchGroupRef "@baseboard_fab2_lib.baseboard_fab2(sch_1):\MG_DQ_NEAR_DIMM_NG_M_F_BYTE0\" )
					)
					( Status sCSetFlattened )
					( Origin gBackEnd )
				)
				( attribute "RELATIVE_PROPAGATION_DELAY" "-50.00 MIL,50.00 MIL"
					( Parent
						( matchGroupRef "@baseboard_fab2_lib.baseboard_fab2(sch_1):\MG_DQ_NEAR_DIMM_NG_M_F_BYTE0\" )
					)
					( Units "uMatchProp" "ns" 1.000000)
					( Status sCSetFlattened )
					( Origin gBackEnd )
				)
			)
			( pinPair "@baseboard_fab2_lib.baseboard_fab2(sch_1):\PP4257\"
				( pinRef "@baseboard_fab2_lib.baseboard_fab2(sch_1):page28_i172:DDR5_DQ(2)" )
				( pinRef "@baseboard_fab2_lib.baseboard_fab2(sch_1):page53_i111:DQ(3)" )
				( attribute "RELATIVE_PROPAGATION_DELAY_SCOPE" "G"
					( Parent
						( matchGroupRef "@baseboard_fab2_lib.baseboard_fab2(sch_1):\MG_DQ-DQS_FAR_DIMM_NG_M_F_BYTE0\" )
					)
					( Status sCSetFlattened )
					( Origin gBackEnd )
				)
				( attribute "RELATIVE_PROPAGATION_DELAY" "0.00 MIL,195.00 MIL"
					( Parent
						( matchGroupRef "@baseboard_fab2_lib.baseboard_fab2(sch_1):\MG_DQ-DQS_FAR_DIMM_NG_M_F_BYTE0\" )
					)
					( Units "uMatchProp" "ns" 1.000000)
					( Status sCSetFlattened )
					( Origin gBackEnd )
				)
				( attribute "RELATIVE_PROPAGATION_DELAY_SCOPE" "G"
					( Parent
						( matchGroupRef "@crescent_city_bb_fab1_lib.crescent_city_bb_fab1(sch_1):\MG_DQ_FAR_DIMM_NG_M_F_BYTE0\" )
					)
					( Status sCSetFlattened )
					( Origin gBackEnd )
				)
				( attribute "RELATIVE_PROPAGATION_DELAY" "-50.00 MIL,50.00 MIL"
					( Parent
						( matchGroupRef "@crescent_city_bb_fab1_lib.crescent_city_bb_fab1(sch_1):\MG_DQ_FAR_DIMM_NG_M_F_BYTE0\" )
					)
					( Units "uMatchProp" "ns" 1.000000)
					( Status sCSetFlattened )
					( Origin gBackEnd )
				)
			)
			( pinPair "@baseboard_fab2_lib.baseboard_fab2(sch_1):\PP4259\"
				( pinRef "@baseboard_fab2_lib.baseboard_fab2(sch_1):page54_i111:DQ(2)" )
				( pinRef "@baseboard_fab2_lib.baseboard_fab2(sch_1):page28_i172:DDR5_DQ(2)" )
				( attribute "RELATIVE_PROPAGATION_DELAY_SCOPE" "G"
					( Parent
						( matchGroupRef "@baseboard_fab2_lib.baseboard_fab2(sch_1):\MG_DQ-DQS_NEAR_DIMM_NG_M_F_BYTE0\" )
					)
					( Status sCSetFlattened )
					( Origin gBackEnd )
				)
				( attribute "RELATIVE_PROPAGATION_DELAY" "0.00 MIL,195.00 MIL"
					( Parent
						( matchGroupRef "@baseboard_fab2_lib.baseboard_fab2(sch_1):\MG_DQ-DQS_NEAR_DIMM_NG_M_F_BYTE0\" )
					)
					( Units "uMatchProp" "ns" 1.000000)
					( Status sCSetFlattened )
					( Origin gBackEnd )
				)
				( attribute "RELATIVE_PROPAGATION_DELAY_SCOPE" "G"
					( Parent
						( matchGroupRef "@baseboard_fab2_lib.baseboard_fab2(sch_1):\MG_DQ_NEAR_DIMM_NG_M_F_BYTE0\" )
					)
					( Status sCSetFlattened )
					( Origin gBackEnd )
				)
				( attribute "RELATIVE_PROPAGATION_DELAY" "-50.00 MIL,50.00 MIL"
					( Parent
						( matchGroupRef "@baseboard_fab2_lib.baseboard_fab2(sch_1):\MG_DQ_NEAR_DIMM_NG_M_F_BYTE0\" )
					)
					( Units "uMatchProp" "ns" 1.000000)
					( Status sCSetFlattened )
					( Origin gBackEnd )
				)
			)
			( pinPair "@baseboard_fab2_lib.baseboard_fab2(sch_1):\PP4260\"
				( pinRef "@baseboard_fab2_lib.baseboard_fab2(sch_1):page28_i172:DDR5_DQ(3)" )
				( pinRef "@baseboard_fab2_lib.baseboard_fab2(sch_1):page53_i111:DQ(2)" )
				( attribute "RELATIVE_PROPAGATION_DELAY_SCOPE" "G"
					( Parent
						( matchGroupRef "@baseboard_fab2_lib.baseboard_fab2(sch_1):\MG_DQ-DQS_FAR_DIMM_NG_M_F_BYTE0\" )
					)
					( Status sCSetFlattened )
					( Origin gBackEnd )
				)
				( attribute "RELATIVE_PROPAGATION_DELAY" "0.00 MIL,195.00 MIL"
					( Parent
						( matchGroupRef "@baseboard_fab2_lib.baseboard_fab2(sch_1):\MG_DQ-DQS_FAR_DIMM_NG_M_F_BYTE0\" )
					)
					( Units "uMatchProp" "ns" 1.000000)
					( Status sCSetFlattened )
					( Origin gBackEnd )
				)
				( attribute "RELATIVE_PROPAGATION_DELAY_SCOPE" "G"
					( Parent
						( matchGroupRef "@crescent_city_bb_fab1_lib.crescent_city_bb_fab1(sch_1):\MG_DQ_FAR_DIMM_NG_M_F_BYTE0\" )
					)
					( Status sCSetFlattened )
					( Origin gBackEnd )
				)
				( attribute "RELATIVE_PROPAGATION_DELAY" "-50.00 MIL,50.00 MIL"
					( Parent
						( matchGroupRef "@crescent_city_bb_fab1_lib.crescent_city_bb_fab1(sch_1):\MG_DQ_FAR_DIMM_NG_M_F_BYTE0\" )
					)
					( Units "uMatchProp" "ns" 1.000000)
					( Status sCSetFlattened )
					( Origin gBackEnd )
				)
			)
			( pinPair "@baseboard_fab2_lib.baseboard_fab2(sch_1):\PP4262\"
				( pinRef "@baseboard_fab2_lib.baseboard_fab2(sch_1):page54_i111:DQ(3)" )
				( pinRef "@baseboard_fab2_lib.baseboard_fab2(sch_1):page28_i172:DDR5_DQ(3)" )
				( attribute "RELATIVE_PROPAGATION_DELAY_SCOPE" "G"
					( Parent
						( matchGroupRef "@baseboard_fab2_lib.baseboard_fab2(sch_1):\MG_DQ-DQS_NEAR_DIMM_NG_M_F_BYTE0\" )
					)
					( Status sCSetFlattened )
					( Origin gBackEnd )
				)
				( attribute "RELATIVE_PROPAGATION_DELAY" "0.00 MIL,195.00 MIL"
					( Parent
						( matchGroupRef "@baseboard_fab2_lib.baseboard_fab2(sch_1):\MG_DQ-DQS_NEAR_DIMM_NG_M_F_BYTE0\" )
					)
					( Units "uMatchProp" "ns" 1.000000)
					( Status sCSetFlattened )
					( Origin gBackEnd )
				)
				( attribute "RELATIVE_PROPAGATION_DELAY_SCOPE" "G"
					( Parent
						( matchGroupRef "@baseboard_fab2_lib.baseboard_fab2(sch_1):\MG_DQ_NEAR_DIMM_NG_M_F_BYTE0\" )
					)
					( Status sCSetFlattened )
					( Origin gBackEnd )
				)
				( attribute "RELATIVE_PROPAGATION_DELAY" "-50.00 MIL,50.00 MIL"
					( Parent
						( matchGroupRef "@baseboard_fab2_lib.baseboard_fab2(sch_1):\MG_DQ_NEAR_DIMM_NG_M_F_BYTE0\" )
					)
					( Units "uMatchProp" "ns" 1.000000)
					( Status sCSetFlattened )
					( Origin gBackEnd )
				)
			)
			( pinPair "@baseboard_fab2_lib.baseboard_fab2(sch_1):\PP4263\"
				( pinRef "@baseboard_fab2_lib.baseboard_fab2(sch_1):page28_i172:DDR5_DQ(4)" )
				( pinRef "@baseboard_fab2_lib.baseboard_fab2(sch_1):page53_i111:DQ(5)" )
				( attribute "RELATIVE_PROPAGATION_DELAY_SCOPE" "G"
					( Parent
						( matchGroupRef "@baseboard_fab2_lib.baseboard_fab2(sch_1):\MG_DQ-DQS_FAR_DIMM_NG_M_F_BYTE0\" )
					)
					( Status sCSetFlattened )
					( Origin gBackEnd )
				)
				( attribute "RELATIVE_PROPAGATION_DELAY" "0.00 MIL,195.00 MIL"
					( Parent
						( matchGroupRef "@baseboard_fab2_lib.baseboard_fab2(sch_1):\MG_DQ-DQS_FAR_DIMM_NG_M_F_BYTE0\" )
					)
					( Units "uMatchProp" "ns" 1.000000)
					( Status sCSetFlattened )
					( Origin gBackEnd )
				)
				( attribute "RELATIVE_PROPAGATION_DELAY_SCOPE" "G"
					( Parent
						( matchGroupRef "@crescent_city_bb_fab1_lib.crescent_city_bb_fab1(sch_1):\MG_DQ_FAR_DIMM_NG_M_F_BYTE0\" )
					)
					( Origin gBackEnd )
				)
				( attribute "RELATIVE_PROPAGATION_DELAY" "TARGET,TARGET"
					( Parent
						( matchGroupRef "@crescent_city_bb_fab1_lib.crescent_city_bb_fab1(sch_1):\MG_DQ_FAR_DIMM_NG_M_F_BYTE0\" )
					)
					( Units "uMatchProp" "ns" 1.000000)
					( Origin gBackEnd )
				)
			)
			( pinPair "@baseboard_fab2_lib.baseboard_fab2(sch_1):\PP4265\"
				( pinRef "@baseboard_fab2_lib.baseboard_fab2(sch_1):page54_i111:DQ(4)" )
				( pinRef "@baseboard_fab2_lib.baseboard_fab2(sch_1):page28_i172:DDR5_DQ(4)" )
				( attribute "RELATIVE_PROPAGATION_DELAY_SCOPE" "G"
					( Parent
						( matchGroupRef "@baseboard_fab2_lib.baseboard_fab2(sch_1):\MG_DQ-DQS_NEAR_DIMM_NG_M_F_BYTE0\" )
					)
					( Status sCSetFlattened )
					( Origin gBackEnd )
				)
				( attribute "RELATIVE_PROPAGATION_DELAY" "0.00 MIL,195.00 MIL"
					( Parent
						( matchGroupRef "@baseboard_fab2_lib.baseboard_fab2(sch_1):\MG_DQ-DQS_NEAR_DIMM_NG_M_F_BYTE0\" )
					)
					( Units "uMatchProp" "ns" 1.000000)
					( Status sCSetFlattened )
					( Origin gBackEnd )
				)
				( attribute "RELATIVE_PROPAGATION_DELAY_SCOPE" "G"
					( Parent
						( matchGroupRef "@baseboard_fab2_lib.baseboard_fab2(sch_1):\MG_DQ_NEAR_DIMM_NG_M_F_BYTE0\" )
					)
					( Status sCSetFlattened )
					( Origin gBackEnd )
				)
				( attribute "RELATIVE_PROPAGATION_DELAY" "-50.00 MIL,50.00 MIL"
					( Parent
						( matchGroupRef "@baseboard_fab2_lib.baseboard_fab2(sch_1):\MG_DQ_NEAR_DIMM_NG_M_F_BYTE0\" )
					)
					( Units "uMatchProp" "ns" 1.000000)
					( Status sCSetFlattened )
					( Origin gBackEnd )
				)
			)
			( pinPair "@baseboard_fab2_lib.baseboard_fab2(sch_1):\PP4266\"
				( pinRef "@baseboard_fab2_lib.baseboard_fab2(sch_1):page28_i172:DDR5_DQ(5)" )
				( pinRef "@baseboard_fab2_lib.baseboard_fab2(sch_1):page53_i111:DQ(4)" )
				( attribute "RELATIVE_PROPAGATION_DELAY_SCOPE" "G"
					( Parent
						( matchGroupRef "@baseboard_fab2_lib.baseboard_fab2(sch_1):\MG_DQ-DQS_FAR_DIMM_NG_M_F_BYTE0\" )
					)
					( Status sCSetFlattened )
					( Origin gBackEnd )
				)
				( attribute "RELATIVE_PROPAGATION_DELAY" "0.00 MIL,195.00 MIL"
					( Parent
						( matchGroupRef "@baseboard_fab2_lib.baseboard_fab2(sch_1):\MG_DQ-DQS_FAR_DIMM_NG_M_F_BYTE0\" )
					)
					( Units "uMatchProp" "ns" 1.000000)
					( Status sCSetFlattened )
					( Origin gBackEnd )
				)
				( attribute "RELATIVE_PROPAGATION_DELAY_SCOPE" "G"
					( Parent
						( matchGroupRef "@crescent_city_bb_fab1_lib.crescent_city_bb_fab1(sch_1):\MG_DQ_FAR_DIMM_NG_M_F_BYTE0\" )
					)
					( Status sCSetFlattened )
					( Origin gBackEnd )
				)
				( attribute "RELATIVE_PROPAGATION_DELAY" "-50.00 MIL,50.00 MIL"
					( Parent
						( matchGroupRef "@crescent_city_bb_fab1_lib.crescent_city_bb_fab1(sch_1):\MG_DQ_FAR_DIMM_NG_M_F_BYTE0\" )
					)
					( Units "uMatchProp" "ns" 1.000000)
					( Status sCSetFlattened )
					( Origin gBackEnd )
				)
			)
			( pinPair "@baseboard_fab2_lib.baseboard_fab2(sch_1):\PP4268\"
				( pinRef "@baseboard_fab2_lib.baseboard_fab2(sch_1):page54_i111:DQ(5)" )
				( pinRef "@baseboard_fab2_lib.baseboard_fab2(sch_1):page28_i172:DDR5_DQ(5)" )
				( attribute "RELATIVE_PROPAGATION_DELAY_SCOPE" "G"
					( Parent
						( matchGroupRef "@baseboard_fab2_lib.baseboard_fab2(sch_1):\MG_DQ-DQS_NEAR_DIMM_NG_M_F_BYTE0\" )
					)
					( Status sCSetFlattened )
					( Origin gBackEnd )
				)
				( attribute "RELATIVE_PROPAGATION_DELAY" "0.00 MIL,195.00 MIL"
					( Parent
						( matchGroupRef "@baseboard_fab2_lib.baseboard_fab2(sch_1):\MG_DQ-DQS_NEAR_DIMM_NG_M_F_BYTE0\" )
					)
					( Units "uMatchProp" "ns" 1.000000)
					( Status sCSetFlattened )
					( Origin gBackEnd )
				)
				( attribute "RELATIVE_PROPAGATION_DELAY_SCOPE" "G"
					( Parent
						( matchGroupRef "@baseboard_fab2_lib.baseboard_fab2(sch_1):\MG_DQ_NEAR_DIMM_NG_M_F_BYTE0\" )
					)
					( Status sCSetFlattened )
					( Origin gBackEnd )
				)
				( attribute "RELATIVE_PROPAGATION_DELAY" "-50.00 MIL,50.00 MIL"
					( Parent
						( matchGroupRef "@baseboard_fab2_lib.baseboard_fab2(sch_1):\MG_DQ_NEAR_DIMM_NG_M_F_BYTE0\" )
					)
					( Units "uMatchProp" "ns" 1.000000)
					( Status sCSetFlattened )
					( Origin gBackEnd )
				)
			)
			( pinPair "@baseboard_fab2_lib.baseboard_fab2(sch_1):\PP4269\"
				( pinRef "@baseboard_fab2_lib.baseboard_fab2(sch_1):page28_i172:DDR5_DQ(6)" )
				( pinRef "@baseboard_fab2_lib.baseboard_fab2(sch_1):page53_i111:DQ(7)" )
				( attribute "RELATIVE_PROPAGATION_DELAY_SCOPE" "G"
					( Parent
						( matchGroupRef "@baseboard_fab2_lib.baseboard_fab2(sch_1):\MG_DQ-DQS_FAR_DIMM_NG_M_F_BYTE0\" )
					)
					( Status sCSetFlattened )
					( Origin gBackEnd )
				)
				( attribute "RELATIVE_PROPAGATION_DELAY" "0.00 MIL,195.00 MIL"
					( Parent
						( matchGroupRef "@baseboard_fab2_lib.baseboard_fab2(sch_1):\MG_DQ-DQS_FAR_DIMM_NG_M_F_BYTE0\" )
					)
					( Units "uMatchProp" "ns" 1.000000)
					( Status sCSetFlattened )
					( Origin gBackEnd )
				)
				( attribute "RELATIVE_PROPAGATION_DELAY_SCOPE" "G"
					( Parent
						( matchGroupRef "@crescent_city_bb_fab1_lib.crescent_city_bb_fab1(sch_1):\MG_DQ_FAR_DIMM_NG_M_F_BYTE0\" )
					)
					( Status sCSetFlattened )
					( Origin gBackEnd )
				)
				( attribute "RELATIVE_PROPAGATION_DELAY" "-50.00 MIL,50.00 MIL"
					( Parent
						( matchGroupRef "@crescent_city_bb_fab1_lib.crescent_city_bb_fab1(sch_1):\MG_DQ_FAR_DIMM_NG_M_F_BYTE0\" )
					)
					( Units "uMatchProp" "ns" 1.000000)
					( Status sCSetFlattened )
					( Origin gBackEnd )
				)
			)
			( pinPair "@baseboard_fab2_lib.baseboard_fab2(sch_1):\PP4271\"
				( pinRef "@baseboard_fab2_lib.baseboard_fab2(sch_1):page28_i172:DDR5_DQ(6)" )
				( pinRef "@baseboard_fab2_lib.baseboard_fab2(sch_1):page54_i111:DQ(6)" )
				( attribute "RELATIVE_PROPAGATION_DELAY_SCOPE" "G"
					( Parent
						( matchGroupRef "@baseboard_fab2_lib.baseboard_fab2(sch_1):\MG_DQ-DQS_NEAR_DIMM_NG_M_F_BYTE0\" )
					)
					( Status sCSetFlattened )
					( Origin gBackEnd )
				)
				( attribute "RELATIVE_PROPAGATION_DELAY" "0.00 MIL,195.00 MIL"
					( Parent
						( matchGroupRef "@baseboard_fab2_lib.baseboard_fab2(sch_1):\MG_DQ-DQS_NEAR_DIMM_NG_M_F_BYTE0\" )
					)
					( Units "uMatchProp" "ns" 1.000000)
					( Status sCSetFlattened )
					( Origin gBackEnd )
				)
				( attribute "RELATIVE_PROPAGATION_DELAY_SCOPE" "G"
					( Parent
						( matchGroupRef "@baseboard_fab2_lib.baseboard_fab2(sch_1):\MG_DQ_NEAR_DIMM_NG_M_F_BYTE0\" )
					)
					( Status sCSetFlattened )
					( Origin gBackEnd )
				)
				( attribute "RELATIVE_PROPAGATION_DELAY" "-50.00 MIL,50.00 MIL"
					( Parent
						( matchGroupRef "@baseboard_fab2_lib.baseboard_fab2(sch_1):\MG_DQ_NEAR_DIMM_NG_M_F_BYTE0\" )
					)
					( Units "uMatchProp" "ns" 1.000000)
					( Status sCSetFlattened )
					( Origin gBackEnd )
				)
			)
			( pinPair "@baseboard_fab2_lib.baseboard_fab2(sch_1):\PP4272\"
				( pinRef "@baseboard_fab2_lib.baseboard_fab2(sch_1):page28_i172:DDR5_DQ(7)" )
				( pinRef "@baseboard_fab2_lib.baseboard_fab2(sch_1):page53_i111:DQ(6)" )
				( attribute "RELATIVE_PROPAGATION_DELAY_SCOPE" "G"
					( Parent
						( matchGroupRef "@baseboard_fab2_lib.baseboard_fab2(sch_1):\MG_DQ-DQS_FAR_DIMM_NG_M_F_BYTE0\" )
					)
					( Status sCSetFlattened )
					( Origin gBackEnd )
				)
				( attribute "RELATIVE_PROPAGATION_DELAY" "0.00 MIL,195.00 MIL"
					( Parent
						( matchGroupRef "@baseboard_fab2_lib.baseboard_fab2(sch_1):\MG_DQ-DQS_FAR_DIMM_NG_M_F_BYTE0\" )
					)
					( Units "uMatchProp" "ns" 1.000000)
					( Status sCSetFlattened )
					( Origin gBackEnd )
				)
				( attribute "RELATIVE_PROPAGATION_DELAY_SCOPE" "G"
					( Parent
						( matchGroupRef "@crescent_city_bb_fab1_lib.crescent_city_bb_fab1(sch_1):\MG_DQ_FAR_DIMM_NG_M_F_BYTE0\" )
					)
					( Status sCSetFlattened )
					( Origin gBackEnd )
				)
				( attribute "RELATIVE_PROPAGATION_DELAY" "-50.00 MIL,50.00 MIL"
					( Parent
						( matchGroupRef "@crescent_city_bb_fab1_lib.crescent_city_bb_fab1(sch_1):\MG_DQ_FAR_DIMM_NG_M_F_BYTE0\" )
					)
					( Units "uMatchProp" "ns" 1.000000)
					( Status sCSetFlattened )
					( Origin gBackEnd )
				)
			)
			( pinPair "@baseboard_fab2_lib.baseboard_fab2(sch_1):\PP4274\"
				( pinRef "@baseboard_fab2_lib.baseboard_fab2(sch_1):page28_i172:DDR5_DQ(7)" )
				( pinRef "@baseboard_fab2_lib.baseboard_fab2(sch_1):page54_i111:DQ(7)" )
				( attribute "RELATIVE_PROPAGATION_DELAY_SCOPE" "G"
					( Parent
						( matchGroupRef "@baseboard_fab2_lib.baseboard_fab2(sch_1):\MG_DQ-DQS_NEAR_DIMM_NG_M_F_BYTE0\" )
					)
					( Status sCSetFlattened )
					( Origin gBackEnd )
				)
				( attribute "RELATIVE_PROPAGATION_DELAY" "0.00 MIL,195.00 MIL"
					( Parent
						( matchGroupRef "@baseboard_fab2_lib.baseboard_fab2(sch_1):\MG_DQ-DQS_NEAR_DIMM_NG_M_F_BYTE0\" )
					)
					( Units "uMatchProp" "ns" 1.000000)
					( Status sCSetFlattened )
					( Origin gBackEnd )
				)
				( attribute "RELATIVE_PROPAGATION_DELAY_SCOPE" "G"
					( Parent
						( matchGroupRef "@baseboard_fab2_lib.baseboard_fab2(sch_1):\MG_DQ_NEAR_DIMM_NG_M_F_BYTE0\" )
					)
					( Status sCSetFlattened )
					( Origin gBackEnd )
				)
				( attribute "RELATIVE_PROPAGATION_DELAY" "-50.00 MIL,50.00 MIL"
					( Parent
						( matchGroupRef "@baseboard_fab2_lib.baseboard_fab2(sch_1):\MG_DQ_NEAR_DIMM_NG_M_F_BYTE0\" )
					)
					( Units "uMatchProp" "ns" 1.000000)
					( Status sCSetFlattened )
					( Origin gBackEnd )
				)
			)
			( pinPair "@baseboard_fab2_lib.baseboard_fab2(sch_1):\PP4227\"
				( pinRef "@baseboard_fab2_lib.baseboard_fab2(sch_1):page28_i172:DDR5_DQ(8)" )
				( pinRef "@baseboard_fab2_lib.baseboard_fab2(sch_1):page53_i111:DQ(9)" )
				( attribute "RELATIVE_PROPAGATION_DELAY_SCOPE" "G"
					( Parent
						( matchGroupRef "@baseboard_fab2_lib.baseboard_fab2(sch_1):\MG_DQ-DQS_FAR_DIMM_NG_M_F_BYTE1\" )
					)
					( Status sCSetFlattened )
					( Origin gBackEnd )
				)
				( attribute "RELATIVE_PROPAGATION_DELAY" "0.00 MIL,195.00 MIL"
					( Parent
						( matchGroupRef "@baseboard_fab2_lib.baseboard_fab2(sch_1):\MG_DQ-DQS_FAR_DIMM_NG_M_F_BYTE1\" )
					)
					( Units "uMatchProp" "ns" 1.000000)
					( Status sCSetFlattened )
					( Origin gBackEnd )
				)
				( attribute "RELATIVE_PROPAGATION_DELAY_SCOPE" "G"
					( Parent
						( matchGroupRef "@crescent_city_bb_fab1_lib.crescent_city_bb_fab1(sch_1):\MG_DQ_FAR_DIMM_NG_M_F_BYTE1\" )
					)
					( Status sCSetFlattened )
					( Origin gBackEnd )
				)
				( attribute "RELATIVE_PROPAGATION_DELAY" "-50.00 MIL,50.00 MIL"
					( Parent
						( matchGroupRef "@crescent_city_bb_fab1_lib.crescent_city_bb_fab1(sch_1):\MG_DQ_FAR_DIMM_NG_M_F_BYTE1\" )
					)
					( Units "uMatchProp" "ns" 1.000000)
					( Status sCSetFlattened )
					( Origin gBackEnd )
				)
			)
			( pinPair "@baseboard_fab2_lib.baseboard_fab2(sch_1):\PP4229\"
				( pinRef "@baseboard_fab2_lib.baseboard_fab2(sch_1):page54_i111:DQ(8)" )
				( pinRef "@baseboard_fab2_lib.baseboard_fab2(sch_1):page28_i172:DDR5_DQ(8)" )
				( attribute "RELATIVE_PROPAGATION_DELAY_SCOPE" "G"
					( Parent
						( matchGroupRef "@baseboard_fab2_lib.baseboard_fab2(sch_1):\MG_DQ-DQS_NEAR_DIMM_NG_M_F_BYTE1\" )
					)
					( Status sCSetFlattened )
					( Origin gBackEnd )
				)
				( attribute "RELATIVE_PROPAGATION_DELAY" "0.00 MIL,195.00 MIL"
					( Parent
						( matchGroupRef "@baseboard_fab2_lib.baseboard_fab2(sch_1):\MG_DQ-DQS_NEAR_DIMM_NG_M_F_BYTE1\" )
					)
					( Units "uMatchProp" "ns" 1.000000)
					( Status sCSetFlattened )
					( Origin gBackEnd )
				)
				( attribute "RELATIVE_PROPAGATION_DELAY_SCOPE" "G"
					( Parent
						( matchGroupRef "@baseboard_fab2_lib.baseboard_fab2(sch_1):\MG_DQ_NEAR_DIMM_NG_M_F_BYTE1\" )
					)
					( Status sCSetFlattened )
					( Origin gBackEnd )
				)
				( attribute "RELATIVE_PROPAGATION_DELAY" "-50.00 MIL,50.00 MIL"
					( Parent
						( matchGroupRef "@baseboard_fab2_lib.baseboard_fab2(sch_1):\MG_DQ_NEAR_DIMM_NG_M_F_BYTE1\" )
					)
					( Units "uMatchProp" "ns" 1.000000)
					( Status sCSetFlattened )
					( Origin gBackEnd )
				)
			)
			( pinPair "@baseboard_fab2_lib.baseboard_fab2(sch_1):\PP4878\"
				( pinRef "@baseboard_fab2_lib.baseboard_fab2(sch_1):page25_i172:DDR2_DQ(1)" )
				( pinRef "@baseboard_fab2_lib.baseboard_fab2(sch_1):page47_i111:DQ(0)" )
				( attribute "RELATIVE_PROPAGATION_DELAY_SCOPE" "G"
					( Parent
						( matchGroupRef "@baseboard_fab2_lib.baseboard_fab2(sch_1):\MG_DQ-DQS_FAR_DIMM_NG_M_C_BYTE0\" )
					)
					( Status sCSetFlattened )
					( Origin gBackEnd )
				)
				( attribute "RELATIVE_PROPAGATION_DELAY" "0.00 MIL,195.00 MIL"
					( Parent
						( matchGroupRef "@baseboard_fab2_lib.baseboard_fab2(sch_1):\MG_DQ-DQS_FAR_DIMM_NG_M_C_BYTE0\" )
					)
					( Units "uMatchProp" "ns" 1.000000)
					( Status sCSetFlattened )
					( Origin gBackEnd )
				)
				( attribute "RELATIVE_PROPAGATION_DELAY_SCOPE" "G"
					( Parent
						( matchGroupRef "@baseboard_fab2_lib.baseboard_fab2(sch_1):\MG_DQ_FAR_DIMM_NG_M_C_BYTE0\" )
					)
					( Status sCSetFlattened )
					( Origin gBackEnd )
				)
				( attribute "RELATIVE_PROPAGATION_DELAY" "-50.00 MIL,50.00 MIL"
					( Parent
						( matchGroupRef "@baseboard_fab2_lib.baseboard_fab2(sch_1):\MG_DQ_FAR_DIMM_NG_M_C_BYTE0\" )
					)
					( Units "uMatchProp" "ns" 1.000000)
					( Status sCSetFlattened )
					( Origin gBackEnd )
				)
			)
			( pinPair "@baseboard_fab2_lib.baseboard_fab2(sch_1):\PP4880\"
				( pinRef "@baseboard_fab2_lib.baseboard_fab2(sch_1):page25_i172:DDR2_DQ(1)" )
				( pinRef "@baseboard_fab2_lib.baseboard_fab2(sch_1):page48_i111:DQ(1)" )
				( attribute "RELATIVE_PROPAGATION_DELAY_SCOPE" "G"
					( Parent
						( matchGroupRef "@baseboard_fab2_lib.baseboard_fab2(sch_1):\MG_DQ-DQS_NEAR_DIMM_NG_M_C_BYTE0\" )
					)
					( Status sCSetFlattened )
					( Origin gBackEnd )
				)
				( attribute "RELATIVE_PROPAGATION_DELAY" "0.00 MIL,195.00 MIL"
					( Parent
						( matchGroupRef "@baseboard_fab2_lib.baseboard_fab2(sch_1):\MG_DQ-DQS_NEAR_DIMM_NG_M_C_BYTE0\" )
					)
					( Units "uMatchProp" "ns" 1.000000)
					( Status sCSetFlattened )
					( Origin gBackEnd )
				)
				( attribute "RELATIVE_PROPAGATION_DELAY_SCOPE" "G"
					( Parent
						( matchGroupRef "@baseboard_fab2_lib.baseboard_fab2(sch_1):\MG_DQ_NEAR_DIMM_NG_M_C_BYTE0\" )
					)
					( Status sCSetFlattened )
					( Origin gBackEnd )
				)
				( attribute "RELATIVE_PROPAGATION_DELAY" "-50.00 MIL,50.00 MIL"
					( Parent
						( matchGroupRef "@baseboard_fab2_lib.baseboard_fab2(sch_1):\MG_DQ_NEAR_DIMM_NG_M_C_BYTE0\" )
					)
					( Units "uMatchProp" "ns" 1.000000)
					( Status sCSetFlattened )
					( Origin gBackEnd )
				)
			)
			( pinPair "@baseboard_fab2_lib.baseboard_fab2(sch_1):\PP4881\"
				( pinRef "@baseboard_fab2_lib.baseboard_fab2(sch_1):page25_i172:DDR2_DQ(2)" )
				( pinRef "@baseboard_fab2_lib.baseboard_fab2(sch_1):page47_i111:DQ(3)" )
				( attribute "RELATIVE_PROPAGATION_DELAY_SCOPE" "G"
					( Parent
						( matchGroupRef "@baseboard_fab2_lib.baseboard_fab2(sch_1):\MG_DQ-DQS_FAR_DIMM_NG_M_C_BYTE0\" )
					)
					( Status sCSetFlattened )
					( Origin gBackEnd )
				)
				( attribute "RELATIVE_PROPAGATION_DELAY" "0.00 MIL,195.00 MIL"
					( Parent
						( matchGroupRef "@baseboard_fab2_lib.baseboard_fab2(sch_1):\MG_DQ-DQS_FAR_DIMM_NG_M_C_BYTE0\" )
					)
					( Units "uMatchProp" "ns" 1.000000)
					( Status sCSetFlattened )
					( Origin gBackEnd )
				)
				( attribute "RELATIVE_PROPAGATION_DELAY_SCOPE" "G"
					( Parent
						( matchGroupRef "@baseboard_fab2_lib.baseboard_fab2(sch_1):\MG_DQ_FAR_DIMM_NG_M_C_BYTE0\" )
					)
					( Status sCSetFlattened )
					( Origin gBackEnd )
				)
				( attribute "RELATIVE_PROPAGATION_DELAY" "-50.00 MIL,50.00 MIL"
					( Parent
						( matchGroupRef "@baseboard_fab2_lib.baseboard_fab2(sch_1):\MG_DQ_FAR_DIMM_NG_M_C_BYTE0\" )
					)
					( Units "uMatchProp" "ns" 1.000000)
					( Status sCSetFlattened )
					( Origin gBackEnd )
				)
			)
			( pinPair "@baseboard_fab2_lib.baseboard_fab2(sch_1):\PP4883\"
				( pinRef "@baseboard_fab2_lib.baseboard_fab2(sch_1):page25_i172:DDR2_DQ(2)" )
				( pinRef "@baseboard_fab2_lib.baseboard_fab2(sch_1):page48_i111:DQ(2)" )
				( attribute "RELATIVE_PROPAGATION_DELAY_SCOPE" "G"
					( Parent
						( matchGroupRef "@baseboard_fab2_lib.baseboard_fab2(sch_1):\MG_DQ-DQS_NEAR_DIMM_NG_M_C_BYTE0\" )
					)
					( Status sCSetFlattened )
					( Origin gBackEnd )
				)
				( attribute "RELATIVE_PROPAGATION_DELAY" "0.00 MIL,195.00 MIL"
					( Parent
						( matchGroupRef "@baseboard_fab2_lib.baseboard_fab2(sch_1):\MG_DQ-DQS_NEAR_DIMM_NG_M_C_BYTE0\" )
					)
					( Units "uMatchProp" "ns" 1.000000)
					( Status sCSetFlattened )
					( Origin gBackEnd )
				)
				( attribute "RELATIVE_PROPAGATION_DELAY_SCOPE" "G"
					( Parent
						( matchGroupRef "@baseboard_fab2_lib.baseboard_fab2(sch_1):\MG_DQ_NEAR_DIMM_NG_M_C_BYTE0\" )
					)
					( Status sCSetFlattened )
					( Origin gBackEnd )
				)
				( attribute "RELATIVE_PROPAGATION_DELAY" "-50.00 MIL,50.00 MIL"
					( Parent
						( matchGroupRef "@baseboard_fab2_lib.baseboard_fab2(sch_1):\MG_DQ_NEAR_DIMM_NG_M_C_BYTE0\" )
					)
					( Units "uMatchProp" "ns" 1.000000)
					( Status sCSetFlattened )
					( Origin gBackEnd )
				)
			)
			( pinPair "@baseboard_fab2_lib.baseboard_fab2(sch_1):\PP4884\"
				( pinRef "@baseboard_fab2_lib.baseboard_fab2(sch_1):page25_i172:DDR2_DQ(3)" )
				( pinRef "@baseboard_fab2_lib.baseboard_fab2(sch_1):page47_i111:DQ(2)" )
				( attribute "RELATIVE_PROPAGATION_DELAY_SCOPE" "G"
					( Parent
						( matchGroupRef "@baseboard_fab2_lib.baseboard_fab2(sch_1):\MG_DQ-DQS_FAR_DIMM_NG_M_C_BYTE0\" )
					)
					( Status sCSetFlattened )
					( Origin gBackEnd )
				)
				( attribute "RELATIVE_PROPAGATION_DELAY" "0.00 MIL,195.00 MIL"
					( Parent
						( matchGroupRef "@baseboard_fab2_lib.baseboard_fab2(sch_1):\MG_DQ-DQS_FAR_DIMM_NG_M_C_BYTE0\" )
					)
					( Units "uMatchProp" "ns" 1.000000)
					( Status sCSetFlattened )
					( Origin gBackEnd )
				)
				( attribute "RELATIVE_PROPAGATION_DELAY_SCOPE" "G"
					( Parent
						( matchGroupRef "@baseboard_fab2_lib.baseboard_fab2(sch_1):\MG_DQ_FAR_DIMM_NG_M_C_BYTE0\" )
					)
					( Status sCSetFlattened )
					( Origin gBackEnd )
				)
				( attribute "RELATIVE_PROPAGATION_DELAY" "-50.00 MIL,50.00 MIL"
					( Parent
						( matchGroupRef "@baseboard_fab2_lib.baseboard_fab2(sch_1):\MG_DQ_FAR_DIMM_NG_M_C_BYTE0\" )
					)
					( Units "uMatchProp" "ns" 1.000000)
					( Status sCSetFlattened )
					( Origin gBackEnd )
				)
			)
			( pinPair "@baseboard_fab2_lib.baseboard_fab2(sch_1):\PP4886\"
				( pinRef "@baseboard_fab2_lib.baseboard_fab2(sch_1):page25_i172:DDR2_DQ(3)" )
				( pinRef "@baseboard_fab2_lib.baseboard_fab2(sch_1):page48_i111:DQ(3)" )
				( attribute "RELATIVE_PROPAGATION_DELAY_SCOPE" "G"
					( Parent
						( matchGroupRef "@baseboard_fab2_lib.baseboard_fab2(sch_1):\MG_DQ-DQS_NEAR_DIMM_NG_M_C_BYTE0\" )
					)
					( Status sCSetFlattened )
					( Origin gBackEnd )
				)
				( attribute "RELATIVE_PROPAGATION_DELAY" "0.00 MIL,195.00 MIL"
					( Parent
						( matchGroupRef "@baseboard_fab2_lib.baseboard_fab2(sch_1):\MG_DQ-DQS_NEAR_DIMM_NG_M_C_BYTE0\" )
					)
					( Units "uMatchProp" "ns" 1.000000)
					( Status sCSetFlattened )
					( Origin gBackEnd )
				)
				( attribute "RELATIVE_PROPAGATION_DELAY_SCOPE" "G"
					( Parent
						( matchGroupRef "@baseboard_fab2_lib.baseboard_fab2(sch_1):\MG_DQ_NEAR_DIMM_NG_M_C_BYTE0\" )
					)
					( Status sCSetFlattened )
					( Origin gBackEnd )
				)
				( attribute "RELATIVE_PROPAGATION_DELAY" "-50.00 MIL,50.00 MIL"
					( Parent
						( matchGroupRef "@baseboard_fab2_lib.baseboard_fab2(sch_1):\MG_DQ_NEAR_DIMM_NG_M_C_BYTE0\" )
					)
					( Units "uMatchProp" "ns" 1.000000)
					( Status sCSetFlattened )
					( Origin gBackEnd )
				)
			)
			( pinPair "@baseboard_fab2_lib.baseboard_fab2(sch_1):\PP4887\"
				( pinRef "@baseboard_fab2_lib.baseboard_fab2(sch_1):page25_i172:DDR2_DQ(4)" )
				( pinRef "@baseboard_fab2_lib.baseboard_fab2(sch_1):page47_i111:DQ(5)" )
				( attribute "RELATIVE_PROPAGATION_DELAY_SCOPE" "G"
					( Parent
						( matchGroupRef "@baseboard_fab2_lib.baseboard_fab2(sch_1):\MG_DQ-DQS_FAR_DIMM_NG_M_C_BYTE0\" )
					)
					( Status sCSetFlattened )
					( Origin gBackEnd )
				)
				( attribute "RELATIVE_PROPAGATION_DELAY" "0.00 MIL,195.00 MIL"
					( Parent
						( matchGroupRef "@baseboard_fab2_lib.baseboard_fab2(sch_1):\MG_DQ-DQS_FAR_DIMM_NG_M_C_BYTE0\" )
					)
					( Units "uMatchProp" "ns" 1.000000)
					( Status sCSetFlattened )
					( Origin gBackEnd )
				)
				( attribute "RELATIVE_PROPAGATION_DELAY_SCOPE" "G"
					( Parent
						( matchGroupRef "@baseboard_fab2_lib.baseboard_fab2(sch_1):\MG_DQ_FAR_DIMM_NG_M_C_BYTE0\" )
					)
					( Status sCSetFlattened )
					( Origin gBackEnd )
				)
				( attribute "RELATIVE_PROPAGATION_DELAY" "-50.00 MIL,50.00 MIL"
					( Parent
						( matchGroupRef "@baseboard_fab2_lib.baseboard_fab2(sch_1):\MG_DQ_FAR_DIMM_NG_M_C_BYTE0\" )
					)
					( Units "uMatchProp" "ns" 1.000000)
					( Status sCSetFlattened )
					( Origin gBackEnd )
				)
			)
			( pinPair "@baseboard_fab2_lib.baseboard_fab2(sch_1):\PP4889\"
				( pinRef "@baseboard_fab2_lib.baseboard_fab2(sch_1):page25_i172:DDR2_DQ(4)" )
				( pinRef "@baseboard_fab2_lib.baseboard_fab2(sch_1):page48_i111:DQ(4)" )
				( attribute "RELATIVE_PROPAGATION_DELAY_SCOPE" "G"
					( Parent
						( matchGroupRef "@baseboard_fab2_lib.baseboard_fab2(sch_1):\MG_DQ-DQS_NEAR_DIMM_NG_M_C_BYTE0\" )
					)
					( Status sCSetFlattened )
					( Origin gBackEnd )
				)
				( attribute "RELATIVE_PROPAGATION_DELAY" "0.00 MIL,195.00 MIL"
					( Parent
						( matchGroupRef "@baseboard_fab2_lib.baseboard_fab2(sch_1):\MG_DQ-DQS_NEAR_DIMM_NG_M_C_BYTE0\" )
					)
					( Units "uMatchProp" "ns" 1.000000)
					( Status sCSetFlattened )
					( Origin gBackEnd )
				)
				( attribute "RELATIVE_PROPAGATION_DELAY_SCOPE" "G"
					( Parent
						( matchGroupRef "@baseboard_fab2_lib.baseboard_fab2(sch_1):\MG_DQ_NEAR_DIMM_NG_M_C_BYTE0\" )
					)
					( Status sCSetFlattened )
					( Origin gBackEnd )
				)
				( attribute "RELATIVE_PROPAGATION_DELAY" "-50.00 MIL,50.00 MIL"
					( Parent
						( matchGroupRef "@baseboard_fab2_lib.baseboard_fab2(sch_1):\MG_DQ_NEAR_DIMM_NG_M_C_BYTE0\" )
					)
					( Units "uMatchProp" "ns" 1.000000)
					( Status sCSetFlattened )
					( Origin gBackEnd )
				)
			)
			( pinPair "@baseboard_fab2_lib.baseboard_fab2(sch_1):\PP4890\"
				( pinRef "@baseboard_fab2_lib.baseboard_fab2(sch_1):page25_i172:DDR2_DQ(5)" )
				( pinRef "@baseboard_fab2_lib.baseboard_fab2(sch_1):page47_i111:DQ(4)" )
				( attribute "RELATIVE_PROPAGATION_DELAY_SCOPE" "G"
					( Parent
						( matchGroupRef "@baseboard_fab2_lib.baseboard_fab2(sch_1):\MG_DQ-DQS_FAR_DIMM_NG_M_C_BYTE0\" )
					)
					( Status sCSetFlattened )
					( Origin gBackEnd )
				)
				( attribute "RELATIVE_PROPAGATION_DELAY" "0.00 MIL,195.00 MIL"
					( Parent
						( matchGroupRef "@baseboard_fab2_lib.baseboard_fab2(sch_1):\MG_DQ-DQS_FAR_DIMM_NG_M_C_BYTE0\" )
					)
					( Units "uMatchProp" "ns" 1.000000)
					( Status sCSetFlattened )
					( Origin gBackEnd )
				)
				( attribute "RELATIVE_PROPAGATION_DELAY_SCOPE" "G"
					( Parent
						( matchGroupRef "@baseboard_fab2_lib.baseboard_fab2(sch_1):\MG_DQ_FAR_DIMM_NG_M_C_BYTE0\" )
					)
					( Status sCSetFlattened )
					( Origin gBackEnd )
				)
				( attribute "RELATIVE_PROPAGATION_DELAY" "-50.00 MIL,50.00 MIL"
					( Parent
						( matchGroupRef "@baseboard_fab2_lib.baseboard_fab2(sch_1):\MG_DQ_FAR_DIMM_NG_M_C_BYTE0\" )
					)
					( Units "uMatchProp" "ns" 1.000000)
					( Status sCSetFlattened )
					( Origin gBackEnd )
				)
			)
			( pinPair "@baseboard_fab2_lib.baseboard_fab2(sch_1):\PP4892\"
				( pinRef "@baseboard_fab2_lib.baseboard_fab2(sch_1):page25_i172:DDR2_DQ(5)" )
				( pinRef "@baseboard_fab2_lib.baseboard_fab2(sch_1):page48_i111:DQ(5)" )
				( attribute "RELATIVE_PROPAGATION_DELAY_SCOPE" "G"
					( Parent
						( matchGroupRef "@baseboard_fab2_lib.baseboard_fab2(sch_1):\MG_DQ-DQS_NEAR_DIMM_NG_M_C_BYTE0\" )
					)
					( Status sCSetFlattened )
					( Origin gBackEnd )
				)
				( attribute "RELATIVE_PROPAGATION_DELAY" "0.00 MIL,195.00 MIL"
					( Parent
						( matchGroupRef "@baseboard_fab2_lib.baseboard_fab2(sch_1):\MG_DQ-DQS_NEAR_DIMM_NG_M_C_BYTE0\" )
					)
					( Units "uMatchProp" "ns" 1.000000)
					( Status sCSetFlattened )
					( Origin gBackEnd )
				)
				( attribute "RELATIVE_PROPAGATION_DELAY_SCOPE" "G"
					( Parent
						( matchGroupRef "@baseboard_fab2_lib.baseboard_fab2(sch_1):\MG_DQ_NEAR_DIMM_NG_M_C_BYTE0\" )
					)
					( Status sCSetFlattened )
					( Origin gBackEnd )
				)
				( attribute "RELATIVE_PROPAGATION_DELAY" "-50.00 MIL,50.00 MIL"
					( Parent
						( matchGroupRef "@baseboard_fab2_lib.baseboard_fab2(sch_1):\MG_DQ_NEAR_DIMM_NG_M_C_BYTE0\" )
					)
					( Units "uMatchProp" "ns" 1.000000)
					( Status sCSetFlattened )
					( Origin gBackEnd )
				)
			)
			( pinPair "@baseboard_fab2_lib.baseboard_fab2(sch_1):\PP4893\"
				( pinRef "@baseboard_fab2_lib.baseboard_fab2(sch_1):page25_i172:DDR2_DQ(6)" )
				( pinRef "@baseboard_fab2_lib.baseboard_fab2(sch_1):page47_i111:DQ(7)" )
				( attribute "RELATIVE_PROPAGATION_DELAY_SCOPE" "G"
					( Parent
						( matchGroupRef "@baseboard_fab2_lib.baseboard_fab2(sch_1):\MG_DQ-DQS_FAR_DIMM_NG_M_C_BYTE0\" )
					)
					( Status sCSetFlattened )
					( Origin gBackEnd )
				)
				( attribute "RELATIVE_PROPAGATION_DELAY" "0.00 MIL,195.00 MIL"
					( Parent
						( matchGroupRef "@baseboard_fab2_lib.baseboard_fab2(sch_1):\MG_DQ-DQS_FAR_DIMM_NG_M_C_BYTE0\" )
					)
					( Units "uMatchProp" "ns" 1.000000)
					( Status sCSetFlattened )
					( Origin gBackEnd )
				)
				( attribute "RELATIVE_PROPAGATION_DELAY_SCOPE" "G"
					( Parent
						( matchGroupRef "@baseboard_fab2_lib.baseboard_fab2(sch_1):\MG_DQ_FAR_DIMM_NG_M_C_BYTE0\" )
					)
					( Status sCSetFlattened )
					( Origin gBackEnd )
				)
				( attribute "RELATIVE_PROPAGATION_DELAY" "-50.00 MIL,50.00 MIL"
					( Parent
						( matchGroupRef "@baseboard_fab2_lib.baseboard_fab2(sch_1):\MG_DQ_FAR_DIMM_NG_M_C_BYTE0\" )
					)
					( Units "uMatchProp" "ns" 1.000000)
					( Status sCSetFlattened )
					( Origin gBackEnd )
				)
			)
			( pinPair "@baseboard_fab2_lib.baseboard_fab2(sch_1):\PP4895\"
				( pinRef "@baseboard_fab2_lib.baseboard_fab2(sch_1):page25_i172:DDR2_DQ(6)" )
				( pinRef "@baseboard_fab2_lib.baseboard_fab2(sch_1):page48_i111:DQ(6)" )
				( attribute "RELATIVE_PROPAGATION_DELAY_SCOPE" "G"
					( Parent
						( matchGroupRef "@baseboard_fab2_lib.baseboard_fab2(sch_1):\MG_DQ-DQS_NEAR_DIMM_NG_M_C_BYTE0\" )
					)
					( Status sCSetFlattened )
					( Origin gBackEnd )
				)
				( attribute "RELATIVE_PROPAGATION_DELAY" "0.00 MIL,195.00 MIL"
					( Parent
						( matchGroupRef "@baseboard_fab2_lib.baseboard_fab2(sch_1):\MG_DQ-DQS_NEAR_DIMM_NG_M_C_BYTE0\" )
					)
					( Units "uMatchProp" "ns" 1.000000)
					( Status sCSetFlattened )
					( Origin gBackEnd )
				)
				( attribute "RELATIVE_PROPAGATION_DELAY_SCOPE" "G"
					( Parent
						( matchGroupRef "@baseboard_fab2_lib.baseboard_fab2(sch_1):\MG_DQ_NEAR_DIMM_NG_M_C_BYTE0\" )
					)
					( Status sCSetFlattened )
					( Origin gBackEnd )
				)
				( attribute "RELATIVE_PROPAGATION_DELAY" "-50.00 MIL,50.00 MIL"
					( Parent
						( matchGroupRef "@baseboard_fab2_lib.baseboard_fab2(sch_1):\MG_DQ_NEAR_DIMM_NG_M_C_BYTE0\" )
					)
					( Units "uMatchProp" "ns" 1.000000)
					( Status sCSetFlattened )
					( Origin gBackEnd )
				)
			)
			( pinPair "@baseboard_fab2_lib.baseboard_fab2(sch_1):\PP4896\"
				( pinRef "@baseboard_fab2_lib.baseboard_fab2(sch_1):page25_i172:DDR2_DQ(7)" )
				( pinRef "@baseboard_fab2_lib.baseboard_fab2(sch_1):page47_i111:DQ(6)" )
				( attribute "RELATIVE_PROPAGATION_DELAY_SCOPE" "G"
					( Parent
						( matchGroupRef "@baseboard_fab2_lib.baseboard_fab2(sch_1):\MG_DQ-DQS_FAR_DIMM_NG_M_C_BYTE0\" )
					)
					( Status sCSetFlattened )
					( Origin gBackEnd )
				)
				( attribute "RELATIVE_PROPAGATION_DELAY" "0.00 MIL,195.00 MIL"
					( Parent
						( matchGroupRef "@baseboard_fab2_lib.baseboard_fab2(sch_1):\MG_DQ-DQS_FAR_DIMM_NG_M_C_BYTE0\" )
					)
					( Units "uMatchProp" "ns" 1.000000)
					( Status sCSetFlattened )
					( Origin gBackEnd )
				)
				( attribute "RELATIVE_PROPAGATION_DELAY_SCOPE" "G"
					( Parent
						( matchGroupRef "@baseboard_fab2_lib.baseboard_fab2(sch_1):\MG_DQ_FAR_DIMM_NG_M_C_BYTE0\" )
					)
					( Status sCSetFlattened )
					( Origin gBackEnd )
				)
				( attribute "RELATIVE_PROPAGATION_DELAY" "-50.00 MIL,50.00 MIL"
					( Parent
						( matchGroupRef "@baseboard_fab2_lib.baseboard_fab2(sch_1):\MG_DQ_FAR_DIMM_NG_M_C_BYTE0\" )
					)
					( Units "uMatchProp" "ns" 1.000000)
					( Status sCSetFlattened )
					( Origin gBackEnd )
				)
			)
			( pinPair "@baseboard_fab2_lib.baseboard_fab2(sch_1):\PP4898\"
				( pinRef "@baseboard_fab2_lib.baseboard_fab2(sch_1):page25_i172:DDR2_DQ(7)" )
				( pinRef "@baseboard_fab2_lib.baseboard_fab2(sch_1):page48_i111:DQ(7)" )
				( attribute "RELATIVE_PROPAGATION_DELAY_SCOPE" "G"
					( Parent
						( matchGroupRef "@baseboard_fab2_lib.baseboard_fab2(sch_1):\MG_DQ-DQS_NEAR_DIMM_NG_M_C_BYTE0\" )
					)
					( Status sCSetFlattened )
					( Origin gBackEnd )
				)
				( attribute "RELATIVE_PROPAGATION_DELAY" "0.00 MIL,195.00 MIL"
					( Parent
						( matchGroupRef "@baseboard_fab2_lib.baseboard_fab2(sch_1):\MG_DQ-DQS_NEAR_DIMM_NG_M_C_BYTE0\" )
					)
					( Units "uMatchProp" "ns" 1.000000)
					( Status sCSetFlattened )
					( Origin gBackEnd )
				)
				( attribute "RELATIVE_PROPAGATION_DELAY_SCOPE" "G"
					( Parent
						( matchGroupRef "@baseboard_fab2_lib.baseboard_fab2(sch_1):\MG_DQ_NEAR_DIMM_NG_M_C_BYTE0\" )
					)
					( Status sCSetFlattened )
					( Origin gBackEnd )
				)
				( attribute "RELATIVE_PROPAGATION_DELAY" "-50.00 MIL,50.00 MIL"
					( Parent
						( matchGroupRef "@baseboard_fab2_lib.baseboard_fab2(sch_1):\MG_DQ_NEAR_DIMM_NG_M_C_BYTE0\" )
					)
					( Units "uMatchProp" "ns" 1.000000)
					( Status sCSetFlattened )
					( Origin gBackEnd )
				)
			)
			( pinPair "@baseboard_fab2_lib.baseboard_fab2(sch_1):\PP4851\"
				( pinRef "@baseboard_fab2_lib.baseboard_fab2(sch_1):page25_i172:DDR2_DQ(8)" )
				( pinRef "@baseboard_fab2_lib.baseboard_fab2(sch_1):page47_i111:DQ(9)" )
				( attribute "RELATIVE_PROPAGATION_DELAY_SCOPE" "G"
					( Parent
						( matchGroupRef "@baseboard_fab2_lib.baseboard_fab2(sch_1):\MG_DQ-DQS_FAR_DIMM_NG_M_C_BYTE1\" )
					)
					( Status sCSetFlattened )
					( Origin gBackEnd )
				)
				( attribute "RELATIVE_PROPAGATION_DELAY" "0.00 MIL,195.00 MIL"
					( Parent
						( matchGroupRef "@baseboard_fab2_lib.baseboard_fab2(sch_1):\MG_DQ-DQS_FAR_DIMM_NG_M_C_BYTE1\" )
					)
					( Units "uMatchProp" "ns" 1.000000)
					( Status sCSetFlattened )
					( Origin gBackEnd )
				)
				( attribute "RELATIVE_PROPAGATION_DELAY_SCOPE" "G"
					( Parent
						( matchGroupRef "@baseboard_fab2_lib.baseboard_fab2(sch_1):\MG_DQ_FAR_DIMM_NG_M_C_BYTE1\" )
					)
					( Status sCSetFlattened )
					( Origin gBackEnd )
				)
				( attribute "RELATIVE_PROPAGATION_DELAY" "-50.00 MIL,50.00 MIL"
					( Parent
						( matchGroupRef "@baseboard_fab2_lib.baseboard_fab2(sch_1):\MG_DQ_FAR_DIMM_NG_M_C_BYTE1\" )
					)
					( Units "uMatchProp" "ns" 1.000000)
					( Status sCSetFlattened )
					( Origin gBackEnd )
				)
			)
			( pinPair "@baseboard_fab2_lib.baseboard_fab2(sch_1):\PP4853\"
				( pinRef "@baseboard_fab2_lib.baseboard_fab2(sch_1):page25_i172:DDR2_DQ(8)" )
				( pinRef "@baseboard_fab2_lib.baseboard_fab2(sch_1):page48_i111:DQ(8)" )
				( attribute "RELATIVE_PROPAGATION_DELAY_SCOPE" "G"
					( Parent
						( matchGroupRef "@baseboard_fab2_lib.baseboard_fab2(sch_1):\MG_DQ-DQS_NEAR_DIMM_NG_M_C_BYTE1\" )
					)
					( Status sCSetFlattened )
					( Origin gBackEnd )
				)
				( attribute "RELATIVE_PROPAGATION_DELAY" "0.00 MIL,195.00 MIL"
					( Parent
						( matchGroupRef "@baseboard_fab2_lib.baseboard_fab2(sch_1):\MG_DQ-DQS_NEAR_DIMM_NG_M_C_BYTE1\" )
					)
					( Units "uMatchProp" "ns" 1.000000)
					( Status sCSetFlattened )
					( Origin gBackEnd )
				)
				( attribute "RELATIVE_PROPAGATION_DELAY_SCOPE" "G"
					( Parent
						( matchGroupRef "@baseboard_fab2_lib.baseboard_fab2(sch_1):\MG_DQ_NEAR_DIMM_NG_M_C_BYTE1\" )
					)
					( Status sCSetFlattened )
					( Origin gBackEnd )
				)
				( attribute "RELATIVE_PROPAGATION_DELAY" "-50.00 MIL,50.00 MIL"
					( Parent
						( matchGroupRef "@baseboard_fab2_lib.baseboard_fab2(sch_1):\MG_DQ_NEAR_DIMM_NG_M_C_BYTE1\" )
					)
					( Units "uMatchProp" "ns" 1.000000)
					( Status sCSetFlattened )
					( Origin gBackEnd )
				)
			)
			( pinPair "@baseboard_fab2_lib.baseboard_fab2(sch_1):\PP4854\"
				( pinRef "@baseboard_fab2_lib.baseboard_fab2(sch_1):page25_i172:DDR2_DQ(9)" )
				( pinRef "@baseboard_fab2_lib.baseboard_fab2(sch_1):page47_i111:DQ(8)" )
				( attribute "RELATIVE_PROPAGATION_DELAY_SCOPE" "G"
					( Parent
						( matchGroupRef "@baseboard_fab2_lib.baseboard_fab2(sch_1):\MG_DQ-DQS_FAR_DIMM_NG_M_C_BYTE1\" )
					)
					( Status sCSetFlattened )
					( Origin gBackEnd )
				)
				( attribute "RELATIVE_PROPAGATION_DELAY" "0.00 MIL,195.00 MIL"
					( Parent
						( matchGroupRef "@baseboard_fab2_lib.baseboard_fab2(sch_1):\MG_DQ-DQS_FAR_DIMM_NG_M_C_BYTE1\" )
					)
					( Units "uMatchProp" "ns" 1.000000)
					( Status sCSetFlattened )
					( Origin gBackEnd )
				)
				( attribute "RELATIVE_PROPAGATION_DELAY_SCOPE" "G"
					( Parent
						( matchGroupRef "@baseboard_fab2_lib.baseboard_fab2(sch_1):\MG_DQ_FAR_DIMM_NG_M_C_BYTE1\" )
					)
					( Status sCSetFlattened )
					( Origin gBackEnd )
				)
				( attribute "RELATIVE_PROPAGATION_DELAY" "-50.00 MIL,50.00 MIL"
					( Parent
						( matchGroupRef "@baseboard_fab2_lib.baseboard_fab2(sch_1):\MG_DQ_FAR_DIMM_NG_M_C_BYTE1\" )
					)
					( Units "uMatchProp" "ns" 1.000000)
					( Status sCSetFlattened )
					( Origin gBackEnd )
				)
			)
			( pinPair "@baseboard_fab2_lib.baseboard_fab2(sch_1):\PP4856\"
				( pinRef "@baseboard_fab2_lib.baseboard_fab2(sch_1):page25_i172:DDR2_DQ(9)" )
				( pinRef "@baseboard_fab2_lib.baseboard_fab2(sch_1):page48_i111:DQ(9)" )
				( attribute "RELATIVE_PROPAGATION_DELAY_SCOPE" "G"
					( Parent
						( matchGroupRef "@baseboard_fab2_lib.baseboard_fab2(sch_1):\MG_DQ-DQS_NEAR_DIMM_NG_M_C_BYTE1\" )
					)
					( Status sCSetFlattened )
					( Origin gBackEnd )
				)
				( attribute "RELATIVE_PROPAGATION_DELAY" "0.00 MIL,195.00 MIL"
					( Parent
						( matchGroupRef "@baseboard_fab2_lib.baseboard_fab2(sch_1):\MG_DQ-DQS_NEAR_DIMM_NG_M_C_BYTE1\" )
					)
					( Units "uMatchProp" "ns" 1.000000)
					( Status sCSetFlattened )
					( Origin gBackEnd )
				)
				( attribute "RELATIVE_PROPAGATION_DELAY_SCOPE" "G"
					( Parent
						( matchGroupRef "@baseboard_fab2_lib.baseboard_fab2(sch_1):\MG_DQ_NEAR_DIMM_NG_M_C_BYTE1\" )
					)
					( Status sCSetFlattened )
					( Origin gBackEnd )
				)
				( attribute "RELATIVE_PROPAGATION_DELAY" "-50.00 MIL,50.00 MIL"
					( Parent
						( matchGroupRef "@baseboard_fab2_lib.baseboard_fab2(sch_1):\MG_DQ_NEAR_DIMM_NG_M_C_BYTE1\" )
					)
					( Units "uMatchProp" "ns" 1.000000)
					( Status sCSetFlattened )
					( Origin gBackEnd )
				)
			)
			( pinPair "@baseboard_fab2_lib.baseboard_fab2(sch_1):\PP4857\"
				( pinRef "@baseboard_fab2_lib.baseboard_fab2(sch_1):page25_i172:DDR2_DQ(10)" )
				( pinRef "@baseboard_fab2_lib.baseboard_fab2(sch_1):page47_i111:DQ(11)" )
				( attribute "RELATIVE_PROPAGATION_DELAY_SCOPE" "G"
					( Parent
						( matchGroupRef "@baseboard_fab2_lib.baseboard_fab2(sch_1):\MG_DQ-DQS_FAR_DIMM_NG_M_C_BYTE1\" )
					)
					( Status sCSetFlattened )
					( Origin gBackEnd )
				)
				( attribute "RELATIVE_PROPAGATION_DELAY" "0.00 MIL,195.00 MIL"
					( Parent
						( matchGroupRef "@baseboard_fab2_lib.baseboard_fab2(sch_1):\MG_DQ-DQS_FAR_DIMM_NG_M_C_BYTE1\" )
					)
					( Units "uMatchProp" "ns" 1.000000)
					( Status sCSetFlattened )
					( Origin gBackEnd )
				)
				( attribute "RELATIVE_PROPAGATION_DELAY_SCOPE" "G"
					( Parent
						( matchGroupRef "@baseboard_fab2_lib.baseboard_fab2(sch_1):\MG_DQ_FAR_DIMM_NG_M_C_BYTE1\" )
					)
					( Status sCSetFlattened )
					( Origin gBackEnd )
				)
				( attribute "RELATIVE_PROPAGATION_DELAY" "-50.00 MIL,50.00 MIL"
					( Parent
						( matchGroupRef "@baseboard_fab2_lib.baseboard_fab2(sch_1):\MG_DQ_FAR_DIMM_NG_M_C_BYTE1\" )
					)
					( Units "uMatchProp" "ns" 1.000000)
					( Status sCSetFlattened )
					( Origin gBackEnd )
				)
			)
			( pinPair "@baseboard_fab2_lib.baseboard_fab2(sch_1):\PP4859\"
				( pinRef "@baseboard_fab2_lib.baseboard_fab2(sch_1):page25_i172:DDR2_DQ(10)" )
				( pinRef "@baseboard_fab2_lib.baseboard_fab2(sch_1):page48_i111:DQ(10)" )
				( attribute "RELATIVE_PROPAGATION_DELAY_SCOPE" "G"
					( Parent
						( matchGroupRef "@baseboard_fab2_lib.baseboard_fab2(sch_1):\MG_DQ-DQS_NEAR_DIMM_NG_M_C_BYTE1\" )
					)
					( Status sCSetFlattened )
					( Origin gBackEnd )
				)
				( attribute "RELATIVE_PROPAGATION_DELAY" "0.00 MIL,195.00 MIL"
					( Parent
						( matchGroupRef "@baseboard_fab2_lib.baseboard_fab2(sch_1):\MG_DQ-DQS_NEAR_DIMM_NG_M_C_BYTE1\" )
					)
					( Units "uMatchProp" "ns" 1.000000)
					( Status sCSetFlattened )
					( Origin gBackEnd )
				)
				( attribute "RELATIVE_PROPAGATION_DELAY_SCOPE" "G"
					( Parent
						( matchGroupRef "@baseboard_fab2_lib.baseboard_fab2(sch_1):\MG_DQ_NEAR_DIMM_NG_M_C_BYTE1\" )
					)
					( Status sCSetFlattened )
					( Origin gBackEnd )
				)
				( attribute "RELATIVE_PROPAGATION_DELAY" "-50.00 MIL,50.00 MIL"
					( Parent
						( matchGroupRef "@baseboard_fab2_lib.baseboard_fab2(sch_1):\MG_DQ_NEAR_DIMM_NG_M_C_BYTE1\" )
					)
					( Units "uMatchProp" "ns" 1.000000)
					( Status sCSetFlattened )
					( Origin gBackEnd )
				)
			)
			( pinPair "@baseboard_fab2_lib.baseboard_fab2(sch_1):\PP4860\"
				( pinRef "@baseboard_fab2_lib.baseboard_fab2(sch_1):page25_i172:DDR2_DQ(11)" )
				( pinRef "@baseboard_fab2_lib.baseboard_fab2(sch_1):page47_i111:DQ(10)" )
				( attribute "RELATIVE_PROPAGATION_DELAY_SCOPE" "G"
					( Parent
						( matchGroupRef "@baseboard_fab2_lib.baseboard_fab2(sch_1):\MG_DQ-DQS_FAR_DIMM_NG_M_C_BYTE1\" )
					)
					( Status sCSetFlattened )
					( Origin gBackEnd )
				)
				( attribute "RELATIVE_PROPAGATION_DELAY" "0.00 MIL,195.00 MIL"
					( Parent
						( matchGroupRef "@baseboard_fab2_lib.baseboard_fab2(sch_1):\MG_DQ-DQS_FAR_DIMM_NG_M_C_BYTE1\" )
					)
					( Units "uMatchProp" "ns" 1.000000)
					( Status sCSetFlattened )
					( Origin gBackEnd )
				)
				( attribute "RELATIVE_PROPAGATION_DELAY_SCOPE" "G"
					( Parent
						( matchGroupRef "@baseboard_fab2_lib.baseboard_fab2(sch_1):\MG_DQ_FAR_DIMM_NG_M_C_BYTE1\" )
					)
					( Status sCSetFlattened )
					( Origin gBackEnd )
				)
				( attribute "RELATIVE_PROPAGATION_DELAY" "-50.00 MIL,50.00 MIL"
					( Parent
						( matchGroupRef "@baseboard_fab2_lib.baseboard_fab2(sch_1):\MG_DQ_FAR_DIMM_NG_M_C_BYTE1\" )
					)
					( Units "uMatchProp" "ns" 1.000000)
					( Status sCSetFlattened )
					( Origin gBackEnd )
				)
			)
			( pinPair "@baseboard_fab2_lib.baseboard_fab2(sch_1):\PP4862\"
				( pinRef "@baseboard_fab2_lib.baseboard_fab2(sch_1):page25_i172:DDR2_DQ(11)" )
				( pinRef "@baseboard_fab2_lib.baseboard_fab2(sch_1):page48_i111:DQ(11)" )
				( attribute "RELATIVE_PROPAGATION_DELAY_SCOPE" "G"
					( Parent
						( matchGroupRef "@baseboard_fab2_lib.baseboard_fab2(sch_1):\MG_DQ-DQS_NEAR_DIMM_NG_M_C_BYTE1\" )
					)
					( Status sCSetFlattened )
					( Origin gBackEnd )
				)
				( attribute "RELATIVE_PROPAGATION_DELAY" "0.00 MIL,195.00 MIL"
					( Parent
						( matchGroupRef "@baseboard_fab2_lib.baseboard_fab2(sch_1):\MG_DQ-DQS_NEAR_DIMM_NG_M_C_BYTE1\" )
					)
					( Units "uMatchProp" "ns" 1.000000)
					( Status sCSetFlattened )
					( Origin gBackEnd )
				)
				( attribute "RELATIVE_PROPAGATION_DELAY_SCOPE" "G"
					( Parent
						( matchGroupRef "@baseboard_fab2_lib.baseboard_fab2(sch_1):\MG_DQ_NEAR_DIMM_NG_M_C_BYTE1\" )
					)
					( Status sCSetFlattened )
					( Origin gBackEnd )
				)
				( attribute "RELATIVE_PROPAGATION_DELAY" "-50.00 MIL,50.00 MIL"
					( Parent
						( matchGroupRef "@baseboard_fab2_lib.baseboard_fab2(sch_1):\MG_DQ_NEAR_DIMM_NG_M_C_BYTE1\" )
					)
					( Units "uMatchProp" "ns" 1.000000)
					( Status sCSetFlattened )
					( Origin gBackEnd )
				)
			)
			( pinPair "@baseboard_fab2_lib.baseboard_fab2(sch_1):\PP4863\"
				( pinRef "@baseboard_fab2_lib.baseboard_fab2(sch_1):page25_i172:DDR2_DQ(12)" )
				( pinRef "@baseboard_fab2_lib.baseboard_fab2(sch_1):page47_i111:DQ(13)" )
				( attribute "RELATIVE_PROPAGATION_DELAY_SCOPE" "G"
					( Parent
						( matchGroupRef "@baseboard_fab2_lib.baseboard_fab2(sch_1):\MG_DQ-DQS_FAR_DIMM_NG_M_C_BYTE1\" )
					)
					( Status sCSetFlattened )
					( Origin gBackEnd )
				)
				( attribute "RELATIVE_PROPAGATION_DELAY" "0.00 MIL,195.00 MIL"
					( Parent
						( matchGroupRef "@baseboard_fab2_lib.baseboard_fab2(sch_1):\MG_DQ-DQS_FAR_DIMM_NG_M_C_BYTE1\" )
					)
					( Units "uMatchProp" "ns" 1.000000)
					( Status sCSetFlattened )
					( Origin gBackEnd )
				)
				( attribute "RELATIVE_PROPAGATION_DELAY_SCOPE" "G"
					( Parent
						( matchGroupRef "@baseboard_fab2_lib.baseboard_fab2(sch_1):\MG_DQ_FAR_DIMM_NG_M_C_BYTE1\" )
					)
					( Status sCSetFlattened )
					( Origin gBackEnd )
				)
				( attribute "RELATIVE_PROPAGATION_DELAY" "-50.00 MIL,50.00 MIL"
					( Parent
						( matchGroupRef "@baseboard_fab2_lib.baseboard_fab2(sch_1):\MG_DQ_FAR_DIMM_NG_M_C_BYTE1\" )
					)
					( Units "uMatchProp" "ns" 1.000000)
					( Status sCSetFlattened )
					( Origin gBackEnd )
				)
			)
			( pinPair "@baseboard_fab2_lib.baseboard_fab2(sch_1):\PP4865\"
				( pinRef "@baseboard_fab2_lib.baseboard_fab2(sch_1):page25_i172:DDR2_DQ(12)" )
				( pinRef "@baseboard_fab2_lib.baseboard_fab2(sch_1):page48_i111:DQ(12)" )
				( attribute "RELATIVE_PROPAGATION_DELAY_SCOPE" "G"
					( Parent
						( matchGroupRef "@baseboard_fab2_lib.baseboard_fab2(sch_1):\MG_DQ-DQS_NEAR_DIMM_NG_M_C_BYTE1\" )
					)
					( Status sCSetFlattened )
					( Origin gBackEnd )
				)
				( attribute "RELATIVE_PROPAGATION_DELAY" "0.00 MIL,195.00 MIL"
					( Parent
						( matchGroupRef "@baseboard_fab2_lib.baseboard_fab2(sch_1):\MG_DQ-DQS_NEAR_DIMM_NG_M_C_BYTE1\" )
					)
					( Units "uMatchProp" "ns" 1.000000)
					( Status sCSetFlattened )
					( Origin gBackEnd )
				)
				( attribute "RELATIVE_PROPAGATION_DELAY_SCOPE" "G"
					( Parent
						( matchGroupRef "@baseboard_fab2_lib.baseboard_fab2(sch_1):\MG_DQ_NEAR_DIMM_NG_M_C_BYTE1\" )
					)
					( Status sCSetFlattened )
					( Origin gBackEnd )
				)
				( attribute "RELATIVE_PROPAGATION_DELAY" "-50.00 MIL,50.00 MIL"
					( Parent
						( matchGroupRef "@baseboard_fab2_lib.baseboard_fab2(sch_1):\MG_DQ_NEAR_DIMM_NG_M_C_BYTE1\" )
					)
					( Units "uMatchProp" "ns" 1.000000)
					( Status sCSetFlattened )
					( Origin gBackEnd )
				)
			)
			( pinPair "@baseboard_fab2_lib.baseboard_fab2(sch_1):\PP4866\"
				( pinRef "@baseboard_fab2_lib.baseboard_fab2(sch_1):page25_i172:DDR2_DQ(13)" )
				( pinRef "@baseboard_fab2_lib.baseboard_fab2(sch_1):page47_i111:DQ(12)" )
				( attribute "RELATIVE_PROPAGATION_DELAY_SCOPE" "G"
					( Parent
						( matchGroupRef "@baseboard_fab2_lib.baseboard_fab2(sch_1):\MG_DQ-DQS_FAR_DIMM_NG_M_C_BYTE1\" )
					)
					( Status sCSetFlattened )
					( Origin gBackEnd )
				)
				( attribute "RELATIVE_PROPAGATION_DELAY" "0.00 MIL,195.00 MIL"
					( Parent
						( matchGroupRef "@baseboard_fab2_lib.baseboard_fab2(sch_1):\MG_DQ-DQS_FAR_DIMM_NG_M_C_BYTE1\" )
					)
					( Units "uMatchProp" "ns" 1.000000)
					( Status sCSetFlattened )
					( Origin gBackEnd )
				)
				( attribute "RELATIVE_PROPAGATION_DELAY_SCOPE" "G"
					( Parent
						( matchGroupRef "@baseboard_fab2_lib.baseboard_fab2(sch_1):\MG_DQ_FAR_DIMM_NG_M_C_BYTE1\" )
					)
					( Status sCSetFlattened )
					( Origin gBackEnd )
				)
				( attribute "RELATIVE_PROPAGATION_DELAY" "-50.00 MIL,50.00 MIL"
					( Parent
						( matchGroupRef "@baseboard_fab2_lib.baseboard_fab2(sch_1):\MG_DQ_FAR_DIMM_NG_M_C_BYTE1\" )
					)
					( Units "uMatchProp" "ns" 1.000000)
					( Status sCSetFlattened )
					( Origin gBackEnd )
				)
			)
			( pinPair "@baseboard_fab2_lib.baseboard_fab2(sch_1):\PP4868\"
				( pinRef "@baseboard_fab2_lib.baseboard_fab2(sch_1):page25_i172:DDR2_DQ(13)" )
				( pinRef "@baseboard_fab2_lib.baseboard_fab2(sch_1):page48_i111:DQ(13)" )
				( attribute "RELATIVE_PROPAGATION_DELAY_SCOPE" "G"
					( Parent
						( matchGroupRef "@baseboard_fab2_lib.baseboard_fab2(sch_1):\MG_DQ-DQS_NEAR_DIMM_NG_M_C_BYTE1\" )
					)
					( Status sCSetFlattened )
					( Origin gBackEnd )
				)
				( attribute "RELATIVE_PROPAGATION_DELAY" "0.00 MIL,195.00 MIL"
					( Parent
						( matchGroupRef "@baseboard_fab2_lib.baseboard_fab2(sch_1):\MG_DQ-DQS_NEAR_DIMM_NG_M_C_BYTE1\" )
					)
					( Units "uMatchProp" "ns" 1.000000)
					( Status sCSetFlattened )
					( Origin gBackEnd )
				)
				( attribute "RELATIVE_PROPAGATION_DELAY_SCOPE" "G"
					( Parent
						( matchGroupRef "@baseboard_fab2_lib.baseboard_fab2(sch_1):\MG_DQ_NEAR_DIMM_NG_M_C_BYTE1\" )
					)
					( Status sCSetFlattened )
					( Origin gBackEnd )
				)
				( attribute "RELATIVE_PROPAGATION_DELAY" "-50.00 MIL,50.00 MIL"
					( Parent
						( matchGroupRef "@baseboard_fab2_lib.baseboard_fab2(sch_1):\MG_DQ_NEAR_DIMM_NG_M_C_BYTE1\" )
					)
					( Units "uMatchProp" "ns" 1.000000)
					( Status sCSetFlattened )
					( Origin gBackEnd )
				)
			)
			( pinPair "@baseboard_fab2_lib.baseboard_fab2(sch_1):\PP4869\"
				( pinRef "@baseboard_fab2_lib.baseboard_fab2(sch_1):page25_i172:DDR2_DQ(14)" )
				( pinRef "@baseboard_fab2_lib.baseboard_fab2(sch_1):page47_i111:DQ(15)" )
				( attribute "RELATIVE_PROPAGATION_DELAY_SCOPE" "G"
					( Parent
						( matchGroupRef "@baseboard_fab2_lib.baseboard_fab2(sch_1):\MG_DQ-DQS_FAR_DIMM_NG_M_C_BYTE1\" )
					)
					( Status sCSetFlattened )
					( Origin gBackEnd )
				)
				( attribute "RELATIVE_PROPAGATION_DELAY" "0.00 MIL,195.00 MIL"
					( Parent
						( matchGroupRef "@baseboard_fab2_lib.baseboard_fab2(sch_1):\MG_DQ-DQS_FAR_DIMM_NG_M_C_BYTE1\" )
					)
					( Units "uMatchProp" "ns" 1.000000)
					( Status sCSetFlattened )
					( Origin gBackEnd )
				)
				( attribute "RELATIVE_PROPAGATION_DELAY_SCOPE" "G"
					( Parent
						( matchGroupRef "@baseboard_fab2_lib.baseboard_fab2(sch_1):\MG_DQ_FAR_DIMM_NG_M_C_BYTE1\" )
					)
					( Status sCSetFlattened )
					( Origin gBackEnd )
				)
				( attribute "RELATIVE_PROPAGATION_DELAY" "-50.00 MIL,50.00 MIL"
					( Parent
						( matchGroupRef "@baseboard_fab2_lib.baseboard_fab2(sch_1):\MG_DQ_FAR_DIMM_NG_M_C_BYTE1\" )
					)
					( Units "uMatchProp" "ns" 1.000000)
					( Status sCSetFlattened )
					( Origin gBackEnd )
				)
			)
			( pinPair "@baseboard_fab2_lib.baseboard_fab2(sch_1):\PP4871\"
				( pinRef "@baseboard_fab2_lib.baseboard_fab2(sch_1):page25_i172:DDR2_DQ(14)" )
				( pinRef "@baseboard_fab2_lib.baseboard_fab2(sch_1):page48_i111:DQ(14)" )
				( attribute "RELATIVE_PROPAGATION_DELAY_SCOPE" "G"
					( Parent
						( matchGroupRef "@baseboard_fab2_lib.baseboard_fab2(sch_1):\MG_DQ-DQS_NEAR_DIMM_NG_M_C_BYTE1\" )
					)
					( Status sCSetFlattened )
					( Origin gBackEnd )
				)
				( attribute "RELATIVE_PROPAGATION_DELAY" "0.00 MIL,195.00 MIL"
					( Parent
						( matchGroupRef "@baseboard_fab2_lib.baseboard_fab2(sch_1):\MG_DQ-DQS_NEAR_DIMM_NG_M_C_BYTE1\" )
					)
					( Units "uMatchProp" "ns" 1.000000)
					( Status sCSetFlattened )
					( Origin gBackEnd )
				)
				( attribute "RELATIVE_PROPAGATION_DELAY_SCOPE" "G"
					( Parent
						( matchGroupRef "@baseboard_fab2_lib.baseboard_fab2(sch_1):\MG_DQ_NEAR_DIMM_NG_M_C_BYTE1\" )
					)
					( Status sCSetFlattened )
					( Origin gBackEnd )
				)
				( attribute "RELATIVE_PROPAGATION_DELAY" "-50.00 MIL,50.00 MIL"
					( Parent
						( matchGroupRef "@baseboard_fab2_lib.baseboard_fab2(sch_1):\MG_DQ_NEAR_DIMM_NG_M_C_BYTE1\" )
					)
					( Units "uMatchProp" "ns" 1.000000)
					( Status sCSetFlattened )
					( Origin gBackEnd )
				)
			)
			( pinPair "@baseboard_fab2_lib.baseboard_fab2(sch_1):\PP4872\"
				( pinRef "@baseboard_fab2_lib.baseboard_fab2(sch_1):page25_i172:DDR2_DQ(15)" )
				( pinRef "@baseboard_fab2_lib.baseboard_fab2(sch_1):page47_i111:DQ(14)" )
				( attribute "RELATIVE_PROPAGATION_DELAY_SCOPE" "G"
					( Parent
						( matchGroupRef "@baseboard_fab2_lib.baseboard_fab2(sch_1):\MG_DQ-DQS_FAR_DIMM_NG_M_C_BYTE1\" )
					)
					( Status sCSetFlattened )
					( Origin gBackEnd )
				)
				( attribute "RELATIVE_PROPAGATION_DELAY" "0.00 MIL,195.00 MIL"
					( Parent
						( matchGroupRef "@baseboard_fab2_lib.baseboard_fab2(sch_1):\MG_DQ-DQS_FAR_DIMM_NG_M_C_BYTE1\" )
					)
					( Units "uMatchProp" "ns" 1.000000)
					( Status sCSetFlattened )
					( Origin gBackEnd )
				)
				( attribute "RELATIVE_PROPAGATION_DELAY_SCOPE" "G"
					( Parent
						( matchGroupRef "@baseboard_fab2_lib.baseboard_fab2(sch_1):\MG_DQ_FAR_DIMM_NG_M_C_BYTE1\" )
					)
					( Status sCSetFlattened )
					( Origin gBackEnd )
				)
				( attribute "RELATIVE_PROPAGATION_DELAY" "-50.00 MIL,50.00 MIL"
					( Parent
						( matchGroupRef "@baseboard_fab2_lib.baseboard_fab2(sch_1):\MG_DQ_FAR_DIMM_NG_M_C_BYTE1\" )
					)
					( Units "uMatchProp" "ns" 1.000000)
					( Status sCSetFlattened )
					( Origin gBackEnd )
				)
			)
			( pinPair "@baseboard_fab2_lib.baseboard_fab2(sch_1):\PP4874\"
				( pinRef "@baseboard_fab2_lib.baseboard_fab2(sch_1):page25_i172:DDR2_DQ(15)" )
				( pinRef "@baseboard_fab2_lib.baseboard_fab2(sch_1):page48_i111:DQ(15)" )
				( attribute "RELATIVE_PROPAGATION_DELAY_SCOPE" "G"
					( Parent
						( matchGroupRef "@baseboard_fab2_lib.baseboard_fab2(sch_1):\MG_DQ-DQS_NEAR_DIMM_NG_M_C_BYTE1\" )
					)
					( Status sCSetFlattened )
					( Origin gBackEnd )
				)
				( attribute "RELATIVE_PROPAGATION_DELAY" "0.00 MIL,195.00 MIL"
					( Parent
						( matchGroupRef "@baseboard_fab2_lib.baseboard_fab2(sch_1):\MG_DQ-DQS_NEAR_DIMM_NG_M_C_BYTE1\" )
					)
					( Units "uMatchProp" "ns" 1.000000)
					( Status sCSetFlattened )
					( Origin gBackEnd )
				)
				( attribute "RELATIVE_PROPAGATION_DELAY_SCOPE" "G"
					( Parent
						( matchGroupRef "@baseboard_fab2_lib.baseboard_fab2(sch_1):\MG_DQ_NEAR_DIMM_NG_M_C_BYTE1\" )
					)
					( Status sCSetFlattened )
					( Origin gBackEnd )
				)
				( attribute "RELATIVE_PROPAGATION_DELAY" "-50.00 MIL,50.00 MIL"
					( Parent
						( matchGroupRef "@baseboard_fab2_lib.baseboard_fab2(sch_1):\MG_DQ_NEAR_DIMM_NG_M_C_BYTE1\" )
					)
					( Units "uMatchProp" "ns" 1.000000)
					( Status sCSetFlattened )
					( Origin gBackEnd )
				)
			)
			( pinPair "@baseboard_fab2_lib.baseboard_fab2(sch_1):\PP4827\"
				( pinRef "@baseboard_fab2_lib.baseboard_fab2(sch_1):page25_i172:DDR2_DQ(16)" )
				( pinRef "@baseboard_fab2_lib.baseboard_fab2(sch_1):page47_i111:DQ(17)" )
				( attribute "RELATIVE_PROPAGATION_DELAY_SCOPE" "G"
					( Parent
						( matchGroupRef "@baseboard_fab2_lib.baseboard_fab2(sch_1):\MG_DQ-DQS_FAR_DIMM_NG_M_C_BYTE2\" )
					)
					( Status sCSetFlattened )
					( Origin gBackEnd )
				)
				( attribute "RELATIVE_PROPAGATION_DELAY" "0.00 MIL,195.00 MIL"
					( Parent
						( matchGroupRef "@baseboard_fab2_lib.baseboard_fab2(sch_1):\MG_DQ-DQS_FAR_DIMM_NG_M_C_BYTE2\" )
					)
					( Units "uMatchProp" "ns" 1.000000)
					( Status sCSetFlattened )
					( Origin gBackEnd )
				)
				( attribute "RELATIVE_PROPAGATION_DELAY_SCOPE" "G"
					( Parent
						( matchGroupRef "@baseboard_fab2_lib.baseboard_fab2(sch_1):\MG_DQ_FAR_DIMM_NG_M_C_BYTE2\" )
					)
					( Status sCSetFlattened )
					( Origin gBackEnd )
				)
				( attribute "RELATIVE_PROPAGATION_DELAY" "-50.00 MIL,50.00 MIL"
					( Parent
						( matchGroupRef "@baseboard_fab2_lib.baseboard_fab2(sch_1):\MG_DQ_FAR_DIMM_NG_M_C_BYTE2\" )
					)
					( Units "uMatchProp" "ns" 1.000000)
					( Status sCSetFlattened )
					( Origin gBackEnd )
				)
			)
			( pinPair "@baseboard_fab2_lib.baseboard_fab2(sch_1):\PP4829\"
				( pinRef "@baseboard_fab2_lib.baseboard_fab2(sch_1):page25_i172:DDR2_DQ(16)" )
				( pinRef "@baseboard_fab2_lib.baseboard_fab2(sch_1):page48_i111:DQ(16)" )
				( attribute "RELATIVE_PROPAGATION_DELAY_SCOPE" "G"
					( Parent
						( matchGroupRef "@baseboard_fab2_lib.baseboard_fab2(sch_1):\MG_DQ-DQS_NEAR_DIMM_NG_M_C_BYTE2\" )
					)
					( Status sCSetFlattened )
					( Origin gBackEnd )
				)
				( attribute "RELATIVE_PROPAGATION_DELAY" "0.00 MIL,195.00 MIL"
					( Parent
						( matchGroupRef "@baseboard_fab2_lib.baseboard_fab2(sch_1):\MG_DQ-DQS_NEAR_DIMM_NG_M_C_BYTE2\" )
					)
					( Units "uMatchProp" "ns" 1.000000)
					( Status sCSetFlattened )
					( Origin gBackEnd )
				)
				( attribute "RELATIVE_PROPAGATION_DELAY_SCOPE" "G"
					( Parent
						( matchGroupRef "@baseboard_fab2_lib.baseboard_fab2(sch_1):\MG_DQ_NEAR_DIMM_NG_M_C_BYTE2\" )
					)
					( Status sCSetFlattened )
					( Origin gBackEnd )
				)
				( attribute "RELATIVE_PROPAGATION_DELAY" "-50.00 MIL,50.00 MIL"
					( Parent
						( matchGroupRef "@baseboard_fab2_lib.baseboard_fab2(sch_1):\MG_DQ_NEAR_DIMM_NG_M_C_BYTE2\" )
					)
					( Units "uMatchProp" "ns" 1.000000)
					( Status sCSetFlattened )
					( Origin gBackEnd )
				)
			)
			( pinPair "@baseboard_fab2_lib.baseboard_fab2(sch_1):\PP4830\"
				( pinRef "@baseboard_fab2_lib.baseboard_fab2(sch_1):page25_i172:DDR2_DQ(17)" )
				( pinRef "@baseboard_fab2_lib.baseboard_fab2(sch_1):page47_i111:DQ(16)" )
				( attribute "RELATIVE_PROPAGATION_DELAY_SCOPE" "G"
					( Parent
						( matchGroupRef "@baseboard_fab2_lib.baseboard_fab2(sch_1):\MG_DQ-DQS_FAR_DIMM_NG_M_C_BYTE2\" )
					)
					( Status sCSetFlattened )
					( Origin gBackEnd )
				)
				( attribute "RELATIVE_PROPAGATION_DELAY" "0.00 MIL,195.00 MIL"
					( Parent
						( matchGroupRef "@baseboard_fab2_lib.baseboard_fab2(sch_1):\MG_DQ-DQS_FAR_DIMM_NG_M_C_BYTE2\" )
					)
					( Units "uMatchProp" "ns" 1.000000)
					( Status sCSetFlattened )
					( Origin gBackEnd )
				)
				( attribute "RELATIVE_PROPAGATION_DELAY_SCOPE" "G"
					( Parent
						( matchGroupRef "@baseboard_fab2_lib.baseboard_fab2(sch_1):\MG_DQ_FAR_DIMM_NG_M_C_BYTE2\" )
					)
					( Status sCSetFlattened )
					( Origin gBackEnd )
				)
				( attribute "RELATIVE_PROPAGATION_DELAY" "-50.00 MIL,50.00 MIL"
					( Parent
						( matchGroupRef "@baseboard_fab2_lib.baseboard_fab2(sch_1):\MG_DQ_FAR_DIMM_NG_M_C_BYTE2\" )
					)
					( Units "uMatchProp" "ns" 1.000000)
					( Status sCSetFlattened )
					( Origin gBackEnd )
				)
			)
			( pinPair "@baseboard_fab2_lib.baseboard_fab2(sch_1):\PP4832\"
				( pinRef "@baseboard_fab2_lib.baseboard_fab2(sch_1):page25_i172:DDR2_DQ(17)" )
				( pinRef "@baseboard_fab2_lib.baseboard_fab2(sch_1):page48_i111:DQ(17)" )
				( attribute "RELATIVE_PROPAGATION_DELAY_SCOPE" "G"
					( Parent
						( matchGroupRef "@baseboard_fab2_lib.baseboard_fab2(sch_1):\MG_DQ-DQS_NEAR_DIMM_NG_M_C_BYTE2\" )
					)
					( Status sCSetFlattened )
					( Origin gBackEnd )
				)
				( attribute "RELATIVE_PROPAGATION_DELAY" "0.00 MIL,195.00 MIL"
					( Parent
						( matchGroupRef "@baseboard_fab2_lib.baseboard_fab2(sch_1):\MG_DQ-DQS_NEAR_DIMM_NG_M_C_BYTE2\" )
					)
					( Units "uMatchProp" "ns" 1.000000)
					( Status sCSetFlattened )
					( Origin gBackEnd )
				)
				( attribute "RELATIVE_PROPAGATION_DELAY_SCOPE" "G"
					( Parent
						( matchGroupRef "@baseboard_fab2_lib.baseboard_fab2(sch_1):\MG_DQ_NEAR_DIMM_NG_M_C_BYTE2\" )
					)
					( Status sCSetFlattened )
					( Origin gBackEnd )
				)
				( attribute "RELATIVE_PROPAGATION_DELAY" "-50.00 MIL,50.00 MIL"
					( Parent
						( matchGroupRef "@baseboard_fab2_lib.baseboard_fab2(sch_1):\MG_DQ_NEAR_DIMM_NG_M_C_BYTE2\" )
					)
					( Units "uMatchProp" "ns" 1.000000)
					( Status sCSetFlattened )
					( Origin gBackEnd )
				)
			)
			( pinPair "@baseboard_fab2_lib.baseboard_fab2(sch_1):\PP4833\"
				( pinRef "@baseboard_fab2_lib.baseboard_fab2(sch_1):page25_i172:DDR2_DQ(18)" )
				( pinRef "@baseboard_fab2_lib.baseboard_fab2(sch_1):page47_i111:DQ(19)" )
				( attribute "RELATIVE_PROPAGATION_DELAY_SCOPE" "G"
					( Parent
						( matchGroupRef "@baseboard_fab2_lib.baseboard_fab2(sch_1):\MG_DQ-DQS_FAR_DIMM_NG_M_C_BYTE2\" )
					)
					( Status sCSetFlattened )
					( Origin gBackEnd )
				)
				( attribute "RELATIVE_PROPAGATION_DELAY" "0.00 MIL,195.00 MIL"
					( Parent
						( matchGroupRef "@baseboard_fab2_lib.baseboard_fab2(sch_1):\MG_DQ-DQS_FAR_DIMM_NG_M_C_BYTE2\" )
					)
					( Units "uMatchProp" "ns" 1.000000)
					( Status sCSetFlattened )
					( Origin gBackEnd )
				)
				( attribute "RELATIVE_PROPAGATION_DELAY_SCOPE" "G"
					( Parent
						( matchGroupRef "@baseboard_fab2_lib.baseboard_fab2(sch_1):\MG_DQ_FAR_DIMM_NG_M_C_BYTE2\" )
					)
					( Status sCSetFlattened )
					( Origin gBackEnd )
				)
				( attribute "RELATIVE_PROPAGATION_DELAY" "-50.00 MIL,50.00 MIL"
					( Parent
						( matchGroupRef "@baseboard_fab2_lib.baseboard_fab2(sch_1):\MG_DQ_FAR_DIMM_NG_M_C_BYTE2\" )
					)
					( Units "uMatchProp" "ns" 1.000000)
					( Status sCSetFlattened )
					( Origin gBackEnd )
				)
			)
			( pinPair "@baseboard_fab2_lib.baseboard_fab2(sch_1):\PP4835\"
				( pinRef "@baseboard_fab2_lib.baseboard_fab2(sch_1):page25_i172:DDR2_DQ(18)" )
				( pinRef "@baseboard_fab2_lib.baseboard_fab2(sch_1):page48_i111:DQ(18)" )
				( attribute "RELATIVE_PROPAGATION_DELAY_SCOPE" "G"
					( Parent
						( matchGroupRef "@baseboard_fab2_lib.baseboard_fab2(sch_1):\MG_DQ-DQS_NEAR_DIMM_NG_M_C_BYTE2\" )
					)
					( Status sCSetFlattened )
					( Origin gBackEnd )
				)
				( attribute "RELATIVE_PROPAGATION_DELAY" "0.00 MIL,195.00 MIL"
					( Parent
						( matchGroupRef "@baseboard_fab2_lib.baseboard_fab2(sch_1):\MG_DQ-DQS_NEAR_DIMM_NG_M_C_BYTE2\" )
					)
					( Units "uMatchProp" "ns" 1.000000)
					( Status sCSetFlattened )
					( Origin gBackEnd )
				)
				( attribute "RELATIVE_PROPAGATION_DELAY_SCOPE" "G"
					( Parent
						( matchGroupRef "@baseboard_fab2_lib.baseboard_fab2(sch_1):\MG_DQ_NEAR_DIMM_NG_M_C_BYTE2\" )
					)
					( Status sCSetFlattened )
					( Origin gBackEnd )
				)
				( attribute "RELATIVE_PROPAGATION_DELAY" "-50.00 MIL,50.00 MIL"
					( Parent
						( matchGroupRef "@baseboard_fab2_lib.baseboard_fab2(sch_1):\MG_DQ_NEAR_DIMM_NG_M_C_BYTE2\" )
					)
					( Units "uMatchProp" "ns" 1.000000)
					( Status sCSetFlattened )
					( Origin gBackEnd )
				)
			)
			( pinPair "@baseboard_fab2_lib.baseboard_fab2(sch_1):\PP4836\"
				( pinRef "@baseboard_fab2_lib.baseboard_fab2(sch_1):page25_i172:DDR2_DQ(19)" )
				( pinRef "@baseboard_fab2_lib.baseboard_fab2(sch_1):page47_i111:DQ(18)" )
				( attribute "RELATIVE_PROPAGATION_DELAY_SCOPE" "G"
					( Parent
						( matchGroupRef "@baseboard_fab2_lib.baseboard_fab2(sch_1):\MG_DQ-DQS_FAR_DIMM_NG_M_C_BYTE2\" )
					)
					( Status sCSetFlattened )
					( Origin gBackEnd )
				)
				( attribute "RELATIVE_PROPAGATION_DELAY" "0.00 MIL,195.00 MIL"
					( Parent
						( matchGroupRef "@baseboard_fab2_lib.baseboard_fab2(sch_1):\MG_DQ-DQS_FAR_DIMM_NG_M_C_BYTE2\" )
					)
					( Units "uMatchProp" "ns" 1.000000)
					( Status sCSetFlattened )
					( Origin gBackEnd )
				)
				( attribute "RELATIVE_PROPAGATION_DELAY_SCOPE" "G"
					( Parent
						( matchGroupRef "@baseboard_fab2_lib.baseboard_fab2(sch_1):\MG_DQ_FAR_DIMM_NG_M_C_BYTE2\" )
					)
					( Status sCSetFlattened )
					( Origin gBackEnd )
				)
				( attribute "RELATIVE_PROPAGATION_DELAY" "-50.00 MIL,50.00 MIL"
					( Parent
						( matchGroupRef "@baseboard_fab2_lib.baseboard_fab2(sch_1):\MG_DQ_FAR_DIMM_NG_M_C_BYTE2\" )
					)
					( Units "uMatchProp" "ns" 1.000000)
					( Status sCSetFlattened )
					( Origin gBackEnd )
				)
			)
			( pinPair "@baseboard_fab2_lib.baseboard_fab2(sch_1):\PP4838\"
				( pinRef "@baseboard_fab2_lib.baseboard_fab2(sch_1):page25_i172:DDR2_DQ(19)" )
				( pinRef "@baseboard_fab2_lib.baseboard_fab2(sch_1):page48_i111:DQ(19)" )
				( attribute "RELATIVE_PROPAGATION_DELAY_SCOPE" "G"
					( Parent
						( matchGroupRef "@baseboard_fab2_lib.baseboard_fab2(sch_1):\MG_DQ-DQS_NEAR_DIMM_NG_M_C_BYTE2\" )
					)
					( Status sCSetFlattened )
					( Origin gBackEnd )
				)
				( attribute "RELATIVE_PROPAGATION_DELAY" "0.00 MIL,195.00 MIL"
					( Parent
						( matchGroupRef "@baseboard_fab2_lib.baseboard_fab2(sch_1):\MG_DQ-DQS_NEAR_DIMM_NG_M_C_BYTE2\" )
					)
					( Units "uMatchProp" "ns" 1.000000)
					( Status sCSetFlattened )
					( Origin gBackEnd )
				)
				( attribute "RELATIVE_PROPAGATION_DELAY_SCOPE" "G"
					( Parent
						( matchGroupRef "@baseboard_fab2_lib.baseboard_fab2(sch_1):\MG_DQ_NEAR_DIMM_NG_M_C_BYTE2\" )
					)
					( Status sCSetFlattened )
					( Origin gBackEnd )
				)
				( attribute "RELATIVE_PROPAGATION_DELAY" "-50.00 MIL,50.00 MIL"
					( Parent
						( matchGroupRef "@baseboard_fab2_lib.baseboard_fab2(sch_1):\MG_DQ_NEAR_DIMM_NG_M_C_BYTE2\" )
					)
					( Units "uMatchProp" "ns" 1.000000)
					( Status sCSetFlattened )
					( Origin gBackEnd )
				)
			)
			( pinPair "@baseboard_fab2_lib.baseboard_fab2(sch_1):\PP4839\"
				( pinRef "@baseboard_fab2_lib.baseboard_fab2(sch_1):page25_i172:DDR2_DQ(20)" )
				( pinRef "@baseboard_fab2_lib.baseboard_fab2(sch_1):page47_i111:DQ(21)" )
				( attribute "RELATIVE_PROPAGATION_DELAY_SCOPE" "G"
					( Parent
						( matchGroupRef "@baseboard_fab2_lib.baseboard_fab2(sch_1):\MG_DQ-DQS_FAR_DIMM_NG_M_C_BYTE2\" )
					)
					( Status sCSetFlattened )
					( Origin gBackEnd )
				)
				( attribute "RELATIVE_PROPAGATION_DELAY" "0.00 MIL,195.00 MIL"
					( Parent
						( matchGroupRef "@baseboard_fab2_lib.baseboard_fab2(sch_1):\MG_DQ-DQS_FAR_DIMM_NG_M_C_BYTE2\" )
					)
					( Units "uMatchProp" "ns" 1.000000)
					( Status sCSetFlattened )
					( Origin gBackEnd )
				)
				( attribute "RELATIVE_PROPAGATION_DELAY_SCOPE" "G"
					( Parent
						( matchGroupRef "@baseboard_fab2_lib.baseboard_fab2(sch_1):\MG_DQ_FAR_DIMM_NG_M_C_BYTE2\" )
					)
					( Status sCSetFlattened )
					( Origin gBackEnd )
				)
				( attribute "RELATIVE_PROPAGATION_DELAY" "-50.00 MIL,50.00 MIL"
					( Parent
						( matchGroupRef "@baseboard_fab2_lib.baseboard_fab2(sch_1):\MG_DQ_FAR_DIMM_NG_M_C_BYTE2\" )
					)
					( Units "uMatchProp" "ns" 1.000000)
					( Status sCSetFlattened )
					( Origin gBackEnd )
				)
			)
			( pinPair "@baseboard_fab2_lib.baseboard_fab2(sch_1):\PP4841\"
				( pinRef "@baseboard_fab2_lib.baseboard_fab2(sch_1):page25_i172:DDR2_DQ(20)" )
				( pinRef "@baseboard_fab2_lib.baseboard_fab2(sch_1):page48_i111:DQ(20)" )
				( attribute "RELATIVE_PROPAGATION_DELAY_SCOPE" "G"
					( Parent
						( matchGroupRef "@baseboard_fab2_lib.baseboard_fab2(sch_1):\MG_DQ-DQS_NEAR_DIMM_NG_M_C_BYTE2\" )
					)
					( Status sCSetFlattened )
					( Origin gBackEnd )
				)
				( attribute "RELATIVE_PROPAGATION_DELAY" "0.00 MIL,195.00 MIL"
					( Parent
						( matchGroupRef "@baseboard_fab2_lib.baseboard_fab2(sch_1):\MG_DQ-DQS_NEAR_DIMM_NG_M_C_BYTE2\" )
					)
					( Units "uMatchProp" "ns" 1.000000)
					( Status sCSetFlattened )
					( Origin gBackEnd )
				)
				( attribute "RELATIVE_PROPAGATION_DELAY_SCOPE" "G"
					( Parent
						( matchGroupRef "@baseboard_fab2_lib.baseboard_fab2(sch_1):\MG_DQ_NEAR_DIMM_NG_M_C_BYTE2\" )
					)
					( Status sCSetFlattened )
					( Origin gBackEnd )
				)
				( attribute "RELATIVE_PROPAGATION_DELAY" "-50.00 MIL,50.00 MIL"
					( Parent
						( matchGroupRef "@baseboard_fab2_lib.baseboard_fab2(sch_1):\MG_DQ_NEAR_DIMM_NG_M_C_BYTE2\" )
					)
					( Units "uMatchProp" "ns" 1.000000)
					( Status sCSetFlattened )
					( Origin gBackEnd )
				)
			)
			( pinPair "@baseboard_fab2_lib.baseboard_fab2(sch_1):\PP4842\"
				( pinRef "@baseboard_fab2_lib.baseboard_fab2(sch_1):page25_i172:DDR2_DQ(21)" )
				( pinRef "@baseboard_fab2_lib.baseboard_fab2(sch_1):page47_i111:DQ(20)" )
				( attribute "RELATIVE_PROPAGATION_DELAY_SCOPE" "G"
					( Parent
						( matchGroupRef "@baseboard_fab2_lib.baseboard_fab2(sch_1):\MG_DQ-DQS_FAR_DIMM_NG_M_C_BYTE2\" )
					)
					( Status sCSetFlattened )
					( Origin gBackEnd )
				)
				( attribute "RELATIVE_PROPAGATION_DELAY" "0.00 MIL,195.00 MIL"
					( Parent
						( matchGroupRef "@baseboard_fab2_lib.baseboard_fab2(sch_1):\MG_DQ-DQS_FAR_DIMM_NG_M_C_BYTE2\" )
					)
					( Units "uMatchProp" "ns" 1.000000)
					( Status sCSetFlattened )
					( Origin gBackEnd )
				)
				( attribute "RELATIVE_PROPAGATION_DELAY_SCOPE" "G"
					( Parent
						( matchGroupRef "@baseboard_fab2_lib.baseboard_fab2(sch_1):\MG_DQ_FAR_DIMM_NG_M_C_BYTE2\" )
					)
					( Status sCSetFlattened )
					( Origin gBackEnd )
				)
				( attribute "RELATIVE_PROPAGATION_DELAY" "-50.00 MIL,50.00 MIL"
					( Parent
						( matchGroupRef "@baseboard_fab2_lib.baseboard_fab2(sch_1):\MG_DQ_FAR_DIMM_NG_M_C_BYTE2\" )
					)
					( Units "uMatchProp" "ns" 1.000000)
					( Status sCSetFlattened )
					( Origin gBackEnd )
				)
			)
			( pinPair "@baseboard_fab2_lib.baseboard_fab2(sch_1):\PP4844\"
				( pinRef "@baseboard_fab2_lib.baseboard_fab2(sch_1):page25_i172:DDR2_DQ(21)" )
				( pinRef "@baseboard_fab2_lib.baseboard_fab2(sch_1):page48_i111:DQ(21)" )
				( attribute "RELATIVE_PROPAGATION_DELAY_SCOPE" "G"
					( Parent
						( matchGroupRef "@baseboard_fab2_lib.baseboard_fab2(sch_1):\MG_DQ-DQS_NEAR_DIMM_NG_M_C_BYTE2\" )
					)
					( Status sCSetFlattened )
					( Origin gBackEnd )
				)
				( attribute "RELATIVE_PROPAGATION_DELAY" "0.00 MIL,195.00 MIL"
					( Parent
						( matchGroupRef "@baseboard_fab2_lib.baseboard_fab2(sch_1):\MG_DQ-DQS_NEAR_DIMM_NG_M_C_BYTE2\" )
					)
					( Units "uMatchProp" "ns" 1.000000)
					( Status sCSetFlattened )
					( Origin gBackEnd )
				)
				( attribute "RELATIVE_PROPAGATION_DELAY_SCOPE" "G"
					( Parent
						( matchGroupRef "@baseboard_fab2_lib.baseboard_fab2(sch_1):\MG_DQ_NEAR_DIMM_NG_M_C_BYTE2\" )
					)
					( Status sCSetFlattened )
					( Origin gBackEnd )
				)
				( attribute "RELATIVE_PROPAGATION_DELAY" "-50.00 MIL,50.00 MIL"
					( Parent
						( matchGroupRef "@baseboard_fab2_lib.baseboard_fab2(sch_1):\MG_DQ_NEAR_DIMM_NG_M_C_BYTE2\" )
					)
					( Units "uMatchProp" "ns" 1.000000)
					( Status sCSetFlattened )
					( Origin gBackEnd )
				)
			)
			( pinPair "@baseboard_fab2_lib.baseboard_fab2(sch_1):\PP4845\"
				( pinRef "@baseboard_fab2_lib.baseboard_fab2(sch_1):page25_i172:DDR2_DQ(22)" )
				( pinRef "@baseboard_fab2_lib.baseboard_fab2(sch_1):page47_i111:DQ(23)" )
				( attribute "RELATIVE_PROPAGATION_DELAY_SCOPE" "G"
					( Parent
						( matchGroupRef "@baseboard_fab2_lib.baseboard_fab2(sch_1):\MG_DQ-DQS_FAR_DIMM_NG_M_C_BYTE2\" )
					)
					( Status sCSetFlattened )
					( Origin gBackEnd )
				)
				( attribute "RELATIVE_PROPAGATION_DELAY" "0.00 MIL,195.00 MIL"
					( Parent
						( matchGroupRef "@baseboard_fab2_lib.baseboard_fab2(sch_1):\MG_DQ-DQS_FAR_DIMM_NG_M_C_BYTE2\" )
					)
					( Units "uMatchProp" "ns" 1.000000)
					( Status sCSetFlattened )
					( Origin gBackEnd )
				)
				( attribute "RELATIVE_PROPAGATION_DELAY_SCOPE" "G"
					( Parent
						( matchGroupRef "@baseboard_fab2_lib.baseboard_fab2(sch_1):\MG_DQ_FAR_DIMM_NG_M_C_BYTE2\" )
					)
					( Status sCSetFlattened )
					( Origin gBackEnd )
				)
				( attribute "RELATIVE_PROPAGATION_DELAY" "-50.00 MIL,50.00 MIL"
					( Parent
						( matchGroupRef "@baseboard_fab2_lib.baseboard_fab2(sch_1):\MG_DQ_FAR_DIMM_NG_M_C_BYTE2\" )
					)
					( Units "uMatchProp" "ns" 1.000000)
					( Status sCSetFlattened )
					( Origin gBackEnd )
				)
			)
			( pinPair "@baseboard_fab2_lib.baseboard_fab2(sch_1):\PP4847\"
				( pinRef "@baseboard_fab2_lib.baseboard_fab2(sch_1):page25_i172:DDR2_DQ(22)" )
				( pinRef "@baseboard_fab2_lib.baseboard_fab2(sch_1):page48_i111:DQ(22)" )
				( attribute "RELATIVE_PROPAGATION_DELAY_SCOPE" "G"
					( Parent
						( matchGroupRef "@baseboard_fab2_lib.baseboard_fab2(sch_1):\MG_DQ-DQS_NEAR_DIMM_NG_M_C_BYTE2\" )
					)
					( Status sCSetFlattened )
					( Origin gBackEnd )
				)
				( attribute "RELATIVE_PROPAGATION_DELAY" "0.00 MIL,195.00 MIL"
					( Parent
						( matchGroupRef "@baseboard_fab2_lib.baseboard_fab2(sch_1):\MG_DQ-DQS_NEAR_DIMM_NG_M_C_BYTE2\" )
					)
					( Units "uMatchProp" "ns" 1.000000)
					( Status sCSetFlattened )
					( Origin gBackEnd )
				)
				( attribute "RELATIVE_PROPAGATION_DELAY_SCOPE" "G"
					( Parent
						( matchGroupRef "@baseboard_fab2_lib.baseboard_fab2(sch_1):\MG_DQ_NEAR_DIMM_NG_M_C_BYTE2\" )
					)
					( Status sCSetFlattened )
					( Origin gBackEnd )
				)
				( attribute "RELATIVE_PROPAGATION_DELAY" "-50.00 MIL,50.00 MIL"
					( Parent
						( matchGroupRef "@baseboard_fab2_lib.baseboard_fab2(sch_1):\MG_DQ_NEAR_DIMM_NG_M_C_BYTE2\" )
					)
					( Units "uMatchProp" "ns" 1.000000)
					( Status sCSetFlattened )
					( Origin gBackEnd )
				)
			)
			( pinPair "@baseboard_fab2_lib.baseboard_fab2(sch_1):\PP4848\"
				( pinRef "@baseboard_fab2_lib.baseboard_fab2(sch_1):page25_i172:DDR2_DQ(23)" )
				( pinRef "@baseboard_fab2_lib.baseboard_fab2(sch_1):page47_i111:DQ(22)" )
				( attribute "RELATIVE_PROPAGATION_DELAY_SCOPE" "G"
					( Parent
						( matchGroupRef "@baseboard_fab2_lib.baseboard_fab2(sch_1):\MG_DQ-DQS_FAR_DIMM_NG_M_C_BYTE2\" )
					)
					( Status sCSetFlattened )
					( Origin gBackEnd )
				)
				( attribute "RELATIVE_PROPAGATION_DELAY" "0.00 MIL,195.00 MIL"
					( Parent
						( matchGroupRef "@baseboard_fab2_lib.baseboard_fab2(sch_1):\MG_DQ-DQS_FAR_DIMM_NG_M_C_BYTE2\" )
					)
					( Units "uMatchProp" "ns" 1.000000)
					( Status sCSetFlattened )
					( Origin gBackEnd )
				)
				( attribute "RELATIVE_PROPAGATION_DELAY_SCOPE" "G"
					( Parent
						( matchGroupRef "@baseboard_fab2_lib.baseboard_fab2(sch_1):\MG_DQ_FAR_DIMM_NG_M_C_BYTE2\" )
					)
					( Status sCSetFlattened )
					( Origin gBackEnd )
				)
				( attribute "RELATIVE_PROPAGATION_DELAY" "-50.00 MIL,50.00 MIL"
					( Parent
						( matchGroupRef "@baseboard_fab2_lib.baseboard_fab2(sch_1):\MG_DQ_FAR_DIMM_NG_M_C_BYTE2\" )
					)
					( Units "uMatchProp" "ns" 1.000000)
					( Status sCSetFlattened )
					( Origin gBackEnd )
				)
			)
			( pinPair "@baseboard_fab2_lib.baseboard_fab2(sch_1):\PP4850\"
				( pinRef "@baseboard_fab2_lib.baseboard_fab2(sch_1):page25_i172:DDR2_DQ(23)" )
				( pinRef "@baseboard_fab2_lib.baseboard_fab2(sch_1):page48_i111:DQ(23)" )
				( attribute "RELATIVE_PROPAGATION_DELAY_SCOPE" "G"
					( Parent
						( matchGroupRef "@baseboard_fab2_lib.baseboard_fab2(sch_1):\MG_DQ-DQS_NEAR_DIMM_NG_M_C_BYTE2\" )
					)
					( Status sCSetFlattened )
					( Origin gBackEnd )
				)
				( attribute "RELATIVE_PROPAGATION_DELAY" "0.00 MIL,195.00 MIL"
					( Parent
						( matchGroupRef "@baseboard_fab2_lib.baseboard_fab2(sch_1):\MG_DQ-DQS_NEAR_DIMM_NG_M_C_BYTE2\" )
					)
					( Units "uMatchProp" "ns" 1.000000)
					( Status sCSetFlattened )
					( Origin gBackEnd )
				)
				( attribute "RELATIVE_PROPAGATION_DELAY_SCOPE" "G"
					( Parent
						( matchGroupRef "@baseboard_fab2_lib.baseboard_fab2(sch_1):\MG_DQ_NEAR_DIMM_NG_M_C_BYTE2\" )
					)
					( Status sCSetFlattened )
					( Origin gBackEnd )
				)
				( attribute "RELATIVE_PROPAGATION_DELAY" "-50.00 MIL,50.00 MIL"
					( Parent
						( matchGroupRef "@baseboard_fab2_lib.baseboard_fab2(sch_1):\MG_DQ_NEAR_DIMM_NG_M_C_BYTE2\" )
					)
					( Units "uMatchProp" "ns" 1.000000)
					( Status sCSetFlattened )
					( Origin gBackEnd )
				)
			)
			( pinPair "@baseboard_fab2_lib.baseboard_fab2(sch_1):\PP4803\"
				( pinRef "@baseboard_fab2_lib.baseboard_fab2(sch_1):page25_i172:DDR2_DQ(24)" )
				( pinRef "@baseboard_fab2_lib.baseboard_fab2(sch_1):page47_i111:DQ(25)" )
				( attribute "RELATIVE_PROPAGATION_DELAY_SCOPE" "G"
					( Parent
						( matchGroupRef "@baseboard_fab2_lib.baseboard_fab2(sch_1):\MG_DQ-DQS_FAR_DIMM_NG_M_C_BYTE3\" )
					)
					( Status sCSetFlattened )
					( Origin gBackEnd )
				)
				( attribute "RELATIVE_PROPAGATION_DELAY" "0.00 MIL,195.00 MIL"
					( Parent
						( matchGroupRef "@baseboard_fab2_lib.baseboard_fab2(sch_1):\MG_DQ-DQS_FAR_DIMM_NG_M_C_BYTE3\" )
					)
					( Units "uMatchProp" "ns" 1.000000)
					( Status sCSetFlattened )
					( Origin gBackEnd )
				)
				( attribute "RELATIVE_PROPAGATION_DELAY_SCOPE" "G"
					( Parent
						( matchGroupRef "@baseboard_fab2_lib.baseboard_fab2(sch_1):\MG_DQ_FAR_DIMM_NG_M_C_BYTE3\" )
					)
					( Status sCSetFlattened )
					( Origin gBackEnd )
				)
				( attribute "RELATIVE_PROPAGATION_DELAY" "-50.00 MIL,50.00 MIL"
					( Parent
						( matchGroupRef "@baseboard_fab2_lib.baseboard_fab2(sch_1):\MG_DQ_FAR_DIMM_NG_M_C_BYTE3\" )
					)
					( Units "uMatchProp" "ns" 1.000000)
					( Status sCSetFlattened )
					( Origin gBackEnd )
				)
			)
			( pinPair "@baseboard_fab2_lib.baseboard_fab2(sch_1):\PP4805\"
				( pinRef "@baseboard_fab2_lib.baseboard_fab2(sch_1):page25_i172:DDR2_DQ(24)" )
				( pinRef "@baseboard_fab2_lib.baseboard_fab2(sch_1):page48_i111:DQ(24)" )
				( attribute "RELATIVE_PROPAGATION_DELAY_SCOPE" "G"
					( Parent
						( matchGroupRef "@baseboard_fab2_lib.baseboard_fab2(sch_1):\MG_DQ-DQS_NEAR_DIMM_NG_M_C_BYTE3\" )
					)
					( Status sCSetFlattened )
					( Origin gBackEnd )
				)
				( attribute "RELATIVE_PROPAGATION_DELAY" "0.00 MIL,195.00 MIL"
					( Parent
						( matchGroupRef "@baseboard_fab2_lib.baseboard_fab2(sch_1):\MG_DQ-DQS_NEAR_DIMM_NG_M_C_BYTE3\" )
					)
					( Units "uMatchProp" "ns" 1.000000)
					( Status sCSetFlattened )
					( Origin gBackEnd )
				)
				( attribute "RELATIVE_PROPAGATION_DELAY_SCOPE" "G"
					( Parent
						( matchGroupRef "@baseboard_fab2_lib.baseboard_fab2(sch_1):\MG_DQ_NEAR_DIMM_NG_M_C_BYTE3\" )
					)
					( Status sCSetFlattened )
					( Origin gBackEnd )
				)
				( attribute "RELATIVE_PROPAGATION_DELAY" "-50.00 MIL,50.00 MIL"
					( Parent
						( matchGroupRef "@baseboard_fab2_lib.baseboard_fab2(sch_1):\MG_DQ_NEAR_DIMM_NG_M_C_BYTE3\" )
					)
					( Units "uMatchProp" "ns" 1.000000)
					( Status sCSetFlattened )
					( Origin gBackEnd )
				)
			)
			( pinPair "@baseboard_fab2_lib.baseboard_fab2(sch_1):\PP4806\"
				( pinRef "@baseboard_fab2_lib.baseboard_fab2(sch_1):page25_i172:DDR2_DQ(25)" )
				( pinRef "@baseboard_fab2_lib.baseboard_fab2(sch_1):page47_i111:DQ(24)" )
				( attribute "RELATIVE_PROPAGATION_DELAY_SCOPE" "G"
					( Parent
						( matchGroupRef "@baseboard_fab2_lib.baseboard_fab2(sch_1):\MG_DQ-DQS_FAR_DIMM_NG_M_C_BYTE3\" )
					)
					( Status sCSetFlattened )
					( Origin gBackEnd )
				)
				( attribute "RELATIVE_PROPAGATION_DELAY" "0.00 MIL,195.00 MIL"
					( Parent
						( matchGroupRef "@baseboard_fab2_lib.baseboard_fab2(sch_1):\MG_DQ-DQS_FAR_DIMM_NG_M_C_BYTE3\" )
					)
					( Units "uMatchProp" "ns" 1.000000)
					( Status sCSetFlattened )
					( Origin gBackEnd )
				)
				( attribute "RELATIVE_PROPAGATION_DELAY_SCOPE" "G"
					( Parent
						( matchGroupRef "@baseboard_fab2_lib.baseboard_fab2(sch_1):\MG_DQ_FAR_DIMM_NG_M_C_BYTE3\" )
					)
					( Status sCSetFlattened )
					( Origin gBackEnd )
				)
				( attribute "RELATIVE_PROPAGATION_DELAY" "-50.00 MIL,50.00 MIL"
					( Parent
						( matchGroupRef "@baseboard_fab2_lib.baseboard_fab2(sch_1):\MG_DQ_FAR_DIMM_NG_M_C_BYTE3\" )
					)
					( Units "uMatchProp" "ns" 1.000000)
					( Status sCSetFlattened )
					( Origin gBackEnd )
				)
			)
			( pinPair "@baseboard_fab2_lib.baseboard_fab2(sch_1):\PP4808\"
				( pinRef "@baseboard_fab2_lib.baseboard_fab2(sch_1):page25_i172:DDR2_DQ(25)" )
				( pinRef "@baseboard_fab2_lib.baseboard_fab2(sch_1):page48_i111:DQ(25)" )
				( attribute "RELATIVE_PROPAGATION_DELAY_SCOPE" "G"
					( Parent
						( matchGroupRef "@baseboard_fab2_lib.baseboard_fab2(sch_1):\MG_DQ-DQS_NEAR_DIMM_NG_M_C_BYTE3\" )
					)
					( Status sCSetFlattened )
					( Origin gBackEnd )
				)
				( attribute "RELATIVE_PROPAGATION_DELAY" "0.00 MIL,195.00 MIL"
					( Parent
						( matchGroupRef "@baseboard_fab2_lib.baseboard_fab2(sch_1):\MG_DQ-DQS_NEAR_DIMM_NG_M_C_BYTE3\" )
					)
					( Units "uMatchProp" "ns" 1.000000)
					( Status sCSetFlattened )
					( Origin gBackEnd )
				)
				( attribute "RELATIVE_PROPAGATION_DELAY_SCOPE" "G"
					( Parent
						( matchGroupRef "@baseboard_fab2_lib.baseboard_fab2(sch_1):\MG_DQ_NEAR_DIMM_NG_M_C_BYTE3\" )
					)
					( Status sCSetFlattened )
					( Origin gBackEnd )
				)
				( attribute "RELATIVE_PROPAGATION_DELAY" "-50.00 MIL,50.00 MIL"
					( Parent
						( matchGroupRef "@baseboard_fab2_lib.baseboard_fab2(sch_1):\MG_DQ_NEAR_DIMM_NG_M_C_BYTE3\" )
					)
					( Units "uMatchProp" "ns" 1.000000)
					( Status sCSetFlattened )
					( Origin gBackEnd )
				)
			)
			( pinPair "@baseboard_fab2_lib.baseboard_fab2(sch_1):\PP4809\"
				( pinRef "@baseboard_fab2_lib.baseboard_fab2(sch_1):page25_i172:DDR2_DQ(26)" )
				( pinRef "@baseboard_fab2_lib.baseboard_fab2(sch_1):page47_i111:DQ(27)" )
				( attribute "RELATIVE_PROPAGATION_DELAY_SCOPE" "G"
					( Parent
						( matchGroupRef "@baseboard_fab2_lib.baseboard_fab2(sch_1):\MG_DQ-DQS_FAR_DIMM_NG_M_C_BYTE3\" )
					)
					( Status sCSetFlattened )
					( Origin gBackEnd )
				)
				( attribute "RELATIVE_PROPAGATION_DELAY" "0.00 MIL,195.00 MIL"
					( Parent
						( matchGroupRef "@baseboard_fab2_lib.baseboard_fab2(sch_1):\MG_DQ-DQS_FAR_DIMM_NG_M_C_BYTE3\" )
					)
					( Units "uMatchProp" "ns" 1.000000)
					( Status sCSetFlattened )
					( Origin gBackEnd )
				)
				( attribute "RELATIVE_PROPAGATION_DELAY_SCOPE" "G"
					( Parent
						( matchGroupRef "@baseboard_fab2_lib.baseboard_fab2(sch_1):\MG_DQ_FAR_DIMM_NG_M_C_BYTE3\" )
					)
					( Status sCSetFlattened )
					( Origin gBackEnd )
				)
				( attribute "RELATIVE_PROPAGATION_DELAY" "-50.00 MIL,50.00 MIL"
					( Parent
						( matchGroupRef "@baseboard_fab2_lib.baseboard_fab2(sch_1):\MG_DQ_FAR_DIMM_NG_M_C_BYTE3\" )
					)
					( Units "uMatchProp" "ns" 1.000000)
					( Status sCSetFlattened )
					( Origin gBackEnd )
				)
			)
			( pinPair "@baseboard_fab2_lib.baseboard_fab2(sch_1):\PP4811\"
				( pinRef "@baseboard_fab2_lib.baseboard_fab2(sch_1):page25_i172:DDR2_DQ(26)" )
				( pinRef "@baseboard_fab2_lib.baseboard_fab2(sch_1):page48_i111:DQ(26)" )
				( attribute "RELATIVE_PROPAGATION_DELAY_SCOPE" "G"
					( Parent
						( matchGroupRef "@baseboard_fab2_lib.baseboard_fab2(sch_1):\MG_DQ-DQS_NEAR_DIMM_NG_M_C_BYTE3\" )
					)
					( Status sCSetFlattened )
					( Origin gBackEnd )
				)
				( attribute "RELATIVE_PROPAGATION_DELAY" "0.00 MIL,195.00 MIL"
					( Parent
						( matchGroupRef "@baseboard_fab2_lib.baseboard_fab2(sch_1):\MG_DQ-DQS_NEAR_DIMM_NG_M_C_BYTE3\" )
					)
					( Units "uMatchProp" "ns" 1.000000)
					( Status sCSetFlattened )
					( Origin gBackEnd )
				)
				( attribute "RELATIVE_PROPAGATION_DELAY_SCOPE" "G"
					( Parent
						( matchGroupRef "@baseboard_fab2_lib.baseboard_fab2(sch_1):\MG_DQ_NEAR_DIMM_NG_M_C_BYTE3\" )
					)
					( Status sCSetFlattened )
					( Origin gBackEnd )
				)
				( attribute "RELATIVE_PROPAGATION_DELAY" "-50.00 MIL,50.00 MIL"
					( Parent
						( matchGroupRef "@baseboard_fab2_lib.baseboard_fab2(sch_1):\MG_DQ_NEAR_DIMM_NG_M_C_BYTE3\" )
					)
					( Units "uMatchProp" "ns" 1.000000)
					( Status sCSetFlattened )
					( Origin gBackEnd )
				)
			)
			( pinPair "@baseboard_fab2_lib.baseboard_fab2(sch_1):\PP4812\"
				( pinRef "@baseboard_fab2_lib.baseboard_fab2(sch_1):page25_i172:DDR2_DQ(27)" )
				( pinRef "@baseboard_fab2_lib.baseboard_fab2(sch_1):page47_i111:DQ(26)" )
				( attribute "RELATIVE_PROPAGATION_DELAY_SCOPE" "G"
					( Parent
						( matchGroupRef "@baseboard_fab2_lib.baseboard_fab2(sch_1):\MG_DQ-DQS_FAR_DIMM_NG_M_C_BYTE3\" )
					)
					( Status sCSetFlattened )
					( Origin gBackEnd )
				)
				( attribute "RELATIVE_PROPAGATION_DELAY" "0.00 MIL,195.00 MIL"
					( Parent
						( matchGroupRef "@baseboard_fab2_lib.baseboard_fab2(sch_1):\MG_DQ-DQS_FAR_DIMM_NG_M_C_BYTE3\" )
					)
					( Units "uMatchProp" "ns" 1.000000)
					( Status sCSetFlattened )
					( Origin gBackEnd )
				)
				( attribute "RELATIVE_PROPAGATION_DELAY_SCOPE" "G"
					( Parent
						( matchGroupRef "@baseboard_fab2_lib.baseboard_fab2(sch_1):\MG_DQ_FAR_DIMM_NG_M_C_BYTE3\" )
					)
					( Status sCSetFlattened )
					( Origin gBackEnd )
				)
				( attribute "RELATIVE_PROPAGATION_DELAY" "-50.00 MIL,50.00 MIL"
					( Parent
						( matchGroupRef "@baseboard_fab2_lib.baseboard_fab2(sch_1):\MG_DQ_FAR_DIMM_NG_M_C_BYTE3\" )
					)
					( Units "uMatchProp" "ns" 1.000000)
					( Status sCSetFlattened )
					( Origin gBackEnd )
				)
			)
			( pinPair "@baseboard_fab2_lib.baseboard_fab2(sch_1):\PP4814\"
				( pinRef "@baseboard_fab2_lib.baseboard_fab2(sch_1):page25_i172:DDR2_DQ(27)" )
				( pinRef "@baseboard_fab2_lib.baseboard_fab2(sch_1):page48_i111:DQ(27)" )
				( attribute "RELATIVE_PROPAGATION_DELAY_SCOPE" "G"
					( Parent
						( matchGroupRef "@baseboard_fab2_lib.baseboard_fab2(sch_1):\MG_DQ-DQS_NEAR_DIMM_NG_M_C_BYTE3\" )
					)
					( Status sCSetFlattened )
					( Origin gBackEnd )
				)
				( attribute "RELATIVE_PROPAGATION_DELAY" "0.00 MIL,195.00 MIL"
					( Parent
						( matchGroupRef "@baseboard_fab2_lib.baseboard_fab2(sch_1):\MG_DQ-DQS_NEAR_DIMM_NG_M_C_BYTE3\" )
					)
					( Units "uMatchProp" "ns" 1.000000)
					( Status sCSetFlattened )
					( Origin gBackEnd )
				)
				( attribute "RELATIVE_PROPAGATION_DELAY_SCOPE" "G"
					( Parent
						( matchGroupRef "@baseboard_fab2_lib.baseboard_fab2(sch_1):\MG_DQ_NEAR_DIMM_NG_M_C_BYTE3\" )
					)
					( Status sCSetFlattened )
					( Origin gBackEnd )
				)
				( attribute "RELATIVE_PROPAGATION_DELAY" "-50.00 MIL,50.00 MIL"
					( Parent
						( matchGroupRef "@baseboard_fab2_lib.baseboard_fab2(sch_1):\MG_DQ_NEAR_DIMM_NG_M_C_BYTE3\" )
					)
					( Units "uMatchProp" "ns" 1.000000)
					( Status sCSetFlattened )
					( Origin gBackEnd )
				)
			)
			( pinPair "@baseboard_fab2_lib.baseboard_fab2(sch_1):\PP4815\"
				( pinRef "@baseboard_fab2_lib.baseboard_fab2(sch_1):page25_i172:DDR2_DQ(28)" )
				( pinRef "@baseboard_fab2_lib.baseboard_fab2(sch_1):page47_i111:DQ(29)" )
				( attribute "RELATIVE_PROPAGATION_DELAY_SCOPE" "G"
					( Parent
						( matchGroupRef "@baseboard_fab2_lib.baseboard_fab2(sch_1):\MG_DQ-DQS_FAR_DIMM_NG_M_C_BYTE3\" )
					)
					( Status sCSetFlattened )
					( Origin gBackEnd )
				)
				( attribute "RELATIVE_PROPAGATION_DELAY" "0.00 MIL,195.00 MIL"
					( Parent
						( matchGroupRef "@baseboard_fab2_lib.baseboard_fab2(sch_1):\MG_DQ-DQS_FAR_DIMM_NG_M_C_BYTE3\" )
					)
					( Units "uMatchProp" "ns" 1.000000)
					( Status sCSetFlattened )
					( Origin gBackEnd )
				)
				( attribute "RELATIVE_PROPAGATION_DELAY_SCOPE" "G"
					( Parent
						( matchGroupRef "@baseboard_fab2_lib.baseboard_fab2(sch_1):\MG_DQ_FAR_DIMM_NG_M_C_BYTE3\" )
					)
					( Status sCSetFlattened )
					( Origin gBackEnd )
				)
				( attribute "RELATIVE_PROPAGATION_DELAY" "-50.00 MIL,50.00 MIL"
					( Parent
						( matchGroupRef "@baseboard_fab2_lib.baseboard_fab2(sch_1):\MG_DQ_FAR_DIMM_NG_M_C_BYTE3\" )
					)
					( Units "uMatchProp" "ns" 1.000000)
					( Status sCSetFlattened )
					( Origin gBackEnd )
				)
			)
			( pinPair "@baseboard_fab2_lib.baseboard_fab2(sch_1):\PP4817\"
				( pinRef "@baseboard_fab2_lib.baseboard_fab2(sch_1):page25_i172:DDR2_DQ(28)" )
				( pinRef "@baseboard_fab2_lib.baseboard_fab2(sch_1):page48_i111:DQ(28)" )
				( attribute "RELATIVE_PROPAGATION_DELAY_SCOPE" "G"
					( Parent
						( matchGroupRef "@baseboard_fab2_lib.baseboard_fab2(sch_1):\MG_DQ-DQS_NEAR_DIMM_NG_M_C_BYTE3\" )
					)
					( Status sCSetFlattened )
					( Origin gBackEnd )
				)
				( attribute "RELATIVE_PROPAGATION_DELAY" "0.00 MIL,195.00 MIL"
					( Parent
						( matchGroupRef "@baseboard_fab2_lib.baseboard_fab2(sch_1):\MG_DQ-DQS_NEAR_DIMM_NG_M_C_BYTE3\" )
					)
					( Units "uMatchProp" "ns" 1.000000)
					( Status sCSetFlattened )
					( Origin gBackEnd )
				)
				( attribute "RELATIVE_PROPAGATION_DELAY_SCOPE" "G"
					( Parent
						( matchGroupRef "@baseboard_fab2_lib.baseboard_fab2(sch_1):\MG_DQ_NEAR_DIMM_NG_M_C_BYTE3\" )
					)
					( Status sCSetFlattened )
					( Origin gBackEnd )
				)
				( attribute "RELATIVE_PROPAGATION_DELAY" "-50.00 MIL,50.00 MIL"
					( Parent
						( matchGroupRef "@baseboard_fab2_lib.baseboard_fab2(sch_1):\MG_DQ_NEAR_DIMM_NG_M_C_BYTE3\" )
					)
					( Units "uMatchProp" "ns" 1.000000)
					( Status sCSetFlattened )
					( Origin gBackEnd )
				)
			)
			( pinPair "@baseboard_fab2_lib.baseboard_fab2(sch_1):\PP4818\"
				( pinRef "@baseboard_fab2_lib.baseboard_fab2(sch_1):page25_i172:DDR2_DQ(29)" )
				( pinRef "@baseboard_fab2_lib.baseboard_fab2(sch_1):page47_i111:DQ(28)" )
				( attribute "RELATIVE_PROPAGATION_DELAY_SCOPE" "G"
					( Parent
						( matchGroupRef "@baseboard_fab2_lib.baseboard_fab2(sch_1):\MG_DQ-DQS_FAR_DIMM_NG_M_C_BYTE3\" )
					)
					( Status sCSetFlattened )
					( Origin gBackEnd )
				)
				( attribute "RELATIVE_PROPAGATION_DELAY" "0.00 MIL,195.00 MIL"
					( Parent
						( matchGroupRef "@baseboard_fab2_lib.baseboard_fab2(sch_1):\MG_DQ-DQS_FAR_DIMM_NG_M_C_BYTE3\" )
					)
					( Units "uMatchProp" "ns" 1.000000)
					( Status sCSetFlattened )
					( Origin gBackEnd )
				)
				( attribute "RELATIVE_PROPAGATION_DELAY_SCOPE" "G"
					( Parent
						( matchGroupRef "@baseboard_fab2_lib.baseboard_fab2(sch_1):\MG_DQ_FAR_DIMM_NG_M_C_BYTE3\" )
					)
					( Status sCSetFlattened )
					( Origin gBackEnd )
				)
				( attribute "RELATIVE_PROPAGATION_DELAY" "-50.00 MIL,50.00 MIL"
					( Parent
						( matchGroupRef "@baseboard_fab2_lib.baseboard_fab2(sch_1):\MG_DQ_FAR_DIMM_NG_M_C_BYTE3\" )
					)
					( Units "uMatchProp" "ns" 1.000000)
					( Status sCSetFlattened )
					( Origin gBackEnd )
				)
			)
			( pinPair "@baseboard_fab2_lib.baseboard_fab2(sch_1):\PP4820\"
				( pinRef "@baseboard_fab2_lib.baseboard_fab2(sch_1):page25_i172:DDR2_DQ(29)" )
				( pinRef "@baseboard_fab2_lib.baseboard_fab2(sch_1):page48_i111:DQ(29)" )
				( attribute "RELATIVE_PROPAGATION_DELAY_SCOPE" "G"
					( Parent
						( matchGroupRef "@baseboard_fab2_lib.baseboard_fab2(sch_1):\MG_DQ-DQS_NEAR_DIMM_NG_M_C_BYTE3\" )
					)
					( Status sCSetFlattened )
					( Origin gBackEnd )
				)
				( attribute "RELATIVE_PROPAGATION_DELAY" "0.00 MIL,195.00 MIL"
					( Parent
						( matchGroupRef "@baseboard_fab2_lib.baseboard_fab2(sch_1):\MG_DQ-DQS_NEAR_DIMM_NG_M_C_BYTE3\" )
					)
					( Units "uMatchProp" "ns" 1.000000)
					( Status sCSetFlattened )
					( Origin gBackEnd )
				)
				( attribute "RELATIVE_PROPAGATION_DELAY_SCOPE" "G"
					( Parent
						( matchGroupRef "@baseboard_fab2_lib.baseboard_fab2(sch_1):\MG_DQ_NEAR_DIMM_NG_M_C_BYTE3\" )
					)
					( Status sCSetFlattened )
					( Origin gBackEnd )
				)
				( attribute "RELATIVE_PROPAGATION_DELAY" "-50.00 MIL,50.00 MIL"
					( Parent
						( matchGroupRef "@baseboard_fab2_lib.baseboard_fab2(sch_1):\MG_DQ_NEAR_DIMM_NG_M_C_BYTE3\" )
					)
					( Units "uMatchProp" "ns" 1.000000)
					( Status sCSetFlattened )
					( Origin gBackEnd )
				)
			)
			( pinPair "@baseboard_fab2_lib.baseboard_fab2(sch_1):\PP4821\"
				( pinRef "@baseboard_fab2_lib.baseboard_fab2(sch_1):page25_i172:DDR2_DQ(30)" )
				( pinRef "@baseboard_fab2_lib.baseboard_fab2(sch_1):page47_i111:DQ(31)" )
				( attribute "RELATIVE_PROPAGATION_DELAY_SCOPE" "G"
					( Parent
						( matchGroupRef "@baseboard_fab2_lib.baseboard_fab2(sch_1):\MG_DQ-DQS_FAR_DIMM_NG_M_C_BYTE3\" )
					)
					( Status sCSetFlattened )
					( Origin gBackEnd )
				)
				( attribute "RELATIVE_PROPAGATION_DELAY" "0.00 MIL,195.00 MIL"
					( Parent
						( matchGroupRef "@baseboard_fab2_lib.baseboard_fab2(sch_1):\MG_DQ-DQS_FAR_DIMM_NG_M_C_BYTE3\" )
					)
					( Units "uMatchProp" "ns" 1.000000)
					( Status sCSetFlattened )
					( Origin gBackEnd )
				)
				( attribute "RELATIVE_PROPAGATION_DELAY_SCOPE" "G"
					( Parent
						( matchGroupRef "@baseboard_fab2_lib.baseboard_fab2(sch_1):\MG_DQ_FAR_DIMM_NG_M_C_BYTE3\" )
					)
					( Status sCSetFlattened )
					( Origin gBackEnd )
				)
				( attribute "RELATIVE_PROPAGATION_DELAY" "-50.00 MIL,50.00 MIL"
					( Parent
						( matchGroupRef "@baseboard_fab2_lib.baseboard_fab2(sch_1):\MG_DQ_FAR_DIMM_NG_M_C_BYTE3\" )
					)
					( Units "uMatchProp" "ns" 1.000000)
					( Status sCSetFlattened )
					( Origin gBackEnd )
				)
			)
			( pinPair "@baseboard_fab2_lib.baseboard_fab2(sch_1):\PP4823\"
				( pinRef "@baseboard_fab2_lib.baseboard_fab2(sch_1):page25_i172:DDR2_DQ(30)" )
				( pinRef "@baseboard_fab2_lib.baseboard_fab2(sch_1):page48_i111:DQ(30)" )
				( attribute "RELATIVE_PROPAGATION_DELAY_SCOPE" "G"
					( Parent
						( matchGroupRef "@baseboard_fab2_lib.baseboard_fab2(sch_1):\MG_DQ-DQS_NEAR_DIMM_NG_M_C_BYTE3\" )
					)
					( Status sCSetFlattened )
					( Origin gBackEnd )
				)
				( attribute "RELATIVE_PROPAGATION_DELAY" "0.00 MIL,195.00 MIL"
					( Parent
						( matchGroupRef "@baseboard_fab2_lib.baseboard_fab2(sch_1):\MG_DQ-DQS_NEAR_DIMM_NG_M_C_BYTE3\" )
					)
					( Units "uMatchProp" "ns" 1.000000)
					( Status sCSetFlattened )
					( Origin gBackEnd )
				)
				( attribute "RELATIVE_PROPAGATION_DELAY_SCOPE" "G"
					( Parent
						( matchGroupRef "@baseboard_fab2_lib.baseboard_fab2(sch_1):\MG_DQ_NEAR_DIMM_NG_M_C_BYTE3\" )
					)
					( Status sCSetFlattened )
					( Origin gBackEnd )
				)
				( attribute "RELATIVE_PROPAGATION_DELAY" "-50.00 MIL,50.00 MIL"
					( Parent
						( matchGroupRef "@baseboard_fab2_lib.baseboard_fab2(sch_1):\MG_DQ_NEAR_DIMM_NG_M_C_BYTE3\" )
					)
					( Units "uMatchProp" "ns" 1.000000)
					( Status sCSetFlattened )
					( Origin gBackEnd )
				)
			)
			( pinPair "@baseboard_fab2_lib.baseboard_fab2(sch_1):\PP4824\"
				( pinRef "@baseboard_fab2_lib.baseboard_fab2(sch_1):page25_i172:DDR2_DQ(31)" )
				( pinRef "@baseboard_fab2_lib.baseboard_fab2(sch_1):page47_i111:DQ(30)" )
				( attribute "RELATIVE_PROPAGATION_DELAY_SCOPE" "G"
					( Parent
						( matchGroupRef "@baseboard_fab2_lib.baseboard_fab2(sch_1):\MG_DQ-DQS_FAR_DIMM_NG_M_C_BYTE3\" )
					)
					( Status sCSetFlattened )
					( Origin gBackEnd )
				)
				( attribute "RELATIVE_PROPAGATION_DELAY" "0.00 MIL,195.00 MIL"
					( Parent
						( matchGroupRef "@baseboard_fab2_lib.baseboard_fab2(sch_1):\MG_DQ-DQS_FAR_DIMM_NG_M_C_BYTE3\" )
					)
					( Units "uMatchProp" "ns" 1.000000)
					( Status sCSetFlattened )
					( Origin gBackEnd )
				)
				( attribute "RELATIVE_PROPAGATION_DELAY_SCOPE" "G"
					( Parent
						( matchGroupRef "@baseboard_fab2_lib.baseboard_fab2(sch_1):\MG_DQ_FAR_DIMM_NG_M_C_BYTE3\" )
					)
					( Status sCSetFlattened )
					( Origin gBackEnd )
				)
				( attribute "RELATIVE_PROPAGATION_DELAY" "-50.00 MIL,50.00 MIL"
					( Parent
						( matchGroupRef "@baseboard_fab2_lib.baseboard_fab2(sch_1):\MG_DQ_FAR_DIMM_NG_M_C_BYTE3\" )
					)
					( Units "uMatchProp" "ns" 1.000000)
					( Status sCSetFlattened )
					( Origin gBackEnd )
				)
			)
			( pinPair "@baseboard_fab2_lib.baseboard_fab2(sch_1):\PP4826\"
				( pinRef "@baseboard_fab2_lib.baseboard_fab2(sch_1):page25_i172:DDR2_DQ(31)" )
				( pinRef "@baseboard_fab2_lib.baseboard_fab2(sch_1):page48_i111:DQ(31)" )
				( attribute "RELATIVE_PROPAGATION_DELAY_SCOPE" "G"
					( Parent
						( matchGroupRef "@baseboard_fab2_lib.baseboard_fab2(sch_1):\MG_DQ-DQS_NEAR_DIMM_NG_M_C_BYTE3\" )
					)
					( Status sCSetFlattened )
					( Origin gBackEnd )
				)
				( attribute "RELATIVE_PROPAGATION_DELAY" "0.00 MIL,195.00 MIL"
					( Parent
						( matchGroupRef "@baseboard_fab2_lib.baseboard_fab2(sch_1):\MG_DQ-DQS_NEAR_DIMM_NG_M_C_BYTE3\" )
					)
					( Units "uMatchProp" "ns" 1.000000)
					( Status sCSetFlattened )
					( Origin gBackEnd )
				)
				( attribute "RELATIVE_PROPAGATION_DELAY_SCOPE" "G"
					( Parent
						( matchGroupRef "@baseboard_fab2_lib.baseboard_fab2(sch_1):\MG_DQ_NEAR_DIMM_NG_M_C_BYTE3\" )
					)
					( Status sCSetFlattened )
					( Origin gBackEnd )
				)
				( attribute "RELATIVE_PROPAGATION_DELAY" "-50.00 MIL,50.00 MIL"
					( Parent
						( matchGroupRef "@baseboard_fab2_lib.baseboard_fab2(sch_1):\MG_DQ_NEAR_DIMM_NG_M_C_BYTE3\" )
					)
					( Units "uMatchProp" "ns" 1.000000)
					( Status sCSetFlattened )
					( Origin gBackEnd )
				)
			)
			( pinPair "@baseboard_fab2_lib.baseboard_fab2(sch_1):\PP4779\"
				( pinRef "@baseboard_fab2_lib.baseboard_fab2(sch_1):page25_i172:DDR2_DQ(32)" )
				( pinRef "@baseboard_fab2_lib.baseboard_fab2(sch_1):page47_i111:DQ(33)" )
				( attribute "RELATIVE_PROPAGATION_DELAY_SCOPE" "G"
					( Parent
						( matchGroupRef "@baseboard_fab2_lib.baseboard_fab2(sch_1):\MG_DQ-DQS_FAR_DIMM_NG_M_C_BYTE4\" )
					)
					( Status sCSetFlattened )
					( Origin gBackEnd )
				)
				( attribute "RELATIVE_PROPAGATION_DELAY" "0.00 MIL,195.00 MIL"
					( Parent
						( matchGroupRef "@baseboard_fab2_lib.baseboard_fab2(sch_1):\MG_DQ-DQS_FAR_DIMM_NG_M_C_BYTE4\" )
					)
					( Units "uMatchProp" "ns" 1.000000)
					( Status sCSetFlattened )
					( Origin gBackEnd )
				)
				( attribute "RELATIVE_PROPAGATION_DELAY_SCOPE" "G"
					( Parent
						( matchGroupRef "@baseboard_fab2_lib.baseboard_fab2(sch_1):\MG_DQ_FAR_DIMM_NG_M_C_BYTE4\" )
					)
					( Status sCSetFlattened )
					( Origin gBackEnd )
				)
				( attribute "RELATIVE_PROPAGATION_DELAY" "-50.00 MIL,50.00 MIL"
					( Parent
						( matchGroupRef "@baseboard_fab2_lib.baseboard_fab2(sch_1):\MG_DQ_FAR_DIMM_NG_M_C_BYTE4\" )
					)
					( Units "uMatchProp" "ns" 1.000000)
					( Status sCSetFlattened )
					( Origin gBackEnd )
				)
			)
			( pinPair "@baseboard_fab2_lib.baseboard_fab2(sch_1):\PP4781\"
				( pinRef "@baseboard_fab2_lib.baseboard_fab2(sch_1):page25_i172:DDR2_DQ(32)" )
				( pinRef "@baseboard_fab2_lib.baseboard_fab2(sch_1):page48_i111:DQ(32)" )
				( attribute "RELATIVE_PROPAGATION_DELAY_SCOPE" "G"
					( Parent
						( matchGroupRef "@baseboard_fab2_lib.baseboard_fab2(sch_1):\MG_DQ-DQS_NEAR_DIMM_NG_M_C_BYTE4\" )
					)
					( Status sCSetFlattened )
					( Origin gBackEnd )
				)
				( attribute "RELATIVE_PROPAGATION_DELAY" "0.00 MIL,195.00 MIL"
					( Parent
						( matchGroupRef "@baseboard_fab2_lib.baseboard_fab2(sch_1):\MG_DQ-DQS_NEAR_DIMM_NG_M_C_BYTE4\" )
					)
					( Units "uMatchProp" "ns" 1.000000)
					( Status sCSetFlattened )
					( Origin gBackEnd )
				)
				( attribute "RELATIVE_PROPAGATION_DELAY_SCOPE" "G"
					( Parent
						( matchGroupRef "@baseboard_fab2_lib.baseboard_fab2(sch_1):\MG_DQ_NEAR_DIMM_NG_M_C_BYTE4\" )
					)
					( Status sCSetFlattened )
					( Origin gBackEnd )
				)
				( attribute "RELATIVE_PROPAGATION_DELAY" "-50.00 MIL,50.00 MIL"
					( Parent
						( matchGroupRef "@baseboard_fab2_lib.baseboard_fab2(sch_1):\MG_DQ_NEAR_DIMM_NG_M_C_BYTE4\" )
					)
					( Units "uMatchProp" "ns" 1.000000)
					( Status sCSetFlattened )
					( Origin gBackEnd )
				)
			)
			( pinPair "@baseboard_fab2_lib.baseboard_fab2(sch_1):\PP4782\"
				( pinRef "@baseboard_fab2_lib.baseboard_fab2(sch_1):page25_i172:DDR2_DQ(33)" )
				( pinRef "@baseboard_fab2_lib.baseboard_fab2(sch_1):page47_i111:DQ(32)" )
				( attribute "RELATIVE_PROPAGATION_DELAY_SCOPE" "G"
					( Parent
						( matchGroupRef "@baseboard_fab2_lib.baseboard_fab2(sch_1):\MG_DQ-DQS_FAR_DIMM_NG_M_C_BYTE4\" )
					)
					( Status sCSetFlattened )
					( Origin gBackEnd )
				)
				( attribute "RELATIVE_PROPAGATION_DELAY" "0.00 MIL,195.00 MIL"
					( Parent
						( matchGroupRef "@baseboard_fab2_lib.baseboard_fab2(sch_1):\MG_DQ-DQS_FAR_DIMM_NG_M_C_BYTE4\" )
					)
					( Units "uMatchProp" "ns" 1.000000)
					( Status sCSetFlattened )
					( Origin gBackEnd )
				)
				( attribute "RELATIVE_PROPAGATION_DELAY_SCOPE" "G"
					( Parent
						( matchGroupRef "@baseboard_fab2_lib.baseboard_fab2(sch_1):\MG_DQ_FAR_DIMM_NG_M_C_BYTE4\" )
					)
					( Status sCSetFlattened )
					( Origin gBackEnd )
				)
				( attribute "RELATIVE_PROPAGATION_DELAY" "-50.00 MIL,50.00 MIL"
					( Parent
						( matchGroupRef "@baseboard_fab2_lib.baseboard_fab2(sch_1):\MG_DQ_FAR_DIMM_NG_M_C_BYTE4\" )
					)
					( Units "uMatchProp" "ns" 1.000000)
					( Status sCSetFlattened )
					( Origin gBackEnd )
				)
			)
			( pinPair "@baseboard_fab2_lib.baseboard_fab2(sch_1):\PP4784\"
				( pinRef "@baseboard_fab2_lib.baseboard_fab2(sch_1):page25_i172:DDR2_DQ(33)" )
				( pinRef "@baseboard_fab2_lib.baseboard_fab2(sch_1):page48_i111:DQ(33)" )
				( attribute "RELATIVE_PROPAGATION_DELAY_SCOPE" "G"
					( Parent
						( matchGroupRef "@baseboard_fab2_lib.baseboard_fab2(sch_1):\MG_DQ-DQS_NEAR_DIMM_NG_M_C_BYTE4\" )
					)
					( Status sCSetFlattened )
					( Origin gBackEnd )
				)
				( attribute "RELATIVE_PROPAGATION_DELAY" "0.00 MIL,195.00 MIL"
					( Parent
						( matchGroupRef "@baseboard_fab2_lib.baseboard_fab2(sch_1):\MG_DQ-DQS_NEAR_DIMM_NG_M_C_BYTE4\" )
					)
					( Units "uMatchProp" "ns" 1.000000)
					( Status sCSetFlattened )
					( Origin gBackEnd )
				)
				( attribute "RELATIVE_PROPAGATION_DELAY_SCOPE" "G"
					( Parent
						( matchGroupRef "@baseboard_fab2_lib.baseboard_fab2(sch_1):\MG_DQ_NEAR_DIMM_NG_M_C_BYTE4\" )
					)
					( Status sCSetFlattened )
					( Origin gBackEnd )
				)
				( attribute "RELATIVE_PROPAGATION_DELAY" "-50.00 MIL,50.00 MIL"
					( Parent
						( matchGroupRef "@baseboard_fab2_lib.baseboard_fab2(sch_1):\MG_DQ_NEAR_DIMM_NG_M_C_BYTE4\" )
					)
					( Units "uMatchProp" "ns" 1.000000)
					( Status sCSetFlattened )
					( Origin gBackEnd )
				)
			)
			( pinPair "@baseboard_fab2_lib.baseboard_fab2(sch_1):\PP4785\"
				( pinRef "@baseboard_fab2_lib.baseboard_fab2(sch_1):page25_i172:DDR2_DQ(34)" )
				( pinRef "@baseboard_fab2_lib.baseboard_fab2(sch_1):page47_i111:DQ(35)" )
				( attribute "RELATIVE_PROPAGATION_DELAY_SCOPE" "G"
					( Parent
						( matchGroupRef "@baseboard_fab2_lib.baseboard_fab2(sch_1):\MG_DQ-DQS_FAR_DIMM_NG_M_C_BYTE4\" )
					)
					( Status sCSetFlattened )
					( Origin gBackEnd )
				)
				( attribute "RELATIVE_PROPAGATION_DELAY" "0.00 MIL,195.00 MIL"
					( Parent
						( matchGroupRef "@baseboard_fab2_lib.baseboard_fab2(sch_1):\MG_DQ-DQS_FAR_DIMM_NG_M_C_BYTE4\" )
					)
					( Units "uMatchProp" "ns" 1.000000)
					( Status sCSetFlattened )
					( Origin gBackEnd )
				)
				( attribute "RELATIVE_PROPAGATION_DELAY_SCOPE" "G"
					( Parent
						( matchGroupRef "@baseboard_fab2_lib.baseboard_fab2(sch_1):\MG_DQ_FAR_DIMM_NG_M_C_BYTE4\" )
					)
					( Status sCSetFlattened )
					( Origin gBackEnd )
				)
				( attribute "RELATIVE_PROPAGATION_DELAY" "-50.00 MIL,50.00 MIL"
					( Parent
						( matchGroupRef "@baseboard_fab2_lib.baseboard_fab2(sch_1):\MG_DQ_FAR_DIMM_NG_M_C_BYTE4\" )
					)
					( Units "uMatchProp" "ns" 1.000000)
					( Status sCSetFlattened )
					( Origin gBackEnd )
				)
			)
			( pinPair "@baseboard_fab2_lib.baseboard_fab2(sch_1):\PP4787\"
				( pinRef "@baseboard_fab2_lib.baseboard_fab2(sch_1):page25_i172:DDR2_DQ(34)" )
				( pinRef "@baseboard_fab2_lib.baseboard_fab2(sch_1):page48_i111:DQ(34)" )
				( attribute "RELATIVE_PROPAGATION_DELAY_SCOPE" "G"
					( Parent
						( matchGroupRef "@baseboard_fab2_lib.baseboard_fab2(sch_1):\MG_DQ-DQS_NEAR_DIMM_NG_M_C_BYTE4\" )
					)
					( Status sCSetFlattened )
					( Origin gBackEnd )
				)
				( attribute "RELATIVE_PROPAGATION_DELAY" "0.00 MIL,195.00 MIL"
					( Parent
						( matchGroupRef "@baseboard_fab2_lib.baseboard_fab2(sch_1):\MG_DQ-DQS_NEAR_DIMM_NG_M_C_BYTE4\" )
					)
					( Units "uMatchProp" "ns" 1.000000)
					( Status sCSetFlattened )
					( Origin gBackEnd )
				)
				( attribute "RELATIVE_PROPAGATION_DELAY_SCOPE" "G"
					( Parent
						( matchGroupRef "@baseboard_fab2_lib.baseboard_fab2(sch_1):\MG_DQ_NEAR_DIMM_NG_M_C_BYTE4\" )
					)
					( Status sCSetFlattened )
					( Origin gBackEnd )
				)
				( attribute "RELATIVE_PROPAGATION_DELAY" "-50.00 MIL,50.00 MIL"
					( Parent
						( matchGroupRef "@baseboard_fab2_lib.baseboard_fab2(sch_1):\MG_DQ_NEAR_DIMM_NG_M_C_BYTE4\" )
					)
					( Units "uMatchProp" "ns" 1.000000)
					( Status sCSetFlattened )
					( Origin gBackEnd )
				)
			)
			( pinPair "@baseboard_fab2_lib.baseboard_fab2(sch_1):\PP4788\"
				( pinRef "@baseboard_fab2_lib.baseboard_fab2(sch_1):page25_i172:DDR2_DQ(35)" )
				( pinRef "@baseboard_fab2_lib.baseboard_fab2(sch_1):page47_i111:DQ(34)" )
				( attribute "RELATIVE_PROPAGATION_DELAY_SCOPE" "G"
					( Parent
						( matchGroupRef "@baseboard_fab2_lib.baseboard_fab2(sch_1):\MG_DQ-DQS_FAR_DIMM_NG_M_C_BYTE4\" )
					)
					( Status sCSetFlattened )
					( Origin gBackEnd )
				)
				( attribute "RELATIVE_PROPAGATION_DELAY" "0.00 MIL,195.00 MIL"
					( Parent
						( matchGroupRef "@baseboard_fab2_lib.baseboard_fab2(sch_1):\MG_DQ-DQS_FAR_DIMM_NG_M_C_BYTE4\" )
					)
					( Units "uMatchProp" "ns" 1.000000)
					( Status sCSetFlattened )
					( Origin gBackEnd )
				)
				( attribute "RELATIVE_PROPAGATION_DELAY_SCOPE" "G"
					( Parent
						( matchGroupRef "@baseboard_fab2_lib.baseboard_fab2(sch_1):\MG_DQ_FAR_DIMM_NG_M_C_BYTE4\" )
					)
					( Status sCSetFlattened )
					( Origin gBackEnd )
				)
				( attribute "RELATIVE_PROPAGATION_DELAY" "-50.00 MIL,50.00 MIL"
					( Parent
						( matchGroupRef "@baseboard_fab2_lib.baseboard_fab2(sch_1):\MG_DQ_FAR_DIMM_NG_M_C_BYTE4\" )
					)
					( Units "uMatchProp" "ns" 1.000000)
					( Status sCSetFlattened )
					( Origin gBackEnd )
				)
			)
			( pinPair "@baseboard_fab2_lib.baseboard_fab2(sch_1):\PP4790\"
				( pinRef "@baseboard_fab2_lib.baseboard_fab2(sch_1):page25_i172:DDR2_DQ(35)" )
				( pinRef "@baseboard_fab2_lib.baseboard_fab2(sch_1):page48_i111:DQ(35)" )
				( attribute "RELATIVE_PROPAGATION_DELAY_SCOPE" "G"
					( Parent
						( matchGroupRef "@baseboard_fab2_lib.baseboard_fab2(sch_1):\MG_DQ-DQS_NEAR_DIMM_NG_M_C_BYTE4\" )
					)
					( Status sCSetFlattened )
					( Origin gBackEnd )
				)
				( attribute "RELATIVE_PROPAGATION_DELAY" "0.00 MIL,195.00 MIL"
					( Parent
						( matchGroupRef "@baseboard_fab2_lib.baseboard_fab2(sch_1):\MG_DQ-DQS_NEAR_DIMM_NG_M_C_BYTE4\" )
					)
					( Units "uMatchProp" "ns" 1.000000)
					( Status sCSetFlattened )
					( Origin gBackEnd )
				)
				( attribute "RELATIVE_PROPAGATION_DELAY_SCOPE" "G"
					( Parent
						( matchGroupRef "@baseboard_fab2_lib.baseboard_fab2(sch_1):\MG_DQ_NEAR_DIMM_NG_M_C_BYTE4\" )
					)
					( Status sCSetFlattened )
					( Origin gBackEnd )
				)
				( attribute "RELATIVE_PROPAGATION_DELAY" "-50.00 MIL,50.00 MIL"
					( Parent
						( matchGroupRef "@baseboard_fab2_lib.baseboard_fab2(sch_1):\MG_DQ_NEAR_DIMM_NG_M_C_BYTE4\" )
					)
					( Units "uMatchProp" "ns" 1.000000)
					( Status sCSetFlattened )
					( Origin gBackEnd )
				)
			)
			( pinPair "@baseboard_fab2_lib.baseboard_fab2(sch_1):\PP4791\"
				( pinRef "@baseboard_fab2_lib.baseboard_fab2(sch_1):page25_i172:DDR2_DQ(36)" )
				( pinRef "@baseboard_fab2_lib.baseboard_fab2(sch_1):page47_i111:DQ(37)" )
				( attribute "RELATIVE_PROPAGATION_DELAY_SCOPE" "G"
					( Parent
						( matchGroupRef "@baseboard_fab2_lib.baseboard_fab2(sch_1):\MG_DQ-DQS_FAR_DIMM_NG_M_C_BYTE4\" )
					)
					( Status sCSetFlattened )
					( Origin gBackEnd )
				)
				( attribute "RELATIVE_PROPAGATION_DELAY" "0.00 MIL,195.00 MIL"
					( Parent
						( matchGroupRef "@baseboard_fab2_lib.baseboard_fab2(sch_1):\MG_DQ-DQS_FAR_DIMM_NG_M_C_BYTE4\" )
					)
					( Units "uMatchProp" "ns" 1.000000)
					( Status sCSetFlattened )
					( Origin gBackEnd )
				)
				( attribute "RELATIVE_PROPAGATION_DELAY_SCOPE" "G"
					( Parent
						( matchGroupRef "@baseboard_fab2_lib.baseboard_fab2(sch_1):\MG_DQ_FAR_DIMM_NG_M_C_BYTE4\" )
					)
					( Status sCSetFlattened )
					( Origin gBackEnd )
				)
				( attribute "RELATIVE_PROPAGATION_DELAY" "-50.00 MIL,50.00 MIL"
					( Parent
						( matchGroupRef "@baseboard_fab2_lib.baseboard_fab2(sch_1):\MG_DQ_FAR_DIMM_NG_M_C_BYTE4\" )
					)
					( Units "uMatchProp" "ns" 1.000000)
					( Status sCSetFlattened )
					( Origin gBackEnd )
				)
			)
			( pinPair "@baseboard_fab2_lib.baseboard_fab2(sch_1):\PP4793\"
				( pinRef "@baseboard_fab2_lib.baseboard_fab2(sch_1):page25_i172:DDR2_DQ(36)" )
				( pinRef "@baseboard_fab2_lib.baseboard_fab2(sch_1):page48_i111:DQ(36)" )
				( attribute "RELATIVE_PROPAGATION_DELAY_SCOPE" "G"
					( Parent
						( matchGroupRef "@baseboard_fab2_lib.baseboard_fab2(sch_1):\MG_DQ-DQS_NEAR_DIMM_NG_M_C_BYTE4\" )
					)
					( Status sCSetFlattened )
					( Origin gBackEnd )
				)
				( attribute "RELATIVE_PROPAGATION_DELAY" "0.00 MIL,195.00 MIL"
					( Parent
						( matchGroupRef "@baseboard_fab2_lib.baseboard_fab2(sch_1):\MG_DQ-DQS_NEAR_DIMM_NG_M_C_BYTE4\" )
					)
					( Units "uMatchProp" "ns" 1.000000)
					( Status sCSetFlattened )
					( Origin gBackEnd )
				)
				( attribute "RELATIVE_PROPAGATION_DELAY_SCOPE" "G"
					( Parent
						( matchGroupRef "@baseboard_fab2_lib.baseboard_fab2(sch_1):\MG_DQ_NEAR_DIMM_NG_M_C_BYTE4\" )
					)
					( Status sCSetFlattened )
					( Origin gBackEnd )
				)
				( attribute "RELATIVE_PROPAGATION_DELAY" "-50.00 MIL,50.00 MIL"
					( Parent
						( matchGroupRef "@baseboard_fab2_lib.baseboard_fab2(sch_1):\MG_DQ_NEAR_DIMM_NG_M_C_BYTE4\" )
					)
					( Units "uMatchProp" "ns" 1.000000)
					( Status sCSetFlattened )
					( Origin gBackEnd )
				)
			)
			( pinPair "@baseboard_fab2_lib.baseboard_fab2(sch_1):\PP4794\"
				( pinRef "@baseboard_fab2_lib.baseboard_fab2(sch_1):page25_i172:DDR2_DQ(37)" )
				( pinRef "@baseboard_fab2_lib.baseboard_fab2(sch_1):page47_i111:DQ(36)" )
				( attribute "RELATIVE_PROPAGATION_DELAY_SCOPE" "G"
					( Parent
						( matchGroupRef "@baseboard_fab2_lib.baseboard_fab2(sch_1):\MG_DQ-DQS_FAR_DIMM_NG_M_C_BYTE4\" )
					)
					( Status sCSetFlattened )
					( Origin gBackEnd )
				)
				( attribute "RELATIVE_PROPAGATION_DELAY" "0.00 MIL,195.00 MIL"
					( Parent
						( matchGroupRef "@baseboard_fab2_lib.baseboard_fab2(sch_1):\MG_DQ-DQS_FAR_DIMM_NG_M_C_BYTE4\" )
					)
					( Units "uMatchProp" "ns" 1.000000)
					( Status sCSetFlattened )
					( Origin gBackEnd )
				)
				( attribute "RELATIVE_PROPAGATION_DELAY_SCOPE" "G"
					( Parent
						( matchGroupRef "@baseboard_fab2_lib.baseboard_fab2(sch_1):\MG_DQ_FAR_DIMM_NG_M_C_BYTE4\" )
					)
					( Status sCSetFlattened )
					( Origin gBackEnd )
				)
				( attribute "RELATIVE_PROPAGATION_DELAY" "-50.00 MIL,50.00 MIL"
					( Parent
						( matchGroupRef "@baseboard_fab2_lib.baseboard_fab2(sch_1):\MG_DQ_FAR_DIMM_NG_M_C_BYTE4\" )
					)
					( Units "uMatchProp" "ns" 1.000000)
					( Status sCSetFlattened )
					( Origin gBackEnd )
				)
			)
			( pinPair "@baseboard_fab2_lib.baseboard_fab2(sch_1):\PP4796\"
				( pinRef "@baseboard_fab2_lib.baseboard_fab2(sch_1):page25_i172:DDR2_DQ(37)" )
				( pinRef "@baseboard_fab2_lib.baseboard_fab2(sch_1):page48_i111:DQ(37)" )
				( attribute "RELATIVE_PROPAGATION_DELAY_SCOPE" "G"
					( Parent
						( matchGroupRef "@baseboard_fab2_lib.baseboard_fab2(sch_1):\MG_DQ-DQS_NEAR_DIMM_NG_M_C_BYTE4\" )
					)
					( Status sCSetFlattened )
					( Origin gBackEnd )
				)
				( attribute "RELATIVE_PROPAGATION_DELAY" "0.00 MIL,195.00 MIL"
					( Parent
						( matchGroupRef "@baseboard_fab2_lib.baseboard_fab2(sch_1):\MG_DQ-DQS_NEAR_DIMM_NG_M_C_BYTE4\" )
					)
					( Units "uMatchProp" "ns" 1.000000)
					( Status sCSetFlattened )
					( Origin gBackEnd )
				)
				( attribute "RELATIVE_PROPAGATION_DELAY_SCOPE" "G"
					( Parent
						( matchGroupRef "@baseboard_fab2_lib.baseboard_fab2(sch_1):\MG_DQ_NEAR_DIMM_NG_M_C_BYTE4\" )
					)
					( Status sCSetFlattened )
					( Origin gBackEnd )
				)
				( attribute "RELATIVE_PROPAGATION_DELAY" "-50.00 MIL,50.00 MIL"
					( Parent
						( matchGroupRef "@baseboard_fab2_lib.baseboard_fab2(sch_1):\MG_DQ_NEAR_DIMM_NG_M_C_BYTE4\" )
					)
					( Units "uMatchProp" "ns" 1.000000)
					( Status sCSetFlattened )
					( Origin gBackEnd )
				)
			)
			( pinPair "@baseboard_fab2_lib.baseboard_fab2(sch_1):\PP4797\"
				( pinRef "@baseboard_fab2_lib.baseboard_fab2(sch_1):page25_i172:DDR2_DQ(38)" )
				( pinRef "@baseboard_fab2_lib.baseboard_fab2(sch_1):page47_i111:DQ(39)" )
				( attribute "RELATIVE_PROPAGATION_DELAY_SCOPE" "G"
					( Parent
						( matchGroupRef "@baseboard_fab2_lib.baseboard_fab2(sch_1):\MG_DQ-DQS_FAR_DIMM_NG_M_C_BYTE4\" )
					)
					( Status sCSetFlattened )
					( Origin gBackEnd )
				)
				( attribute "RELATIVE_PROPAGATION_DELAY" "0.00 MIL,195.00 MIL"
					( Parent
						( matchGroupRef "@baseboard_fab2_lib.baseboard_fab2(sch_1):\MG_DQ-DQS_FAR_DIMM_NG_M_C_BYTE4\" )
					)
					( Units "uMatchProp" "ns" 1.000000)
					( Status sCSetFlattened )
					( Origin gBackEnd )
				)
				( attribute "RELATIVE_PROPAGATION_DELAY_SCOPE" "G"
					( Parent
						( matchGroupRef "@baseboard_fab2_lib.baseboard_fab2(sch_1):\MG_DQ_FAR_DIMM_NG_M_C_BYTE4\" )
					)
					( Status sCSetFlattened )
					( Origin gBackEnd )
				)
				( attribute "RELATIVE_PROPAGATION_DELAY" "-50.00 MIL,50.00 MIL"
					( Parent
						( matchGroupRef "@baseboard_fab2_lib.baseboard_fab2(sch_1):\MG_DQ_FAR_DIMM_NG_M_C_BYTE4\" )
					)
					( Units "uMatchProp" "ns" 1.000000)
					( Status sCSetFlattened )
					( Origin gBackEnd )
				)
			)
			( pinPair "@baseboard_fab2_lib.baseboard_fab2(sch_1):\PP4799\"
				( pinRef "@baseboard_fab2_lib.baseboard_fab2(sch_1):page25_i172:DDR2_DQ(38)" )
				( pinRef "@baseboard_fab2_lib.baseboard_fab2(sch_1):page48_i111:DQ(38)" )
				( attribute "RELATIVE_PROPAGATION_DELAY_SCOPE" "G"
					( Parent
						( matchGroupRef "@baseboard_fab2_lib.baseboard_fab2(sch_1):\MG_DQ-DQS_NEAR_DIMM_NG_M_C_BYTE4\" )
					)
					( Status sCSetFlattened )
					( Origin gBackEnd )
				)
				( attribute "RELATIVE_PROPAGATION_DELAY" "0.00 MIL,195.00 MIL"
					( Parent
						( matchGroupRef "@baseboard_fab2_lib.baseboard_fab2(sch_1):\MG_DQ-DQS_NEAR_DIMM_NG_M_C_BYTE4\" )
					)
					( Units "uMatchProp" "ns" 1.000000)
					( Status sCSetFlattened )
					( Origin gBackEnd )
				)
				( attribute "RELATIVE_PROPAGATION_DELAY_SCOPE" "G"
					( Parent
						( matchGroupRef "@baseboard_fab2_lib.baseboard_fab2(sch_1):\MG_DQ_NEAR_DIMM_NG_M_C_BYTE4\" )
					)
					( Status sCSetFlattened )
					( Origin gBackEnd )
				)
				( attribute "RELATIVE_PROPAGATION_DELAY" "-50.00 MIL,50.00 MIL"
					( Parent
						( matchGroupRef "@baseboard_fab2_lib.baseboard_fab2(sch_1):\MG_DQ_NEAR_DIMM_NG_M_C_BYTE4\" )
					)
					( Units "uMatchProp" "ns" 1.000000)
					( Status sCSetFlattened )
					( Origin gBackEnd )
				)
			)
			( pinPair "@baseboard_fab2_lib.baseboard_fab2(sch_1):\PP4800\"
				( pinRef "@baseboard_fab2_lib.baseboard_fab2(sch_1):page25_i172:DDR2_DQ(39)" )
				( pinRef "@baseboard_fab2_lib.baseboard_fab2(sch_1):page47_i111:DQ(38)" )
				( attribute "RELATIVE_PROPAGATION_DELAY_SCOPE" "G"
					( Parent
						( matchGroupRef "@baseboard_fab2_lib.baseboard_fab2(sch_1):\MG_DQ-DQS_FAR_DIMM_NG_M_C_BYTE4\" )
					)
					( Status sCSetFlattened )
					( Origin gBackEnd )
				)
				( attribute "RELATIVE_PROPAGATION_DELAY" "0.00 MIL,195.00 MIL"
					( Parent
						( matchGroupRef "@baseboard_fab2_lib.baseboard_fab2(sch_1):\MG_DQ-DQS_FAR_DIMM_NG_M_C_BYTE4\" )
					)
					( Units "uMatchProp" "ns" 1.000000)
					( Status sCSetFlattened )
					( Origin gBackEnd )
				)
				( attribute "RELATIVE_PROPAGATION_DELAY_SCOPE" "G"
					( Parent
						( matchGroupRef "@baseboard_fab2_lib.baseboard_fab2(sch_1):\MG_DQ_FAR_DIMM_NG_M_C_BYTE4\" )
					)
					( Status sCSetFlattened )
					( Origin gBackEnd )
				)
				( attribute "RELATIVE_PROPAGATION_DELAY" "-50.00 MIL,50.00 MIL"
					( Parent
						( matchGroupRef "@baseboard_fab2_lib.baseboard_fab2(sch_1):\MG_DQ_FAR_DIMM_NG_M_C_BYTE4\" )
					)
					( Units "uMatchProp" "ns" 1.000000)
					( Status sCSetFlattened )
					( Origin gBackEnd )
				)
			)
			( pinPair "@baseboard_fab2_lib.baseboard_fab2(sch_1):\PP4802\"
				( pinRef "@baseboard_fab2_lib.baseboard_fab2(sch_1):page25_i172:DDR2_DQ(39)" )
				( pinRef "@baseboard_fab2_lib.baseboard_fab2(sch_1):page48_i111:DQ(39)" )
				( attribute "RELATIVE_PROPAGATION_DELAY_SCOPE" "G"
					( Parent
						( matchGroupRef "@baseboard_fab2_lib.baseboard_fab2(sch_1):\MG_DQ-DQS_NEAR_DIMM_NG_M_C_BYTE4\" )
					)
					( Status sCSetFlattened )
					( Origin gBackEnd )
				)
				( attribute "RELATIVE_PROPAGATION_DELAY" "0.00 MIL,195.00 MIL"
					( Parent
						( matchGroupRef "@baseboard_fab2_lib.baseboard_fab2(sch_1):\MG_DQ-DQS_NEAR_DIMM_NG_M_C_BYTE4\" )
					)
					( Units "uMatchProp" "ns" 1.000000)
					( Status sCSetFlattened )
					( Origin gBackEnd )
				)
				( attribute "RELATIVE_PROPAGATION_DELAY_SCOPE" "G"
					( Parent
						( matchGroupRef "@baseboard_fab2_lib.baseboard_fab2(sch_1):\MG_DQ_NEAR_DIMM_NG_M_C_BYTE4\" )
					)
					( Status sCSetFlattened )
					( Origin gBackEnd )
				)
				( attribute "RELATIVE_PROPAGATION_DELAY" "-50.00 MIL,50.00 MIL"
					( Parent
						( matchGroupRef "@baseboard_fab2_lib.baseboard_fab2(sch_1):\MG_DQ_NEAR_DIMM_NG_M_C_BYTE4\" )
					)
					( Units "uMatchProp" "ns" 1.000000)
					( Status sCSetFlattened )
					( Origin gBackEnd )
				)
			)
			( pinPair "@baseboard_fab2_lib.baseboard_fab2(sch_1):\PP4755\"
				( pinRef "@baseboard_fab2_lib.baseboard_fab2(sch_1):page25_i172:DDR2_DQ(40)" )
				( pinRef "@baseboard_fab2_lib.baseboard_fab2(sch_1):page47_i111:DQ(41)" )
				( attribute "RELATIVE_PROPAGATION_DELAY_SCOPE" "G"
					( Parent
						( matchGroupRef "@baseboard_fab2_lib.baseboard_fab2(sch_1):\MG_DQ-DQS_FAR_DIMM_NG_M_C_BYTE5\" )
					)
					( Status sCSetFlattened )
					( Origin gBackEnd )
				)
				( attribute "RELATIVE_PROPAGATION_DELAY" "0.00 MIL,195.00 MIL"
					( Parent
						( matchGroupRef "@baseboard_fab2_lib.baseboard_fab2(sch_1):\MG_DQ-DQS_FAR_DIMM_NG_M_C_BYTE5\" )
					)
					( Units "uMatchProp" "ns" 1.000000)
					( Status sCSetFlattened )
					( Origin gBackEnd )
				)
				( attribute "RELATIVE_PROPAGATION_DELAY_SCOPE" "G"
					( Parent
						( matchGroupRef "@baseboard_fab2_lib.baseboard_fab2(sch_1):\MG_DQ_FAR_DIMM_NG_M_C_BYTE5\" )
					)
					( Status sCSetFlattened )
					( Origin gBackEnd )
				)
				( attribute "RELATIVE_PROPAGATION_DELAY" "-50.00 MIL,50.00 MIL"
					( Parent
						( matchGroupRef "@baseboard_fab2_lib.baseboard_fab2(sch_1):\MG_DQ_FAR_DIMM_NG_M_C_BYTE5\" )
					)
					( Units "uMatchProp" "ns" 1.000000)
					( Status sCSetFlattened )
					( Origin gBackEnd )
				)
			)
			( pinPair "@baseboard_fab2_lib.baseboard_fab2(sch_1):\PP4757\"
				( pinRef "@baseboard_fab2_lib.baseboard_fab2(sch_1):page25_i172:DDR2_DQ(40)" )
				( pinRef "@baseboard_fab2_lib.baseboard_fab2(sch_1):page48_i111:DQ(40)" )
				( attribute "RELATIVE_PROPAGATION_DELAY_SCOPE" "G"
					( Parent
						( matchGroupRef "@baseboard_fab2_lib.baseboard_fab2(sch_1):\MG_DQ-DQS_NEAR_DIMM_NG_M_C_BYTE5\" )
					)
					( Status sCSetFlattened )
					( Origin gBackEnd )
				)
				( attribute "RELATIVE_PROPAGATION_DELAY" "0.00 MIL,195.00 MIL"
					( Parent
						( matchGroupRef "@baseboard_fab2_lib.baseboard_fab2(sch_1):\MG_DQ-DQS_NEAR_DIMM_NG_M_C_BYTE5\" )
					)
					( Units "uMatchProp" "ns" 1.000000)
					( Status sCSetFlattened )
					( Origin gBackEnd )
				)
				( attribute "RELATIVE_PROPAGATION_DELAY_SCOPE" "G"
					( Parent
						( matchGroupRef "@baseboard_fab2_lib.baseboard_fab2(sch_1):\MG_DQ_NEAR_DIMM_NG_M_C_BYTE5\" )
					)
					( Status sCSetFlattened )
					( Origin gBackEnd )
				)
				( attribute "RELATIVE_PROPAGATION_DELAY" "-50.00 MIL,50.00 MIL"
					( Parent
						( matchGroupRef "@baseboard_fab2_lib.baseboard_fab2(sch_1):\MG_DQ_NEAR_DIMM_NG_M_C_BYTE5\" )
					)
					( Units "uMatchProp" "ns" 1.000000)
					( Status sCSetFlattened )
					( Origin gBackEnd )
				)
			)
			( pinPair "@baseboard_fab2_lib.baseboard_fab2(sch_1):\PP4758\"
				( pinRef "@baseboard_fab2_lib.baseboard_fab2(sch_1):page25_i172:DDR2_DQ(41)" )
				( pinRef "@baseboard_fab2_lib.baseboard_fab2(sch_1):page47_i111:DQ(40)" )
				( attribute "RELATIVE_PROPAGATION_DELAY_SCOPE" "G"
					( Parent
						( matchGroupRef "@baseboard_fab2_lib.baseboard_fab2(sch_1):\MG_DQ-DQS_FAR_DIMM_NG_M_C_BYTE5\" )
					)
					( Status sCSetFlattened )
					( Origin gBackEnd )
				)
				( attribute "RELATIVE_PROPAGATION_DELAY" "0.00 MIL,195.00 MIL"
					( Parent
						( matchGroupRef "@baseboard_fab2_lib.baseboard_fab2(sch_1):\MG_DQ-DQS_FAR_DIMM_NG_M_C_BYTE5\" )
					)
					( Units "uMatchProp" "ns" 1.000000)
					( Status sCSetFlattened )
					( Origin gBackEnd )
				)
				( attribute "RELATIVE_PROPAGATION_DELAY_SCOPE" "G"
					( Parent
						( matchGroupRef "@baseboard_fab2_lib.baseboard_fab2(sch_1):\MG_DQ_FAR_DIMM_NG_M_C_BYTE5\" )
					)
					( Status sCSetFlattened )
					( Origin gBackEnd )
				)
				( attribute "RELATIVE_PROPAGATION_DELAY" "-50.00 MIL,50.00 MIL"
					( Parent
						( matchGroupRef "@baseboard_fab2_lib.baseboard_fab2(sch_1):\MG_DQ_FAR_DIMM_NG_M_C_BYTE5\" )
					)
					( Units "uMatchProp" "ns" 1.000000)
					( Status sCSetFlattened )
					( Origin gBackEnd )
				)
			)
			( pinPair "@baseboard_fab2_lib.baseboard_fab2(sch_1):\PP4760\"
				( pinRef "@baseboard_fab2_lib.baseboard_fab2(sch_1):page25_i172:DDR2_DQ(41)" )
				( pinRef "@baseboard_fab2_lib.baseboard_fab2(sch_1):page48_i111:DQ(41)" )
				( attribute "RELATIVE_PROPAGATION_DELAY_SCOPE" "G"
					( Parent
						( matchGroupRef "@baseboard_fab2_lib.baseboard_fab2(sch_1):\MG_DQ-DQS_NEAR_DIMM_NG_M_C_BYTE5\" )
					)
					( Status sCSetFlattened )
					( Origin gBackEnd )
				)
				( attribute "RELATIVE_PROPAGATION_DELAY" "0.00 MIL,195.00 MIL"
					( Parent
						( matchGroupRef "@baseboard_fab2_lib.baseboard_fab2(sch_1):\MG_DQ-DQS_NEAR_DIMM_NG_M_C_BYTE5\" )
					)
					( Units "uMatchProp" "ns" 1.000000)
					( Status sCSetFlattened )
					( Origin gBackEnd )
				)
				( attribute "RELATIVE_PROPAGATION_DELAY_SCOPE" "G"
					( Parent
						( matchGroupRef "@baseboard_fab2_lib.baseboard_fab2(sch_1):\MG_DQ_NEAR_DIMM_NG_M_C_BYTE5\" )
					)
					( Status sCSetFlattened )
					( Origin gBackEnd )
				)
				( attribute "RELATIVE_PROPAGATION_DELAY" "-50.00 MIL,50.00 MIL"
					( Parent
						( matchGroupRef "@baseboard_fab2_lib.baseboard_fab2(sch_1):\MG_DQ_NEAR_DIMM_NG_M_C_BYTE5\" )
					)
					( Units "uMatchProp" "ns" 1.000000)
					( Status sCSetFlattened )
					( Origin gBackEnd )
				)
			)
			( pinPair "@baseboard_fab2_lib.baseboard_fab2(sch_1):\PP4761\"
				( pinRef "@baseboard_fab2_lib.baseboard_fab2(sch_1):page25_i172:DDR2_DQ(42)" )
				( pinRef "@baseboard_fab2_lib.baseboard_fab2(sch_1):page47_i111:DQ(43)" )
				( attribute "RELATIVE_PROPAGATION_DELAY_SCOPE" "G"
					( Parent
						( matchGroupRef "@baseboard_fab2_lib.baseboard_fab2(sch_1):\MG_DQ-DQS_FAR_DIMM_NG_M_C_BYTE5\" )
					)
					( Status sCSetFlattened )
					( Origin gBackEnd )
				)
				( attribute "RELATIVE_PROPAGATION_DELAY" "0.00 MIL,195.00 MIL"
					( Parent
						( matchGroupRef "@baseboard_fab2_lib.baseboard_fab2(sch_1):\MG_DQ-DQS_FAR_DIMM_NG_M_C_BYTE5\" )
					)
					( Units "uMatchProp" "ns" 1.000000)
					( Status sCSetFlattened )
					( Origin gBackEnd )
				)
				( attribute "RELATIVE_PROPAGATION_DELAY_SCOPE" "G"
					( Parent
						( matchGroupRef "@baseboard_fab2_lib.baseboard_fab2(sch_1):\MG_DQ_FAR_DIMM_NG_M_C_BYTE5\" )
					)
					( Status sCSetFlattened )
					( Origin gBackEnd )
				)
				( attribute "RELATIVE_PROPAGATION_DELAY" "-50.00 MIL,50.00 MIL"
					( Parent
						( matchGroupRef "@baseboard_fab2_lib.baseboard_fab2(sch_1):\MG_DQ_FAR_DIMM_NG_M_C_BYTE5\" )
					)
					( Units "uMatchProp" "ns" 1.000000)
					( Status sCSetFlattened )
					( Origin gBackEnd )
				)
			)
			( pinPair "@baseboard_fab2_lib.baseboard_fab2(sch_1):\PP4763\"
				( pinRef "@baseboard_fab2_lib.baseboard_fab2(sch_1):page25_i172:DDR2_DQ(42)" )
				( pinRef "@baseboard_fab2_lib.baseboard_fab2(sch_1):page48_i111:DQ(42)" )
				( attribute "RELATIVE_PROPAGATION_DELAY_SCOPE" "G"
					( Parent
						( matchGroupRef "@baseboard_fab2_lib.baseboard_fab2(sch_1):\MG_DQ-DQS_NEAR_DIMM_NG_M_C_BYTE5\" )
					)
					( Status sCSetFlattened )
					( Origin gBackEnd )
				)
				( attribute "RELATIVE_PROPAGATION_DELAY" "0.00 MIL,195.00 MIL"
					( Parent
						( matchGroupRef "@baseboard_fab2_lib.baseboard_fab2(sch_1):\MG_DQ-DQS_NEAR_DIMM_NG_M_C_BYTE5\" )
					)
					( Units "uMatchProp" "ns" 1.000000)
					( Status sCSetFlattened )
					( Origin gBackEnd )
				)
				( attribute "RELATIVE_PROPAGATION_DELAY_SCOPE" "G"
					( Parent
						( matchGroupRef "@baseboard_fab2_lib.baseboard_fab2(sch_1):\MG_DQ_NEAR_DIMM_NG_M_C_BYTE5\" )
					)
					( Status sCSetFlattened )
					( Origin gBackEnd )
				)
				( attribute "RELATIVE_PROPAGATION_DELAY" "-50.00 MIL,50.00 MIL"
					( Parent
						( matchGroupRef "@baseboard_fab2_lib.baseboard_fab2(sch_1):\MG_DQ_NEAR_DIMM_NG_M_C_BYTE5\" )
					)
					( Units "uMatchProp" "ns" 1.000000)
					( Status sCSetFlattened )
					( Origin gBackEnd )
				)
			)
			( pinPair "@baseboard_fab2_lib.baseboard_fab2(sch_1):\PP4764\"
				( pinRef "@baseboard_fab2_lib.baseboard_fab2(sch_1):page25_i172:DDR2_DQ(43)" )
				( pinRef "@baseboard_fab2_lib.baseboard_fab2(sch_1):page47_i111:DQ(42)" )
				( attribute "RELATIVE_PROPAGATION_DELAY_SCOPE" "G"
					( Parent
						( matchGroupRef "@baseboard_fab2_lib.baseboard_fab2(sch_1):\MG_DQ-DQS_FAR_DIMM_NG_M_C_BYTE5\" )
					)
					( Status sCSetFlattened )
					( Origin gBackEnd )
				)
				( attribute "RELATIVE_PROPAGATION_DELAY" "0.00 MIL,195.00 MIL"
					( Parent
						( matchGroupRef "@baseboard_fab2_lib.baseboard_fab2(sch_1):\MG_DQ-DQS_FAR_DIMM_NG_M_C_BYTE5\" )
					)
					( Units "uMatchProp" "ns" 1.000000)
					( Status sCSetFlattened )
					( Origin gBackEnd )
				)
				( attribute "RELATIVE_PROPAGATION_DELAY_SCOPE" "G"
					( Parent
						( matchGroupRef "@baseboard_fab2_lib.baseboard_fab2(sch_1):\MG_DQ_FAR_DIMM_NG_M_C_BYTE5\" )
					)
					( Status sCSetFlattened )
					( Origin gBackEnd )
				)
				( attribute "RELATIVE_PROPAGATION_DELAY" "-50.00 MIL,50.00 MIL"
					( Parent
						( matchGroupRef "@baseboard_fab2_lib.baseboard_fab2(sch_1):\MG_DQ_FAR_DIMM_NG_M_C_BYTE5\" )
					)
					( Units "uMatchProp" "ns" 1.000000)
					( Status sCSetFlattened )
					( Origin gBackEnd )
				)
			)
			( pinPair "@baseboard_fab2_lib.baseboard_fab2(sch_1):\PP4766\"
				( pinRef "@baseboard_fab2_lib.baseboard_fab2(sch_1):page25_i172:DDR2_DQ(43)" )
				( pinRef "@baseboard_fab2_lib.baseboard_fab2(sch_1):page48_i111:DQ(43)" )
				( attribute "RELATIVE_PROPAGATION_DELAY_SCOPE" "G"
					( Parent
						( matchGroupRef "@baseboard_fab2_lib.baseboard_fab2(sch_1):\MG_DQ-DQS_NEAR_DIMM_NG_M_C_BYTE5\" )
					)
					( Status sCSetFlattened )
					( Origin gBackEnd )
				)
				( attribute "RELATIVE_PROPAGATION_DELAY" "0.00 MIL,195.00 MIL"
					( Parent
						( matchGroupRef "@baseboard_fab2_lib.baseboard_fab2(sch_1):\MG_DQ-DQS_NEAR_DIMM_NG_M_C_BYTE5\" )
					)
					( Units "uMatchProp" "ns" 1.000000)
					( Status sCSetFlattened )
					( Origin gBackEnd )
				)
				( attribute "RELATIVE_PROPAGATION_DELAY_SCOPE" "G"
					( Parent
						( matchGroupRef "@baseboard_fab2_lib.baseboard_fab2(sch_1):\MG_DQ_NEAR_DIMM_NG_M_C_BYTE5\" )
					)
					( Status sCSetFlattened )
					( Origin gBackEnd )
				)
				( attribute "RELATIVE_PROPAGATION_DELAY" "-50.00 MIL,50.00 MIL"
					( Parent
						( matchGroupRef "@baseboard_fab2_lib.baseboard_fab2(sch_1):\MG_DQ_NEAR_DIMM_NG_M_C_BYTE5\" )
					)
					( Units "uMatchProp" "ns" 1.000000)
					( Status sCSetFlattened )
					( Origin gBackEnd )
				)
			)
			( pinPair "@baseboard_fab2_lib.baseboard_fab2(sch_1):\PP4767\"
				( pinRef "@baseboard_fab2_lib.baseboard_fab2(sch_1):page25_i172:DDR2_DQ(44)" )
				( pinRef "@baseboard_fab2_lib.baseboard_fab2(sch_1):page47_i111:DQ(45)" )
				( attribute "RELATIVE_PROPAGATION_DELAY_SCOPE" "G"
					( Parent
						( matchGroupRef "@baseboard_fab2_lib.baseboard_fab2(sch_1):\MG_DQ-DQS_FAR_DIMM_NG_M_C_BYTE5\" )
					)
					( Status sCSetFlattened )
					( Origin gBackEnd )
				)
				( attribute "RELATIVE_PROPAGATION_DELAY" "0.00 MIL,195.00 MIL"
					( Parent
						( matchGroupRef "@baseboard_fab2_lib.baseboard_fab2(sch_1):\MG_DQ-DQS_FAR_DIMM_NG_M_C_BYTE5\" )
					)
					( Units "uMatchProp" "ns" 1.000000)
					( Status sCSetFlattened )
					( Origin gBackEnd )
				)
				( attribute "RELATIVE_PROPAGATION_DELAY_SCOPE" "G"
					( Parent
						( matchGroupRef "@baseboard_fab2_lib.baseboard_fab2(sch_1):\MG_DQ_FAR_DIMM_NG_M_C_BYTE5\" )
					)
					( Status sCSetFlattened )
					( Origin gBackEnd )
				)
				( attribute "RELATIVE_PROPAGATION_DELAY" "-50.00 MIL,50.00 MIL"
					( Parent
						( matchGroupRef "@baseboard_fab2_lib.baseboard_fab2(sch_1):\MG_DQ_FAR_DIMM_NG_M_C_BYTE5\" )
					)
					( Units "uMatchProp" "ns" 1.000000)
					( Status sCSetFlattened )
					( Origin gBackEnd )
				)
			)
			( pinPair "@baseboard_fab2_lib.baseboard_fab2(sch_1):\PP4769\"
				( pinRef "@baseboard_fab2_lib.baseboard_fab2(sch_1):page25_i172:DDR2_DQ(44)" )
				( pinRef "@baseboard_fab2_lib.baseboard_fab2(sch_1):page48_i111:DQ(44)" )
				( attribute "RELATIVE_PROPAGATION_DELAY_SCOPE" "G"
					( Parent
						( matchGroupRef "@baseboard_fab2_lib.baseboard_fab2(sch_1):\MG_DQ-DQS_NEAR_DIMM_NG_M_C_BYTE5\" )
					)
					( Status sCSetFlattened )
					( Origin gBackEnd )
				)
				( attribute "RELATIVE_PROPAGATION_DELAY" "0.00 MIL,195.00 MIL"
					( Parent
						( matchGroupRef "@baseboard_fab2_lib.baseboard_fab2(sch_1):\MG_DQ-DQS_NEAR_DIMM_NG_M_C_BYTE5\" )
					)
					( Units "uMatchProp" "ns" 1.000000)
					( Status sCSetFlattened )
					( Origin gBackEnd )
				)
				( attribute "RELATIVE_PROPAGATION_DELAY_SCOPE" "G"
					( Parent
						( matchGroupRef "@baseboard_fab2_lib.baseboard_fab2(sch_1):\MG_DQ_NEAR_DIMM_NG_M_C_BYTE5\" )
					)
					( Status sCSetFlattened )
					( Origin gBackEnd )
				)
				( attribute "RELATIVE_PROPAGATION_DELAY" "-50.00 MIL,50.00 MIL"
					( Parent
						( matchGroupRef "@baseboard_fab2_lib.baseboard_fab2(sch_1):\MG_DQ_NEAR_DIMM_NG_M_C_BYTE5\" )
					)
					( Units "uMatchProp" "ns" 1.000000)
					( Status sCSetFlattened )
					( Origin gBackEnd )
				)
			)
			( pinPair "@baseboard_fab2_lib.baseboard_fab2(sch_1):\PP4770\"
				( pinRef "@baseboard_fab2_lib.baseboard_fab2(sch_1):page25_i172:DDR2_DQ(45)" )
				( pinRef "@baseboard_fab2_lib.baseboard_fab2(sch_1):page47_i111:DQ(44)" )
				( attribute "RELATIVE_PROPAGATION_DELAY_SCOPE" "G"
					( Parent
						( matchGroupRef "@baseboard_fab2_lib.baseboard_fab2(sch_1):\MG_DQ-DQS_FAR_DIMM_NG_M_C_BYTE5\" )
					)
					( Status sCSetFlattened )
					( Origin gBackEnd )
				)
				( attribute "RELATIVE_PROPAGATION_DELAY" "0.00 MIL,195.00 MIL"
					( Parent
						( matchGroupRef "@baseboard_fab2_lib.baseboard_fab2(sch_1):\MG_DQ-DQS_FAR_DIMM_NG_M_C_BYTE5\" )
					)
					( Units "uMatchProp" "ns" 1.000000)
					( Status sCSetFlattened )
					( Origin gBackEnd )
				)
				( attribute "RELATIVE_PROPAGATION_DELAY_SCOPE" "G"
					( Parent
						( matchGroupRef "@baseboard_fab2_lib.baseboard_fab2(sch_1):\MG_DQ_FAR_DIMM_NG_M_C_BYTE5\" )
					)
					( Status sCSetFlattened )
					( Origin gBackEnd )
				)
				( attribute "RELATIVE_PROPAGATION_DELAY" "-50.00 MIL,50.00 MIL"
					( Parent
						( matchGroupRef "@baseboard_fab2_lib.baseboard_fab2(sch_1):\MG_DQ_FAR_DIMM_NG_M_C_BYTE5\" )
					)
					( Units "uMatchProp" "ns" 1.000000)
					( Status sCSetFlattened )
					( Origin gBackEnd )
				)
			)
			( pinPair "@baseboard_fab2_lib.baseboard_fab2(sch_1):\PP4772\"
				( pinRef "@baseboard_fab2_lib.baseboard_fab2(sch_1):page25_i172:DDR2_DQ(45)" )
				( pinRef "@baseboard_fab2_lib.baseboard_fab2(sch_1):page48_i111:DQ(45)" )
				( attribute "RELATIVE_PROPAGATION_DELAY_SCOPE" "G"
					( Parent
						( matchGroupRef "@baseboard_fab2_lib.baseboard_fab2(sch_1):\MG_DQ-DQS_NEAR_DIMM_NG_M_C_BYTE5\" )
					)
					( Status sCSetFlattened )
					( Origin gBackEnd )
				)
				( attribute "RELATIVE_PROPAGATION_DELAY" "0.00 MIL,195.00 MIL"
					( Parent
						( matchGroupRef "@baseboard_fab2_lib.baseboard_fab2(sch_1):\MG_DQ-DQS_NEAR_DIMM_NG_M_C_BYTE5\" )
					)
					( Units "uMatchProp" "ns" 1.000000)
					( Status sCSetFlattened )
					( Origin gBackEnd )
				)
				( attribute "RELATIVE_PROPAGATION_DELAY_SCOPE" "G"
					( Parent
						( matchGroupRef "@baseboard_fab2_lib.baseboard_fab2(sch_1):\MG_DQ_NEAR_DIMM_NG_M_C_BYTE5\" )
					)
					( Status sCSetFlattened )
					( Origin gBackEnd )
				)
				( attribute "RELATIVE_PROPAGATION_DELAY" "-50.00 MIL,50.00 MIL"
					( Parent
						( matchGroupRef "@baseboard_fab2_lib.baseboard_fab2(sch_1):\MG_DQ_NEAR_DIMM_NG_M_C_BYTE5\" )
					)
					( Units "uMatchProp" "ns" 1.000000)
					( Status sCSetFlattened )
					( Origin gBackEnd )
				)
			)
			( pinPair "@baseboard_fab2_lib.baseboard_fab2(sch_1):\PP4773\"
				( pinRef "@baseboard_fab2_lib.baseboard_fab2(sch_1):page25_i172:DDR2_DQ(46)" )
				( pinRef "@baseboard_fab2_lib.baseboard_fab2(sch_1):page47_i111:DQ(47)" )
				( attribute "RELATIVE_PROPAGATION_DELAY_SCOPE" "G"
					( Parent
						( matchGroupRef "@baseboard_fab2_lib.baseboard_fab2(sch_1):\MG_DQ-DQS_FAR_DIMM_NG_M_C_BYTE5\" )
					)
					( Status sCSetFlattened )
					( Origin gBackEnd )
				)
				( attribute "RELATIVE_PROPAGATION_DELAY" "0.00 MIL,195.00 MIL"
					( Parent
						( matchGroupRef "@baseboard_fab2_lib.baseboard_fab2(sch_1):\MG_DQ-DQS_FAR_DIMM_NG_M_C_BYTE5\" )
					)
					( Units "uMatchProp" "ns" 1.000000)
					( Status sCSetFlattened )
					( Origin gBackEnd )
				)
				( attribute "RELATIVE_PROPAGATION_DELAY_SCOPE" "G"
					( Parent
						( matchGroupRef "@baseboard_fab2_lib.baseboard_fab2(sch_1):\MG_DQ_FAR_DIMM_NG_M_C_BYTE5\" )
					)
					( Status sCSetFlattened )
					( Origin gBackEnd )
				)
				( attribute "RELATIVE_PROPAGATION_DELAY" "-50.00 MIL,50.00 MIL"
					( Parent
						( matchGroupRef "@baseboard_fab2_lib.baseboard_fab2(sch_1):\MG_DQ_FAR_DIMM_NG_M_C_BYTE5\" )
					)
					( Units "uMatchProp" "ns" 1.000000)
					( Status sCSetFlattened )
					( Origin gBackEnd )
				)
			)
			( pinPair "@baseboard_fab2_lib.baseboard_fab2(sch_1):\PP4775\"
				( pinRef "@baseboard_fab2_lib.baseboard_fab2(sch_1):page25_i172:DDR2_DQ(46)" )
				( pinRef "@baseboard_fab2_lib.baseboard_fab2(sch_1):page48_i111:DQ(46)" )
				( attribute "RELATIVE_PROPAGATION_DELAY_SCOPE" "G"
					( Parent
						( matchGroupRef "@baseboard_fab2_lib.baseboard_fab2(sch_1):\MG_DQ-DQS_NEAR_DIMM_NG_M_C_BYTE5\" )
					)
					( Status sCSetFlattened )
					( Origin gBackEnd )
				)
				( attribute "RELATIVE_PROPAGATION_DELAY" "0.00 MIL,195.00 MIL"
					( Parent
						( matchGroupRef "@baseboard_fab2_lib.baseboard_fab2(sch_1):\MG_DQ-DQS_NEAR_DIMM_NG_M_C_BYTE5\" )
					)
					( Units "uMatchProp" "ns" 1.000000)
					( Status sCSetFlattened )
					( Origin gBackEnd )
				)
				( attribute "RELATIVE_PROPAGATION_DELAY_SCOPE" "G"
					( Parent
						( matchGroupRef "@baseboard_fab2_lib.baseboard_fab2(sch_1):\MG_DQ_NEAR_DIMM_NG_M_C_BYTE5\" )
					)
					( Status sCSetFlattened )
					( Origin gBackEnd )
				)
				( attribute "RELATIVE_PROPAGATION_DELAY" "-50.00 MIL,50.00 MIL"
					( Parent
						( matchGroupRef "@baseboard_fab2_lib.baseboard_fab2(sch_1):\MG_DQ_NEAR_DIMM_NG_M_C_BYTE5\" )
					)
					( Units "uMatchProp" "ns" 1.000000)
					( Status sCSetFlattened )
					( Origin gBackEnd )
				)
			)
			( pinPair "@baseboard_fab2_lib.baseboard_fab2(sch_1):\PP4776\"
				( pinRef "@baseboard_fab2_lib.baseboard_fab2(sch_1):page25_i172:DDR2_DQ(47)" )
				( pinRef "@baseboard_fab2_lib.baseboard_fab2(sch_1):page47_i111:DQ(46)" )
				( attribute "RELATIVE_PROPAGATION_DELAY_SCOPE" "G"
					( Parent
						( matchGroupRef "@baseboard_fab2_lib.baseboard_fab2(sch_1):\MG_DQ-DQS_FAR_DIMM_NG_M_C_BYTE5\" )
					)
					( Status sCSetFlattened )
					( Origin gBackEnd )
				)
				( attribute "RELATIVE_PROPAGATION_DELAY" "0.00 MIL,195.00 MIL"
					( Parent
						( matchGroupRef "@baseboard_fab2_lib.baseboard_fab2(sch_1):\MG_DQ-DQS_FAR_DIMM_NG_M_C_BYTE5\" )
					)
					( Units "uMatchProp" "ns" 1.000000)
					( Status sCSetFlattened )
					( Origin gBackEnd )
				)
				( attribute "RELATIVE_PROPAGATION_DELAY_SCOPE" "G"
					( Parent
						( matchGroupRef "@baseboard_fab2_lib.baseboard_fab2(sch_1):\MG_DQ_FAR_DIMM_NG_M_C_BYTE5\" )
					)
					( Status sCSetFlattened )
					( Origin gBackEnd )
				)
				( attribute "RELATIVE_PROPAGATION_DELAY" "-50.00 MIL,50.00 MIL"
					( Parent
						( matchGroupRef "@baseboard_fab2_lib.baseboard_fab2(sch_1):\MG_DQ_FAR_DIMM_NG_M_C_BYTE5\" )
					)
					( Units "uMatchProp" "ns" 1.000000)
					( Status sCSetFlattened )
					( Origin gBackEnd )
				)
			)
			( pinPair "@baseboard_fab2_lib.baseboard_fab2(sch_1):\PP4778\"
				( pinRef "@baseboard_fab2_lib.baseboard_fab2(sch_1):page25_i172:DDR2_DQ(47)" )
				( pinRef "@baseboard_fab2_lib.baseboard_fab2(sch_1):page48_i111:DQ(47)" )
				( attribute "RELATIVE_PROPAGATION_DELAY_SCOPE" "G"
					( Parent
						( matchGroupRef "@baseboard_fab2_lib.baseboard_fab2(sch_1):\MG_DQ-DQS_NEAR_DIMM_NG_M_C_BYTE5\" )
					)
					( Status sCSetFlattened )
					( Origin gBackEnd )
				)
				( attribute "RELATIVE_PROPAGATION_DELAY" "0.00 MIL,195.00 MIL"
					( Parent
						( matchGroupRef "@baseboard_fab2_lib.baseboard_fab2(sch_1):\MG_DQ-DQS_NEAR_DIMM_NG_M_C_BYTE5\" )
					)
					( Units "uMatchProp" "ns" 1.000000)
					( Status sCSetFlattened )
					( Origin gBackEnd )
				)
				( attribute "RELATIVE_PROPAGATION_DELAY_SCOPE" "G"
					( Parent
						( matchGroupRef "@baseboard_fab2_lib.baseboard_fab2(sch_1):\MG_DQ_NEAR_DIMM_NG_M_C_BYTE5\" )
					)
					( Status sCSetFlattened )
					( Origin gBackEnd )
				)
				( attribute "RELATIVE_PROPAGATION_DELAY" "-50.00 MIL,50.00 MIL"
					( Parent
						( matchGroupRef "@baseboard_fab2_lib.baseboard_fab2(sch_1):\MG_DQ_NEAR_DIMM_NG_M_C_BYTE5\" )
					)
					( Units "uMatchProp" "ns" 1.000000)
					( Status sCSetFlattened )
					( Origin gBackEnd )
				)
			)
			( pinPair "@baseboard_fab2_lib.baseboard_fab2(sch_1):\PP4731\"
				( pinRef "@baseboard_fab2_lib.baseboard_fab2(sch_1):page25_i172:DDR2_DQ(48)" )
				( pinRef "@baseboard_fab2_lib.baseboard_fab2(sch_1):page47_i111:DQ(49)" )
				( attribute "RELATIVE_PROPAGATION_DELAY_SCOPE" "G"
					( Parent
						( matchGroupRef "@baseboard_fab2_lib.baseboard_fab2(sch_1):\MG_DQ-DQS_FAR_DIMM_NG_M_C_BYTE6\" )
					)
					( Status sCSetFlattened )
					( Origin gBackEnd )
				)
				( attribute "RELATIVE_PROPAGATION_DELAY" "0.00 MIL,195.00 MIL"
					( Parent
						( matchGroupRef "@baseboard_fab2_lib.baseboard_fab2(sch_1):\MG_DQ-DQS_FAR_DIMM_NG_M_C_BYTE6\" )
					)
					( Units "uMatchProp" "ns" 1.000000)
					( Status sCSetFlattened )
					( Origin gBackEnd )
				)
				( attribute "RELATIVE_PROPAGATION_DELAY_SCOPE" "G"
					( Parent
						( matchGroupRef "@crescent_city_bb_fab1_lib.crescent_city_bb_fab1(sch_1):\MG_DQ_FAR_DIMM_NG_M_C_BYTE6\" )
					)
					( Status sCSetFlattened )
					( Origin gBackEnd )
				)
				( attribute "RELATIVE_PROPAGATION_DELAY" "-50.00 MIL,50.00 MIL"
					( Parent
						( matchGroupRef "@crescent_city_bb_fab1_lib.crescent_city_bb_fab1(sch_1):\MG_DQ_FAR_DIMM_NG_M_C_BYTE6\" )
					)
					( Units "uMatchProp" "ns" 1.000000)
					( Status sCSetFlattened )
					( Origin gBackEnd )
				)
			)
			( pinPair "@baseboard_fab2_lib.baseboard_fab2(sch_1):\PP4733\"
				( pinRef "@baseboard_fab2_lib.baseboard_fab2(sch_1):page25_i172:DDR2_DQ(48)" )
				( pinRef "@baseboard_fab2_lib.baseboard_fab2(sch_1):page48_i111:DQ(48)" )
				( attribute "RELATIVE_PROPAGATION_DELAY_SCOPE" "G"
					( Parent
						( matchGroupRef "@baseboard_fab2_lib.baseboard_fab2(sch_1):\MG_DQ-DQS_NEAR_DIMM_NG_M_C_BYTE6\" )
					)
					( Status sCSetFlattened )
					( Origin gBackEnd )
				)
				( attribute "RELATIVE_PROPAGATION_DELAY" "0.00 MIL,195.00 MIL"
					( Parent
						( matchGroupRef "@baseboard_fab2_lib.baseboard_fab2(sch_1):\MG_DQ-DQS_NEAR_DIMM_NG_M_C_BYTE6\" )
					)
					( Units "uMatchProp" "ns" 1.000000)
					( Status sCSetFlattened )
					( Origin gBackEnd )
				)
				( attribute "RELATIVE_PROPAGATION_DELAY_SCOPE" "G"
					( Parent
						( matchGroupRef "@crescent_city_bb_fab1_lib.crescent_city_bb_fab1(sch_1):\MG_DQ_NEAR_DIMM_NG_M_C_BYTE6\" )
					)
					( Status sCSetFlattened )
					( Origin gBackEnd )
				)
				( attribute "RELATIVE_PROPAGATION_DELAY" "-50.00 MIL,50.00 MIL"
					( Parent
						( matchGroupRef "@crescent_city_bb_fab1_lib.crescent_city_bb_fab1(sch_1):\MG_DQ_NEAR_DIMM_NG_M_C_BYTE6\" )
					)
					( Units "uMatchProp" "ns" 1.000000)
					( Status sCSetFlattened )
					( Origin gBackEnd )
				)
			)
			( pinPair "@baseboard_fab2_lib.baseboard_fab2(sch_1):\PP4734\"
				( pinRef "@baseboard_fab2_lib.baseboard_fab2(sch_1):page25_i172:DDR2_DQ(49)" )
				( pinRef "@baseboard_fab2_lib.baseboard_fab2(sch_1):page47_i111:DQ(48)" )
				( attribute "RELATIVE_PROPAGATION_DELAY_SCOPE" "G"
					( Parent
						( matchGroupRef "@baseboard_fab2_lib.baseboard_fab2(sch_1):\MG_DQ-DQS_FAR_DIMM_NG_M_C_BYTE6\" )
					)
					( Status sCSetFlattened )
					( Origin gBackEnd )
				)
				( attribute "RELATIVE_PROPAGATION_DELAY" "0.00 MIL,195.00 MIL"
					( Parent
						( matchGroupRef "@baseboard_fab2_lib.baseboard_fab2(sch_1):\MG_DQ-DQS_FAR_DIMM_NG_M_C_BYTE6\" )
					)
					( Units "uMatchProp" "ns" 1.000000)
					( Status sCSetFlattened )
					( Origin gBackEnd )
				)
				( attribute "RELATIVE_PROPAGATION_DELAY_SCOPE" "G"
					( Parent
						( matchGroupRef "@crescent_city_bb_fab1_lib.crescent_city_bb_fab1(sch_1):\MG_DQ_FAR_DIMM_NG_M_C_BYTE6\" )
					)
					( Status sCSetFlattened )
					( Origin gBackEnd )
				)
				( attribute "RELATIVE_PROPAGATION_DELAY" "-50.00 MIL,50.00 MIL"
					( Parent
						( matchGroupRef "@crescent_city_bb_fab1_lib.crescent_city_bb_fab1(sch_1):\MG_DQ_FAR_DIMM_NG_M_C_BYTE6\" )
					)
					( Units "uMatchProp" "ns" 1.000000)
					( Status sCSetFlattened )
					( Origin gBackEnd )
				)
			)
			( pinPair "@baseboard_fab2_lib.baseboard_fab2(sch_1):\PP4736\"
				( pinRef "@baseboard_fab2_lib.baseboard_fab2(sch_1):page25_i172:DDR2_DQ(49)" )
				( pinRef "@baseboard_fab2_lib.baseboard_fab2(sch_1):page48_i111:DQ(49)" )
				( attribute "RELATIVE_PROPAGATION_DELAY_SCOPE" "G"
					( Parent
						( matchGroupRef "@baseboard_fab2_lib.baseboard_fab2(sch_1):\MG_DQ-DQS_NEAR_DIMM_NG_M_C_BYTE6\" )
					)
					( Status sCSetFlattened )
					( Origin gBackEnd )
				)
				( attribute "RELATIVE_PROPAGATION_DELAY" "0.00 MIL,195.00 MIL"
					( Parent
						( matchGroupRef "@baseboard_fab2_lib.baseboard_fab2(sch_1):\MG_DQ-DQS_NEAR_DIMM_NG_M_C_BYTE6\" )
					)
					( Units "uMatchProp" "ns" 1.000000)
					( Status sCSetFlattened )
					( Origin gBackEnd )
				)
				( attribute "RELATIVE_PROPAGATION_DELAY_SCOPE" "G"
					( Parent
						( matchGroupRef "@crescent_city_bb_fab1_lib.crescent_city_bb_fab1(sch_1):\MG_DQ_NEAR_DIMM_NG_M_C_BYTE6\" )
					)
					( Status sCSetFlattened )
					( Origin gBackEnd )
				)
				( attribute "RELATIVE_PROPAGATION_DELAY" "-50.00 MIL,50.00 MIL"
					( Parent
						( matchGroupRef "@crescent_city_bb_fab1_lib.crescent_city_bb_fab1(sch_1):\MG_DQ_NEAR_DIMM_NG_M_C_BYTE6\" )
					)
					( Units "uMatchProp" "ns" 1.000000)
					( Status sCSetFlattened )
					( Origin gBackEnd )
				)
			)
			( pinPair "@baseboard_fab2_lib.baseboard_fab2(sch_1):\PP4737\"
				( pinRef "@baseboard_fab2_lib.baseboard_fab2(sch_1):page25_i172:DDR2_DQ(50)" )
				( pinRef "@baseboard_fab2_lib.baseboard_fab2(sch_1):page47_i111:DQ(51)" )
				( attribute "RELATIVE_PROPAGATION_DELAY_SCOPE" "G"
					( Parent
						( matchGroupRef "@baseboard_fab2_lib.baseboard_fab2(sch_1):\MG_DQ-DQS_FAR_DIMM_NG_M_C_BYTE6\" )
					)
					( Status sCSetFlattened )
					( Origin gBackEnd )
				)
				( attribute "RELATIVE_PROPAGATION_DELAY" "0.00 MIL,195.00 MIL"
					( Parent
						( matchGroupRef "@baseboard_fab2_lib.baseboard_fab2(sch_1):\MG_DQ-DQS_FAR_DIMM_NG_M_C_BYTE6\" )
					)
					( Units "uMatchProp" "ns" 1.000000)
					( Status sCSetFlattened )
					( Origin gBackEnd )
				)
				( attribute "RELATIVE_PROPAGATION_DELAY_SCOPE" "G"
					( Parent
						( matchGroupRef "@crescent_city_bb_fab1_lib.crescent_city_bb_fab1(sch_1):\MG_DQ_FAR_DIMM_NG_M_C_BYTE6\" )
					)
					( Status sCSetFlattened )
					( Origin gBackEnd )
				)
				( attribute "RELATIVE_PROPAGATION_DELAY" "-50.00 MIL,50.00 MIL"
					( Parent
						( matchGroupRef "@crescent_city_bb_fab1_lib.crescent_city_bb_fab1(sch_1):\MG_DQ_FAR_DIMM_NG_M_C_BYTE6\" )
					)
					( Units "uMatchProp" "ns" 1.000000)
					( Status sCSetFlattened )
					( Origin gBackEnd )
				)
			)
			( pinPair "@baseboard_fab2_lib.baseboard_fab2(sch_1):\PP4739\"
				( pinRef "@baseboard_fab2_lib.baseboard_fab2(sch_1):page25_i172:DDR2_DQ(50)" )
				( pinRef "@baseboard_fab2_lib.baseboard_fab2(sch_1):page48_i111:DQ(50)" )
				( attribute "RELATIVE_PROPAGATION_DELAY_SCOPE" "G"
					( Parent
						( matchGroupRef "@baseboard_fab2_lib.baseboard_fab2(sch_1):\MG_DQ-DQS_NEAR_DIMM_NG_M_C_BYTE6\" )
					)
					( Status sCSetFlattened )
					( Origin gBackEnd )
				)
				( attribute "RELATIVE_PROPAGATION_DELAY" "0.00 MIL,195.00 MIL"
					( Parent
						( matchGroupRef "@baseboard_fab2_lib.baseboard_fab2(sch_1):\MG_DQ-DQS_NEAR_DIMM_NG_M_C_BYTE6\" )
					)
					( Units "uMatchProp" "ns" 1.000000)
					( Status sCSetFlattened )
					( Origin gBackEnd )
				)
				( attribute "RELATIVE_PROPAGATION_DELAY_SCOPE" "G"
					( Parent
						( matchGroupRef "@crescent_city_bb_fab1_lib.crescent_city_bb_fab1(sch_1):\MG_DQ_NEAR_DIMM_NG_M_C_BYTE6\" )
					)
					( Status sCSetFlattened )
					( Origin gBackEnd )
				)
				( attribute "RELATIVE_PROPAGATION_DELAY" "-50.00 MIL,50.00 MIL"
					( Parent
						( matchGroupRef "@crescent_city_bb_fab1_lib.crescent_city_bb_fab1(sch_1):\MG_DQ_NEAR_DIMM_NG_M_C_BYTE6\" )
					)
					( Units "uMatchProp" "ns" 1.000000)
					( Status sCSetFlattened )
					( Origin gBackEnd )
				)
			)
			( pinPair "@baseboard_fab2_lib.baseboard_fab2(sch_1):\PP4740\"
				( pinRef "@baseboard_fab2_lib.baseboard_fab2(sch_1):page25_i172:DDR2_DQ(51)" )
				( pinRef "@baseboard_fab2_lib.baseboard_fab2(sch_1):page47_i111:DQ(50)" )
				( attribute "RELATIVE_PROPAGATION_DELAY_SCOPE" "G"
					( Parent
						( matchGroupRef "@baseboard_fab2_lib.baseboard_fab2(sch_1):\MG_DQ-DQS_FAR_DIMM_NG_M_C_BYTE6\" )
					)
					( Status sCSetFlattened )
					( Origin gBackEnd )
				)
				( attribute "RELATIVE_PROPAGATION_DELAY" "0.00 MIL,195.00 MIL"
					( Parent
						( matchGroupRef "@baseboard_fab2_lib.baseboard_fab2(sch_1):\MG_DQ-DQS_FAR_DIMM_NG_M_C_BYTE6\" )
					)
					( Units "uMatchProp" "ns" 1.000000)
					( Status sCSetFlattened )
					( Origin gBackEnd )
				)
				( attribute "RELATIVE_PROPAGATION_DELAY_SCOPE" "G"
					( Parent
						( matchGroupRef "@crescent_city_bb_fab1_lib.crescent_city_bb_fab1(sch_1):\MG_DQ_FAR_DIMM_NG_M_C_BYTE6\" )
					)
					( Status sCSetFlattened )
					( Origin gBackEnd )
				)
				( attribute "RELATIVE_PROPAGATION_DELAY" "-50.00 MIL,50.00 MIL"
					( Parent
						( matchGroupRef "@crescent_city_bb_fab1_lib.crescent_city_bb_fab1(sch_1):\MG_DQ_FAR_DIMM_NG_M_C_BYTE6\" )
					)
					( Units "uMatchProp" "ns" 1.000000)
					( Status sCSetFlattened )
					( Origin gBackEnd )
				)
			)
			( pinPair "@baseboard_fab2_lib.baseboard_fab2(sch_1):\PP4742\"
				( pinRef "@baseboard_fab2_lib.baseboard_fab2(sch_1):page25_i172:DDR2_DQ(51)" )
				( pinRef "@baseboard_fab2_lib.baseboard_fab2(sch_1):page48_i111:DQ(51)" )
				( attribute "RELATIVE_PROPAGATION_DELAY_SCOPE" "G"
					( Parent
						( matchGroupRef "@baseboard_fab2_lib.baseboard_fab2(sch_1):\MG_DQ-DQS_NEAR_DIMM_NG_M_C_BYTE6\" )
					)
					( Status sCSetFlattened )
					( Origin gBackEnd )
				)
				( attribute "RELATIVE_PROPAGATION_DELAY" "0.00 MIL,195.00 MIL"
					( Parent
						( matchGroupRef "@baseboard_fab2_lib.baseboard_fab2(sch_1):\MG_DQ-DQS_NEAR_DIMM_NG_M_C_BYTE6\" )
					)
					( Units "uMatchProp" "ns" 1.000000)
					( Status sCSetFlattened )
					( Origin gBackEnd )
				)
				( attribute "RELATIVE_PROPAGATION_DELAY_SCOPE" "G"
					( Parent
						( matchGroupRef "@crescent_city_bb_fab1_lib.crescent_city_bb_fab1(sch_1):\MG_DQ_NEAR_DIMM_NG_M_C_BYTE6\" )
					)
					( Status sCSetFlattened )
					( Origin gBackEnd )
				)
				( attribute "RELATIVE_PROPAGATION_DELAY" "-50.00 MIL,50.00 MIL"
					( Parent
						( matchGroupRef "@crescent_city_bb_fab1_lib.crescent_city_bb_fab1(sch_1):\MG_DQ_NEAR_DIMM_NG_M_C_BYTE6\" )
					)
					( Units "uMatchProp" "ns" 1.000000)
					( Status sCSetFlattened )
					( Origin gBackEnd )
				)
			)
			( pinPair "@baseboard_fab2_lib.baseboard_fab2(sch_1):\PP4743\"
				( pinRef "@baseboard_fab2_lib.baseboard_fab2(sch_1):page25_i172:DDR2_DQ(52)" )
				( pinRef "@baseboard_fab2_lib.baseboard_fab2(sch_1):page47_i111:DQ(53)" )
				( attribute "RELATIVE_PROPAGATION_DELAY_SCOPE" "G"
					( Parent
						( matchGroupRef "@baseboard_fab2_lib.baseboard_fab2(sch_1):\MG_DQ-DQS_FAR_DIMM_NG_M_C_BYTE6\" )
					)
					( Status sCSetFlattened )
					( Origin gBackEnd )
				)
				( attribute "RELATIVE_PROPAGATION_DELAY" "0.00 MIL,195.00 MIL"
					( Parent
						( matchGroupRef "@baseboard_fab2_lib.baseboard_fab2(sch_1):\MG_DQ-DQS_FAR_DIMM_NG_M_C_BYTE6\" )
					)
					( Units "uMatchProp" "ns" 1.000000)
					( Status sCSetFlattened )
					( Origin gBackEnd )
				)
				( attribute "RELATIVE_PROPAGATION_DELAY_SCOPE" "G"
					( Parent
						( matchGroupRef "@crescent_city_bb_fab1_lib.crescent_city_bb_fab1(sch_1):\MG_DQ_FAR_DIMM_NG_M_C_BYTE6\" )
					)
					( Status sCSetFlattened )
					( Origin gBackEnd )
				)
				( attribute "RELATIVE_PROPAGATION_DELAY" "-50.00 MIL,50.00 MIL"
					( Parent
						( matchGroupRef "@crescent_city_bb_fab1_lib.crescent_city_bb_fab1(sch_1):\MG_DQ_FAR_DIMM_NG_M_C_BYTE6\" )
					)
					( Units "uMatchProp" "ns" 1.000000)
					( Status sCSetFlattened )
					( Origin gBackEnd )
				)
			)
			( pinPair "@baseboard_fab2_lib.baseboard_fab2(sch_1):\PP4745\"
				( pinRef "@baseboard_fab2_lib.baseboard_fab2(sch_1):page25_i172:DDR2_DQ(52)" )
				( pinRef "@baseboard_fab2_lib.baseboard_fab2(sch_1):page48_i111:DQ(52)" )
				( attribute "RELATIVE_PROPAGATION_DELAY_SCOPE" "G"
					( Parent
						( matchGroupRef "@baseboard_fab2_lib.baseboard_fab2(sch_1):\MG_DQ-DQS_NEAR_DIMM_NG_M_C_BYTE6\" )
					)
					( Status sCSetFlattened )
					( Origin gBackEnd )
				)
				( attribute "RELATIVE_PROPAGATION_DELAY" "0.00 MIL,195.00 MIL"
					( Parent
						( matchGroupRef "@baseboard_fab2_lib.baseboard_fab2(sch_1):\MG_DQ-DQS_NEAR_DIMM_NG_M_C_BYTE6\" )
					)
					( Units "uMatchProp" "ns" 1.000000)
					( Status sCSetFlattened )
					( Origin gBackEnd )
				)
				( attribute "RELATIVE_PROPAGATION_DELAY_SCOPE" "G"
					( Parent
						( matchGroupRef "@crescent_city_bb_fab1_lib.crescent_city_bb_fab1(sch_1):\MG_DQ_NEAR_DIMM_NG_M_C_BYTE6\" )
					)
					( Status sCSetFlattened )
					( Origin gBackEnd )
				)
				( attribute "RELATIVE_PROPAGATION_DELAY" "-50.00 MIL,50.00 MIL"
					( Parent
						( matchGroupRef "@crescent_city_bb_fab1_lib.crescent_city_bb_fab1(sch_1):\MG_DQ_NEAR_DIMM_NG_M_C_BYTE6\" )
					)
					( Units "uMatchProp" "ns" 1.000000)
					( Status sCSetFlattened )
					( Origin gBackEnd )
				)
			)
			( pinPair "@baseboard_fab2_lib.baseboard_fab2(sch_1):\PP4746\"
				( pinRef "@baseboard_fab2_lib.baseboard_fab2(sch_1):page25_i172:DDR2_DQ(53)" )
				( pinRef "@baseboard_fab2_lib.baseboard_fab2(sch_1):page47_i111:DQ(52)" )
				( attribute "RELATIVE_PROPAGATION_DELAY_SCOPE" "G"
					( Parent
						( matchGroupRef "@baseboard_fab2_lib.baseboard_fab2(sch_1):\MG_DQ-DQS_FAR_DIMM_NG_M_C_BYTE6\" )
					)
					( Status sCSetFlattened )
					( Origin gBackEnd )
				)
				( attribute "RELATIVE_PROPAGATION_DELAY" "0.00 MIL,195.00 MIL"
					( Parent
						( matchGroupRef "@baseboard_fab2_lib.baseboard_fab2(sch_1):\MG_DQ-DQS_FAR_DIMM_NG_M_C_BYTE6\" )
					)
					( Units "uMatchProp" "ns" 1.000000)
					( Status sCSetFlattened )
					( Origin gBackEnd )
				)
				( attribute "RELATIVE_PROPAGATION_DELAY_SCOPE" "G"
					( Parent
						( matchGroupRef "@crescent_city_bb_fab1_lib.crescent_city_bb_fab1(sch_1):\MG_DQ_FAR_DIMM_NG_M_C_BYTE6\" )
					)
					( Status sCSetFlattened )
					( Origin gBackEnd )
				)
				( attribute "RELATIVE_PROPAGATION_DELAY" "-50.00 MIL,50.00 MIL"
					( Parent
						( matchGroupRef "@crescent_city_bb_fab1_lib.crescent_city_bb_fab1(sch_1):\MG_DQ_FAR_DIMM_NG_M_C_BYTE6\" )
					)
					( Units "uMatchProp" "ns" 1.000000)
					( Status sCSetFlattened )
					( Origin gBackEnd )
				)
			)
			( pinPair "@baseboard_fab2_lib.baseboard_fab2(sch_1):\PP4748\"
				( pinRef "@baseboard_fab2_lib.baseboard_fab2(sch_1):page25_i172:DDR2_DQ(53)" )
				( pinRef "@baseboard_fab2_lib.baseboard_fab2(sch_1):page48_i111:DQ(53)" )
				( attribute "RELATIVE_PROPAGATION_DELAY_SCOPE" "G"
					( Parent
						( matchGroupRef "@baseboard_fab2_lib.baseboard_fab2(sch_1):\MG_DQ-DQS_NEAR_DIMM_NG_M_C_BYTE6\" )
					)
					( Status sCSetFlattened )
					( Origin gBackEnd )
				)
				( attribute "RELATIVE_PROPAGATION_DELAY" "0.00 MIL,195.00 MIL"
					( Parent
						( matchGroupRef "@baseboard_fab2_lib.baseboard_fab2(sch_1):\MG_DQ-DQS_NEAR_DIMM_NG_M_C_BYTE6\" )
					)
					( Units "uMatchProp" "ns" 1.000000)
					( Status sCSetFlattened )
					( Origin gBackEnd )
				)
				( attribute "RELATIVE_PROPAGATION_DELAY_SCOPE" "G"
					( Parent
						( matchGroupRef "@crescent_city_bb_fab1_lib.crescent_city_bb_fab1(sch_1):\MG_DQ_NEAR_DIMM_NG_M_C_BYTE6\" )
					)
					( Status sCSetFlattened )
					( Origin gBackEnd )
				)
				( attribute "RELATIVE_PROPAGATION_DELAY" "-50.00 MIL,50.00 MIL"
					( Parent
						( matchGroupRef "@crescent_city_bb_fab1_lib.crescent_city_bb_fab1(sch_1):\MG_DQ_NEAR_DIMM_NG_M_C_BYTE6\" )
					)
					( Units "uMatchProp" "ns" 1.000000)
					( Status sCSetFlattened )
					( Origin gBackEnd )
				)
			)
			( pinPair "@baseboard_fab2_lib.baseboard_fab2(sch_1):\PP4749\"
				( pinRef "@baseboard_fab2_lib.baseboard_fab2(sch_1):page25_i172:DDR2_DQ(54)" )
				( pinRef "@baseboard_fab2_lib.baseboard_fab2(sch_1):page47_i111:DQ(55)" )
				( attribute "RELATIVE_PROPAGATION_DELAY_SCOPE" "G"
					( Parent
						( matchGroupRef "@baseboard_fab2_lib.baseboard_fab2(sch_1):\MG_DQ-DQS_FAR_DIMM_NG_M_C_BYTE6\" )
					)
					( Status sCSetFlattened )
					( Origin gBackEnd )
				)
				( attribute "RELATIVE_PROPAGATION_DELAY" "0.00 MIL,195.00 MIL"
					( Parent
						( matchGroupRef "@baseboard_fab2_lib.baseboard_fab2(sch_1):\MG_DQ-DQS_FAR_DIMM_NG_M_C_BYTE6\" )
					)
					( Units "uMatchProp" "ns" 1.000000)
					( Status sCSetFlattened )
					( Origin gBackEnd )
				)
				( attribute "RELATIVE_PROPAGATION_DELAY_SCOPE" "G"
					( Parent
						( matchGroupRef "@crescent_city_bb_fab1_lib.crescent_city_bb_fab1(sch_1):\MG_DQ_FAR_DIMM_NG_M_C_BYTE6\" )
					)
					( Status sCSetFlattened )
					( Origin gBackEnd )
				)
				( attribute "RELATIVE_PROPAGATION_DELAY" "-50.00 MIL,50.00 MIL"
					( Parent
						( matchGroupRef "@crescent_city_bb_fab1_lib.crescent_city_bb_fab1(sch_1):\MG_DQ_FAR_DIMM_NG_M_C_BYTE6\" )
					)
					( Units "uMatchProp" "ns" 1.000000)
					( Status sCSetFlattened )
					( Origin gBackEnd )
				)
			)
			( pinPair "@baseboard_fab2_lib.baseboard_fab2(sch_1):\PP4751\"
				( pinRef "@baseboard_fab2_lib.baseboard_fab2(sch_1):page25_i172:DDR2_DQ(54)" )
				( pinRef "@baseboard_fab2_lib.baseboard_fab2(sch_1):page48_i111:DQ(54)" )
				( attribute "RELATIVE_PROPAGATION_DELAY_SCOPE" "G"
					( Parent
						( matchGroupRef "@baseboard_fab2_lib.baseboard_fab2(sch_1):\MG_DQ-DQS_NEAR_DIMM_NG_M_C_BYTE6\" )
					)
					( Status sCSetFlattened )
					( Origin gBackEnd )
				)
				( attribute "RELATIVE_PROPAGATION_DELAY" "0.00 MIL,195.00 MIL"
					( Parent
						( matchGroupRef "@baseboard_fab2_lib.baseboard_fab2(sch_1):\MG_DQ-DQS_NEAR_DIMM_NG_M_C_BYTE6\" )
					)
					( Units "uMatchProp" "ns" 1.000000)
					( Status sCSetFlattened )
					( Origin gBackEnd )
				)
				( attribute "RELATIVE_PROPAGATION_DELAY_SCOPE" "G"
					( Parent
						( matchGroupRef "@crescent_city_bb_fab1_lib.crescent_city_bb_fab1(sch_1):\MG_DQ_NEAR_DIMM_NG_M_C_BYTE6\" )
					)
					( Status sCSetFlattened )
					( Origin gBackEnd )
				)
				( attribute "RELATIVE_PROPAGATION_DELAY" "-50.00 MIL,50.00 MIL"
					( Parent
						( matchGroupRef "@crescent_city_bb_fab1_lib.crescent_city_bb_fab1(sch_1):\MG_DQ_NEAR_DIMM_NG_M_C_BYTE6\" )
					)
					( Units "uMatchProp" "ns" 1.000000)
					( Status sCSetFlattened )
					( Origin gBackEnd )
				)
			)
			( pinPair "@baseboard_fab2_lib.baseboard_fab2(sch_1):\PP4752\"
				( pinRef "@baseboard_fab2_lib.baseboard_fab2(sch_1):page25_i172:DDR2_DQ(55)" )
				( pinRef "@baseboard_fab2_lib.baseboard_fab2(sch_1):page47_i111:DQ(54)" )
				( attribute "RELATIVE_PROPAGATION_DELAY_SCOPE" "G"
					( Parent
						( matchGroupRef "@baseboard_fab2_lib.baseboard_fab2(sch_1):\MG_DQ-DQS_FAR_DIMM_NG_M_C_BYTE6\" )
					)
					( Status sCSetFlattened )
					( Origin gBackEnd )
				)
				( attribute "RELATIVE_PROPAGATION_DELAY" "0.00 MIL,195.00 MIL"
					( Parent
						( matchGroupRef "@baseboard_fab2_lib.baseboard_fab2(sch_1):\MG_DQ-DQS_FAR_DIMM_NG_M_C_BYTE6\" )
					)
					( Units "uMatchProp" "ns" 1.000000)
					( Status sCSetFlattened )
					( Origin gBackEnd )
				)
				( attribute "RELATIVE_PROPAGATION_DELAY_SCOPE" "G"
					( Parent
						( matchGroupRef "@crescent_city_bb_fab1_lib.crescent_city_bb_fab1(sch_1):\MG_DQ_FAR_DIMM_NG_M_C_BYTE6\" )
					)
					( Origin gBackEnd )
				)
				( attribute "RELATIVE_PROPAGATION_DELAY" "TARGET,TARGET"
					( Parent
						( matchGroupRef "@crescent_city_bb_fab1_lib.crescent_city_bb_fab1(sch_1):\MG_DQ_FAR_DIMM_NG_M_C_BYTE6\" )
					)
					( Units "uMatchProp" "ns" 1.000000)
					( Origin gBackEnd )
				)
			)
			( pinPair "@baseboard_fab2_lib.baseboard_fab2(sch_1):\PP4754\"
				( pinRef "@baseboard_fab2_lib.baseboard_fab2(sch_1):page25_i172:DDR2_DQ(55)" )
				( pinRef "@baseboard_fab2_lib.baseboard_fab2(sch_1):page48_i111:DQ(55)" )
				( attribute "RELATIVE_PROPAGATION_DELAY_SCOPE" "G"
					( Parent
						( matchGroupRef "@baseboard_fab2_lib.baseboard_fab2(sch_1):\MG_DQ-DQS_NEAR_DIMM_NG_M_C_BYTE6\" )
					)
					( Status sCSetFlattened )
					( Origin gBackEnd )
				)
				( attribute "RELATIVE_PROPAGATION_DELAY" "0.00 MIL,195.00 MIL"
					( Parent
						( matchGroupRef "@baseboard_fab2_lib.baseboard_fab2(sch_1):\MG_DQ-DQS_NEAR_DIMM_NG_M_C_BYTE6\" )
					)
					( Units "uMatchProp" "ns" 1.000000)
					( Status sCSetFlattened )
					( Origin gBackEnd )
				)
				( attribute "RELATIVE_PROPAGATION_DELAY_SCOPE" "G"
					( Parent
						( matchGroupRef "@crescent_city_bb_fab1_lib.crescent_city_bb_fab1(sch_1):\MG_DQ_NEAR_DIMM_NG_M_C_BYTE6\" )
					)
					( Origin gBackEnd )
				)
				( attribute "RELATIVE_PROPAGATION_DELAY" "TARGET,TARGET"
					( Parent
						( matchGroupRef "@crescent_city_bb_fab1_lib.crescent_city_bb_fab1(sch_1):\MG_DQ_NEAR_DIMM_NG_M_C_BYTE6\" )
					)
					( Units "uMatchProp" "ns" 1.000000)
					( Origin gBackEnd )
				)
			)
			( pinPair "@baseboard_fab2_lib.baseboard_fab2(sch_1):\PP4707\"
				( pinRef "@baseboard_fab2_lib.baseboard_fab2(sch_1):page25_i172:DDR2_DQ(56)" )
				( pinRef "@baseboard_fab2_lib.baseboard_fab2(sch_1):page47_i111:DQ(57)" )
				( attribute "RELATIVE_PROPAGATION_DELAY_SCOPE" "G"
					( Parent
						( matchGroupRef "@baseboard_fab2_lib.baseboard_fab2(sch_1):\MG_DQ-DQS_FAR_DIMM_NG_M_C_BYTE7\" )
					)
					( Status sCSetFlattened )
					( Origin gBackEnd )
				)
				( attribute "RELATIVE_PROPAGATION_DELAY" "0.00 MIL,195.00 MIL"
					( Parent
						( matchGroupRef "@baseboard_fab2_lib.baseboard_fab2(sch_1):\MG_DQ-DQS_FAR_DIMM_NG_M_C_BYTE7\" )
					)
					( Units "uMatchProp" "ns" 1.000000)
					( Status sCSetFlattened )
					( Origin gBackEnd )
				)
				( attribute "RELATIVE_PROPAGATION_DELAY_SCOPE" "G"
					( Parent
						( matchGroupRef "@baseboard_fab2_lib.baseboard_fab2(sch_1):\MG_DQ_FAR_DIMM_NG_M_C_BYTE7\" )
					)
					( Status sCSetFlattened )
					( Origin gBackEnd )
				)
				( attribute "RELATIVE_PROPAGATION_DELAY" "-50.00 MIL,50.00 MIL"
					( Parent
						( matchGroupRef "@baseboard_fab2_lib.baseboard_fab2(sch_1):\MG_DQ_FAR_DIMM_NG_M_C_BYTE7\" )
					)
					( Units "uMatchProp" "ns" 1.000000)
					( Status sCSetFlattened )
					( Origin gBackEnd )
				)
			)
			( pinPair "@baseboard_fab2_lib.baseboard_fab2(sch_1):\PP4709\"
				( pinRef "@baseboard_fab2_lib.baseboard_fab2(sch_1):page25_i172:DDR2_DQ(56)" )
				( pinRef "@baseboard_fab2_lib.baseboard_fab2(sch_1):page48_i111:DQ(56)" )
				( attribute "RELATIVE_PROPAGATION_DELAY_SCOPE" "G"
					( Parent
						( matchGroupRef "@baseboard_fab2_lib.baseboard_fab2(sch_1):\MG_DQ-DQS_NEAR_DIMM_NG_M_C_BYTE7\" )
					)
					( Status sCSetFlattened )
					( Origin gBackEnd )
				)
				( attribute "RELATIVE_PROPAGATION_DELAY" "0.00 MIL,195.00 MIL"
					( Parent
						( matchGroupRef "@baseboard_fab2_lib.baseboard_fab2(sch_1):\MG_DQ-DQS_NEAR_DIMM_NG_M_C_BYTE7\" )
					)
					( Units "uMatchProp" "ns" 1.000000)
					( Status sCSetFlattened )
					( Origin gBackEnd )
				)
				( attribute "RELATIVE_PROPAGATION_DELAY_SCOPE" "G"
					( Parent
						( matchGroupRef "@baseboard_fab2_lib.baseboard_fab2(sch_1):\MG_DQ_NEAR_DIMM_NG_M_C_BYTE7\" )
					)
					( Status sCSetFlattened )
					( Origin gBackEnd )
				)
				( attribute "RELATIVE_PROPAGATION_DELAY" "-50.00 MIL,50.00 MIL"
					( Parent
						( matchGroupRef "@baseboard_fab2_lib.baseboard_fab2(sch_1):\MG_DQ_NEAR_DIMM_NG_M_C_BYTE7\" )
					)
					( Units "uMatchProp" "ns" 1.000000)
					( Status sCSetFlattened )
					( Origin gBackEnd )
				)
			)
			( pinPair "@baseboard_fab2_lib.baseboard_fab2(sch_1):\PP4710\"
				( pinRef "@baseboard_fab2_lib.baseboard_fab2(sch_1):page25_i172:DDR2_DQ(57)" )
				( pinRef "@baseboard_fab2_lib.baseboard_fab2(sch_1):page47_i111:DQ(56)" )
				( attribute "RELATIVE_PROPAGATION_DELAY_SCOPE" "G"
					( Parent
						( matchGroupRef "@baseboard_fab2_lib.baseboard_fab2(sch_1):\MG_DQ-DQS_FAR_DIMM_NG_M_C_BYTE7\" )
					)
					( Status sCSetFlattened )
					( Origin gBackEnd )
				)
				( attribute "RELATIVE_PROPAGATION_DELAY" "0.00 MIL,195.00 MIL"
					( Parent
						( matchGroupRef "@baseboard_fab2_lib.baseboard_fab2(sch_1):\MG_DQ-DQS_FAR_DIMM_NG_M_C_BYTE7\" )
					)
					( Units "uMatchProp" "ns" 1.000000)
					( Status sCSetFlattened )
					( Origin gBackEnd )
				)
				( attribute "RELATIVE_PROPAGATION_DELAY_SCOPE" "G"
					( Parent
						( matchGroupRef "@baseboard_fab2_lib.baseboard_fab2(sch_1):\MG_DQ_FAR_DIMM_NG_M_C_BYTE7\" )
					)
					( Status sCSetFlattened )
					( Origin gBackEnd )
				)
				( attribute "RELATIVE_PROPAGATION_DELAY" "-50.00 MIL,50.00 MIL"
					( Parent
						( matchGroupRef "@baseboard_fab2_lib.baseboard_fab2(sch_1):\MG_DQ_FAR_DIMM_NG_M_C_BYTE7\" )
					)
					( Units "uMatchProp" "ns" 1.000000)
					( Status sCSetFlattened )
					( Origin gBackEnd )
				)
			)
			( pinPair "@baseboard_fab2_lib.baseboard_fab2(sch_1):\PP4712\"
				( pinRef "@baseboard_fab2_lib.baseboard_fab2(sch_1):page25_i172:DDR2_DQ(57)" )
				( pinRef "@baseboard_fab2_lib.baseboard_fab2(sch_1):page48_i111:DQ(57)" )
				( attribute "RELATIVE_PROPAGATION_DELAY_SCOPE" "G"
					( Parent
						( matchGroupRef "@baseboard_fab2_lib.baseboard_fab2(sch_1):\MG_DQ-DQS_NEAR_DIMM_NG_M_C_BYTE7\" )
					)
					( Status sCSetFlattened )
					( Origin gBackEnd )
				)
				( attribute "RELATIVE_PROPAGATION_DELAY" "0.00 MIL,195.00 MIL"
					( Parent
						( matchGroupRef "@baseboard_fab2_lib.baseboard_fab2(sch_1):\MG_DQ-DQS_NEAR_DIMM_NG_M_C_BYTE7\" )
					)
					( Units "uMatchProp" "ns" 1.000000)
					( Status sCSetFlattened )
					( Origin gBackEnd )
				)
				( attribute "RELATIVE_PROPAGATION_DELAY_SCOPE" "G"
					( Parent
						( matchGroupRef "@baseboard_fab2_lib.baseboard_fab2(sch_1):\MG_DQ_NEAR_DIMM_NG_M_C_BYTE7\" )
					)
					( Status sCSetFlattened )
					( Origin gBackEnd )
				)
				( attribute "RELATIVE_PROPAGATION_DELAY" "-50.00 MIL,50.00 MIL"
					( Parent
						( matchGroupRef "@baseboard_fab2_lib.baseboard_fab2(sch_1):\MG_DQ_NEAR_DIMM_NG_M_C_BYTE7\" )
					)
					( Units "uMatchProp" "ns" 1.000000)
					( Status sCSetFlattened )
					( Origin gBackEnd )
				)
			)
			( pinPair "@baseboard_fab2_lib.baseboard_fab2(sch_1):\PP4713\"
				( pinRef "@baseboard_fab2_lib.baseboard_fab2(sch_1):page25_i172:DDR2_DQ(58)" )
				( pinRef "@baseboard_fab2_lib.baseboard_fab2(sch_1):page47_i111:DQ(59)" )
				( attribute "RELATIVE_PROPAGATION_DELAY_SCOPE" "G"
					( Parent
						( matchGroupRef "@baseboard_fab2_lib.baseboard_fab2(sch_1):\MG_DQ-DQS_FAR_DIMM_NG_M_C_BYTE7\" )
					)
					( Status sCSetFlattened )
					( Origin gBackEnd )
				)
				( attribute "RELATIVE_PROPAGATION_DELAY" "0.00 MIL,195.00 MIL"
					( Parent
						( matchGroupRef "@baseboard_fab2_lib.baseboard_fab2(sch_1):\MG_DQ-DQS_FAR_DIMM_NG_M_C_BYTE7\" )
					)
					( Units "uMatchProp" "ns" 1.000000)
					( Status sCSetFlattened )
					( Origin gBackEnd )
				)
				( attribute "RELATIVE_PROPAGATION_DELAY_SCOPE" "G"
					( Parent
						( matchGroupRef "@baseboard_fab2_lib.baseboard_fab2(sch_1):\MG_DQ_FAR_DIMM_NG_M_C_BYTE7\" )
					)
					( Status sCSetFlattened )
					( Origin gBackEnd )
				)
				( attribute "RELATIVE_PROPAGATION_DELAY" "-50.00 MIL,50.00 MIL"
					( Parent
						( matchGroupRef "@baseboard_fab2_lib.baseboard_fab2(sch_1):\MG_DQ_FAR_DIMM_NG_M_C_BYTE7\" )
					)
					( Units "uMatchProp" "ns" 1.000000)
					( Status sCSetFlattened )
					( Origin gBackEnd )
				)
			)
			( pinPair "@baseboard_fab2_lib.baseboard_fab2(sch_1):\PP4715\"
				( pinRef "@baseboard_fab2_lib.baseboard_fab2(sch_1):page25_i172:DDR2_DQ(58)" )
				( pinRef "@baseboard_fab2_lib.baseboard_fab2(sch_1):page48_i111:DQ(58)" )
				( attribute "RELATIVE_PROPAGATION_DELAY_SCOPE" "G"
					( Parent
						( matchGroupRef "@baseboard_fab2_lib.baseboard_fab2(sch_1):\MG_DQ-DQS_NEAR_DIMM_NG_M_C_BYTE7\" )
					)
					( Status sCSetFlattened )
					( Origin gBackEnd )
				)
				( attribute "RELATIVE_PROPAGATION_DELAY" "0.00 MIL,195.00 MIL"
					( Parent
						( matchGroupRef "@baseboard_fab2_lib.baseboard_fab2(sch_1):\MG_DQ-DQS_NEAR_DIMM_NG_M_C_BYTE7\" )
					)
					( Units "uMatchProp" "ns" 1.000000)
					( Status sCSetFlattened )
					( Origin gBackEnd )
				)
				( attribute "RELATIVE_PROPAGATION_DELAY_SCOPE" "G"
					( Parent
						( matchGroupRef "@baseboard_fab2_lib.baseboard_fab2(sch_1):\MG_DQ_NEAR_DIMM_NG_M_C_BYTE7\" )
					)
					( Status sCSetFlattened )
					( Origin gBackEnd )
				)
				( attribute "RELATIVE_PROPAGATION_DELAY" "-50.00 MIL,50.00 MIL"
					( Parent
						( matchGroupRef "@baseboard_fab2_lib.baseboard_fab2(sch_1):\MG_DQ_NEAR_DIMM_NG_M_C_BYTE7\" )
					)
					( Units "uMatchProp" "ns" 1.000000)
					( Status sCSetFlattened )
					( Origin gBackEnd )
				)
			)
			( pinPair "@baseboard_fab2_lib.baseboard_fab2(sch_1):\PP4716\"
				( pinRef "@baseboard_fab2_lib.baseboard_fab2(sch_1):page25_i172:DDR2_DQ(59)" )
				( pinRef "@baseboard_fab2_lib.baseboard_fab2(sch_1):page47_i111:DQ(58)" )
				( attribute "RELATIVE_PROPAGATION_DELAY_SCOPE" "G"
					( Parent
						( matchGroupRef "@baseboard_fab2_lib.baseboard_fab2(sch_1):\MG_DQ-DQS_FAR_DIMM_NG_M_C_BYTE7\" )
					)
					( Status sCSetFlattened )
					( Origin gBackEnd )
				)
				( attribute "RELATIVE_PROPAGATION_DELAY" "0.00 MIL,195.00 MIL"
					( Parent
						( matchGroupRef "@baseboard_fab2_lib.baseboard_fab2(sch_1):\MG_DQ-DQS_FAR_DIMM_NG_M_C_BYTE7\" )
					)
					( Units "uMatchProp" "ns" 1.000000)
					( Status sCSetFlattened )
					( Origin gBackEnd )
				)
				( attribute "RELATIVE_PROPAGATION_DELAY_SCOPE" "G"
					( Parent
						( matchGroupRef "@baseboard_fab2_lib.baseboard_fab2(sch_1):\MG_DQ_FAR_DIMM_NG_M_C_BYTE7\" )
					)
					( Status sCSetFlattened )
					( Origin gBackEnd )
				)
				( attribute "RELATIVE_PROPAGATION_DELAY" "-50.00 MIL,50.00 MIL"
					( Parent
						( matchGroupRef "@baseboard_fab2_lib.baseboard_fab2(sch_1):\MG_DQ_FAR_DIMM_NG_M_C_BYTE7\" )
					)
					( Units "uMatchProp" "ns" 1.000000)
					( Status sCSetFlattened )
					( Origin gBackEnd )
				)
			)
			( pinPair "@baseboard_fab2_lib.baseboard_fab2(sch_1):\PP4718\"
				( pinRef "@baseboard_fab2_lib.baseboard_fab2(sch_1):page25_i172:DDR2_DQ(59)" )
				( pinRef "@baseboard_fab2_lib.baseboard_fab2(sch_1):page48_i111:DQ(59)" )
				( attribute "RELATIVE_PROPAGATION_DELAY_SCOPE" "G"
					( Parent
						( matchGroupRef "@baseboard_fab2_lib.baseboard_fab2(sch_1):\MG_DQ-DQS_NEAR_DIMM_NG_M_C_BYTE7\" )
					)
					( Status sCSetFlattened )
					( Origin gBackEnd )
				)
				( attribute "RELATIVE_PROPAGATION_DELAY" "0.00 MIL,195.00 MIL"
					( Parent
						( matchGroupRef "@baseboard_fab2_lib.baseboard_fab2(sch_1):\MG_DQ-DQS_NEAR_DIMM_NG_M_C_BYTE7\" )
					)
					( Units "uMatchProp" "ns" 1.000000)
					( Status sCSetFlattened )
					( Origin gBackEnd )
				)
				( attribute "RELATIVE_PROPAGATION_DELAY_SCOPE" "G"
					( Parent
						( matchGroupRef "@baseboard_fab2_lib.baseboard_fab2(sch_1):\MG_DQ_NEAR_DIMM_NG_M_C_BYTE7\" )
					)
					( Status sCSetFlattened )
					( Origin gBackEnd )
				)
				( attribute "RELATIVE_PROPAGATION_DELAY" "-50.00 MIL,50.00 MIL"
					( Parent
						( matchGroupRef "@baseboard_fab2_lib.baseboard_fab2(sch_1):\MG_DQ_NEAR_DIMM_NG_M_C_BYTE7\" )
					)
					( Units "uMatchProp" "ns" 1.000000)
					( Status sCSetFlattened )
					( Origin gBackEnd )
				)
			)
			( pinPair "@baseboard_fab2_lib.baseboard_fab2(sch_1):\PP4719\"
				( pinRef "@baseboard_fab2_lib.baseboard_fab2(sch_1):page25_i172:DDR2_DQ(60)" )
				( pinRef "@baseboard_fab2_lib.baseboard_fab2(sch_1):page47_i111:DQ(61)" )
				( attribute "RELATIVE_PROPAGATION_DELAY_SCOPE" "G"
					( Parent
						( matchGroupRef "@baseboard_fab2_lib.baseboard_fab2(sch_1):\MG_DQ-DQS_FAR_DIMM_NG_M_C_BYTE7\" )
					)
					( Status sCSetFlattened )
					( Origin gBackEnd )
				)
				( attribute "RELATIVE_PROPAGATION_DELAY" "0.00 MIL,195.00 MIL"
					( Parent
						( matchGroupRef "@baseboard_fab2_lib.baseboard_fab2(sch_1):\MG_DQ-DQS_FAR_DIMM_NG_M_C_BYTE7\" )
					)
					( Units "uMatchProp" "ns" 1.000000)
					( Status sCSetFlattened )
					( Origin gBackEnd )
				)
				( attribute "RELATIVE_PROPAGATION_DELAY_SCOPE" "G"
					( Parent
						( matchGroupRef "@baseboard_fab2_lib.baseboard_fab2(sch_1):\MG_DQ_FAR_DIMM_NG_M_C_BYTE7\" )
					)
					( Status sCSetFlattened )
					( Origin gBackEnd )
				)
				( attribute "RELATIVE_PROPAGATION_DELAY" "-50.00 MIL,50.00 MIL"
					( Parent
						( matchGroupRef "@baseboard_fab2_lib.baseboard_fab2(sch_1):\MG_DQ_FAR_DIMM_NG_M_C_BYTE7\" )
					)
					( Units "uMatchProp" "ns" 1.000000)
					( Status sCSetFlattened )
					( Origin gBackEnd )
				)
			)
			( pinPair "@baseboard_fab2_lib.baseboard_fab2(sch_1):\PP4721\"
				( pinRef "@baseboard_fab2_lib.baseboard_fab2(sch_1):page25_i172:DDR2_DQ(60)" )
				( pinRef "@baseboard_fab2_lib.baseboard_fab2(sch_1):page48_i111:DQ(60)" )
				( attribute "RELATIVE_PROPAGATION_DELAY_SCOPE" "G"
					( Parent
						( matchGroupRef "@baseboard_fab2_lib.baseboard_fab2(sch_1):\MG_DQ-DQS_NEAR_DIMM_NG_M_C_BYTE7\" )
					)
					( Status sCSetFlattened )
					( Origin gBackEnd )
				)
				( attribute "RELATIVE_PROPAGATION_DELAY" "0.00 MIL,195.00 MIL"
					( Parent
						( matchGroupRef "@baseboard_fab2_lib.baseboard_fab2(sch_1):\MG_DQ-DQS_NEAR_DIMM_NG_M_C_BYTE7\" )
					)
					( Units "uMatchProp" "ns" 1.000000)
					( Status sCSetFlattened )
					( Origin gBackEnd )
				)
				( attribute "RELATIVE_PROPAGATION_DELAY_SCOPE" "G"
					( Parent
						( matchGroupRef "@baseboard_fab2_lib.baseboard_fab2(sch_1):\MG_DQ_NEAR_DIMM_NG_M_C_BYTE7\" )
					)
					( Status sCSetFlattened )
					( Origin gBackEnd )
				)
				( attribute "RELATIVE_PROPAGATION_DELAY" "-50.00 MIL,50.00 MIL"
					( Parent
						( matchGroupRef "@baseboard_fab2_lib.baseboard_fab2(sch_1):\MG_DQ_NEAR_DIMM_NG_M_C_BYTE7\" )
					)
					( Units "uMatchProp" "ns" 1.000000)
					( Status sCSetFlattened )
					( Origin gBackEnd )
				)
			)
			( pinPair "@baseboard_fab2_lib.baseboard_fab2(sch_1):\PP4722\"
				( pinRef "@baseboard_fab2_lib.baseboard_fab2(sch_1):page25_i172:DDR2_DQ(61)" )
				( pinRef "@baseboard_fab2_lib.baseboard_fab2(sch_1):page47_i111:DQ(60)" )
				( attribute "RELATIVE_PROPAGATION_DELAY_SCOPE" "G"
					( Parent
						( matchGroupRef "@baseboard_fab2_lib.baseboard_fab2(sch_1):\MG_DQ-DQS_FAR_DIMM_NG_M_C_BYTE7\" )
					)
					( Status sCSetFlattened )
					( Origin gBackEnd )
				)
				( attribute "RELATIVE_PROPAGATION_DELAY" "0.00 MIL,195.00 MIL"
					( Parent
						( matchGroupRef "@baseboard_fab2_lib.baseboard_fab2(sch_1):\MG_DQ-DQS_FAR_DIMM_NG_M_C_BYTE7\" )
					)
					( Units "uMatchProp" "ns" 1.000000)
					( Status sCSetFlattened )
					( Origin gBackEnd )
				)
				( attribute "RELATIVE_PROPAGATION_DELAY_SCOPE" "G"
					( Parent
						( matchGroupRef "@baseboard_fab2_lib.baseboard_fab2(sch_1):\MG_DQ_FAR_DIMM_NG_M_C_BYTE7\" )
					)
					( Status sCSetFlattened )
					( Origin gBackEnd )
				)
				( attribute "RELATIVE_PROPAGATION_DELAY" "-50.00 MIL,50.00 MIL"
					( Parent
						( matchGroupRef "@baseboard_fab2_lib.baseboard_fab2(sch_1):\MG_DQ_FAR_DIMM_NG_M_C_BYTE7\" )
					)
					( Units "uMatchProp" "ns" 1.000000)
					( Status sCSetFlattened )
					( Origin gBackEnd )
				)
			)
			( pinPair "@baseboard_fab2_lib.baseboard_fab2(sch_1):\PP4724\"
				( pinRef "@baseboard_fab2_lib.baseboard_fab2(sch_1):page25_i172:DDR2_DQ(61)" )
				( pinRef "@baseboard_fab2_lib.baseboard_fab2(sch_1):page48_i111:DQ(61)" )
				( attribute "RELATIVE_PROPAGATION_DELAY_SCOPE" "G"
					( Parent
						( matchGroupRef "@baseboard_fab2_lib.baseboard_fab2(sch_1):\MG_DQ-DQS_NEAR_DIMM_NG_M_C_BYTE7\" )
					)
					( Status sCSetFlattened )
					( Origin gBackEnd )
				)
				( attribute "RELATIVE_PROPAGATION_DELAY" "0.00 MIL,195.00 MIL"
					( Parent
						( matchGroupRef "@baseboard_fab2_lib.baseboard_fab2(sch_1):\MG_DQ-DQS_NEAR_DIMM_NG_M_C_BYTE7\" )
					)
					( Units "uMatchProp" "ns" 1.000000)
					( Status sCSetFlattened )
					( Origin gBackEnd )
				)
				( attribute "RELATIVE_PROPAGATION_DELAY_SCOPE" "G"
					( Parent
						( matchGroupRef "@baseboard_fab2_lib.baseboard_fab2(sch_1):\MG_DQ_NEAR_DIMM_NG_M_C_BYTE7\" )
					)
					( Status sCSetFlattened )
					( Origin gBackEnd )
				)
				( attribute "RELATIVE_PROPAGATION_DELAY" "-50.00 MIL,50.00 MIL"
					( Parent
						( matchGroupRef "@baseboard_fab2_lib.baseboard_fab2(sch_1):\MG_DQ_NEAR_DIMM_NG_M_C_BYTE7\" )
					)
					( Units "uMatchProp" "ns" 1.000000)
					( Status sCSetFlattened )
					( Origin gBackEnd )
				)
			)
			( pinPair "@baseboard_fab2_lib.baseboard_fab2(sch_1):\PP4725\"
				( pinRef "@baseboard_fab2_lib.baseboard_fab2(sch_1):page25_i172:DDR2_DQ(62)" )
				( pinRef "@baseboard_fab2_lib.baseboard_fab2(sch_1):page47_i111:DQ(63)" )
				( attribute "RELATIVE_PROPAGATION_DELAY_SCOPE" "G"
					( Parent
						( matchGroupRef "@baseboard_fab2_lib.baseboard_fab2(sch_1):\MG_DQ-DQS_FAR_DIMM_NG_M_C_BYTE7\" )
					)
					( Status sCSetFlattened )
					( Origin gBackEnd )
				)
				( attribute "RELATIVE_PROPAGATION_DELAY" "0.00 MIL,195.00 MIL"
					( Parent
						( matchGroupRef "@baseboard_fab2_lib.baseboard_fab2(sch_1):\MG_DQ-DQS_FAR_DIMM_NG_M_C_BYTE7\" )
					)
					( Units "uMatchProp" "ns" 1.000000)
					( Status sCSetFlattened )
					( Origin gBackEnd )
				)
				( attribute "RELATIVE_PROPAGATION_DELAY_SCOPE" "G"
					( Parent
						( matchGroupRef "@baseboard_fab2_lib.baseboard_fab2(sch_1):\MG_DQ_FAR_DIMM_NG_M_C_BYTE7\" )
					)
					( Status sCSetFlattened )
					( Origin gBackEnd )
				)
				( attribute "RELATIVE_PROPAGATION_DELAY" "-50.00 MIL,50.00 MIL"
					( Parent
						( matchGroupRef "@baseboard_fab2_lib.baseboard_fab2(sch_1):\MG_DQ_FAR_DIMM_NG_M_C_BYTE7\" )
					)
					( Units "uMatchProp" "ns" 1.000000)
					( Status sCSetFlattened )
					( Origin gBackEnd )
				)
			)
			( pinPair "@baseboard_fab2_lib.baseboard_fab2(sch_1):\PP4727\"
				( pinRef "@baseboard_fab2_lib.baseboard_fab2(sch_1):page25_i172:DDR2_DQ(62)" )
				( pinRef "@baseboard_fab2_lib.baseboard_fab2(sch_1):page48_i111:DQ(62)" )
				( attribute "RELATIVE_PROPAGATION_DELAY_SCOPE" "G"
					( Parent
						( matchGroupRef "@baseboard_fab2_lib.baseboard_fab2(sch_1):\MG_DQ-DQS_NEAR_DIMM_NG_M_C_BYTE7\" )
					)
					( Status sCSetFlattened )
					( Origin gBackEnd )
				)
				( attribute "RELATIVE_PROPAGATION_DELAY" "0.00 MIL,195.00 MIL"
					( Parent
						( matchGroupRef "@baseboard_fab2_lib.baseboard_fab2(sch_1):\MG_DQ-DQS_NEAR_DIMM_NG_M_C_BYTE7\" )
					)
					( Units "uMatchProp" "ns" 1.000000)
					( Status sCSetFlattened )
					( Origin gBackEnd )
				)
				( attribute "RELATIVE_PROPAGATION_DELAY_SCOPE" "G"
					( Parent
						( matchGroupRef "@baseboard_fab2_lib.baseboard_fab2(sch_1):\MG_DQ_NEAR_DIMM_NG_M_C_BYTE7\" )
					)
					( Status sCSetFlattened )
					( Origin gBackEnd )
				)
				( attribute "RELATIVE_PROPAGATION_DELAY" "-50.00 MIL,50.00 MIL"
					( Parent
						( matchGroupRef "@baseboard_fab2_lib.baseboard_fab2(sch_1):\MG_DQ_NEAR_DIMM_NG_M_C_BYTE7\" )
					)
					( Units "uMatchProp" "ns" 1.000000)
					( Status sCSetFlattened )
					( Origin gBackEnd )
				)
			)
			( pinPair "@baseboard_fab2_lib.baseboard_fab2(sch_1):\PP4728\"
				( pinRef "@baseboard_fab2_lib.baseboard_fab2(sch_1):page25_i172:DDR2_DQ(63)" )
				( pinRef "@baseboard_fab2_lib.baseboard_fab2(sch_1):page47_i111:DQ(62)" )
				( attribute "RELATIVE_PROPAGATION_DELAY_SCOPE" "G"
					( Parent
						( matchGroupRef "@baseboard_fab2_lib.baseboard_fab2(sch_1):\MG_DQ-DQS_FAR_DIMM_NG_M_C_BYTE7\" )
					)
					( Status sCSetFlattened )
					( Origin gBackEnd )
				)
				( attribute "RELATIVE_PROPAGATION_DELAY" "0.00 MIL,195.00 MIL"
					( Parent
						( matchGroupRef "@baseboard_fab2_lib.baseboard_fab2(sch_1):\MG_DQ-DQS_FAR_DIMM_NG_M_C_BYTE7\" )
					)
					( Units "uMatchProp" "ns" 1.000000)
					( Status sCSetFlattened )
					( Origin gBackEnd )
				)
				( attribute "RELATIVE_PROPAGATION_DELAY_SCOPE" "G"
					( Parent
						( matchGroupRef "@baseboard_fab2_lib.baseboard_fab2(sch_1):\MG_DQ_FAR_DIMM_NG_M_C_BYTE7\" )
					)
					( Status sCSetFlattened )
					( Origin gBackEnd )
				)
				( attribute "RELATIVE_PROPAGATION_DELAY" "-50.00 MIL,50.00 MIL"
					( Parent
						( matchGroupRef "@baseboard_fab2_lib.baseboard_fab2(sch_1):\MG_DQ_FAR_DIMM_NG_M_C_BYTE7\" )
					)
					( Units "uMatchProp" "ns" 1.000000)
					( Status sCSetFlattened )
					( Origin gBackEnd )
				)
			)
			( pinPair "@baseboard_fab2_lib.baseboard_fab2(sch_1):\PP4730\"
				( pinRef "@baseboard_fab2_lib.baseboard_fab2(sch_1):page25_i172:DDR2_DQ(63)" )
				( pinRef "@baseboard_fab2_lib.baseboard_fab2(sch_1):page48_i111:DQ(63)" )
				( attribute "RELATIVE_PROPAGATION_DELAY_SCOPE" "G"
					( Parent
						( matchGroupRef "@baseboard_fab2_lib.baseboard_fab2(sch_1):\MG_DQ-DQS_NEAR_DIMM_NG_M_C_BYTE7\" )
					)
					( Status sCSetFlattened )
					( Origin gBackEnd )
				)
				( attribute "RELATIVE_PROPAGATION_DELAY" "0.00 MIL,195.00 MIL"
					( Parent
						( matchGroupRef "@baseboard_fab2_lib.baseboard_fab2(sch_1):\MG_DQ-DQS_NEAR_DIMM_NG_M_C_BYTE7\" )
					)
					( Units "uMatchProp" "ns" 1.000000)
					( Status sCSetFlattened )
					( Origin gBackEnd )
				)
				( attribute "RELATIVE_PROPAGATION_DELAY_SCOPE" "G"
					( Parent
						( matchGroupRef "@baseboard_fab2_lib.baseboard_fab2(sch_1):\MG_DQ_NEAR_DIMM_NG_M_C_BYTE7\" )
					)
					( Status sCSetFlattened )
					( Origin gBackEnd )
				)
				( attribute "RELATIVE_PROPAGATION_DELAY" "-50.00 MIL,50.00 MIL"
					( Parent
						( matchGroupRef "@baseboard_fab2_lib.baseboard_fab2(sch_1):\MG_DQ_NEAR_DIMM_NG_M_C_BYTE7\" )
					)
					( Units "uMatchProp" "ns" 1.000000)
					( Status sCSetFlattened )
					( Origin gBackEnd )
				)
			)
			( pinPair "@baseboard_fab2_lib.baseboard_fab2(sch_1):\PP4683\"
				( pinRef "@baseboard_fab2_lib.baseboard_fab2(sch_1):page26_i172:DDR3_DQ(0)" )
				( pinRef "@baseboard_fab2_lib.baseboard_fab2(sch_1):page49_i111:DQ(1)" )
				( attribute "RELATIVE_PROPAGATION_DELAY_SCOPE" "G"
					( Parent
						( matchGroupRef "@baseboard_fab2_lib.baseboard_fab2(sch_1):\MG_DQ-DQS_FAR_DIMM_NG_M_D_BYTE0\" )
					)
					( Status sCSetFlattened )
					( Origin gBackEnd )
				)
				( attribute "RELATIVE_PROPAGATION_DELAY" "0.00 MIL,195.00 MIL"
					( Parent
						( matchGroupRef "@baseboard_fab2_lib.baseboard_fab2(sch_1):\MG_DQ-DQS_FAR_DIMM_NG_M_D_BYTE0\" )
					)
					( Units "uMatchProp" "ns" 1.000000)
					( Status sCSetFlattened )
					( Origin gBackEnd )
				)
				( attribute "RELATIVE_PROPAGATION_DELAY_SCOPE" "G"
					( Parent
						( matchGroupRef "@baseboard_fab2_lib.baseboard_fab2(sch_1):\MG_DQ_FAR_DIMM_NG_M_D_BYTE0\" )
					)
					( Status sCSetFlattened )
					( Origin gBackEnd )
				)
				( attribute "RELATIVE_PROPAGATION_DELAY" "-50.00 MIL,50.00 MIL"
					( Parent
						( matchGroupRef "@baseboard_fab2_lib.baseboard_fab2(sch_1):\MG_DQ_FAR_DIMM_NG_M_D_BYTE0\" )
					)
					( Units "uMatchProp" "ns" 1.000000)
					( Status sCSetFlattened )
					( Origin gBackEnd )
				)
			)
			( pinPair "@baseboard_fab2_lib.baseboard_fab2(sch_1):\PP4685\"
				( pinRef "@baseboard_fab2_lib.baseboard_fab2(sch_1):page50_i158:DQ(0)" )
				( pinRef "@baseboard_fab2_lib.baseboard_fab2(sch_1):page26_i172:DDR3_DQ(0)" )
				( attribute "RELATIVE_PROPAGATION_DELAY_SCOPE" "G"
					( Parent
						( matchGroupRef "@baseboard_fab2_lib.baseboard_fab2(sch_1):\MG_DQ-DQS_NEAR_DIMM_NG_M_D_BYTE0\" )
					)
					( Status sCSetFlattened )
					( Origin gBackEnd )
				)
				( attribute "RELATIVE_PROPAGATION_DELAY" "0.00 MIL,195.00 MIL"
					( Parent
						( matchGroupRef "@baseboard_fab2_lib.baseboard_fab2(sch_1):\MG_DQ-DQS_NEAR_DIMM_NG_M_D_BYTE0\" )
					)
					( Units "uMatchProp" "ns" 1.000000)
					( Status sCSetFlattened )
					( Origin gBackEnd )
				)
				( attribute "RELATIVE_PROPAGATION_DELAY_SCOPE" "G"
					( Parent
						( matchGroupRef "@baseboard_fab2_lib.baseboard_fab2(sch_1):\MG_DQ_NEAR_DIMM_NG_M_D_BYTE0\" )
					)
					( Status sCSetFlattened )
					( Origin gBackEnd )
				)
				( attribute "RELATIVE_PROPAGATION_DELAY" "-50.00 MIL,50.00 MIL"
					( Parent
						( matchGroupRef "@baseboard_fab2_lib.baseboard_fab2(sch_1):\MG_DQ_NEAR_DIMM_NG_M_D_BYTE0\" )
					)
					( Units "uMatchProp" "ns" 1.000000)
					( Status sCSetFlattened )
					( Origin gBackEnd )
				)
			)
			( pinPair "@baseboard_fab2_lib.baseboard_fab2(sch_1):\PP4686\"
				( pinRef "@baseboard_fab2_lib.baseboard_fab2(sch_1):page26_i172:DDR3_DQ(1)" )
				( pinRef "@baseboard_fab2_lib.baseboard_fab2(sch_1):page49_i111:DQ(0)" )
				( attribute "RELATIVE_PROPAGATION_DELAY_SCOPE" "G"
					( Parent
						( matchGroupRef "@baseboard_fab2_lib.baseboard_fab2(sch_1):\MG_DQ-DQS_FAR_DIMM_NG_M_D_BYTE0\" )
					)
					( Status sCSetFlattened )
					( Origin gBackEnd )
				)
				( attribute "RELATIVE_PROPAGATION_DELAY" "0.00 MIL,195.00 MIL"
					( Parent
						( matchGroupRef "@baseboard_fab2_lib.baseboard_fab2(sch_1):\MG_DQ-DQS_FAR_DIMM_NG_M_D_BYTE0\" )
					)
					( Units "uMatchProp" "ns" 1.000000)
					( Status sCSetFlattened )
					( Origin gBackEnd )
				)
				( attribute "RELATIVE_PROPAGATION_DELAY_SCOPE" "G"
					( Parent
						( matchGroupRef "@baseboard_fab2_lib.baseboard_fab2(sch_1):\MG_DQ_FAR_DIMM_NG_M_D_BYTE0\" )
					)
					( Status sCSetFlattened )
					( Origin gBackEnd )
				)
				( attribute "RELATIVE_PROPAGATION_DELAY" "-50.00 MIL,50.00 MIL"
					( Parent
						( matchGroupRef "@baseboard_fab2_lib.baseboard_fab2(sch_1):\MG_DQ_FAR_DIMM_NG_M_D_BYTE0\" )
					)
					( Units "uMatchProp" "ns" 1.000000)
					( Status sCSetFlattened )
					( Origin gBackEnd )
				)
			)
			( pinPair "@baseboard_fab2_lib.baseboard_fab2(sch_1):\PP4688\"
				( pinRef "@baseboard_fab2_lib.baseboard_fab2(sch_1):page50_i158:DQ(1)" )
				( pinRef "@baseboard_fab2_lib.baseboard_fab2(sch_1):page26_i172:DDR3_DQ(1)" )
				( attribute "RELATIVE_PROPAGATION_DELAY_SCOPE" "G"
					( Parent
						( matchGroupRef "@baseboard_fab2_lib.baseboard_fab2(sch_1):\MG_DQ-DQS_NEAR_DIMM_NG_M_D_BYTE0\" )
					)
					( Status sCSetFlattened )
					( Origin gBackEnd )
				)
				( attribute "RELATIVE_PROPAGATION_DELAY" "0.00 MIL,195.00 MIL"
					( Parent
						( matchGroupRef "@baseboard_fab2_lib.baseboard_fab2(sch_1):\MG_DQ-DQS_NEAR_DIMM_NG_M_D_BYTE0\" )
					)
					( Units "uMatchProp" "ns" 1.000000)
					( Status sCSetFlattened )
					( Origin gBackEnd )
				)
				( attribute "RELATIVE_PROPAGATION_DELAY_SCOPE" "G"
					( Parent
						( matchGroupRef "@baseboard_fab2_lib.baseboard_fab2(sch_1):\MG_DQ_NEAR_DIMM_NG_M_D_BYTE0\" )
					)
					( Status sCSetFlattened )
					( Origin gBackEnd )
				)
				( attribute "RELATIVE_PROPAGATION_DELAY" "-50.00 MIL,50.00 MIL"
					( Parent
						( matchGroupRef "@baseboard_fab2_lib.baseboard_fab2(sch_1):\MG_DQ_NEAR_DIMM_NG_M_D_BYTE0\" )
					)
					( Units "uMatchProp" "ns" 1.000000)
					( Status sCSetFlattened )
					( Origin gBackEnd )
				)
			)
			( pinPair "@baseboard_fab2_lib.baseboard_fab2(sch_1):\PP4689\"
				( pinRef "@baseboard_fab2_lib.baseboard_fab2(sch_1):page26_i172:DDR3_DQ(2)" )
				( pinRef "@baseboard_fab2_lib.baseboard_fab2(sch_1):page49_i111:DQ(3)" )
				( attribute "RELATIVE_PROPAGATION_DELAY_SCOPE" "G"
					( Parent
						( matchGroupRef "@baseboard_fab2_lib.baseboard_fab2(sch_1):\MG_DQ-DQS_FAR_DIMM_NG_M_D_BYTE0\" )
					)
					( Status sCSetFlattened )
					( Origin gBackEnd )
				)
				( attribute "RELATIVE_PROPAGATION_DELAY" "0.00 MIL,195.00 MIL"
					( Parent
						( matchGroupRef "@baseboard_fab2_lib.baseboard_fab2(sch_1):\MG_DQ-DQS_FAR_DIMM_NG_M_D_BYTE0\" )
					)
					( Units "uMatchProp" "ns" 1.000000)
					( Status sCSetFlattened )
					( Origin gBackEnd )
				)
				( attribute "RELATIVE_PROPAGATION_DELAY_SCOPE" "G"
					( Parent
						( matchGroupRef "@baseboard_fab2_lib.baseboard_fab2(sch_1):\MG_DQ_FAR_DIMM_NG_M_D_BYTE0\" )
					)
					( Status sCSetFlattened )
					( Origin gBackEnd )
				)
				( attribute "RELATIVE_PROPAGATION_DELAY" "-50.00 MIL,50.00 MIL"
					( Parent
						( matchGroupRef "@baseboard_fab2_lib.baseboard_fab2(sch_1):\MG_DQ_FAR_DIMM_NG_M_D_BYTE0\" )
					)
					( Units "uMatchProp" "ns" 1.000000)
					( Status sCSetFlattened )
					( Origin gBackEnd )
				)
			)
			( pinPair "@baseboard_fab2_lib.baseboard_fab2(sch_1):\PP4691\"
				( pinRef "@baseboard_fab2_lib.baseboard_fab2(sch_1):page50_i158:DQ(2)" )
				( pinRef "@baseboard_fab2_lib.baseboard_fab2(sch_1):page26_i172:DDR3_DQ(2)" )
				( attribute "RELATIVE_PROPAGATION_DELAY_SCOPE" "G"
					( Parent
						( matchGroupRef "@baseboard_fab2_lib.baseboard_fab2(sch_1):\MG_DQ-DQS_NEAR_DIMM_NG_M_D_BYTE0\" )
					)
					( Status sCSetFlattened )
					( Origin gBackEnd )
				)
				( attribute "RELATIVE_PROPAGATION_DELAY" "0.00 MIL,195.00 MIL"
					( Parent
						( matchGroupRef "@baseboard_fab2_lib.baseboard_fab2(sch_1):\MG_DQ-DQS_NEAR_DIMM_NG_M_D_BYTE0\" )
					)
					( Units "uMatchProp" "ns" 1.000000)
					( Status sCSetFlattened )
					( Origin gBackEnd )
				)
				( attribute "RELATIVE_PROPAGATION_DELAY_SCOPE" "G"
					( Parent
						( matchGroupRef "@baseboard_fab2_lib.baseboard_fab2(sch_1):\MG_DQ_NEAR_DIMM_NG_M_D_BYTE0\" )
					)
					( Status sCSetFlattened )
					( Origin gBackEnd )
				)
				( attribute "RELATIVE_PROPAGATION_DELAY" "-50.00 MIL,50.00 MIL"
					( Parent
						( matchGroupRef "@baseboard_fab2_lib.baseboard_fab2(sch_1):\MG_DQ_NEAR_DIMM_NG_M_D_BYTE0\" )
					)
					( Units "uMatchProp" "ns" 1.000000)
					( Status sCSetFlattened )
					( Origin gBackEnd )
				)
			)
			( pinPair "@baseboard_fab2_lib.baseboard_fab2(sch_1):\PP4692\"
				( pinRef "@baseboard_fab2_lib.baseboard_fab2(sch_1):page26_i172:DDR3_DQ(3)" )
				( pinRef "@baseboard_fab2_lib.baseboard_fab2(sch_1):page49_i111:DQ(2)" )
				( attribute "RELATIVE_PROPAGATION_DELAY_SCOPE" "G"
					( Parent
						( matchGroupRef "@baseboard_fab2_lib.baseboard_fab2(sch_1):\MG_DQ-DQS_FAR_DIMM_NG_M_D_BYTE0\" )
					)
					( Status sCSetFlattened )
					( Origin gBackEnd )
				)
				( attribute "RELATIVE_PROPAGATION_DELAY" "0.00 MIL,195.00 MIL"
					( Parent
						( matchGroupRef "@baseboard_fab2_lib.baseboard_fab2(sch_1):\MG_DQ-DQS_FAR_DIMM_NG_M_D_BYTE0\" )
					)
					( Units "uMatchProp" "ns" 1.000000)
					( Status sCSetFlattened )
					( Origin gBackEnd )
				)
				( attribute "RELATIVE_PROPAGATION_DELAY_SCOPE" "G"
					( Parent
						( matchGroupRef "@baseboard_fab2_lib.baseboard_fab2(sch_1):\MG_DQ_FAR_DIMM_NG_M_D_BYTE0\" )
					)
					( Status sCSetFlattened )
					( Origin gBackEnd )
				)
				( attribute "RELATIVE_PROPAGATION_DELAY" "-50.00 MIL,50.00 MIL"
					( Parent
						( matchGroupRef "@baseboard_fab2_lib.baseboard_fab2(sch_1):\MG_DQ_FAR_DIMM_NG_M_D_BYTE0\" )
					)
					( Units "uMatchProp" "ns" 1.000000)
					( Status sCSetFlattened )
					( Origin gBackEnd )
				)
			)
			( pinPair "@baseboard_fab2_lib.baseboard_fab2(sch_1):\PP4694\"
				( pinRef "@baseboard_fab2_lib.baseboard_fab2(sch_1):page50_i158:DQ(3)" )
				( pinRef "@baseboard_fab2_lib.baseboard_fab2(sch_1):page26_i172:DDR3_DQ(3)" )
				( attribute "RELATIVE_PROPAGATION_DELAY_SCOPE" "G"
					( Parent
						( matchGroupRef "@baseboard_fab2_lib.baseboard_fab2(sch_1):\MG_DQ-DQS_NEAR_DIMM_NG_M_D_BYTE0\" )
					)
					( Status sCSetFlattened )
					( Origin gBackEnd )
				)
				( attribute "RELATIVE_PROPAGATION_DELAY" "0.00 MIL,195.00 MIL"
					( Parent
						( matchGroupRef "@baseboard_fab2_lib.baseboard_fab2(sch_1):\MG_DQ-DQS_NEAR_DIMM_NG_M_D_BYTE0\" )
					)
					( Units "uMatchProp" "ns" 1.000000)
					( Status sCSetFlattened )
					( Origin gBackEnd )
				)
				( attribute "RELATIVE_PROPAGATION_DELAY_SCOPE" "G"
					( Parent
						( matchGroupRef "@baseboard_fab2_lib.baseboard_fab2(sch_1):\MG_DQ_NEAR_DIMM_NG_M_D_BYTE0\" )
					)
					( Status sCSetFlattened )
					( Origin gBackEnd )
				)
				( attribute "RELATIVE_PROPAGATION_DELAY" "-50.00 MIL,50.00 MIL"
					( Parent
						( matchGroupRef "@baseboard_fab2_lib.baseboard_fab2(sch_1):\MG_DQ_NEAR_DIMM_NG_M_D_BYTE0\" )
					)
					( Units "uMatchProp" "ns" 1.000000)
					( Status sCSetFlattened )
					( Origin gBackEnd )
				)
			)
			( pinPair "@baseboard_fab2_lib.baseboard_fab2(sch_1):\PP4695\"
				( pinRef "@baseboard_fab2_lib.baseboard_fab2(sch_1):page26_i172:DDR3_DQ(4)" )
				( pinRef "@baseboard_fab2_lib.baseboard_fab2(sch_1):page49_i111:DQ(5)" )
				( attribute "RELATIVE_PROPAGATION_DELAY_SCOPE" "G"
					( Parent
						( matchGroupRef "@baseboard_fab2_lib.baseboard_fab2(sch_1):\MG_DQ-DQS_FAR_DIMM_NG_M_D_BYTE0\" )
					)
					( Status sCSetFlattened )
					( Origin gBackEnd )
				)
				( attribute "RELATIVE_PROPAGATION_DELAY" "0.00 MIL,195.00 MIL"
					( Parent
						( matchGroupRef "@baseboard_fab2_lib.baseboard_fab2(sch_1):\MG_DQ-DQS_FAR_DIMM_NG_M_D_BYTE0\" )
					)
					( Units "uMatchProp" "ns" 1.000000)
					( Status sCSetFlattened )
					( Origin gBackEnd )
				)
				( attribute "RELATIVE_PROPAGATION_DELAY_SCOPE" "G"
					( Parent
						( matchGroupRef "@baseboard_fab2_lib.baseboard_fab2(sch_1):\MG_DQ_FAR_DIMM_NG_M_D_BYTE0\" )
					)
					( Status sCSetFlattened )
					( Origin gBackEnd )
				)
				( attribute "RELATIVE_PROPAGATION_DELAY" "-50.00 MIL,50.00 MIL"
					( Parent
						( matchGroupRef "@baseboard_fab2_lib.baseboard_fab2(sch_1):\MG_DQ_FAR_DIMM_NG_M_D_BYTE0\" )
					)
					( Units "uMatchProp" "ns" 1.000000)
					( Status sCSetFlattened )
					( Origin gBackEnd )
				)
			)
			( pinPair "@baseboard_fab2_lib.baseboard_fab2(sch_1):\PP4697\"
				( pinRef "@baseboard_fab2_lib.baseboard_fab2(sch_1):page26_i172:DDR3_DQ(4)" )
				( pinRef "@baseboard_fab2_lib.baseboard_fab2(sch_1):page50_i158:DQ(4)" )
				( attribute "RELATIVE_PROPAGATION_DELAY_SCOPE" "G"
					( Parent
						( matchGroupRef "@baseboard_fab2_lib.baseboard_fab2(sch_1):\MG_DQ-DQS_NEAR_DIMM_NG_M_D_BYTE0\" )
					)
					( Status sCSetFlattened )
					( Origin gBackEnd )
				)
				( attribute "RELATIVE_PROPAGATION_DELAY" "0.00 MIL,195.00 MIL"
					( Parent
						( matchGroupRef "@baseboard_fab2_lib.baseboard_fab2(sch_1):\MG_DQ-DQS_NEAR_DIMM_NG_M_D_BYTE0\" )
					)
					( Units "uMatchProp" "ns" 1.000000)
					( Status sCSetFlattened )
					( Origin gBackEnd )
				)
				( attribute "RELATIVE_PROPAGATION_DELAY_SCOPE" "G"
					( Parent
						( matchGroupRef "@baseboard_fab2_lib.baseboard_fab2(sch_1):\MG_DQ_NEAR_DIMM_NG_M_D_BYTE0\" )
					)
					( Status sCSetFlattened )
					( Origin gBackEnd )
				)
				( attribute "RELATIVE_PROPAGATION_DELAY" "-50.00 MIL,50.00 MIL"
					( Parent
						( matchGroupRef "@baseboard_fab2_lib.baseboard_fab2(sch_1):\MG_DQ_NEAR_DIMM_NG_M_D_BYTE0\" )
					)
					( Units "uMatchProp" "ns" 1.000000)
					( Status sCSetFlattened )
					( Origin gBackEnd )
				)
			)
			( pinPair "@baseboard_fab2_lib.baseboard_fab2(sch_1):\PP4698\"
				( pinRef "@baseboard_fab2_lib.baseboard_fab2(sch_1):page26_i172:DDR3_DQ(5)" )
				( pinRef "@baseboard_fab2_lib.baseboard_fab2(sch_1):page49_i111:DQ(4)" )
				( attribute "RELATIVE_PROPAGATION_DELAY_SCOPE" "G"
					( Parent
						( matchGroupRef "@baseboard_fab2_lib.baseboard_fab2(sch_1):\MG_DQ-DQS_FAR_DIMM_NG_M_D_BYTE0\" )
					)
					( Status sCSetFlattened )
					( Origin gBackEnd )
				)
				( attribute "RELATIVE_PROPAGATION_DELAY" "0.00 MIL,195.00 MIL"
					( Parent
						( matchGroupRef "@baseboard_fab2_lib.baseboard_fab2(sch_1):\MG_DQ-DQS_FAR_DIMM_NG_M_D_BYTE0\" )
					)
					( Units "uMatchProp" "ns" 1.000000)
					( Status sCSetFlattened )
					( Origin gBackEnd )
				)
				( attribute "RELATIVE_PROPAGATION_DELAY_SCOPE" "G"
					( Parent
						( matchGroupRef "@baseboard_fab2_lib.baseboard_fab2(sch_1):\MG_DQ_FAR_DIMM_NG_M_D_BYTE0\" )
					)
					( Status sCSetFlattened )
					( Origin gBackEnd )
				)
				( attribute "RELATIVE_PROPAGATION_DELAY" "-50.00 MIL,50.00 MIL"
					( Parent
						( matchGroupRef "@baseboard_fab2_lib.baseboard_fab2(sch_1):\MG_DQ_FAR_DIMM_NG_M_D_BYTE0\" )
					)
					( Units "uMatchProp" "ns" 1.000000)
					( Status sCSetFlattened )
					( Origin gBackEnd )
				)
			)
			( pinPair "@baseboard_fab2_lib.baseboard_fab2(sch_1):\PP4700\"
				( pinRef "@baseboard_fab2_lib.baseboard_fab2(sch_1):page50_i158:DQ(5)" )
				( pinRef "@baseboard_fab2_lib.baseboard_fab2(sch_1):page26_i172:DDR3_DQ(5)" )
				( attribute "RELATIVE_PROPAGATION_DELAY_SCOPE" "G"
					( Parent
						( matchGroupRef "@baseboard_fab2_lib.baseboard_fab2(sch_1):\MG_DQ-DQS_NEAR_DIMM_NG_M_D_BYTE0\" )
					)
					( Status sCSetFlattened )
					( Origin gBackEnd )
				)
				( attribute "RELATIVE_PROPAGATION_DELAY" "0.00 MIL,195.00 MIL"
					( Parent
						( matchGroupRef "@baseboard_fab2_lib.baseboard_fab2(sch_1):\MG_DQ-DQS_NEAR_DIMM_NG_M_D_BYTE0\" )
					)
					( Units "uMatchProp" "ns" 1.000000)
					( Status sCSetFlattened )
					( Origin gBackEnd )
				)
				( attribute "RELATIVE_PROPAGATION_DELAY_SCOPE" "G"
					( Parent
						( matchGroupRef "@baseboard_fab2_lib.baseboard_fab2(sch_1):\MG_DQ_NEAR_DIMM_NG_M_D_BYTE0\" )
					)
					( Status sCSetFlattened )
					( Origin gBackEnd )
				)
				( attribute "RELATIVE_PROPAGATION_DELAY" "-50.00 MIL,50.00 MIL"
					( Parent
						( matchGroupRef "@baseboard_fab2_lib.baseboard_fab2(sch_1):\MG_DQ_NEAR_DIMM_NG_M_D_BYTE0\" )
					)
					( Units "uMatchProp" "ns" 1.000000)
					( Status sCSetFlattened )
					( Origin gBackEnd )
				)
			)
			( pinPair "@baseboard_fab2_lib.baseboard_fab2(sch_1):\PP4701\"
				( pinRef "@baseboard_fab2_lib.baseboard_fab2(sch_1):page26_i172:DDR3_DQ(6)" )
				( pinRef "@baseboard_fab2_lib.baseboard_fab2(sch_1):page49_i111:DQ(7)" )
				( attribute "RELATIVE_PROPAGATION_DELAY_SCOPE" "G"
					( Parent
						( matchGroupRef "@baseboard_fab2_lib.baseboard_fab2(sch_1):\MG_DQ-DQS_FAR_DIMM_NG_M_D_BYTE0\" )
					)
					( Status sCSetFlattened )
					( Origin gBackEnd )
				)
				( attribute "RELATIVE_PROPAGATION_DELAY" "0.00 MIL,195.00 MIL"
					( Parent
						( matchGroupRef "@baseboard_fab2_lib.baseboard_fab2(sch_1):\MG_DQ-DQS_FAR_DIMM_NG_M_D_BYTE0\" )
					)
					( Units "uMatchProp" "ns" 1.000000)
					( Status sCSetFlattened )
					( Origin gBackEnd )
				)
				( attribute "RELATIVE_PROPAGATION_DELAY_SCOPE" "G"
					( Parent
						( matchGroupRef "@baseboard_fab2_lib.baseboard_fab2(sch_1):\MG_DQ_FAR_DIMM_NG_M_D_BYTE0\" )
					)
					( Status sCSetFlattened )
					( Origin gBackEnd )
				)
				( attribute "RELATIVE_PROPAGATION_DELAY" "-50.00 MIL,50.00 MIL"
					( Parent
						( matchGroupRef "@baseboard_fab2_lib.baseboard_fab2(sch_1):\MG_DQ_FAR_DIMM_NG_M_D_BYTE0\" )
					)
					( Units "uMatchProp" "ns" 1.000000)
					( Status sCSetFlattened )
					( Origin gBackEnd )
				)
			)
			( pinPair "@baseboard_fab2_lib.baseboard_fab2(sch_1):\PP4703\"
				( pinRef "@baseboard_fab2_lib.baseboard_fab2(sch_1):page50_i158:DQ(6)" )
				( pinRef "@baseboard_fab2_lib.baseboard_fab2(sch_1):page26_i172:DDR3_DQ(6)" )
				( attribute "RELATIVE_PROPAGATION_DELAY_SCOPE" "G"
					( Parent
						( matchGroupRef "@baseboard_fab2_lib.baseboard_fab2(sch_1):\MG_DQ-DQS_NEAR_DIMM_NG_M_D_BYTE0\" )
					)
					( Status sCSetFlattened )
					( Origin gBackEnd )
				)
				( attribute "RELATIVE_PROPAGATION_DELAY" "0.00 MIL,195.00 MIL"
					( Parent
						( matchGroupRef "@baseboard_fab2_lib.baseboard_fab2(sch_1):\MG_DQ-DQS_NEAR_DIMM_NG_M_D_BYTE0\" )
					)
					( Units "uMatchProp" "ns" 1.000000)
					( Status sCSetFlattened )
					( Origin gBackEnd )
				)
				( attribute "RELATIVE_PROPAGATION_DELAY_SCOPE" "G"
					( Parent
						( matchGroupRef "@baseboard_fab2_lib.baseboard_fab2(sch_1):\MG_DQ_NEAR_DIMM_NG_M_D_BYTE0\" )
					)
					( Status sCSetFlattened )
					( Origin gBackEnd )
				)
				( attribute "RELATIVE_PROPAGATION_DELAY" "-50.00 MIL,50.00 MIL"
					( Parent
						( matchGroupRef "@baseboard_fab2_lib.baseboard_fab2(sch_1):\MG_DQ_NEAR_DIMM_NG_M_D_BYTE0\" )
					)
					( Units "uMatchProp" "ns" 1.000000)
					( Status sCSetFlattened )
					( Origin gBackEnd )
				)
			)
			( pinPair "@baseboard_fab2_lib.baseboard_fab2(sch_1):\PP4704\"
				( pinRef "@baseboard_fab2_lib.baseboard_fab2(sch_1):page26_i172:DDR3_DQ(7)" )
				( pinRef "@baseboard_fab2_lib.baseboard_fab2(sch_1):page49_i111:DQ(6)" )
				( attribute "RELATIVE_PROPAGATION_DELAY_SCOPE" "G"
					( Parent
						( matchGroupRef "@baseboard_fab2_lib.baseboard_fab2(sch_1):\MG_DQ-DQS_FAR_DIMM_NG_M_D_BYTE0\" )
					)
					( Status sCSetFlattened )
					( Origin gBackEnd )
				)
				( attribute "RELATIVE_PROPAGATION_DELAY" "0.00 MIL,195.00 MIL"
					( Parent
						( matchGroupRef "@baseboard_fab2_lib.baseboard_fab2(sch_1):\MG_DQ-DQS_FAR_DIMM_NG_M_D_BYTE0\" )
					)
					( Units "uMatchProp" "ns" 1.000000)
					( Status sCSetFlattened )
					( Origin gBackEnd )
				)
				( attribute "RELATIVE_PROPAGATION_DELAY_SCOPE" "G"
					( Parent
						( matchGroupRef "@baseboard_fab2_lib.baseboard_fab2(sch_1):\MG_DQ_FAR_DIMM_NG_M_D_BYTE0\" )
					)
					( Status sCSetFlattened )
					( Origin gBackEnd )
				)
				( attribute "RELATIVE_PROPAGATION_DELAY" "-50.00 MIL,50.00 MIL"
					( Parent
						( matchGroupRef "@baseboard_fab2_lib.baseboard_fab2(sch_1):\MG_DQ_FAR_DIMM_NG_M_D_BYTE0\" )
					)
					( Units "uMatchProp" "ns" 1.000000)
					( Status sCSetFlattened )
					( Origin gBackEnd )
				)
			)
			( pinPair "@baseboard_fab2_lib.baseboard_fab2(sch_1):\PP4706\"
				( pinRef "@baseboard_fab2_lib.baseboard_fab2(sch_1):page50_i158:DQ(7)" )
				( pinRef "@baseboard_fab2_lib.baseboard_fab2(sch_1):page26_i172:DDR3_DQ(7)" )
				( attribute "RELATIVE_PROPAGATION_DELAY_SCOPE" "G"
					( Parent
						( matchGroupRef "@baseboard_fab2_lib.baseboard_fab2(sch_1):\MG_DQ-DQS_NEAR_DIMM_NG_M_D_BYTE0\" )
					)
					( Status sCSetFlattened )
					( Origin gBackEnd )
				)
				( attribute "RELATIVE_PROPAGATION_DELAY" "0.00 MIL,195.00 MIL"
					( Parent
						( matchGroupRef "@baseboard_fab2_lib.baseboard_fab2(sch_1):\MG_DQ-DQS_NEAR_DIMM_NG_M_D_BYTE0\" )
					)
					( Units "uMatchProp" "ns" 1.000000)
					( Status sCSetFlattened )
					( Origin gBackEnd )
				)
				( attribute "RELATIVE_PROPAGATION_DELAY_SCOPE" "G"
					( Parent
						( matchGroupRef "@baseboard_fab2_lib.baseboard_fab2(sch_1):\MG_DQ_NEAR_DIMM_NG_M_D_BYTE0\" )
					)
					( Status sCSetFlattened )
					( Origin gBackEnd )
				)
				( attribute "RELATIVE_PROPAGATION_DELAY" "-50.00 MIL,50.00 MIL"
					( Parent
						( matchGroupRef "@baseboard_fab2_lib.baseboard_fab2(sch_1):\MG_DQ_NEAR_DIMM_NG_M_D_BYTE0\" )
					)
					( Units "uMatchProp" "ns" 1.000000)
					( Status sCSetFlattened )
					( Origin gBackEnd )
				)
			)
			( pinPair "@baseboard_fab2_lib.baseboard_fab2(sch_1):\PP4659\"
				( pinRef "@baseboard_fab2_lib.baseboard_fab2(sch_1):page26_i172:DDR3_DQ(8)" )
				( pinRef "@baseboard_fab2_lib.baseboard_fab2(sch_1):page49_i111:DQ(9)" )
				( attribute "RELATIVE_PROPAGATION_DELAY_SCOPE" "G"
					( Parent
						( matchGroupRef "@baseboard_fab2_lib.baseboard_fab2(sch_1):\MG_DQ-DQS_FAR_DIMM_NG_M_D_BYTE1\" )
					)
					( Status sCSetFlattened )
					( Origin gBackEnd )
				)
				( attribute "RELATIVE_PROPAGATION_DELAY" "0.00 MIL,195.00 MIL"
					( Parent
						( matchGroupRef "@baseboard_fab2_lib.baseboard_fab2(sch_1):\MG_DQ-DQS_FAR_DIMM_NG_M_D_BYTE1\" )
					)
					( Units "uMatchProp" "ns" 1.000000)
					( Status sCSetFlattened )
					( Origin gBackEnd )
				)
				( attribute "RELATIVE_PROPAGATION_DELAY_SCOPE" "G"
					( Parent
						( matchGroupRef "@baseboard_fab2_lib.baseboard_fab2(sch_1):\MG_DQ_FAR_DIMM_NG_M_D_BYTE1\" )
					)
					( Status sCSetFlattened )
					( Origin gBackEnd )
				)
				( attribute "RELATIVE_PROPAGATION_DELAY" "-50.00 MIL,50.00 MIL"
					( Parent
						( matchGroupRef "@baseboard_fab2_lib.baseboard_fab2(sch_1):\MG_DQ_FAR_DIMM_NG_M_D_BYTE1\" )
					)
					( Units "uMatchProp" "ns" 1.000000)
					( Status sCSetFlattened )
					( Origin gBackEnd )
				)
			)
			( pinPair "@baseboard_fab2_lib.baseboard_fab2(sch_1):\PP4661\"
				( pinRef "@baseboard_fab2_lib.baseboard_fab2(sch_1):page50_i158:DQ(8)" )
				( pinRef "@baseboard_fab2_lib.baseboard_fab2(sch_1):page26_i172:DDR3_DQ(8)" )
				( attribute "RELATIVE_PROPAGATION_DELAY_SCOPE" "G"
					( Parent
						( matchGroupRef "@baseboard_fab2_lib.baseboard_fab2(sch_1):\MG_DQ-DQS_NEAR_DIMM_NG_M_D_BYTE1\" )
					)
					( Status sCSetFlattened )
					( Origin gBackEnd )
				)
				( attribute "RELATIVE_PROPAGATION_DELAY" "0.00 MIL,195.00 MIL"
					( Parent
						( matchGroupRef "@baseboard_fab2_lib.baseboard_fab2(sch_1):\MG_DQ-DQS_NEAR_DIMM_NG_M_D_BYTE1\" )
					)
					( Units "uMatchProp" "ns" 1.000000)
					( Status sCSetFlattened )
					( Origin gBackEnd )
				)
				( attribute "RELATIVE_PROPAGATION_DELAY_SCOPE" "G"
					( Parent
						( matchGroupRef "@baseboard_fab2_lib.baseboard_fab2(sch_1):\MG_DQ_NEAR_DIMM_NG_M_D_BYTE1\" )
					)
					( Status sCSetFlattened )
					( Origin gBackEnd )
				)
				( attribute "RELATIVE_PROPAGATION_DELAY" "-50.00 MIL,50.00 MIL"
					( Parent
						( matchGroupRef "@baseboard_fab2_lib.baseboard_fab2(sch_1):\MG_DQ_NEAR_DIMM_NG_M_D_BYTE1\" )
					)
					( Units "uMatchProp" "ns" 1.000000)
					( Status sCSetFlattened )
					( Origin gBackEnd )
				)
			)
			( pinPair "@baseboard_fab2_lib.baseboard_fab2(sch_1):\PP4662\"
				( pinRef "@baseboard_fab2_lib.baseboard_fab2(sch_1):page26_i172:DDR3_DQ(9)" )
				( pinRef "@baseboard_fab2_lib.baseboard_fab2(sch_1):page49_i111:DQ(8)" )
				( attribute "RELATIVE_PROPAGATION_DELAY_SCOPE" "G"
					( Parent
						( matchGroupRef "@baseboard_fab2_lib.baseboard_fab2(sch_1):\MG_DQ-DQS_FAR_DIMM_NG_M_D_BYTE1\" )
					)
					( Status sCSetFlattened )
					( Origin gBackEnd )
				)
				( attribute "RELATIVE_PROPAGATION_DELAY" "0.00 MIL,195.00 MIL"
					( Parent
						( matchGroupRef "@baseboard_fab2_lib.baseboard_fab2(sch_1):\MG_DQ-DQS_FAR_DIMM_NG_M_D_BYTE1\" )
					)
					( Units "uMatchProp" "ns" 1.000000)
					( Status sCSetFlattened )
					( Origin gBackEnd )
				)
				( attribute "RELATIVE_PROPAGATION_DELAY_SCOPE" "G"
					( Parent
						( matchGroupRef "@baseboard_fab2_lib.baseboard_fab2(sch_1):\MG_DQ_FAR_DIMM_NG_M_D_BYTE1\" )
					)
					( Status sCSetFlattened )
					( Origin gBackEnd )
				)
				( attribute "RELATIVE_PROPAGATION_DELAY" "-50.00 MIL,50.00 MIL"
					( Parent
						( matchGroupRef "@baseboard_fab2_lib.baseboard_fab2(sch_1):\MG_DQ_FAR_DIMM_NG_M_D_BYTE1\" )
					)
					( Units "uMatchProp" "ns" 1.000000)
					( Status sCSetFlattened )
					( Origin gBackEnd )
				)
			)
			( pinPair "@baseboard_fab2_lib.baseboard_fab2(sch_1):\PP4664\"
				( pinRef "@baseboard_fab2_lib.baseboard_fab2(sch_1):page50_i158:DQ(9)" )
				( pinRef "@baseboard_fab2_lib.baseboard_fab2(sch_1):page26_i172:DDR3_DQ(9)" )
				( attribute "RELATIVE_PROPAGATION_DELAY_SCOPE" "G"
					( Parent
						( matchGroupRef "@baseboard_fab2_lib.baseboard_fab2(sch_1):\MG_DQ-DQS_NEAR_DIMM_NG_M_D_BYTE1\" )
					)
					( Status sCSetFlattened )
					( Origin gBackEnd )
				)
				( attribute "RELATIVE_PROPAGATION_DELAY" "0.00 MIL,195.00 MIL"
					( Parent
						( matchGroupRef "@baseboard_fab2_lib.baseboard_fab2(sch_1):\MG_DQ-DQS_NEAR_DIMM_NG_M_D_BYTE1\" )
					)
					( Units "uMatchProp" "ns" 1.000000)
					( Status sCSetFlattened )
					( Origin gBackEnd )
				)
				( attribute "RELATIVE_PROPAGATION_DELAY_SCOPE" "G"
					( Parent
						( matchGroupRef "@baseboard_fab2_lib.baseboard_fab2(sch_1):\MG_DQ_NEAR_DIMM_NG_M_D_BYTE1\" )
					)
					( Status sCSetFlattened )
					( Origin gBackEnd )
				)
				( attribute "RELATIVE_PROPAGATION_DELAY" "-50.00 MIL,50.00 MIL"
					( Parent
						( matchGroupRef "@baseboard_fab2_lib.baseboard_fab2(sch_1):\MG_DQ_NEAR_DIMM_NG_M_D_BYTE1\" )
					)
					( Units "uMatchProp" "ns" 1.000000)
					( Status sCSetFlattened )
					( Origin gBackEnd )
				)
			)
			( pinPair "@baseboard_fab2_lib.baseboard_fab2(sch_1):\PP4665\"
				( pinRef "@baseboard_fab2_lib.baseboard_fab2(sch_1):page26_i172:DDR3_DQ(10)" )
				( pinRef "@baseboard_fab2_lib.baseboard_fab2(sch_1):page49_i111:DQ(11)" )
				( attribute "RELATIVE_PROPAGATION_DELAY_SCOPE" "G"
					( Parent
						( matchGroupRef "@baseboard_fab2_lib.baseboard_fab2(sch_1):\MG_DQ-DQS_FAR_DIMM_NG_M_D_BYTE1\" )
					)
					( Status sCSetFlattened )
					( Origin gBackEnd )
				)
				( attribute "RELATIVE_PROPAGATION_DELAY" "0.00 MIL,195.00 MIL"
					( Parent
						( matchGroupRef "@baseboard_fab2_lib.baseboard_fab2(sch_1):\MG_DQ-DQS_FAR_DIMM_NG_M_D_BYTE1\" )
					)
					( Units "uMatchProp" "ns" 1.000000)
					( Status sCSetFlattened )
					( Origin gBackEnd )
				)
				( attribute "RELATIVE_PROPAGATION_DELAY_SCOPE" "G"
					( Parent
						( matchGroupRef "@baseboard_fab2_lib.baseboard_fab2(sch_1):\MG_DQ_FAR_DIMM_NG_M_D_BYTE1\" )
					)
					( Status sCSetFlattened )
					( Origin gBackEnd )
				)
				( attribute "RELATIVE_PROPAGATION_DELAY" "-50.00 MIL,50.00 MIL"
					( Parent
						( matchGroupRef "@baseboard_fab2_lib.baseboard_fab2(sch_1):\MG_DQ_FAR_DIMM_NG_M_D_BYTE1\" )
					)
					( Units "uMatchProp" "ns" 1.000000)
					( Status sCSetFlattened )
					( Origin gBackEnd )
				)
			)
			( pinPair "@baseboard_fab2_lib.baseboard_fab2(sch_1):\PP4667\"
				( pinRef "@baseboard_fab2_lib.baseboard_fab2(sch_1):page50_i158:DQ(10)" )
				( pinRef "@baseboard_fab2_lib.baseboard_fab2(sch_1):page26_i172:DDR3_DQ(10)" )
				( attribute "RELATIVE_PROPAGATION_DELAY_SCOPE" "G"
					( Parent
						( matchGroupRef "@baseboard_fab2_lib.baseboard_fab2(sch_1):\MG_DQ-DQS_NEAR_DIMM_NG_M_D_BYTE1\" )
					)
					( Status sCSetFlattened )
					( Origin gBackEnd )
				)
				( attribute "RELATIVE_PROPAGATION_DELAY" "0.00 MIL,195.00 MIL"
					( Parent
						( matchGroupRef "@baseboard_fab2_lib.baseboard_fab2(sch_1):\MG_DQ-DQS_NEAR_DIMM_NG_M_D_BYTE1\" )
					)
					( Units "uMatchProp" "ns" 1.000000)
					( Status sCSetFlattened )
					( Origin gBackEnd )
				)
				( attribute "RELATIVE_PROPAGATION_DELAY_SCOPE" "G"
					( Parent
						( matchGroupRef "@baseboard_fab2_lib.baseboard_fab2(sch_1):\MG_DQ_NEAR_DIMM_NG_M_D_BYTE1\" )
					)
					( Status sCSetFlattened )
					( Origin gBackEnd )
				)
				( attribute "RELATIVE_PROPAGATION_DELAY" "-50.00 MIL,50.00 MIL"
					( Parent
						( matchGroupRef "@baseboard_fab2_lib.baseboard_fab2(sch_1):\MG_DQ_NEAR_DIMM_NG_M_D_BYTE1\" )
					)
					( Units "uMatchProp" "ns" 1.000000)
					( Status sCSetFlattened )
					( Origin gBackEnd )
				)
			)
			( pinPair "@baseboard_fab2_lib.baseboard_fab2(sch_1):\PP4668\"
				( pinRef "@baseboard_fab2_lib.baseboard_fab2(sch_1):page26_i172:DDR3_DQ(11)" )
				( pinRef "@baseboard_fab2_lib.baseboard_fab2(sch_1):page49_i111:DQ(10)" )
				( attribute "RELATIVE_PROPAGATION_DELAY_SCOPE" "G"
					( Parent
						( matchGroupRef "@baseboard_fab2_lib.baseboard_fab2(sch_1):\MG_DQ-DQS_FAR_DIMM_NG_M_D_BYTE1\" )
					)
					( Status sCSetFlattened )
					( Origin gBackEnd )
				)
				( attribute "RELATIVE_PROPAGATION_DELAY" "0.00 MIL,195.00 MIL"
					( Parent
						( matchGroupRef "@baseboard_fab2_lib.baseboard_fab2(sch_1):\MG_DQ-DQS_FAR_DIMM_NG_M_D_BYTE1\" )
					)
					( Units "uMatchProp" "ns" 1.000000)
					( Status sCSetFlattened )
					( Origin gBackEnd )
				)
				( attribute "RELATIVE_PROPAGATION_DELAY_SCOPE" "G"
					( Parent
						( matchGroupRef "@baseboard_fab2_lib.baseboard_fab2(sch_1):\MG_DQ_FAR_DIMM_NG_M_D_BYTE1\" )
					)
					( Status sCSetFlattened )
					( Origin gBackEnd )
				)
				( attribute "RELATIVE_PROPAGATION_DELAY" "-50.00 MIL,50.00 MIL"
					( Parent
						( matchGroupRef "@baseboard_fab2_lib.baseboard_fab2(sch_1):\MG_DQ_FAR_DIMM_NG_M_D_BYTE1\" )
					)
					( Units "uMatchProp" "ns" 1.000000)
					( Status sCSetFlattened )
					( Origin gBackEnd )
				)
			)
			( pinPair "@baseboard_fab2_lib.baseboard_fab2(sch_1):\PP4670\"
				( pinRef "@baseboard_fab2_lib.baseboard_fab2(sch_1):page50_i158:DQ(11)" )
				( pinRef "@baseboard_fab2_lib.baseboard_fab2(sch_1):page26_i172:DDR3_DQ(11)" )
				( attribute "RELATIVE_PROPAGATION_DELAY_SCOPE" "G"
					( Parent
						( matchGroupRef "@baseboard_fab2_lib.baseboard_fab2(sch_1):\MG_DQ-DQS_NEAR_DIMM_NG_M_D_BYTE1\" )
					)
					( Status sCSetFlattened )
					( Origin gBackEnd )
				)
				( attribute "RELATIVE_PROPAGATION_DELAY" "0.00 MIL,195.00 MIL"
					( Parent
						( matchGroupRef "@baseboard_fab2_lib.baseboard_fab2(sch_1):\MG_DQ-DQS_NEAR_DIMM_NG_M_D_BYTE1\" )
					)
					( Units "uMatchProp" "ns" 1.000000)
					( Status sCSetFlattened )
					( Origin gBackEnd )
				)
				( attribute "RELATIVE_PROPAGATION_DELAY_SCOPE" "G"
					( Parent
						( matchGroupRef "@baseboard_fab2_lib.baseboard_fab2(sch_1):\MG_DQ_NEAR_DIMM_NG_M_D_BYTE1\" )
					)
					( Status sCSetFlattened )
					( Origin gBackEnd )
				)
				( attribute "RELATIVE_PROPAGATION_DELAY" "-50.00 MIL,50.00 MIL"
					( Parent
						( matchGroupRef "@baseboard_fab2_lib.baseboard_fab2(sch_1):\MG_DQ_NEAR_DIMM_NG_M_D_BYTE1\" )
					)
					( Units "uMatchProp" "ns" 1.000000)
					( Status sCSetFlattened )
					( Origin gBackEnd )
				)
			)
			( pinPair "@baseboard_fab2_lib.baseboard_fab2(sch_1):\PP4671\"
				( pinRef "@baseboard_fab2_lib.baseboard_fab2(sch_1):page26_i172:DDR3_DQ(12)" )
				( pinRef "@baseboard_fab2_lib.baseboard_fab2(sch_1):page49_i111:DQ(13)" )
				( attribute "RELATIVE_PROPAGATION_DELAY_SCOPE" "G"
					( Parent
						( matchGroupRef "@baseboard_fab2_lib.baseboard_fab2(sch_1):\MG_DQ-DQS_FAR_DIMM_NG_M_D_BYTE1\" )
					)
					( Status sCSetFlattened )
					( Origin gBackEnd )
				)
				( attribute "RELATIVE_PROPAGATION_DELAY" "0.00 MIL,195.00 MIL"
					( Parent
						( matchGroupRef "@baseboard_fab2_lib.baseboard_fab2(sch_1):\MG_DQ-DQS_FAR_DIMM_NG_M_D_BYTE1\" )
					)
					( Units "uMatchProp" "ns" 1.000000)
					( Status sCSetFlattened )
					( Origin gBackEnd )
				)
				( attribute "RELATIVE_PROPAGATION_DELAY_SCOPE" "G"
					( Parent
						( matchGroupRef "@baseboard_fab2_lib.baseboard_fab2(sch_1):\MG_DQ_FAR_DIMM_NG_M_D_BYTE1\" )
					)
					( Status sCSetFlattened )
					( Origin gBackEnd )
				)
				( attribute "RELATIVE_PROPAGATION_DELAY" "-50.00 MIL,50.00 MIL"
					( Parent
						( matchGroupRef "@baseboard_fab2_lib.baseboard_fab2(sch_1):\MG_DQ_FAR_DIMM_NG_M_D_BYTE1\" )
					)
					( Units "uMatchProp" "ns" 1.000000)
					( Status sCSetFlattened )
					( Origin gBackEnd )
				)
			)
			( pinPair "@baseboard_fab2_lib.baseboard_fab2(sch_1):\PP4673\"
				( pinRef "@baseboard_fab2_lib.baseboard_fab2(sch_1):page50_i158:DQ(12)" )
				( pinRef "@baseboard_fab2_lib.baseboard_fab2(sch_1):page26_i172:DDR3_DQ(12)" )
				( attribute "RELATIVE_PROPAGATION_DELAY_SCOPE" "G"
					( Parent
						( matchGroupRef "@baseboard_fab2_lib.baseboard_fab2(sch_1):\MG_DQ-DQS_NEAR_DIMM_NG_M_D_BYTE1\" )
					)
					( Status sCSetFlattened )
					( Origin gBackEnd )
				)
				( attribute "RELATIVE_PROPAGATION_DELAY" "0.00 MIL,195.00 MIL"
					( Parent
						( matchGroupRef "@baseboard_fab2_lib.baseboard_fab2(sch_1):\MG_DQ-DQS_NEAR_DIMM_NG_M_D_BYTE1\" )
					)
					( Units "uMatchProp" "ns" 1.000000)
					( Status sCSetFlattened )
					( Origin gBackEnd )
				)
				( attribute "RELATIVE_PROPAGATION_DELAY_SCOPE" "G"
					( Parent
						( matchGroupRef "@baseboard_fab2_lib.baseboard_fab2(sch_1):\MG_DQ_NEAR_DIMM_NG_M_D_BYTE1\" )
					)
					( Status sCSetFlattened )
					( Origin gBackEnd )
				)
				( attribute "RELATIVE_PROPAGATION_DELAY" "-50.00 MIL,50.00 MIL"
					( Parent
						( matchGroupRef "@baseboard_fab2_lib.baseboard_fab2(sch_1):\MG_DQ_NEAR_DIMM_NG_M_D_BYTE1\" )
					)
					( Units "uMatchProp" "ns" 1.000000)
					( Status sCSetFlattened )
					( Origin gBackEnd )
				)
			)
			( pinPair "@baseboard_fab2_lib.baseboard_fab2(sch_1):\PP4674\"
				( pinRef "@baseboard_fab2_lib.baseboard_fab2(sch_1):page26_i172:DDR3_DQ(13)" )
				( pinRef "@baseboard_fab2_lib.baseboard_fab2(sch_1):page49_i111:DQ(12)" )
				( attribute "RELATIVE_PROPAGATION_DELAY_SCOPE" "G"
					( Parent
						( matchGroupRef "@baseboard_fab2_lib.baseboard_fab2(sch_1):\MG_DQ-DQS_FAR_DIMM_NG_M_D_BYTE1\" )
					)
					( Status sCSetFlattened )
					( Origin gBackEnd )
				)
				( attribute "RELATIVE_PROPAGATION_DELAY" "0.00 MIL,195.00 MIL"
					( Parent
						( matchGroupRef "@baseboard_fab2_lib.baseboard_fab2(sch_1):\MG_DQ-DQS_FAR_DIMM_NG_M_D_BYTE1\" )
					)
					( Units "uMatchProp" "ns" 1.000000)
					( Status sCSetFlattened )
					( Origin gBackEnd )
				)
				( attribute "RELATIVE_PROPAGATION_DELAY_SCOPE" "G"
					( Parent
						( matchGroupRef "@baseboard_fab2_lib.baseboard_fab2(sch_1):\MG_DQ_FAR_DIMM_NG_M_D_BYTE1\" )
					)
					( Status sCSetFlattened )
					( Origin gBackEnd )
				)
				( attribute "RELATIVE_PROPAGATION_DELAY" "-50.00 MIL,50.00 MIL"
					( Parent
						( matchGroupRef "@baseboard_fab2_lib.baseboard_fab2(sch_1):\MG_DQ_FAR_DIMM_NG_M_D_BYTE1\" )
					)
					( Units "uMatchProp" "ns" 1.000000)
					( Status sCSetFlattened )
					( Origin gBackEnd )
				)
			)
			( pinPair "@baseboard_fab2_lib.baseboard_fab2(sch_1):\PP4676\"
				( pinRef "@baseboard_fab2_lib.baseboard_fab2(sch_1):page50_i158:DQ(13)" )
				( pinRef "@baseboard_fab2_lib.baseboard_fab2(sch_1):page26_i172:DDR3_DQ(13)" )
				( attribute "RELATIVE_PROPAGATION_DELAY_SCOPE" "G"
					( Parent
						( matchGroupRef "@baseboard_fab2_lib.baseboard_fab2(sch_1):\MG_DQ-DQS_NEAR_DIMM_NG_M_D_BYTE1\" )
					)
					( Status sCSetFlattened )
					( Origin gBackEnd )
				)
				( attribute "RELATIVE_PROPAGATION_DELAY" "0.00 MIL,195.00 MIL"
					( Parent
						( matchGroupRef "@baseboard_fab2_lib.baseboard_fab2(sch_1):\MG_DQ-DQS_NEAR_DIMM_NG_M_D_BYTE1\" )
					)
					( Units "uMatchProp" "ns" 1.000000)
					( Status sCSetFlattened )
					( Origin gBackEnd )
				)
				( attribute "RELATIVE_PROPAGATION_DELAY_SCOPE" "G"
					( Parent
						( matchGroupRef "@baseboard_fab2_lib.baseboard_fab2(sch_1):\MG_DQ_NEAR_DIMM_NG_M_D_BYTE1\" )
					)
					( Status sCSetFlattened )
					( Origin gBackEnd )
				)
				( attribute "RELATIVE_PROPAGATION_DELAY" "-50.00 MIL,50.00 MIL"
					( Parent
						( matchGroupRef "@baseboard_fab2_lib.baseboard_fab2(sch_1):\MG_DQ_NEAR_DIMM_NG_M_D_BYTE1\" )
					)
					( Units "uMatchProp" "ns" 1.000000)
					( Status sCSetFlattened )
					( Origin gBackEnd )
				)
			)
			( pinPair "@baseboard_fab2_lib.baseboard_fab2(sch_1):\PP4677\"
				( pinRef "@baseboard_fab2_lib.baseboard_fab2(sch_1):page26_i172:DDR3_DQ(14)" )
				( pinRef "@baseboard_fab2_lib.baseboard_fab2(sch_1):page49_i111:DQ(15)" )
				( attribute "RELATIVE_PROPAGATION_DELAY_SCOPE" "G"
					( Parent
						( matchGroupRef "@baseboard_fab2_lib.baseboard_fab2(sch_1):\MG_DQ-DQS_FAR_DIMM_NG_M_D_BYTE1\" )
					)
					( Status sCSetFlattened )
					( Origin gBackEnd )
				)
				( attribute "RELATIVE_PROPAGATION_DELAY" "0.00 MIL,195.00 MIL"
					( Parent
						( matchGroupRef "@baseboard_fab2_lib.baseboard_fab2(sch_1):\MG_DQ-DQS_FAR_DIMM_NG_M_D_BYTE1\" )
					)
					( Units "uMatchProp" "ns" 1.000000)
					( Status sCSetFlattened )
					( Origin gBackEnd )
				)
				( attribute "RELATIVE_PROPAGATION_DELAY_SCOPE" "G"
					( Parent
						( matchGroupRef "@baseboard_fab2_lib.baseboard_fab2(sch_1):\MG_DQ_FAR_DIMM_NG_M_D_BYTE1\" )
					)
					( Status sCSetFlattened )
					( Origin gBackEnd )
				)
				( attribute "RELATIVE_PROPAGATION_DELAY" "-50.00 MIL,50.00 MIL"
					( Parent
						( matchGroupRef "@baseboard_fab2_lib.baseboard_fab2(sch_1):\MG_DQ_FAR_DIMM_NG_M_D_BYTE1\" )
					)
					( Units "uMatchProp" "ns" 1.000000)
					( Status sCSetFlattened )
					( Origin gBackEnd )
				)
			)
			( pinPair "@baseboard_fab2_lib.baseboard_fab2(sch_1):\PP4679\"
				( pinRef "@baseboard_fab2_lib.baseboard_fab2(sch_1):page50_i158:DQ(14)" )
				( pinRef "@baseboard_fab2_lib.baseboard_fab2(sch_1):page26_i172:DDR3_DQ(14)" )
				( attribute "RELATIVE_PROPAGATION_DELAY_SCOPE" "G"
					( Parent
						( matchGroupRef "@baseboard_fab2_lib.baseboard_fab2(sch_1):\MG_DQ-DQS_NEAR_DIMM_NG_M_D_BYTE1\" )
					)
					( Status sCSetFlattened )
					( Origin gBackEnd )
				)
				( attribute "RELATIVE_PROPAGATION_DELAY" "0.00 MIL,195.00 MIL"
					( Parent
						( matchGroupRef "@baseboard_fab2_lib.baseboard_fab2(sch_1):\MG_DQ-DQS_NEAR_DIMM_NG_M_D_BYTE1\" )
					)
					( Units "uMatchProp" "ns" 1.000000)
					( Status sCSetFlattened )
					( Origin gBackEnd )
				)
				( attribute "RELATIVE_PROPAGATION_DELAY_SCOPE" "G"
					( Parent
						( matchGroupRef "@baseboard_fab2_lib.baseboard_fab2(sch_1):\MG_DQ_NEAR_DIMM_NG_M_D_BYTE1\" )
					)
					( Status sCSetFlattened )
					( Origin gBackEnd )
				)
				( attribute "RELATIVE_PROPAGATION_DELAY" "-50.00 MIL,50.00 MIL"
					( Parent
						( matchGroupRef "@baseboard_fab2_lib.baseboard_fab2(sch_1):\MG_DQ_NEAR_DIMM_NG_M_D_BYTE1\" )
					)
					( Units "uMatchProp" "ns" 1.000000)
					( Status sCSetFlattened )
					( Origin gBackEnd )
				)
			)
			( pinPair "@baseboard_fab2_lib.baseboard_fab2(sch_1):\PP4680\"
				( pinRef "@baseboard_fab2_lib.baseboard_fab2(sch_1):page26_i172:DDR3_DQ(15)" )
				( pinRef "@baseboard_fab2_lib.baseboard_fab2(sch_1):page49_i111:DQ(14)" )
				( attribute "RELATIVE_PROPAGATION_DELAY_SCOPE" "G"
					( Parent
						( matchGroupRef "@baseboard_fab2_lib.baseboard_fab2(sch_1):\MG_DQ-DQS_FAR_DIMM_NG_M_D_BYTE1\" )
					)
					( Status sCSetFlattened )
					( Origin gBackEnd )
				)
				( attribute "RELATIVE_PROPAGATION_DELAY" "0.00 MIL,195.00 MIL"
					( Parent
						( matchGroupRef "@baseboard_fab2_lib.baseboard_fab2(sch_1):\MG_DQ-DQS_FAR_DIMM_NG_M_D_BYTE1\" )
					)
					( Units "uMatchProp" "ns" 1.000000)
					( Status sCSetFlattened )
					( Origin gBackEnd )
				)
				( attribute "RELATIVE_PROPAGATION_DELAY_SCOPE" "G"
					( Parent
						( matchGroupRef "@baseboard_fab2_lib.baseboard_fab2(sch_1):\MG_DQ_FAR_DIMM_NG_M_D_BYTE1\" )
					)
					( Status sCSetFlattened )
					( Origin gBackEnd )
				)
				( attribute "RELATIVE_PROPAGATION_DELAY" "-50.00 MIL,50.00 MIL"
					( Parent
						( matchGroupRef "@baseboard_fab2_lib.baseboard_fab2(sch_1):\MG_DQ_FAR_DIMM_NG_M_D_BYTE1\" )
					)
					( Units "uMatchProp" "ns" 1.000000)
					( Status sCSetFlattened )
					( Origin gBackEnd )
				)
			)
			( pinPair "@baseboard_fab2_lib.baseboard_fab2(sch_1):\PP4682\"
				( pinRef "@baseboard_fab2_lib.baseboard_fab2(sch_1):page50_i158:DQ(15)" )
				( pinRef "@baseboard_fab2_lib.baseboard_fab2(sch_1):page26_i172:DDR3_DQ(15)" )
				( attribute "RELATIVE_PROPAGATION_DELAY_SCOPE" "G"
					( Parent
						( matchGroupRef "@baseboard_fab2_lib.baseboard_fab2(sch_1):\MG_DQ-DQS_NEAR_DIMM_NG_M_D_BYTE1\" )
					)
					( Status sCSetFlattened )
					( Origin gBackEnd )
				)
				( attribute "RELATIVE_PROPAGATION_DELAY" "0.00 MIL,195.00 MIL"
					( Parent
						( matchGroupRef "@baseboard_fab2_lib.baseboard_fab2(sch_1):\MG_DQ-DQS_NEAR_DIMM_NG_M_D_BYTE1\" )
					)
					( Units "uMatchProp" "ns" 1.000000)
					( Status sCSetFlattened )
					( Origin gBackEnd )
				)
				( attribute "RELATIVE_PROPAGATION_DELAY_SCOPE" "G"
					( Parent
						( matchGroupRef "@baseboard_fab2_lib.baseboard_fab2(sch_1):\MG_DQ_NEAR_DIMM_NG_M_D_BYTE1\" )
					)
					( Status sCSetFlattened )
					( Origin gBackEnd )
				)
				( attribute "RELATIVE_PROPAGATION_DELAY" "-50.00 MIL,50.00 MIL"
					( Parent
						( matchGroupRef "@baseboard_fab2_lib.baseboard_fab2(sch_1):\MG_DQ_NEAR_DIMM_NG_M_D_BYTE1\" )
					)
					( Units "uMatchProp" "ns" 1.000000)
					( Status sCSetFlattened )
					( Origin gBackEnd )
				)
			)
			( pinPair "@baseboard_fab2_lib.baseboard_fab2(sch_1):\PP4635\"
				( pinRef "@baseboard_fab2_lib.baseboard_fab2(sch_1):page26_i172:DDR3_DQ(16)" )
				( pinRef "@baseboard_fab2_lib.baseboard_fab2(sch_1):page49_i111:DQ(17)" )
				( attribute "RELATIVE_PROPAGATION_DELAY_SCOPE" "G"
					( Parent
						( matchGroupRef "@baseboard_fab2_lib.baseboard_fab2(sch_1):\MG_DQ-DQS_FAR_DIMM_NG_M_D_BYTE2\" )
					)
					( Status sCSetFlattened )
					( Origin gBackEnd )
				)
				( attribute "RELATIVE_PROPAGATION_DELAY" "0.00 MIL,195.00 MIL"
					( Parent
						( matchGroupRef "@baseboard_fab2_lib.baseboard_fab2(sch_1):\MG_DQ-DQS_FAR_DIMM_NG_M_D_BYTE2\" )
					)
					( Units "uMatchProp" "ns" 1.000000)
					( Status sCSetFlattened )
					( Origin gBackEnd )
				)
				( attribute "RELATIVE_PROPAGATION_DELAY_SCOPE" "G"
					( Parent
						( matchGroupRef "@baseboard_fab2_lib.baseboard_fab2(sch_1):\MG_DQ_FAR_DIMM_NG_M_D_BYTE2\" )
					)
					( Status sCSetFlattened )
					( Origin gBackEnd )
				)
				( attribute "RELATIVE_PROPAGATION_DELAY" "-50.00 MIL,50.00 MIL"
					( Parent
						( matchGroupRef "@baseboard_fab2_lib.baseboard_fab2(sch_1):\MG_DQ_FAR_DIMM_NG_M_D_BYTE2\" )
					)
					( Units "uMatchProp" "ns" 1.000000)
					( Status sCSetFlattened )
					( Origin gBackEnd )
				)
			)
			( pinPair "@baseboard_fab2_lib.baseboard_fab2(sch_1):\PP4637\"
				( pinRef "@baseboard_fab2_lib.baseboard_fab2(sch_1):page26_i172:DDR3_DQ(16)" )
				( pinRef "@baseboard_fab2_lib.baseboard_fab2(sch_1):page50_i158:DQ(16)" )
				( attribute "RELATIVE_PROPAGATION_DELAY_SCOPE" "G"
					( Parent
						( matchGroupRef "@baseboard_fab2_lib.baseboard_fab2(sch_1):\MG_DQ-DQS_NEAR_DIMM_NG_M_D_BYTE2\" )
					)
					( Status sCSetFlattened )
					( Origin gBackEnd )
				)
				( attribute "RELATIVE_PROPAGATION_DELAY" "0.00 MIL,195.00 MIL"
					( Parent
						( matchGroupRef "@baseboard_fab2_lib.baseboard_fab2(sch_1):\MG_DQ-DQS_NEAR_DIMM_NG_M_D_BYTE2\" )
					)
					( Units "uMatchProp" "ns" 1.000000)
					( Status sCSetFlattened )
					( Origin gBackEnd )
				)
				( attribute "RELATIVE_PROPAGATION_DELAY_SCOPE" "G"
					( Parent
						( matchGroupRef "@baseboard_fab2_lib.baseboard_fab2(sch_1):\MG_DQ_NEAR_DIMM_NG_M_D_BYTE2\" )
					)
					( Status sCSetFlattened )
					( Origin gBackEnd )
				)
				( attribute "RELATIVE_PROPAGATION_DELAY" "-50.00 MIL,50.00 MIL"
					( Parent
						( matchGroupRef "@baseboard_fab2_lib.baseboard_fab2(sch_1):\MG_DQ_NEAR_DIMM_NG_M_D_BYTE2\" )
					)
					( Units "uMatchProp" "ns" 1.000000)
					( Status sCSetFlattened )
					( Origin gBackEnd )
				)
			)
			( pinPair "@baseboard_fab2_lib.baseboard_fab2(sch_1):\PP4638\"
				( pinRef "@baseboard_fab2_lib.baseboard_fab2(sch_1):page26_i172:DDR3_DQ(17)" )
				( pinRef "@baseboard_fab2_lib.baseboard_fab2(sch_1):page49_i111:DQ(16)" )
				( attribute "RELATIVE_PROPAGATION_DELAY_SCOPE" "G"
					( Parent
						( matchGroupRef "@baseboard_fab2_lib.baseboard_fab2(sch_1):\MG_DQ-DQS_FAR_DIMM_NG_M_D_BYTE2\" )
					)
					( Status sCSetFlattened )
					( Origin gBackEnd )
				)
				( attribute "RELATIVE_PROPAGATION_DELAY" "0.00 MIL,195.00 MIL"
					( Parent
						( matchGroupRef "@baseboard_fab2_lib.baseboard_fab2(sch_1):\MG_DQ-DQS_FAR_DIMM_NG_M_D_BYTE2\" )
					)
					( Units "uMatchProp" "ns" 1.000000)
					( Status sCSetFlattened )
					( Origin gBackEnd )
				)
				( attribute "RELATIVE_PROPAGATION_DELAY_SCOPE" "G"
					( Parent
						( matchGroupRef "@baseboard_fab2_lib.baseboard_fab2(sch_1):\MG_DQ_FAR_DIMM_NG_M_D_BYTE2\" )
					)
					( Status sCSetFlattened )
					( Origin gBackEnd )
				)
				( attribute "RELATIVE_PROPAGATION_DELAY" "-50.00 MIL,50.00 MIL"
					( Parent
						( matchGroupRef "@baseboard_fab2_lib.baseboard_fab2(sch_1):\MG_DQ_FAR_DIMM_NG_M_D_BYTE2\" )
					)
					( Units "uMatchProp" "ns" 1.000000)
					( Status sCSetFlattened )
					( Origin gBackEnd )
				)
			)
			( pinPair "@baseboard_fab2_lib.baseboard_fab2(sch_1):\PP4640\"
				( pinRef "@baseboard_fab2_lib.baseboard_fab2(sch_1):page26_i172:DDR3_DQ(17)" )
				( pinRef "@baseboard_fab2_lib.baseboard_fab2(sch_1):page50_i158:DQ(17)" )
				( attribute "RELATIVE_PROPAGATION_DELAY_SCOPE" "G"
					( Parent
						( matchGroupRef "@baseboard_fab2_lib.baseboard_fab2(sch_1):\MG_DQ-DQS_NEAR_DIMM_NG_M_D_BYTE2\" )
					)
					( Status sCSetFlattened )
					( Origin gBackEnd )
				)
				( attribute "RELATIVE_PROPAGATION_DELAY" "0.00 MIL,195.00 MIL"
					( Parent
						( matchGroupRef "@baseboard_fab2_lib.baseboard_fab2(sch_1):\MG_DQ-DQS_NEAR_DIMM_NG_M_D_BYTE2\" )
					)
					( Units "uMatchProp" "ns" 1.000000)
					( Status sCSetFlattened )
					( Origin gBackEnd )
				)
				( attribute "RELATIVE_PROPAGATION_DELAY_SCOPE" "G"
					( Parent
						( matchGroupRef "@baseboard_fab2_lib.baseboard_fab2(sch_1):\MG_DQ_NEAR_DIMM_NG_M_D_BYTE2\" )
					)
					( Status sCSetFlattened )
					( Origin gBackEnd )
				)
				( attribute "RELATIVE_PROPAGATION_DELAY" "-50.00 MIL,50.00 MIL"
					( Parent
						( matchGroupRef "@baseboard_fab2_lib.baseboard_fab2(sch_1):\MG_DQ_NEAR_DIMM_NG_M_D_BYTE2\" )
					)
					( Units "uMatchProp" "ns" 1.000000)
					( Status sCSetFlattened )
					( Origin gBackEnd )
				)
			)
			( pinPair "@baseboard_fab2_lib.baseboard_fab2(sch_1):\PP4641\"
				( pinRef "@baseboard_fab2_lib.baseboard_fab2(sch_1):page26_i172:DDR3_DQ(18)" )
				( pinRef "@baseboard_fab2_lib.baseboard_fab2(sch_1):page49_i111:DQ(19)" )
				( attribute "RELATIVE_PROPAGATION_DELAY_SCOPE" "G"
					( Parent
						( matchGroupRef "@baseboard_fab2_lib.baseboard_fab2(sch_1):\MG_DQ-DQS_FAR_DIMM_NG_M_D_BYTE2\" )
					)
					( Status sCSetFlattened )
					( Origin gBackEnd )
				)
				( attribute "RELATIVE_PROPAGATION_DELAY" "0.00 MIL,195.00 MIL"
					( Parent
						( matchGroupRef "@baseboard_fab2_lib.baseboard_fab2(sch_1):\MG_DQ-DQS_FAR_DIMM_NG_M_D_BYTE2\" )
					)
					( Units "uMatchProp" "ns" 1.000000)
					( Status sCSetFlattened )
					( Origin gBackEnd )
				)
				( attribute "RELATIVE_PROPAGATION_DELAY_SCOPE" "G"
					( Parent
						( matchGroupRef "@baseboard_fab2_lib.baseboard_fab2(sch_1):\MG_DQ_FAR_DIMM_NG_M_D_BYTE2\" )
					)
					( Status sCSetFlattened )
					( Origin gBackEnd )
				)
				( attribute "RELATIVE_PROPAGATION_DELAY" "-50.00 MIL,50.00 MIL"
					( Parent
						( matchGroupRef "@baseboard_fab2_lib.baseboard_fab2(sch_1):\MG_DQ_FAR_DIMM_NG_M_D_BYTE2\" )
					)
					( Units "uMatchProp" "ns" 1.000000)
					( Status sCSetFlattened )
					( Origin gBackEnd )
				)
			)
			( pinPair "@baseboard_fab2_lib.baseboard_fab2(sch_1):\PP4643\"
				( pinRef "@baseboard_fab2_lib.baseboard_fab2(sch_1):page26_i172:DDR3_DQ(18)" )
				( pinRef "@baseboard_fab2_lib.baseboard_fab2(sch_1):page50_i158:DQ(18)" )
				( attribute "RELATIVE_PROPAGATION_DELAY_SCOPE" "G"
					( Parent
						( matchGroupRef "@baseboard_fab2_lib.baseboard_fab2(sch_1):\MG_DQ-DQS_NEAR_DIMM_NG_M_D_BYTE2\" )
					)
					( Status sCSetFlattened )
					( Origin gBackEnd )
				)
				( attribute "RELATIVE_PROPAGATION_DELAY" "0.00 MIL,195.00 MIL"
					( Parent
						( matchGroupRef "@baseboard_fab2_lib.baseboard_fab2(sch_1):\MG_DQ-DQS_NEAR_DIMM_NG_M_D_BYTE2\" )
					)
					( Units "uMatchProp" "ns" 1.000000)
					( Status sCSetFlattened )
					( Origin gBackEnd )
				)
				( attribute "RELATIVE_PROPAGATION_DELAY_SCOPE" "G"
					( Parent
						( matchGroupRef "@baseboard_fab2_lib.baseboard_fab2(sch_1):\MG_DQ_NEAR_DIMM_NG_M_D_BYTE2\" )
					)
					( Status sCSetFlattened )
					( Origin gBackEnd )
				)
				( attribute "RELATIVE_PROPAGATION_DELAY" "-50.00 MIL,50.00 MIL"
					( Parent
						( matchGroupRef "@baseboard_fab2_lib.baseboard_fab2(sch_1):\MG_DQ_NEAR_DIMM_NG_M_D_BYTE2\" )
					)
					( Units "uMatchProp" "ns" 1.000000)
					( Status sCSetFlattened )
					( Origin gBackEnd )
				)
			)
			( pinPair "@baseboard_fab2_lib.baseboard_fab2(sch_1):\PP4644\"
				( pinRef "@baseboard_fab2_lib.baseboard_fab2(sch_1):page26_i172:DDR3_DQ(19)" )
				( pinRef "@baseboard_fab2_lib.baseboard_fab2(sch_1):page49_i111:DQ(18)" )
				( attribute "RELATIVE_PROPAGATION_DELAY_SCOPE" "G"
					( Parent
						( matchGroupRef "@baseboard_fab2_lib.baseboard_fab2(sch_1):\MG_DQ-DQS_FAR_DIMM_NG_M_D_BYTE2\" )
					)
					( Status sCSetFlattened )
					( Origin gBackEnd )
				)
				( attribute "RELATIVE_PROPAGATION_DELAY" "0.00 MIL,195.00 MIL"
					( Parent
						( matchGroupRef "@baseboard_fab2_lib.baseboard_fab2(sch_1):\MG_DQ-DQS_FAR_DIMM_NG_M_D_BYTE2\" )
					)
					( Units "uMatchProp" "ns" 1.000000)
					( Status sCSetFlattened )
					( Origin gBackEnd )
				)
				( attribute "RELATIVE_PROPAGATION_DELAY_SCOPE" "G"
					( Parent
						( matchGroupRef "@baseboard_fab2_lib.baseboard_fab2(sch_1):\MG_DQ_FAR_DIMM_NG_M_D_BYTE2\" )
					)
					( Status sCSetFlattened )
					( Origin gBackEnd )
				)
				( attribute "RELATIVE_PROPAGATION_DELAY" "-50.00 MIL,50.00 MIL"
					( Parent
						( matchGroupRef "@baseboard_fab2_lib.baseboard_fab2(sch_1):\MG_DQ_FAR_DIMM_NG_M_D_BYTE2\" )
					)
					( Units "uMatchProp" "ns" 1.000000)
					( Status sCSetFlattened )
					( Origin gBackEnd )
				)
			)
			( pinPair "@baseboard_fab2_lib.baseboard_fab2(sch_1):\PP4646\"
				( pinRef "@baseboard_fab2_lib.baseboard_fab2(sch_1):page26_i172:DDR3_DQ(19)" )
				( pinRef "@baseboard_fab2_lib.baseboard_fab2(sch_1):page50_i158:DQ(19)" )
				( attribute "RELATIVE_PROPAGATION_DELAY_SCOPE" "G"
					( Parent
						( matchGroupRef "@baseboard_fab2_lib.baseboard_fab2(sch_1):\MG_DQ-DQS_NEAR_DIMM_NG_M_D_BYTE2\" )
					)
					( Status sCSetFlattened )
					( Origin gBackEnd )
				)
				( attribute "RELATIVE_PROPAGATION_DELAY" "0.00 MIL,195.00 MIL"
					( Parent
						( matchGroupRef "@baseboard_fab2_lib.baseboard_fab2(sch_1):\MG_DQ-DQS_NEAR_DIMM_NG_M_D_BYTE2\" )
					)
					( Units "uMatchProp" "ns" 1.000000)
					( Status sCSetFlattened )
					( Origin gBackEnd )
				)
				( attribute "RELATIVE_PROPAGATION_DELAY_SCOPE" "G"
					( Parent
						( matchGroupRef "@baseboard_fab2_lib.baseboard_fab2(sch_1):\MG_DQ_NEAR_DIMM_NG_M_D_BYTE2\" )
					)
					( Status sCSetFlattened )
					( Origin gBackEnd )
				)
				( attribute "RELATIVE_PROPAGATION_DELAY" "-50.00 MIL,50.00 MIL"
					( Parent
						( matchGroupRef "@baseboard_fab2_lib.baseboard_fab2(sch_1):\MG_DQ_NEAR_DIMM_NG_M_D_BYTE2\" )
					)
					( Units "uMatchProp" "ns" 1.000000)
					( Status sCSetFlattened )
					( Origin gBackEnd )
				)
			)
			( pinPair "@baseboard_fab2_lib.baseboard_fab2(sch_1):\PP4647\"
				( pinRef "@baseboard_fab2_lib.baseboard_fab2(sch_1):page26_i172:DDR3_DQ(20)" )
				( pinRef "@baseboard_fab2_lib.baseboard_fab2(sch_1):page49_i111:DQ(21)" )
				( attribute "RELATIVE_PROPAGATION_DELAY_SCOPE" "G"
					( Parent
						( matchGroupRef "@baseboard_fab2_lib.baseboard_fab2(sch_1):\MG_DQ-DQS_FAR_DIMM_NG_M_D_BYTE2\" )
					)
					( Status sCSetFlattened )
					( Origin gBackEnd )
				)
				( attribute "RELATIVE_PROPAGATION_DELAY" "0.00 MIL,195.00 MIL"
					( Parent
						( matchGroupRef "@baseboard_fab2_lib.baseboard_fab2(sch_1):\MG_DQ-DQS_FAR_DIMM_NG_M_D_BYTE2\" )
					)
					( Units "uMatchProp" "ns" 1.000000)
					( Status sCSetFlattened )
					( Origin gBackEnd )
				)
				( attribute "RELATIVE_PROPAGATION_DELAY_SCOPE" "G"
					( Parent
						( matchGroupRef "@baseboard_fab2_lib.baseboard_fab2(sch_1):\MG_DQ_FAR_DIMM_NG_M_D_BYTE2\" )
					)
					( Status sCSetFlattened )
					( Origin gBackEnd )
				)
				( attribute "RELATIVE_PROPAGATION_DELAY" "-50.00 MIL,50.00 MIL"
					( Parent
						( matchGroupRef "@baseboard_fab2_lib.baseboard_fab2(sch_1):\MG_DQ_FAR_DIMM_NG_M_D_BYTE2\" )
					)
					( Units "uMatchProp" "ns" 1.000000)
					( Status sCSetFlattened )
					( Origin gBackEnd )
				)
			)
			( pinPair "@baseboard_fab2_lib.baseboard_fab2(sch_1):\PP4649\"
				( pinRef "@baseboard_fab2_lib.baseboard_fab2(sch_1):page26_i172:DDR3_DQ(20)" )
				( pinRef "@baseboard_fab2_lib.baseboard_fab2(sch_1):page50_i158:DQ(20)" )
				( attribute "RELATIVE_PROPAGATION_DELAY_SCOPE" "G"
					( Parent
						( matchGroupRef "@baseboard_fab2_lib.baseboard_fab2(sch_1):\MG_DQ-DQS_NEAR_DIMM_NG_M_D_BYTE2\" )
					)
					( Status sCSetFlattened )
					( Origin gBackEnd )
				)
				( attribute "RELATIVE_PROPAGATION_DELAY" "0.00 MIL,195.00 MIL"
					( Parent
						( matchGroupRef "@baseboard_fab2_lib.baseboard_fab2(sch_1):\MG_DQ-DQS_NEAR_DIMM_NG_M_D_BYTE2\" )
					)
					( Units "uMatchProp" "ns" 1.000000)
					( Status sCSetFlattened )
					( Origin gBackEnd )
				)
				( attribute "RELATIVE_PROPAGATION_DELAY_SCOPE" "G"
					( Parent
						( matchGroupRef "@baseboard_fab2_lib.baseboard_fab2(sch_1):\MG_DQ_NEAR_DIMM_NG_M_D_BYTE2\" )
					)
					( Status sCSetFlattened )
					( Origin gBackEnd )
				)
				( attribute "RELATIVE_PROPAGATION_DELAY" "-50.00 MIL,50.00 MIL"
					( Parent
						( matchGroupRef "@baseboard_fab2_lib.baseboard_fab2(sch_1):\MG_DQ_NEAR_DIMM_NG_M_D_BYTE2\" )
					)
					( Units "uMatchProp" "ns" 1.000000)
					( Status sCSetFlattened )
					( Origin gBackEnd )
				)
			)
			( pinPair "@baseboard_fab2_lib.baseboard_fab2(sch_1):\PP4650\"
				( pinRef "@baseboard_fab2_lib.baseboard_fab2(sch_1):page26_i172:DDR3_DQ(21)" )
				( pinRef "@baseboard_fab2_lib.baseboard_fab2(sch_1):page49_i111:DQ(20)" )
				( attribute "RELATIVE_PROPAGATION_DELAY_SCOPE" "G"
					( Parent
						( matchGroupRef "@baseboard_fab2_lib.baseboard_fab2(sch_1):\MG_DQ-DQS_FAR_DIMM_NG_M_D_BYTE2\" )
					)
					( Status sCSetFlattened )
					( Origin gBackEnd )
				)
				( attribute "RELATIVE_PROPAGATION_DELAY" "0.00 MIL,195.00 MIL"
					( Parent
						( matchGroupRef "@baseboard_fab2_lib.baseboard_fab2(sch_1):\MG_DQ-DQS_FAR_DIMM_NG_M_D_BYTE2\" )
					)
					( Units "uMatchProp" "ns" 1.000000)
					( Status sCSetFlattened )
					( Origin gBackEnd )
				)
				( attribute "RELATIVE_PROPAGATION_DELAY_SCOPE" "G"
					( Parent
						( matchGroupRef "@baseboard_fab2_lib.baseboard_fab2(sch_1):\MG_DQ_FAR_DIMM_NG_M_D_BYTE2\" )
					)
					( Status sCSetFlattened )
					( Origin gBackEnd )
				)
				( attribute "RELATIVE_PROPAGATION_DELAY" "-50.00 MIL,50.00 MIL"
					( Parent
						( matchGroupRef "@baseboard_fab2_lib.baseboard_fab2(sch_1):\MG_DQ_FAR_DIMM_NG_M_D_BYTE2\" )
					)
					( Units "uMatchProp" "ns" 1.000000)
					( Status sCSetFlattened )
					( Origin gBackEnd )
				)
			)
			( pinPair "@baseboard_fab2_lib.baseboard_fab2(sch_1):\PP4652\"
				( pinRef "@baseboard_fab2_lib.baseboard_fab2(sch_1):page26_i172:DDR3_DQ(21)" )
				( pinRef "@baseboard_fab2_lib.baseboard_fab2(sch_1):page50_i158:DQ(21)" )
				( attribute "RELATIVE_PROPAGATION_DELAY_SCOPE" "G"
					( Parent
						( matchGroupRef "@baseboard_fab2_lib.baseboard_fab2(sch_1):\MG_DQ-DQS_NEAR_DIMM_NG_M_D_BYTE2\" )
					)
					( Status sCSetFlattened )
					( Origin gBackEnd )
				)
				( attribute "RELATIVE_PROPAGATION_DELAY" "0.00 MIL,195.00 MIL"
					( Parent
						( matchGroupRef "@baseboard_fab2_lib.baseboard_fab2(sch_1):\MG_DQ-DQS_NEAR_DIMM_NG_M_D_BYTE2\" )
					)
					( Units "uMatchProp" "ns" 1.000000)
					( Status sCSetFlattened )
					( Origin gBackEnd )
				)
				( attribute "RELATIVE_PROPAGATION_DELAY_SCOPE" "G"
					( Parent
						( matchGroupRef "@baseboard_fab2_lib.baseboard_fab2(sch_1):\MG_DQ_NEAR_DIMM_NG_M_D_BYTE2\" )
					)
					( Status sCSetFlattened )
					( Origin gBackEnd )
				)
				( attribute "RELATIVE_PROPAGATION_DELAY" "-50.00 MIL,50.00 MIL"
					( Parent
						( matchGroupRef "@baseboard_fab2_lib.baseboard_fab2(sch_1):\MG_DQ_NEAR_DIMM_NG_M_D_BYTE2\" )
					)
					( Units "uMatchProp" "ns" 1.000000)
					( Status sCSetFlattened )
					( Origin gBackEnd )
				)
			)
			( pinPair "@baseboard_fab2_lib.baseboard_fab2(sch_1):\PP4653\"
				( pinRef "@baseboard_fab2_lib.baseboard_fab2(sch_1):page26_i172:DDR3_DQ(22)" )
				( pinRef "@baseboard_fab2_lib.baseboard_fab2(sch_1):page49_i111:DQ(23)" )
				( attribute "RELATIVE_PROPAGATION_DELAY_SCOPE" "G"
					( Parent
						( matchGroupRef "@baseboard_fab2_lib.baseboard_fab2(sch_1):\MG_DQ-DQS_FAR_DIMM_NG_M_D_BYTE2\" )
					)
					( Status sCSetFlattened )
					( Origin gBackEnd )
				)
				( attribute "RELATIVE_PROPAGATION_DELAY" "0.00 MIL,195.00 MIL"
					( Parent
						( matchGroupRef "@baseboard_fab2_lib.baseboard_fab2(sch_1):\MG_DQ-DQS_FAR_DIMM_NG_M_D_BYTE2\" )
					)
					( Units "uMatchProp" "ns" 1.000000)
					( Status sCSetFlattened )
					( Origin gBackEnd )
				)
				( attribute "RELATIVE_PROPAGATION_DELAY_SCOPE" "G"
					( Parent
						( matchGroupRef "@baseboard_fab2_lib.baseboard_fab2(sch_1):\MG_DQ_FAR_DIMM_NG_M_D_BYTE2\" )
					)
					( Status sCSetFlattened )
					( Origin gBackEnd )
				)
				( attribute "RELATIVE_PROPAGATION_DELAY" "-50.00 MIL,50.00 MIL"
					( Parent
						( matchGroupRef "@baseboard_fab2_lib.baseboard_fab2(sch_1):\MG_DQ_FAR_DIMM_NG_M_D_BYTE2\" )
					)
					( Units "uMatchProp" "ns" 1.000000)
					( Status sCSetFlattened )
					( Origin gBackEnd )
				)
			)
			( pinPair "@baseboard_fab2_lib.baseboard_fab2(sch_1):\PP4655\"
				( pinRef "@baseboard_fab2_lib.baseboard_fab2(sch_1):page26_i172:DDR3_DQ(22)" )
				( pinRef "@baseboard_fab2_lib.baseboard_fab2(sch_1):page50_i158:DQ(22)" )
				( attribute "RELATIVE_PROPAGATION_DELAY_SCOPE" "G"
					( Parent
						( matchGroupRef "@baseboard_fab2_lib.baseboard_fab2(sch_1):\MG_DQ-DQS_NEAR_DIMM_NG_M_D_BYTE2\" )
					)
					( Status sCSetFlattened )
					( Origin gBackEnd )
				)
				( attribute "RELATIVE_PROPAGATION_DELAY" "0.00 MIL,195.00 MIL"
					( Parent
						( matchGroupRef "@baseboard_fab2_lib.baseboard_fab2(sch_1):\MG_DQ-DQS_NEAR_DIMM_NG_M_D_BYTE2\" )
					)
					( Units "uMatchProp" "ns" 1.000000)
					( Status sCSetFlattened )
					( Origin gBackEnd )
				)
				( attribute "RELATIVE_PROPAGATION_DELAY_SCOPE" "G"
					( Parent
						( matchGroupRef "@baseboard_fab2_lib.baseboard_fab2(sch_1):\MG_DQ_NEAR_DIMM_NG_M_D_BYTE2\" )
					)
					( Status sCSetFlattened )
					( Origin gBackEnd )
				)
				( attribute "RELATIVE_PROPAGATION_DELAY" "-50.00 MIL,50.00 MIL"
					( Parent
						( matchGroupRef "@baseboard_fab2_lib.baseboard_fab2(sch_1):\MG_DQ_NEAR_DIMM_NG_M_D_BYTE2\" )
					)
					( Units "uMatchProp" "ns" 1.000000)
					( Status sCSetFlattened )
					( Origin gBackEnd )
				)
			)
			( pinPair "@baseboard_fab2_lib.baseboard_fab2(sch_1):\PP4656\"
				( pinRef "@baseboard_fab2_lib.baseboard_fab2(sch_1):page26_i172:DDR3_DQ(23)" )
				( pinRef "@baseboard_fab2_lib.baseboard_fab2(sch_1):page49_i111:DQ(22)" )
				( attribute "RELATIVE_PROPAGATION_DELAY_SCOPE" "G"
					( Parent
						( matchGroupRef "@baseboard_fab2_lib.baseboard_fab2(sch_1):\MG_DQ-DQS_FAR_DIMM_NG_M_D_BYTE2\" )
					)
					( Status sCSetFlattened )
					( Origin gBackEnd )
				)
				( attribute "RELATIVE_PROPAGATION_DELAY" "0.00 MIL,195.00 MIL"
					( Parent
						( matchGroupRef "@baseboard_fab2_lib.baseboard_fab2(sch_1):\MG_DQ-DQS_FAR_DIMM_NG_M_D_BYTE2\" )
					)
					( Units "uMatchProp" "ns" 1.000000)
					( Status sCSetFlattened )
					( Origin gBackEnd )
				)
				( attribute "RELATIVE_PROPAGATION_DELAY_SCOPE" "G"
					( Parent
						( matchGroupRef "@baseboard_fab2_lib.baseboard_fab2(sch_1):\MG_DQ_FAR_DIMM_NG_M_D_BYTE2\" )
					)
					( Status sCSetFlattened )
					( Origin gBackEnd )
				)
				( attribute "RELATIVE_PROPAGATION_DELAY" "-50.00 MIL,50.00 MIL"
					( Parent
						( matchGroupRef "@baseboard_fab2_lib.baseboard_fab2(sch_1):\MG_DQ_FAR_DIMM_NG_M_D_BYTE2\" )
					)
					( Units "uMatchProp" "ns" 1.000000)
					( Status sCSetFlattened )
					( Origin gBackEnd )
				)
			)
			( pinPair "@baseboard_fab2_lib.baseboard_fab2(sch_1):\PP4658\"
				( pinRef "@baseboard_fab2_lib.baseboard_fab2(sch_1):page26_i172:DDR3_DQ(23)" )
				( pinRef "@baseboard_fab2_lib.baseboard_fab2(sch_1):page50_i158:DQ(23)" )
				( attribute "RELATIVE_PROPAGATION_DELAY_SCOPE" "G"
					( Parent
						( matchGroupRef "@baseboard_fab2_lib.baseboard_fab2(sch_1):\MG_DQ-DQS_NEAR_DIMM_NG_M_D_BYTE2\" )
					)
					( Status sCSetFlattened )
					( Origin gBackEnd )
				)
				( attribute "RELATIVE_PROPAGATION_DELAY" "0.00 MIL,195.00 MIL"
					( Parent
						( matchGroupRef "@baseboard_fab2_lib.baseboard_fab2(sch_1):\MG_DQ-DQS_NEAR_DIMM_NG_M_D_BYTE2\" )
					)
					( Units "uMatchProp" "ns" 1.000000)
					( Status sCSetFlattened )
					( Origin gBackEnd )
				)
				( attribute "RELATIVE_PROPAGATION_DELAY_SCOPE" "G"
					( Parent
						( matchGroupRef "@baseboard_fab2_lib.baseboard_fab2(sch_1):\MG_DQ_NEAR_DIMM_NG_M_D_BYTE2\" )
					)
					( Status sCSetFlattened )
					( Origin gBackEnd )
				)
				( attribute "RELATIVE_PROPAGATION_DELAY" "-50.00 MIL,50.00 MIL"
					( Parent
						( matchGroupRef "@baseboard_fab2_lib.baseboard_fab2(sch_1):\MG_DQ_NEAR_DIMM_NG_M_D_BYTE2\" )
					)
					( Units "uMatchProp" "ns" 1.000000)
					( Status sCSetFlattened )
					( Origin gBackEnd )
				)
			)
			( pinPair "@baseboard_fab2_lib.baseboard_fab2(sch_1):\PP4611\"
				( pinRef "@baseboard_fab2_lib.baseboard_fab2(sch_1):page26_i172:DDR3_DQ(24)" )
				( pinRef "@baseboard_fab2_lib.baseboard_fab2(sch_1):page49_i111:DQ(25)" )
				( attribute "RELATIVE_PROPAGATION_DELAY_SCOPE" "G"
					( Parent
						( matchGroupRef "@baseboard_fab2_lib.baseboard_fab2(sch_1):\MG_DQ-DQS_FAR_DIMM_NG_M_D_BYTE3\" )
					)
					( Status sCSetFlattened )
					( Origin gBackEnd )
				)
				( attribute "RELATIVE_PROPAGATION_DELAY" "0.00 MIL,195.00 MIL"
					( Parent
						( matchGroupRef "@baseboard_fab2_lib.baseboard_fab2(sch_1):\MG_DQ-DQS_FAR_DIMM_NG_M_D_BYTE3\" )
					)
					( Units "uMatchProp" "ns" 1.000000)
					( Status sCSetFlattened )
					( Origin gBackEnd )
				)
				( attribute "RELATIVE_PROPAGATION_DELAY_SCOPE" "G"
					( Parent
						( matchGroupRef "@crescent_city_bb_fab1_lib.crescent_city_bb_fab1(sch_1):\MG_DQ_FAR_DIMM_NG_M_D_BYTE3\" )
					)
					( Origin gBackEnd )
				)
				( attribute "RELATIVE_PROPAGATION_DELAY" "TARGET,TARGET"
					( Parent
						( matchGroupRef "@crescent_city_bb_fab1_lib.crescent_city_bb_fab1(sch_1):\MG_DQ_FAR_DIMM_NG_M_D_BYTE3\" )
					)
					( Units "uMatchProp" "ns" 1.000000)
					( Origin gBackEnd )
				)
			)
			( pinPair "@baseboard_fab2_lib.baseboard_fab2(sch_1):\PP4613\"
				( pinRef "@baseboard_fab2_lib.baseboard_fab2(sch_1):page26_i172:DDR3_DQ(24)" )
				( pinRef "@baseboard_fab2_lib.baseboard_fab2(sch_1):page50_i158:DQ(24)" )
				( attribute "RELATIVE_PROPAGATION_DELAY_SCOPE" "G"
					( Parent
						( matchGroupRef "@baseboard_fab2_lib.baseboard_fab2(sch_1):\MG_DQ-DQS_NEAR_DIMM_NG_M_D_BYTE3\" )
					)
					( Status sCSetFlattened )
					( Origin gBackEnd )
				)
				( attribute "RELATIVE_PROPAGATION_DELAY" "0.00 MIL,195.00 MIL"
					( Parent
						( matchGroupRef "@baseboard_fab2_lib.baseboard_fab2(sch_1):\MG_DQ-DQS_NEAR_DIMM_NG_M_D_BYTE3\" )
					)
					( Units "uMatchProp" "ns" 1.000000)
					( Status sCSetFlattened )
					( Origin gBackEnd )
				)
				( attribute "RELATIVE_PROPAGATION_DELAY_SCOPE" "G"
					( Parent
						( matchGroupRef "@crescent_city_bb_fab1_lib.crescent_city_bb_fab1(sch_1):\MG_DQ_NEAR_DIMM_NG_M_D_BYTE3\" )
					)
					( Status sCSetFlattened )
					( Origin gBackEnd )
				)
				( attribute "RELATIVE_PROPAGATION_DELAY" "-50.00 MIL,50.00 MIL"
					( Parent
						( matchGroupRef "@crescent_city_bb_fab1_lib.crescent_city_bb_fab1(sch_1):\MG_DQ_NEAR_DIMM_NG_M_D_BYTE3\" )
					)
					( Units "uMatchProp" "ns" 1.000000)
					( Status sCSetFlattened )
					( Origin gBackEnd )
				)
			)
			( pinPair "@baseboard_fab2_lib.baseboard_fab2(sch_1):\PP4614\"
				( pinRef "@baseboard_fab2_lib.baseboard_fab2(sch_1):page26_i172:DDR3_DQ(25)" )
				( pinRef "@baseboard_fab2_lib.baseboard_fab2(sch_1):page49_i111:DQ(24)" )
				( attribute "RELATIVE_PROPAGATION_DELAY_SCOPE" "G"
					( Parent
						( matchGroupRef "@baseboard_fab2_lib.baseboard_fab2(sch_1):\MG_DQ-DQS_FAR_DIMM_NG_M_D_BYTE3\" )
					)
					( Status sCSetFlattened )
					( Origin gBackEnd )
				)
				( attribute "RELATIVE_PROPAGATION_DELAY" "0.00 MIL,195.00 MIL"
					( Parent
						( matchGroupRef "@baseboard_fab2_lib.baseboard_fab2(sch_1):\MG_DQ-DQS_FAR_DIMM_NG_M_D_BYTE3\" )
					)
					( Units "uMatchProp" "ns" 1.000000)
					( Status sCSetFlattened )
					( Origin gBackEnd )
				)
				( attribute "RELATIVE_PROPAGATION_DELAY_SCOPE" "G"
					( Parent
						( matchGroupRef "@crescent_city_bb_fab1_lib.crescent_city_bb_fab1(sch_1):\MG_DQ_FAR_DIMM_NG_M_D_BYTE3\" )
					)
					( Status sCSetFlattened )
					( Origin gBackEnd )
				)
				( attribute "RELATIVE_PROPAGATION_DELAY" "-50.00 MIL,50.00 MIL"
					( Parent
						( matchGroupRef "@crescent_city_bb_fab1_lib.crescent_city_bb_fab1(sch_1):\MG_DQ_FAR_DIMM_NG_M_D_BYTE3\" )
					)
					( Units "uMatchProp" "ns" 1.000000)
					( Status sCSetFlattened )
					( Origin gBackEnd )
				)
			)
			( pinPair "@baseboard_fab2_lib.baseboard_fab2(sch_1):\PP4616\"
				( pinRef "@baseboard_fab2_lib.baseboard_fab2(sch_1):page26_i172:DDR3_DQ(25)" )
				( pinRef "@baseboard_fab2_lib.baseboard_fab2(sch_1):page50_i158:DQ(25)" )
				( attribute "RELATIVE_PROPAGATION_DELAY_SCOPE" "G"
					( Parent
						( matchGroupRef "@baseboard_fab2_lib.baseboard_fab2(sch_1):\MG_DQ-DQS_NEAR_DIMM_NG_M_D_BYTE3\" )
					)
					( Status sCSetFlattened )
					( Origin gBackEnd )
				)
				( attribute "RELATIVE_PROPAGATION_DELAY" "0.00 MIL,195.00 MIL"
					( Parent
						( matchGroupRef "@baseboard_fab2_lib.baseboard_fab2(sch_1):\MG_DQ-DQS_NEAR_DIMM_NG_M_D_BYTE3\" )
					)
					( Units "uMatchProp" "ns" 1.000000)
					( Status sCSetFlattened )
					( Origin gBackEnd )
				)
				( attribute "RELATIVE_PROPAGATION_DELAY_SCOPE" "G"
					( Parent
						( matchGroupRef "@crescent_city_bb_fab1_lib.crescent_city_bb_fab1(sch_1):\MG_DQ_NEAR_DIMM_NG_M_D_BYTE3\" )
					)
					( Status sCSetFlattened )
					( Origin gBackEnd )
				)
				( attribute "RELATIVE_PROPAGATION_DELAY" "-50.00 MIL,50.00 MIL"
					( Parent
						( matchGroupRef "@crescent_city_bb_fab1_lib.crescent_city_bb_fab1(sch_1):\MG_DQ_NEAR_DIMM_NG_M_D_BYTE3\" )
					)
					( Units "uMatchProp" "ns" 1.000000)
					( Status sCSetFlattened )
					( Origin gBackEnd )
				)
			)
			( pinPair "@baseboard_fab2_lib.baseboard_fab2(sch_1):\PP4617\"
				( pinRef "@baseboard_fab2_lib.baseboard_fab2(sch_1):page26_i172:DDR3_DQ(26)" )
				( pinRef "@baseboard_fab2_lib.baseboard_fab2(sch_1):page49_i111:DQ(27)" )
				( attribute "RELATIVE_PROPAGATION_DELAY_SCOPE" "G"
					( Parent
						( matchGroupRef "@baseboard_fab2_lib.baseboard_fab2(sch_1):\MG_DQ-DQS_FAR_DIMM_NG_M_D_BYTE3\" )
					)
					( Status sCSetFlattened )
					( Origin gBackEnd )
				)
				( attribute "RELATIVE_PROPAGATION_DELAY" "0.00 MIL,195.00 MIL"
					( Parent
						( matchGroupRef "@baseboard_fab2_lib.baseboard_fab2(sch_1):\MG_DQ-DQS_FAR_DIMM_NG_M_D_BYTE3\" )
					)
					( Units "uMatchProp" "ns" 1.000000)
					( Status sCSetFlattened )
					( Origin gBackEnd )
				)
				( attribute "RELATIVE_PROPAGATION_DELAY_SCOPE" "G"
					( Parent
						( matchGroupRef "@crescent_city_bb_fab1_lib.crescent_city_bb_fab1(sch_1):\MG_DQ_FAR_DIMM_NG_M_D_BYTE3\" )
					)
					( Status sCSetFlattened )
					( Origin gBackEnd )
				)
				( attribute "RELATIVE_PROPAGATION_DELAY" "-50.00 MIL,50.00 MIL"
					( Parent
						( matchGroupRef "@crescent_city_bb_fab1_lib.crescent_city_bb_fab1(sch_1):\MG_DQ_FAR_DIMM_NG_M_D_BYTE3\" )
					)
					( Units "uMatchProp" "ns" 1.000000)
					( Status sCSetFlattened )
					( Origin gBackEnd )
				)
			)
			( pinPair "@baseboard_fab2_lib.baseboard_fab2(sch_1):\PP4619\"
				( pinRef "@baseboard_fab2_lib.baseboard_fab2(sch_1):page50_i158:DQ(26)" )
				( pinRef "@baseboard_fab2_lib.baseboard_fab2(sch_1):page26_i172:DDR3_DQ(26)" )
				( attribute "RELATIVE_PROPAGATION_DELAY_SCOPE" "G"
					( Parent
						( matchGroupRef "@baseboard_fab2_lib.baseboard_fab2(sch_1):\MG_DQ-DQS_NEAR_DIMM_NG_M_D_BYTE3\" )
					)
					( Status sCSetFlattened )
					( Origin gBackEnd )
				)
				( attribute "RELATIVE_PROPAGATION_DELAY" "0.00 MIL,195.00 MIL"
					( Parent
						( matchGroupRef "@baseboard_fab2_lib.baseboard_fab2(sch_1):\MG_DQ-DQS_NEAR_DIMM_NG_M_D_BYTE3\" )
					)
					( Units "uMatchProp" "ns" 1.000000)
					( Status sCSetFlattened )
					( Origin gBackEnd )
				)
				( attribute "RELATIVE_PROPAGATION_DELAY_SCOPE" "G"
					( Parent
						( matchGroupRef "@crescent_city_bb_fab1_lib.crescent_city_bb_fab1(sch_1):\MG_DQ_NEAR_DIMM_NG_M_D_BYTE3\" )
					)
					( Status sCSetFlattened )
					( Origin gBackEnd )
				)
				( attribute "RELATIVE_PROPAGATION_DELAY" "-50.00 MIL,50.00 MIL"
					( Parent
						( matchGroupRef "@crescent_city_bb_fab1_lib.crescent_city_bb_fab1(sch_1):\MG_DQ_NEAR_DIMM_NG_M_D_BYTE3\" )
					)
					( Units "uMatchProp" "ns" 1.000000)
					( Status sCSetFlattened )
					( Origin gBackEnd )
				)
			)
			( pinPair "@baseboard_fab2_lib.baseboard_fab2(sch_1):\PP4620\"
				( pinRef "@baseboard_fab2_lib.baseboard_fab2(sch_1):page26_i172:DDR3_DQ(27)" )
				( pinRef "@baseboard_fab2_lib.baseboard_fab2(sch_1):page49_i111:DQ(26)" )
				( attribute "RELATIVE_PROPAGATION_DELAY_SCOPE" "G"
					( Parent
						( matchGroupRef "@baseboard_fab2_lib.baseboard_fab2(sch_1):\MG_DQ-DQS_FAR_DIMM_NG_M_D_BYTE3\" )
					)
					( Status sCSetFlattened )
					( Origin gBackEnd )
				)
				( attribute "RELATIVE_PROPAGATION_DELAY" "0.00 MIL,195.00 MIL"
					( Parent
						( matchGroupRef "@baseboard_fab2_lib.baseboard_fab2(sch_1):\MG_DQ-DQS_FAR_DIMM_NG_M_D_BYTE3\" )
					)
					( Units "uMatchProp" "ns" 1.000000)
					( Status sCSetFlattened )
					( Origin gBackEnd )
				)
				( attribute "RELATIVE_PROPAGATION_DELAY_SCOPE" "G"
					( Parent
						( matchGroupRef "@crescent_city_bb_fab1_lib.crescent_city_bb_fab1(sch_1):\MG_DQ_FAR_DIMM_NG_M_D_BYTE3\" )
					)
					( Status sCSetFlattened )
					( Origin gBackEnd )
				)
				( attribute "RELATIVE_PROPAGATION_DELAY" "-50.00 MIL,50.00 MIL"
					( Parent
						( matchGroupRef "@crescent_city_bb_fab1_lib.crescent_city_bb_fab1(sch_1):\MG_DQ_FAR_DIMM_NG_M_D_BYTE3\" )
					)
					( Units "uMatchProp" "ns" 1.000000)
					( Status sCSetFlattened )
					( Origin gBackEnd )
				)
			)
			( pinPair "@baseboard_fab2_lib.baseboard_fab2(sch_1):\PP4622\"
				( pinRef "@baseboard_fab2_lib.baseboard_fab2(sch_1):page50_i158:DQ(27)" )
				( pinRef "@baseboard_fab2_lib.baseboard_fab2(sch_1):page26_i172:DDR3_DQ(27)" )
				( attribute "RELATIVE_PROPAGATION_DELAY_SCOPE" "G"
					( Parent
						( matchGroupRef "@baseboard_fab2_lib.baseboard_fab2(sch_1):\MG_DQ-DQS_NEAR_DIMM_NG_M_D_BYTE3\" )
					)
					( Status sCSetFlattened )
					( Origin gBackEnd )
				)
				( attribute "RELATIVE_PROPAGATION_DELAY" "0.00 MIL,195.00 MIL"
					( Parent
						( matchGroupRef "@baseboard_fab2_lib.baseboard_fab2(sch_1):\MG_DQ-DQS_NEAR_DIMM_NG_M_D_BYTE3\" )
					)
					( Units "uMatchProp" "ns" 1.000000)
					( Status sCSetFlattened )
					( Origin gBackEnd )
				)
				( attribute "RELATIVE_PROPAGATION_DELAY_SCOPE" "G"
					( Parent
						( matchGroupRef "@crescent_city_bb_fab1_lib.crescent_city_bb_fab1(sch_1):\MG_DQ_NEAR_DIMM_NG_M_D_BYTE3\" )
					)
					( Origin gBackEnd )
				)
				( attribute "RELATIVE_PROPAGATION_DELAY" "TARGET,TARGET"
					( Parent
						( matchGroupRef "@crescent_city_bb_fab1_lib.crescent_city_bb_fab1(sch_1):\MG_DQ_NEAR_DIMM_NG_M_D_BYTE3\" )
					)
					( Units "uMatchProp" "ns" 1.000000)
					( Origin gBackEnd )
				)
			)
			( pinPair "@baseboard_fab2_lib.baseboard_fab2(sch_1):\PP4623\"
				( pinRef "@baseboard_fab2_lib.baseboard_fab2(sch_1):page26_i172:DDR3_DQ(28)" )
				( pinRef "@baseboard_fab2_lib.baseboard_fab2(sch_1):page49_i111:DQ(29)" )
				( attribute "RELATIVE_PROPAGATION_DELAY_SCOPE" "G"
					( Parent
						( matchGroupRef "@baseboard_fab2_lib.baseboard_fab2(sch_1):\MG_DQ-DQS_FAR_DIMM_NG_M_D_BYTE3\" )
					)
					( Status sCSetFlattened )
					( Origin gBackEnd )
				)
				( attribute "RELATIVE_PROPAGATION_DELAY" "0.00 MIL,195.00 MIL"
					( Parent
						( matchGroupRef "@baseboard_fab2_lib.baseboard_fab2(sch_1):\MG_DQ-DQS_FAR_DIMM_NG_M_D_BYTE3\" )
					)
					( Units "uMatchProp" "ns" 1.000000)
					( Status sCSetFlattened )
					( Origin gBackEnd )
				)
				( attribute "RELATIVE_PROPAGATION_DELAY_SCOPE" "G"
					( Parent
						( matchGroupRef "@crescent_city_bb_fab1_lib.crescent_city_bb_fab1(sch_1):\MG_DQ_FAR_DIMM_NG_M_D_BYTE3\" )
					)
					( Status sCSetFlattened )
					( Origin gBackEnd )
				)
				( attribute "RELATIVE_PROPAGATION_DELAY" "-50.00 MIL,50.00 MIL"
					( Parent
						( matchGroupRef "@crescent_city_bb_fab1_lib.crescent_city_bb_fab1(sch_1):\MG_DQ_FAR_DIMM_NG_M_D_BYTE3\" )
					)
					( Units "uMatchProp" "ns" 1.000000)
					( Status sCSetFlattened )
					( Origin gBackEnd )
				)
			)
			( pinPair "@baseboard_fab2_lib.baseboard_fab2(sch_1):\PP4625\"
				( pinRef "@baseboard_fab2_lib.baseboard_fab2(sch_1):page26_i172:DDR3_DQ(28)" )
				( pinRef "@baseboard_fab2_lib.baseboard_fab2(sch_1):page50_i158:DQ(28)" )
				( attribute "RELATIVE_PROPAGATION_DELAY_SCOPE" "G"
					( Parent
						( matchGroupRef "@baseboard_fab2_lib.baseboard_fab2(sch_1):\MG_DQ-DQS_NEAR_DIMM_NG_M_D_BYTE3\" )
					)
					( Status sCSetFlattened )
					( Origin gBackEnd )
				)
				( attribute "RELATIVE_PROPAGATION_DELAY" "0.00 MIL,195.00 MIL"
					( Parent
						( matchGroupRef "@baseboard_fab2_lib.baseboard_fab2(sch_1):\MG_DQ-DQS_NEAR_DIMM_NG_M_D_BYTE3\" )
					)
					( Units "uMatchProp" "ns" 1.000000)
					( Status sCSetFlattened )
					( Origin gBackEnd )
				)
				( attribute "RELATIVE_PROPAGATION_DELAY_SCOPE" "G"
					( Parent
						( matchGroupRef "@crescent_city_bb_fab1_lib.crescent_city_bb_fab1(sch_1):\MG_DQ_NEAR_DIMM_NG_M_D_BYTE3\" )
					)
					( Status sCSetFlattened )
					( Origin gBackEnd )
				)
				( attribute "RELATIVE_PROPAGATION_DELAY" "-50.00 MIL,50.00 MIL"
					( Parent
						( matchGroupRef "@crescent_city_bb_fab1_lib.crescent_city_bb_fab1(sch_1):\MG_DQ_NEAR_DIMM_NG_M_D_BYTE3\" )
					)
					( Units "uMatchProp" "ns" 1.000000)
					( Status sCSetFlattened )
					( Origin gBackEnd )
				)
			)
			( pinPair "@baseboard_fab2_lib.baseboard_fab2(sch_1):\PP4626\"
				( pinRef "@baseboard_fab2_lib.baseboard_fab2(sch_1):page26_i172:DDR3_DQ(29)" )
				( pinRef "@baseboard_fab2_lib.baseboard_fab2(sch_1):page49_i111:DQ(28)" )
				( attribute "RELATIVE_PROPAGATION_DELAY_SCOPE" "G"
					( Parent
						( matchGroupRef "@baseboard_fab2_lib.baseboard_fab2(sch_1):\MG_DQ-DQS_FAR_DIMM_NG_M_D_BYTE3\" )
					)
					( Status sCSetFlattened )
					( Origin gBackEnd )
				)
				( attribute "RELATIVE_PROPAGATION_DELAY" "0.00 MIL,195.00 MIL"
					( Parent
						( matchGroupRef "@baseboard_fab2_lib.baseboard_fab2(sch_1):\MG_DQ-DQS_FAR_DIMM_NG_M_D_BYTE3\" )
					)
					( Units "uMatchProp" "ns" 1.000000)
					( Status sCSetFlattened )
					( Origin gBackEnd )
				)
				( attribute "RELATIVE_PROPAGATION_DELAY_SCOPE" "G"
					( Parent
						( matchGroupRef "@crescent_city_bb_fab1_lib.crescent_city_bb_fab1(sch_1):\MG_DQ_FAR_DIMM_NG_M_D_BYTE3\" )
					)
					( Status sCSetFlattened )
					( Origin gBackEnd )
				)
				( attribute "RELATIVE_PROPAGATION_DELAY" "-50.00 MIL,50.00 MIL"
					( Parent
						( matchGroupRef "@crescent_city_bb_fab1_lib.crescent_city_bb_fab1(sch_1):\MG_DQ_FAR_DIMM_NG_M_D_BYTE3\" )
					)
					( Units "uMatchProp" "ns" 1.000000)
					( Status sCSetFlattened )
					( Origin gBackEnd )
				)
			)
			( pinPair "@baseboard_fab2_lib.baseboard_fab2(sch_1):\PP4628\"
				( pinRef "@baseboard_fab2_lib.baseboard_fab2(sch_1):page26_i172:DDR3_DQ(29)" )
				( pinRef "@baseboard_fab2_lib.baseboard_fab2(sch_1):page50_i158:DQ(29)" )
				( attribute "RELATIVE_PROPAGATION_DELAY_SCOPE" "G"
					( Parent
						( matchGroupRef "@baseboard_fab2_lib.baseboard_fab2(sch_1):\MG_DQ-DQS_NEAR_DIMM_NG_M_D_BYTE3\" )
					)
					( Status sCSetFlattened )
					( Origin gBackEnd )
				)
				( attribute "RELATIVE_PROPAGATION_DELAY" "0.00 MIL,195.00 MIL"
					( Parent
						( matchGroupRef "@baseboard_fab2_lib.baseboard_fab2(sch_1):\MG_DQ-DQS_NEAR_DIMM_NG_M_D_BYTE3\" )
					)
					( Units "uMatchProp" "ns" 1.000000)
					( Status sCSetFlattened )
					( Origin gBackEnd )
				)
				( attribute "RELATIVE_PROPAGATION_DELAY_SCOPE" "G"
					( Parent
						( matchGroupRef "@crescent_city_bb_fab1_lib.crescent_city_bb_fab1(sch_1):\MG_DQ_NEAR_DIMM_NG_M_D_BYTE3\" )
					)
					( Status sCSetFlattened )
					( Origin gBackEnd )
				)
				( attribute "RELATIVE_PROPAGATION_DELAY" "-50.00 MIL,50.00 MIL"
					( Parent
						( matchGroupRef "@crescent_city_bb_fab1_lib.crescent_city_bb_fab1(sch_1):\MG_DQ_NEAR_DIMM_NG_M_D_BYTE3\" )
					)
					( Units "uMatchProp" "ns" 1.000000)
					( Status sCSetFlattened )
					( Origin gBackEnd )
				)
			)
			( pinPair "@baseboard_fab2_lib.baseboard_fab2(sch_1):\PP4629\"
				( pinRef "@baseboard_fab2_lib.baseboard_fab2(sch_1):page26_i172:DDR3_DQ(30)" )
				( pinRef "@baseboard_fab2_lib.baseboard_fab2(sch_1):page49_i111:DQ(31)" )
				( attribute "RELATIVE_PROPAGATION_DELAY_SCOPE" "G"
					( Parent
						( matchGroupRef "@baseboard_fab2_lib.baseboard_fab2(sch_1):\MG_DQ-DQS_FAR_DIMM_NG_M_D_BYTE3\" )
					)
					( Status sCSetFlattened )
					( Origin gBackEnd )
				)
				( attribute "RELATIVE_PROPAGATION_DELAY" "0.00 MIL,195.00 MIL"
					( Parent
						( matchGroupRef "@baseboard_fab2_lib.baseboard_fab2(sch_1):\MG_DQ-DQS_FAR_DIMM_NG_M_D_BYTE3\" )
					)
					( Units "uMatchProp" "ns" 1.000000)
					( Status sCSetFlattened )
					( Origin gBackEnd )
				)
				( attribute "RELATIVE_PROPAGATION_DELAY_SCOPE" "G"
					( Parent
						( matchGroupRef "@crescent_city_bb_fab1_lib.crescent_city_bb_fab1(sch_1):\MG_DQ_FAR_DIMM_NG_M_D_BYTE3\" )
					)
					( Status sCSetFlattened )
					( Origin gBackEnd )
				)
				( attribute "RELATIVE_PROPAGATION_DELAY" "-50.00 MIL,50.00 MIL"
					( Parent
						( matchGroupRef "@crescent_city_bb_fab1_lib.crescent_city_bb_fab1(sch_1):\MG_DQ_FAR_DIMM_NG_M_D_BYTE3\" )
					)
					( Units "uMatchProp" "ns" 1.000000)
					( Status sCSetFlattened )
					( Origin gBackEnd )
				)
			)
			( pinPair "@baseboard_fab2_lib.baseboard_fab2(sch_1):\PP4631\"
				( pinRef "@baseboard_fab2_lib.baseboard_fab2(sch_1):page50_i158:DQ(30)" )
				( pinRef "@baseboard_fab2_lib.baseboard_fab2(sch_1):page26_i172:DDR3_DQ(30)" )
				( attribute "RELATIVE_PROPAGATION_DELAY_SCOPE" "G"
					( Parent
						( matchGroupRef "@baseboard_fab2_lib.baseboard_fab2(sch_1):\MG_DQ-DQS_NEAR_DIMM_NG_M_D_BYTE3\" )
					)
					( Status sCSetFlattened )
					( Origin gBackEnd )
				)
				( attribute "RELATIVE_PROPAGATION_DELAY" "0.00 MIL,195.00 MIL"
					( Parent
						( matchGroupRef "@baseboard_fab2_lib.baseboard_fab2(sch_1):\MG_DQ-DQS_NEAR_DIMM_NG_M_D_BYTE3\" )
					)
					( Units "uMatchProp" "ns" 1.000000)
					( Status sCSetFlattened )
					( Origin gBackEnd )
				)
				( attribute "RELATIVE_PROPAGATION_DELAY_SCOPE" "G"
					( Parent
						( matchGroupRef "@crescent_city_bb_fab1_lib.crescent_city_bb_fab1(sch_1):\MG_DQ_NEAR_DIMM_NG_M_D_BYTE3\" )
					)
					( Status sCSetFlattened )
					( Origin gBackEnd )
				)
				( attribute "RELATIVE_PROPAGATION_DELAY" "-50.00 MIL,50.00 MIL"
					( Parent
						( matchGroupRef "@crescent_city_bb_fab1_lib.crescent_city_bb_fab1(sch_1):\MG_DQ_NEAR_DIMM_NG_M_D_BYTE3\" )
					)
					( Units "uMatchProp" "ns" 1.000000)
					( Status sCSetFlattened )
					( Origin gBackEnd )
				)
			)
			( pinPair "@baseboard_fab2_lib.baseboard_fab2(sch_1):\PP4632\"
				( pinRef "@baseboard_fab2_lib.baseboard_fab2(sch_1):page26_i172:DDR3_DQ(31)" )
				( pinRef "@baseboard_fab2_lib.baseboard_fab2(sch_1):page49_i111:DQ(30)" )
				( attribute "RELATIVE_PROPAGATION_DELAY_SCOPE" "G"
					( Parent
						( matchGroupRef "@baseboard_fab2_lib.baseboard_fab2(sch_1):\MG_DQ-DQS_FAR_DIMM_NG_M_D_BYTE3\" )
					)
					( Status sCSetFlattened )
					( Origin gBackEnd )
				)
				( attribute "RELATIVE_PROPAGATION_DELAY" "0.00 MIL,195.00 MIL"
					( Parent
						( matchGroupRef "@baseboard_fab2_lib.baseboard_fab2(sch_1):\MG_DQ-DQS_FAR_DIMM_NG_M_D_BYTE3\" )
					)
					( Units "uMatchProp" "ns" 1.000000)
					( Status sCSetFlattened )
					( Origin gBackEnd )
				)
				( attribute "RELATIVE_PROPAGATION_DELAY_SCOPE" "G"
					( Parent
						( matchGroupRef "@crescent_city_bb_fab1_lib.crescent_city_bb_fab1(sch_1):\MG_DQ_FAR_DIMM_NG_M_D_BYTE3\" )
					)
					( Status sCSetFlattened )
					( Origin gBackEnd )
				)
				( attribute "RELATIVE_PROPAGATION_DELAY" "-50.00 MIL,50.00 MIL"
					( Parent
						( matchGroupRef "@crescent_city_bb_fab1_lib.crescent_city_bb_fab1(sch_1):\MG_DQ_FAR_DIMM_NG_M_D_BYTE3\" )
					)
					( Units "uMatchProp" "ns" 1.000000)
					( Status sCSetFlattened )
					( Origin gBackEnd )
				)
			)
			( pinPair "@baseboard_fab2_lib.baseboard_fab2(sch_1):\PP4634\"
				( pinRef "@baseboard_fab2_lib.baseboard_fab2(sch_1):page50_i158:DQ(31)" )
				( pinRef "@baseboard_fab2_lib.baseboard_fab2(sch_1):page26_i172:DDR3_DQ(31)" )
				( attribute "RELATIVE_PROPAGATION_DELAY_SCOPE" "G"
					( Parent
						( matchGroupRef "@baseboard_fab2_lib.baseboard_fab2(sch_1):\MG_DQ-DQS_NEAR_DIMM_NG_M_D_BYTE3\" )
					)
					( Status sCSetFlattened )
					( Origin gBackEnd )
				)
				( attribute "RELATIVE_PROPAGATION_DELAY" "0.00 MIL,195.00 MIL"
					( Parent
						( matchGroupRef "@baseboard_fab2_lib.baseboard_fab2(sch_1):\MG_DQ-DQS_NEAR_DIMM_NG_M_D_BYTE3\" )
					)
					( Units "uMatchProp" "ns" 1.000000)
					( Status sCSetFlattened )
					( Origin gBackEnd )
				)
				( attribute "RELATIVE_PROPAGATION_DELAY_SCOPE" "G"
					( Parent
						( matchGroupRef "@crescent_city_bb_fab1_lib.crescent_city_bb_fab1(sch_1):\MG_DQ_NEAR_DIMM_NG_M_D_BYTE3\" )
					)
					( Status sCSetFlattened )
					( Origin gBackEnd )
				)
				( attribute "RELATIVE_PROPAGATION_DELAY" "-50.00 MIL,50.00 MIL"
					( Parent
						( matchGroupRef "@crescent_city_bb_fab1_lib.crescent_city_bb_fab1(sch_1):\MG_DQ_NEAR_DIMM_NG_M_D_BYTE3\" )
					)
					( Units "uMatchProp" "ns" 1.000000)
					( Status sCSetFlattened )
					( Origin gBackEnd )
				)
			)
			( pinPair "@baseboard_fab2_lib.baseboard_fab2(sch_1):\PP4587\"
				( pinRef "@baseboard_fab2_lib.baseboard_fab2(sch_1):page26_i172:DDR3_DQ(32)" )
				( pinRef "@baseboard_fab2_lib.baseboard_fab2(sch_1):page49_i111:DQ(33)" )
				( attribute "RELATIVE_PROPAGATION_DELAY_SCOPE" "G"
					( Parent
						( matchGroupRef "@baseboard_fab2_lib.baseboard_fab2(sch_1):\MG_DQ-DQS_FAR_DIMM_NG_M_D_BYTE4\" )
					)
					( Status sCSetFlattened )
					( Origin gBackEnd )
				)
				( attribute "RELATIVE_PROPAGATION_DELAY" "0.00 MIL,195.00 MIL"
					( Parent
						( matchGroupRef "@baseboard_fab2_lib.baseboard_fab2(sch_1):\MG_DQ-DQS_FAR_DIMM_NG_M_D_BYTE4\" )
					)
					( Units "uMatchProp" "ns" 1.000000)
					( Status sCSetFlattened )
					( Origin gBackEnd )
				)
				( attribute "RELATIVE_PROPAGATION_DELAY_SCOPE" "G"
					( Parent
						( matchGroupRef "@baseboard_fab2_lib.baseboard_fab2(sch_1):\MG_DQ_FAR_DIMM_NG_M_D_BYTE4\" )
					)
					( Status sCSetFlattened )
					( Origin gBackEnd )
				)
				( attribute "RELATIVE_PROPAGATION_DELAY" "-50.00 MIL,50.00 MIL"
					( Parent
						( matchGroupRef "@baseboard_fab2_lib.baseboard_fab2(sch_1):\MG_DQ_FAR_DIMM_NG_M_D_BYTE4\" )
					)
					( Units "uMatchProp" "ns" 1.000000)
					( Status sCSetFlattened )
					( Origin gBackEnd )
				)
			)
			( pinPair "@baseboard_fab2_lib.baseboard_fab2(sch_1):\PP4589\"
				( pinRef "@baseboard_fab2_lib.baseboard_fab2(sch_1):page50_i158:DQ(32)" )
				( pinRef "@baseboard_fab2_lib.baseboard_fab2(sch_1):page26_i172:DDR3_DQ(32)" )
				( attribute "RELATIVE_PROPAGATION_DELAY_SCOPE" "G"
					( Parent
						( matchGroupRef "@baseboard_fab2_lib.baseboard_fab2(sch_1):\MG_DQ-DQS_NEAR_DIMM_NG_M_D_BYTE4\" )
					)
					( Status sCSetFlattened )
					( Origin gBackEnd )
				)
				( attribute "RELATIVE_PROPAGATION_DELAY" "0.00 MIL,195.00 MIL"
					( Parent
						( matchGroupRef "@baseboard_fab2_lib.baseboard_fab2(sch_1):\MG_DQ-DQS_NEAR_DIMM_NG_M_D_BYTE4\" )
					)
					( Units "uMatchProp" "ns" 1.000000)
					( Status sCSetFlattened )
					( Origin gBackEnd )
				)
				( attribute "RELATIVE_PROPAGATION_DELAY_SCOPE" "G"
					( Parent
						( matchGroupRef "@crescent_city_bb_fab1_lib.crescent_city_bb_fab1(sch_1):\MG_DQ_NEAR_DIMM_NG_M_D_BYTE4\" )
					)
					( Status sCSetFlattened )
					( Origin gBackEnd )
				)
				( attribute "RELATIVE_PROPAGATION_DELAY" "-50.00 MIL,50.00 MIL"
					( Parent
						( matchGroupRef "@crescent_city_bb_fab1_lib.crescent_city_bb_fab1(sch_1):\MG_DQ_NEAR_DIMM_NG_M_D_BYTE4\" )
					)
					( Units "uMatchProp" "ns" 1.000000)
					( Status sCSetFlattened )
					( Origin gBackEnd )
				)
			)
			( pinPair "@baseboard_fab2_lib.baseboard_fab2(sch_1):\PP4590\"
				( pinRef "@baseboard_fab2_lib.baseboard_fab2(sch_1):page26_i172:DDR3_DQ(33)" )
				( pinRef "@baseboard_fab2_lib.baseboard_fab2(sch_1):page49_i111:DQ(32)" )
				( attribute "RELATIVE_PROPAGATION_DELAY_SCOPE" "G"
					( Parent
						( matchGroupRef "@baseboard_fab2_lib.baseboard_fab2(sch_1):\MG_DQ-DQS_FAR_DIMM_NG_M_D_BYTE4\" )
					)
					( Status sCSetFlattened )
					( Origin gBackEnd )
				)
				( attribute "RELATIVE_PROPAGATION_DELAY" "0.00 MIL,195.00 MIL"
					( Parent
						( matchGroupRef "@baseboard_fab2_lib.baseboard_fab2(sch_1):\MG_DQ-DQS_FAR_DIMM_NG_M_D_BYTE4\" )
					)
					( Units "uMatchProp" "ns" 1.000000)
					( Status sCSetFlattened )
					( Origin gBackEnd )
				)
				( attribute "RELATIVE_PROPAGATION_DELAY_SCOPE" "G"
					( Parent
						( matchGroupRef "@baseboard_fab2_lib.baseboard_fab2(sch_1):\MG_DQ_FAR_DIMM_NG_M_D_BYTE4\" )
					)
					( Status sCSetFlattened )
					( Origin gBackEnd )
				)
				( attribute "RELATIVE_PROPAGATION_DELAY" "-50.00 MIL,50.00 MIL"
					( Parent
						( matchGroupRef "@baseboard_fab2_lib.baseboard_fab2(sch_1):\MG_DQ_FAR_DIMM_NG_M_D_BYTE4\" )
					)
					( Units "uMatchProp" "ns" 1.000000)
					( Status sCSetFlattened )
					( Origin gBackEnd )
				)
			)
			( pinPair "@baseboard_fab2_lib.baseboard_fab2(sch_1):\PP4592\"
				( pinRef "@baseboard_fab2_lib.baseboard_fab2(sch_1):page50_i158:DQ(33)" )
				( pinRef "@baseboard_fab2_lib.baseboard_fab2(sch_1):page26_i172:DDR3_DQ(33)" )
				( attribute "RELATIVE_PROPAGATION_DELAY_SCOPE" "G"
					( Parent
						( matchGroupRef "@baseboard_fab2_lib.baseboard_fab2(sch_1):\MG_DQ-DQS_NEAR_DIMM_NG_M_D_BYTE4\" )
					)
					( Status sCSetFlattened )
					( Origin gBackEnd )
				)
				( attribute "RELATIVE_PROPAGATION_DELAY" "0.00 MIL,195.00 MIL"
					( Parent
						( matchGroupRef "@baseboard_fab2_lib.baseboard_fab2(sch_1):\MG_DQ-DQS_NEAR_DIMM_NG_M_D_BYTE4\" )
					)
					( Units "uMatchProp" "ns" 1.000000)
					( Status sCSetFlattened )
					( Origin gBackEnd )
				)
				( attribute "RELATIVE_PROPAGATION_DELAY_SCOPE" "G"
					( Parent
						( matchGroupRef "@crescent_city_bb_fab1_lib.crescent_city_bb_fab1(sch_1):\MG_DQ_NEAR_DIMM_NG_M_D_BYTE4\" )
					)
					( Status sCSetFlattened )
					( Origin gBackEnd )
				)
				( attribute "RELATIVE_PROPAGATION_DELAY" "-50.00 MIL,50.00 MIL"
					( Parent
						( matchGroupRef "@crescent_city_bb_fab1_lib.crescent_city_bb_fab1(sch_1):\MG_DQ_NEAR_DIMM_NG_M_D_BYTE4\" )
					)
					( Units "uMatchProp" "ns" 1.000000)
					( Status sCSetFlattened )
					( Origin gBackEnd )
				)
			)
			( pinPair "@baseboard_fab2_lib.baseboard_fab2(sch_1):\PP4593\"
				( pinRef "@baseboard_fab2_lib.baseboard_fab2(sch_1):page26_i172:DDR3_DQ(34)" )
				( pinRef "@baseboard_fab2_lib.baseboard_fab2(sch_1):page49_i111:DQ(35)" )
				( attribute "RELATIVE_PROPAGATION_DELAY_SCOPE" "G"
					( Parent
						( matchGroupRef "@baseboard_fab2_lib.baseboard_fab2(sch_1):\MG_DQ-DQS_FAR_DIMM_NG_M_D_BYTE4\" )
					)
					( Status sCSetFlattened )
					( Origin gBackEnd )
				)
				( attribute "RELATIVE_PROPAGATION_DELAY" "0.00 MIL,195.00 MIL"
					( Parent
						( matchGroupRef "@baseboard_fab2_lib.baseboard_fab2(sch_1):\MG_DQ-DQS_FAR_DIMM_NG_M_D_BYTE4\" )
					)
					( Units "uMatchProp" "ns" 1.000000)
					( Status sCSetFlattened )
					( Origin gBackEnd )
				)
				( attribute "RELATIVE_PROPAGATION_DELAY_SCOPE" "G"
					( Parent
						( matchGroupRef "@baseboard_fab2_lib.baseboard_fab2(sch_1):\MG_DQ_FAR_DIMM_NG_M_D_BYTE4\" )
					)
					( Status sCSetFlattened )
					( Origin gBackEnd )
				)
				( attribute "RELATIVE_PROPAGATION_DELAY" "-50.00 MIL,50.00 MIL"
					( Parent
						( matchGroupRef "@baseboard_fab2_lib.baseboard_fab2(sch_1):\MG_DQ_FAR_DIMM_NG_M_D_BYTE4\" )
					)
					( Units "uMatchProp" "ns" 1.000000)
					( Status sCSetFlattened )
					( Origin gBackEnd )
				)
			)
			( pinPair "@baseboard_fab2_lib.baseboard_fab2(sch_1):\PP4595\"
				( pinRef "@baseboard_fab2_lib.baseboard_fab2(sch_1):page26_i172:DDR3_DQ(34)" )
				( pinRef "@baseboard_fab2_lib.baseboard_fab2(sch_1):page50_i158:DQ(34)" )
				( attribute "RELATIVE_PROPAGATION_DELAY_SCOPE" "G"
					( Parent
						( matchGroupRef "@baseboard_fab2_lib.baseboard_fab2(sch_1):\MG_DQ-DQS_NEAR_DIMM_NG_M_D_BYTE4\" )
					)
					( Status sCSetFlattened )
					( Origin gBackEnd )
				)
				( attribute "RELATIVE_PROPAGATION_DELAY" "0.00 MIL,195.00 MIL"
					( Parent
						( matchGroupRef "@baseboard_fab2_lib.baseboard_fab2(sch_1):\MG_DQ-DQS_NEAR_DIMM_NG_M_D_BYTE4\" )
					)
					( Units "uMatchProp" "ns" 1.000000)
					( Status sCSetFlattened )
					( Origin gBackEnd )
				)
				( attribute "RELATIVE_PROPAGATION_DELAY_SCOPE" "G"
					( Parent
						( matchGroupRef "@crescent_city_bb_fab1_lib.crescent_city_bb_fab1(sch_1):\MG_DQ_NEAR_DIMM_NG_M_D_BYTE4\" )
					)
					( Status sCSetFlattened )
					( Origin gBackEnd )
				)
				( attribute "RELATIVE_PROPAGATION_DELAY" "-50.00 MIL,50.00 MIL"
					( Parent
						( matchGroupRef "@crescent_city_bb_fab1_lib.crescent_city_bb_fab1(sch_1):\MG_DQ_NEAR_DIMM_NG_M_D_BYTE4\" )
					)
					( Units "uMatchProp" "ns" 1.000000)
					( Status sCSetFlattened )
					( Origin gBackEnd )
				)
			)
			( pinPair "@baseboard_fab2_lib.baseboard_fab2(sch_1):\PP4596\"
				( pinRef "@baseboard_fab2_lib.baseboard_fab2(sch_1):page26_i172:DDR3_DQ(35)" )
				( pinRef "@baseboard_fab2_lib.baseboard_fab2(sch_1):page49_i111:DQ(34)" )
				( attribute "RELATIVE_PROPAGATION_DELAY_SCOPE" "G"
					( Parent
						( matchGroupRef "@baseboard_fab2_lib.baseboard_fab2(sch_1):\MG_DQ-DQS_FAR_DIMM_NG_M_D_BYTE4\" )
					)
					( Status sCSetFlattened )
					( Origin gBackEnd )
				)
				( attribute "RELATIVE_PROPAGATION_DELAY" "0.00 MIL,195.00 MIL"
					( Parent
						( matchGroupRef "@baseboard_fab2_lib.baseboard_fab2(sch_1):\MG_DQ-DQS_FAR_DIMM_NG_M_D_BYTE4\" )
					)
					( Units "uMatchProp" "ns" 1.000000)
					( Status sCSetFlattened )
					( Origin gBackEnd )
				)
				( attribute "RELATIVE_PROPAGATION_DELAY_SCOPE" "G"
					( Parent
						( matchGroupRef "@baseboard_fab2_lib.baseboard_fab2(sch_1):\MG_DQ_FAR_DIMM_NG_M_D_BYTE4\" )
					)
					( Status sCSetFlattened )
					( Origin gBackEnd )
				)
				( attribute "RELATIVE_PROPAGATION_DELAY" "-50.00 MIL,50.00 MIL"
					( Parent
						( matchGroupRef "@baseboard_fab2_lib.baseboard_fab2(sch_1):\MG_DQ_FAR_DIMM_NG_M_D_BYTE4\" )
					)
					( Units "uMatchProp" "ns" 1.000000)
					( Status sCSetFlattened )
					( Origin gBackEnd )
				)
			)
			( pinPair "@baseboard_fab2_lib.baseboard_fab2(sch_1):\PP4598\"
				( pinRef "@baseboard_fab2_lib.baseboard_fab2(sch_1):page26_i172:DDR3_DQ(35)" )
				( pinRef "@baseboard_fab2_lib.baseboard_fab2(sch_1):page50_i158:DQ(35)" )
				( attribute "RELATIVE_PROPAGATION_DELAY_SCOPE" "G"
					( Parent
						( matchGroupRef "@baseboard_fab2_lib.baseboard_fab2(sch_1):\MG_DQ-DQS_NEAR_DIMM_NG_M_D_BYTE4\" )
					)
					( Status sCSetFlattened )
					( Origin gBackEnd )
				)
				( attribute "RELATIVE_PROPAGATION_DELAY" "0.00 MIL,195.00 MIL"
					( Parent
						( matchGroupRef "@baseboard_fab2_lib.baseboard_fab2(sch_1):\MG_DQ-DQS_NEAR_DIMM_NG_M_D_BYTE4\" )
					)
					( Units "uMatchProp" "ns" 1.000000)
					( Status sCSetFlattened )
					( Origin gBackEnd )
				)
				( attribute "RELATIVE_PROPAGATION_DELAY_SCOPE" "G"
					( Parent
						( matchGroupRef "@crescent_city_bb_fab1_lib.crescent_city_bb_fab1(sch_1):\MG_DQ_NEAR_DIMM_NG_M_D_BYTE4\" )
					)
					( Origin gBackEnd )
				)
				( attribute "RELATIVE_PROPAGATION_DELAY" "TARGET,TARGET"
					( Parent
						( matchGroupRef "@crescent_city_bb_fab1_lib.crescent_city_bb_fab1(sch_1):\MG_DQ_NEAR_DIMM_NG_M_D_BYTE4\" )
					)
					( Units "uMatchProp" "ns" 1.000000)
					( Origin gBackEnd )
				)
			)
			( pinPair "@baseboard_fab2_lib.baseboard_fab2(sch_1):\PP4599\"
				( pinRef "@baseboard_fab2_lib.baseboard_fab2(sch_1):page26_i172:DDR3_DQ(36)" )
				( pinRef "@baseboard_fab2_lib.baseboard_fab2(sch_1):page49_i111:DQ(37)" )
				( attribute "RELATIVE_PROPAGATION_DELAY_SCOPE" "G"
					( Parent
						( matchGroupRef "@baseboard_fab2_lib.baseboard_fab2(sch_1):\MG_DQ-DQS_FAR_DIMM_NG_M_D_BYTE4\" )
					)
					( Status sCSetFlattened )
					( Origin gBackEnd )
				)
				( attribute "RELATIVE_PROPAGATION_DELAY" "0.00 MIL,195.00 MIL"
					( Parent
						( matchGroupRef "@baseboard_fab2_lib.baseboard_fab2(sch_1):\MG_DQ-DQS_FAR_DIMM_NG_M_D_BYTE4\" )
					)
					( Units "uMatchProp" "ns" 1.000000)
					( Status sCSetFlattened )
					( Origin gBackEnd )
				)
				( attribute "RELATIVE_PROPAGATION_DELAY_SCOPE" "G"
					( Parent
						( matchGroupRef "@baseboard_fab2_lib.baseboard_fab2(sch_1):\MG_DQ_FAR_DIMM_NG_M_D_BYTE4\" )
					)
					( Status sCSetFlattened )
					( Origin gBackEnd )
				)
				( attribute "RELATIVE_PROPAGATION_DELAY" "-50.00 MIL,50.00 MIL"
					( Parent
						( matchGroupRef "@baseboard_fab2_lib.baseboard_fab2(sch_1):\MG_DQ_FAR_DIMM_NG_M_D_BYTE4\" )
					)
					( Units "uMatchProp" "ns" 1.000000)
					( Status sCSetFlattened )
					( Origin gBackEnd )
				)
			)
			( pinPair "@baseboard_fab2_lib.baseboard_fab2(sch_1):\PP4601\"
				( pinRef "@baseboard_fab2_lib.baseboard_fab2(sch_1):page50_i158:DQ(36)" )
				( pinRef "@baseboard_fab2_lib.baseboard_fab2(sch_1):page26_i172:DDR3_DQ(36)" )
				( attribute "RELATIVE_PROPAGATION_DELAY_SCOPE" "G"
					( Parent
						( matchGroupRef "@baseboard_fab2_lib.baseboard_fab2(sch_1):\MG_DQ-DQS_NEAR_DIMM_NG_M_D_BYTE4\" )
					)
					( Status sCSetFlattened )
					( Origin gBackEnd )
				)
				( attribute "RELATIVE_PROPAGATION_DELAY" "0.00 MIL,195.00 MIL"
					( Parent
						( matchGroupRef "@baseboard_fab2_lib.baseboard_fab2(sch_1):\MG_DQ-DQS_NEAR_DIMM_NG_M_D_BYTE4\" )
					)
					( Units "uMatchProp" "ns" 1.000000)
					( Status sCSetFlattened )
					( Origin gBackEnd )
				)
				( attribute "RELATIVE_PROPAGATION_DELAY_SCOPE" "G"
					( Parent
						( matchGroupRef "@crescent_city_bb_fab1_lib.crescent_city_bb_fab1(sch_1):\MG_DQ_NEAR_DIMM_NG_M_D_BYTE4\" )
					)
					( Status sCSetFlattened )
					( Origin gBackEnd )
				)
				( attribute "RELATIVE_PROPAGATION_DELAY" "-50.00 MIL,50.00 MIL"
					( Parent
						( matchGroupRef "@crescent_city_bb_fab1_lib.crescent_city_bb_fab1(sch_1):\MG_DQ_NEAR_DIMM_NG_M_D_BYTE4\" )
					)
					( Units "uMatchProp" "ns" 1.000000)
					( Status sCSetFlattened )
					( Origin gBackEnd )
				)
			)
			( pinPair "@baseboard_fab2_lib.baseboard_fab2(sch_1):\PP1786\"
				( pinRef "@baseboard_fab2_lib.baseboard_fab2(sch_1):page62_i172:DDR5_DQ(29)" )
				( pinRef "@baseboard_fab2_lib.baseboard_fab2(sch_1):page87_i186:DQ(28)" )
				( attribute "RELATIVE_PROPAGATION_DELAY_SCOPE" "G"
					( Parent
						( matchGroupRef "@baseboard_fab2_lib.baseboard_fab2(sch_1):\MG_DQ-DQS_FAR_DIMM_NG_M_M_BYTE3\" )
					)
					( Status sCSetFlattened )
					( Origin gBackEnd )
				)
				( attribute "RELATIVE_PROPAGATION_DELAY" "0.00 MIL,195.00 MIL"
					( Parent
						( matchGroupRef "@baseboard_fab2_lib.baseboard_fab2(sch_1):\MG_DQ-DQS_FAR_DIMM_NG_M_M_BYTE3\" )
					)
					( Units "uMatchProp" "ns" 1.000000)
					( Status sCSetFlattened )
					( Origin gBackEnd )
				)
				( attribute "RELATIVE_PROPAGATION_DELAY_SCOPE" "G"
					( Parent
						( matchGroupRef "@baseboard_fab2_lib.baseboard_fab2(sch_1):\MG_DQ_FAR_DIMM_NG_M_M_BYTE3\" )
					)
					( Status sCSetFlattened )
					( Origin gBackEnd )
				)
				( attribute "RELATIVE_PROPAGATION_DELAY" "-50.00 MIL,50.00 MIL"
					( Parent
						( matchGroupRef "@baseboard_fab2_lib.baseboard_fab2(sch_1):\MG_DQ_FAR_DIMM_NG_M_M_BYTE3\" )
					)
					( Units "uMatchProp" "ns" 1.000000)
					( Status sCSetFlattened )
					( Origin gBackEnd )
				)
			)
			( pinPair "@baseboard_fab2_lib.baseboard_fab2(sch_1):\PP1787\"
				( pinRef "@baseboard_fab2_lib.baseboard_fab2(sch_1):page62_i172:DDR5_DQ(29)" )
				( pinRef "@baseboard_fab2_lib.baseboard_fab2(sch_1):page88_i111:DQ(29)" )
				( attribute "RELATIVE_PROPAGATION_DELAY_SCOPE" "G"
					( Parent
						( matchGroupRef "@baseboard_fab2_lib.baseboard_fab2(sch_1):\MG_DQ-DQS_NEAR_DIMM_NG_M_M_BYTE3\" )
					)
					( Status sCSetFlattened )
					( Origin gBackEnd )
				)
				( attribute "RELATIVE_PROPAGATION_DELAY" "0.00 MIL,195.00 MIL"
					( Parent
						( matchGroupRef "@baseboard_fab2_lib.baseboard_fab2(sch_1):\MG_DQ-DQS_NEAR_DIMM_NG_M_M_BYTE3\" )
					)
					( Units "uMatchProp" "ns" 1.000000)
					( Status sCSetFlattened )
					( Origin gBackEnd )
				)
				( attribute "RELATIVE_PROPAGATION_DELAY_SCOPE" "G"
					( Parent
						( matchGroupRef "@crescent_city_bb_fab1_lib.crescent_city_bb_fab1(sch_1):\MG_DQ_NEAR_DIMM_NG_M_M_BYTE3\" )
					)
					( Origin gBackEnd )
				)
				( attribute "RELATIVE_PROPAGATION_DELAY" "TARGET,TARGET"
					( Parent
						( matchGroupRef "@crescent_city_bb_fab1_lib.crescent_city_bb_fab1(sch_1):\MG_DQ_NEAR_DIMM_NG_M_M_BYTE3\" )
					)
					( Units "uMatchProp" "ns" 1.000000)
					( Origin gBackEnd )
				)
			)
			( pinPair "@baseboard_fab2_lib.baseboard_fab2(sch_1):\PP1789\"
				( pinRef "@baseboard_fab2_lib.baseboard_fab2(sch_1):page62_i172:DDR5_DQ(30)" )
				( pinRef "@baseboard_fab2_lib.baseboard_fab2(sch_1):page87_i186:DQ(31)" )
				( attribute "RELATIVE_PROPAGATION_DELAY_SCOPE" "G"
					( Parent
						( matchGroupRef "@baseboard_fab2_lib.baseboard_fab2(sch_1):\MG_DQ-DQS_FAR_DIMM_NG_M_M_BYTE3\" )
					)
					( Status sCSetFlattened )
					( Origin gBackEnd )
				)
				( attribute "RELATIVE_PROPAGATION_DELAY" "0.00 MIL,195.00 MIL"
					( Parent
						( matchGroupRef "@baseboard_fab2_lib.baseboard_fab2(sch_1):\MG_DQ-DQS_FAR_DIMM_NG_M_M_BYTE3\" )
					)
					( Units "uMatchProp" "ns" 1.000000)
					( Status sCSetFlattened )
					( Origin gBackEnd )
				)
				( attribute "RELATIVE_PROPAGATION_DELAY_SCOPE" "G"
					( Parent
						( matchGroupRef "@baseboard_fab2_lib.baseboard_fab2(sch_1):\MG_DQ_FAR_DIMM_NG_M_M_BYTE3\" )
					)
					( Status sCSetFlattened )
					( Origin gBackEnd )
				)
				( attribute "RELATIVE_PROPAGATION_DELAY" "-50.00 MIL,50.00 MIL"
					( Parent
						( matchGroupRef "@baseboard_fab2_lib.baseboard_fab2(sch_1):\MG_DQ_FAR_DIMM_NG_M_M_BYTE3\" )
					)
					( Units "uMatchProp" "ns" 1.000000)
					( Status sCSetFlattened )
					( Origin gBackEnd )
				)
			)
			( pinPair "@baseboard_fab2_lib.baseboard_fab2(sch_1):\PP1790\"
				( pinRef "@baseboard_fab2_lib.baseboard_fab2(sch_1):page62_i172:DDR5_DQ(30)" )
				( pinRef "@baseboard_fab2_lib.baseboard_fab2(sch_1):page88_i111:DQ(30)" )
				( attribute "RELATIVE_PROPAGATION_DELAY_SCOPE" "G"
					( Parent
						( matchGroupRef "@baseboard_fab2_lib.baseboard_fab2(sch_1):\MG_DQ-DQS_NEAR_DIMM_NG_M_M_BYTE3\" )
					)
					( Status sCSetFlattened )
					( Origin gBackEnd )
				)
				( attribute "RELATIVE_PROPAGATION_DELAY" "0.00 MIL,195.00 MIL"
					( Parent
						( matchGroupRef "@baseboard_fab2_lib.baseboard_fab2(sch_1):\MG_DQ-DQS_NEAR_DIMM_NG_M_M_BYTE3\" )
					)
					( Units "uMatchProp" "ns" 1.000000)
					( Status sCSetFlattened )
					( Origin gBackEnd )
				)
				( attribute "RELATIVE_PROPAGATION_DELAY_SCOPE" "G"
					( Parent
						( matchGroupRef "@crescent_city_bb_fab1_lib.crescent_city_bb_fab1(sch_1):\MG_DQ_NEAR_DIMM_NG_M_M_BYTE3\" )
					)
					( Status sCSetFlattened )
					( Origin gBackEnd )
				)
				( attribute "RELATIVE_PROPAGATION_DELAY" "-50.00 MIL,50.00 MIL"
					( Parent
						( matchGroupRef "@crescent_city_bb_fab1_lib.crescent_city_bb_fab1(sch_1):\MG_DQ_NEAR_DIMM_NG_M_M_BYTE3\" )
					)
					( Units "uMatchProp" "ns" 1.000000)
					( Status sCSetFlattened )
					( Origin gBackEnd )
				)
			)
			( pinPair "@baseboard_fab2_lib.baseboard_fab2(sch_1):\PP1792\"
				( pinRef "@baseboard_fab2_lib.baseboard_fab2(sch_1):page62_i172:DDR5_DQ(31)" )
				( pinRef "@baseboard_fab2_lib.baseboard_fab2(sch_1):page87_i186:DQ(30)" )
				( attribute "RELATIVE_PROPAGATION_DELAY_SCOPE" "G"
					( Parent
						( matchGroupRef "@baseboard_fab2_lib.baseboard_fab2(sch_1):\MG_DQ-DQS_FAR_DIMM_NG_M_M_BYTE3\" )
					)
					( Status sCSetFlattened )
					( Origin gBackEnd )
				)
				( attribute "RELATIVE_PROPAGATION_DELAY" "0.00 MIL,195.00 MIL"
					( Parent
						( matchGroupRef "@baseboard_fab2_lib.baseboard_fab2(sch_1):\MG_DQ-DQS_FAR_DIMM_NG_M_M_BYTE3\" )
					)
					( Units "uMatchProp" "ns" 1.000000)
					( Status sCSetFlattened )
					( Origin gBackEnd )
				)
				( attribute "RELATIVE_PROPAGATION_DELAY_SCOPE" "G"
					( Parent
						( matchGroupRef "@baseboard_fab2_lib.baseboard_fab2(sch_1):\MG_DQ_FAR_DIMM_NG_M_M_BYTE3\" )
					)
					( Status sCSetFlattened )
					( Origin gBackEnd )
				)
				( attribute "RELATIVE_PROPAGATION_DELAY" "-50.00 MIL,50.00 MIL"
					( Parent
						( matchGroupRef "@baseboard_fab2_lib.baseboard_fab2(sch_1):\MG_DQ_FAR_DIMM_NG_M_M_BYTE3\" )
					)
					( Units "uMatchProp" "ns" 1.000000)
					( Status sCSetFlattened )
					( Origin gBackEnd )
				)
			)
			( pinPair "@baseboard_fab2_lib.baseboard_fab2(sch_1):\PP1793\"
				( pinRef "@baseboard_fab2_lib.baseboard_fab2(sch_1):page62_i172:DDR5_DQ(31)" )
				( pinRef "@baseboard_fab2_lib.baseboard_fab2(sch_1):page88_i111:DQ(31)" )
				( attribute "RELATIVE_PROPAGATION_DELAY_SCOPE" "G"
					( Parent
						( matchGroupRef "@baseboard_fab2_lib.baseboard_fab2(sch_1):\MG_DQ-DQS_NEAR_DIMM_NG_M_M_BYTE3\" )
					)
					( Status sCSetFlattened )
					( Origin gBackEnd )
				)
				( attribute "RELATIVE_PROPAGATION_DELAY" "0.00 MIL,195.00 MIL"
					( Parent
						( matchGroupRef "@baseboard_fab2_lib.baseboard_fab2(sch_1):\MG_DQ-DQS_NEAR_DIMM_NG_M_M_BYTE3\" )
					)
					( Units "uMatchProp" "ns" 1.000000)
					( Status sCSetFlattened )
					( Origin gBackEnd )
				)
				( attribute "RELATIVE_PROPAGATION_DELAY_SCOPE" "G"
					( Parent
						( matchGroupRef "@crescent_city_bb_fab1_lib.crescent_city_bb_fab1(sch_1):\MG_DQ_NEAR_DIMM_NG_M_M_BYTE3\" )
					)
					( Status sCSetFlattened )
					( Origin gBackEnd )
				)
				( attribute "RELATIVE_PROPAGATION_DELAY" "-50.00 MIL,50.00 MIL"
					( Parent
						( matchGroupRef "@crescent_city_bb_fab1_lib.crescent_city_bb_fab1(sch_1):\MG_DQ_NEAR_DIMM_NG_M_M_BYTE3\" )
					)
					( Units "uMatchProp" "ns" 1.000000)
					( Status sCSetFlattened )
					( Origin gBackEnd )
				)
			)
			( pinPair "@baseboard_fab2_lib.baseboard_fab2(sch_1):\PP1747\"
				( pinRef "@baseboard_fab2_lib.baseboard_fab2(sch_1):page62_i172:DDR5_DQ(32)" )
				( pinRef "@baseboard_fab2_lib.baseboard_fab2(sch_1):page87_i186:DQ(33)" )
				( attribute "RELATIVE_PROPAGATION_DELAY_SCOPE" "G"
					( Parent
						( matchGroupRef "@baseboard_fab2_lib.baseboard_fab2(sch_1):\MG_DQ-DQS_FAR_DIMM_NG_M_M_BYTE4\" )
					)
					( Status sCSetFlattened )
					( Origin gBackEnd )
				)
				( attribute "RELATIVE_PROPAGATION_DELAY" "0.00 MIL,195.00 MIL"
					( Parent
						( matchGroupRef "@baseboard_fab2_lib.baseboard_fab2(sch_1):\MG_DQ-DQS_FAR_DIMM_NG_M_M_BYTE4\" )
					)
					( Units "uMatchProp" "ns" 1.000000)
					( Status sCSetFlattened )
					( Origin gBackEnd )
				)
				( attribute "RELATIVE_PROPAGATION_DELAY_SCOPE" "G"
					( Parent
						( matchGroupRef "@crescent_city_bb_fab1_lib.crescent_city_bb_fab1(sch_1):\MG_DQ_FAR_DIMM_NG_M_M_BYTE4\" )
					)
					( Status sCSetFlattened )
					( Origin gBackEnd )
				)
				( attribute "RELATIVE_PROPAGATION_DELAY" "-50.00 MIL,50.00 MIL"
					( Parent
						( matchGroupRef "@crescent_city_bb_fab1_lib.crescent_city_bb_fab1(sch_1):\MG_DQ_FAR_DIMM_NG_M_M_BYTE4\" )
					)
					( Units "uMatchProp" "ns" 1.000000)
					( Status sCSetFlattened )
					( Origin gBackEnd )
				)
			)
			( pinPair "@baseboard_fab2_lib.baseboard_fab2(sch_1):\PP1749\"
				( pinRef "@baseboard_fab2_lib.baseboard_fab2(sch_1):page62_i172:DDR5_DQ(32)" )
				( pinRef "@baseboard_fab2_lib.baseboard_fab2(sch_1):page88_i111:DQ(32)" )
				( attribute "RELATIVE_PROPAGATION_DELAY_SCOPE" "G"
					( Parent
						( matchGroupRef "@baseboard_fab2_lib.baseboard_fab2(sch_1):\MG_DQ-DQS_NEAR_DIMM_NG_M_M_BYTE4\" )
					)
					( Status sCSetFlattened )
					( Origin gBackEnd )
				)
				( attribute "RELATIVE_PROPAGATION_DELAY" "0.00 MIL,195.00 MIL"
					( Parent
						( matchGroupRef "@baseboard_fab2_lib.baseboard_fab2(sch_1):\MG_DQ-DQS_NEAR_DIMM_NG_M_M_BYTE4\" )
					)
					( Units "uMatchProp" "ns" 1.000000)
					( Status sCSetFlattened )
					( Origin gBackEnd )
				)
				( attribute "RELATIVE_PROPAGATION_DELAY_SCOPE" "G"
					( Parent
						( matchGroupRef "@crescent_city_bb_fab1_lib.crescent_city_bb_fab1(sch_1):\MG_DQ_NEAR_DIMM_NG_M_M_BYTE4\" )
					)
					( Status sCSetFlattened )
					( Origin gBackEnd )
				)
				( attribute "RELATIVE_PROPAGATION_DELAY" "-50.00 MIL,50.00 MIL"
					( Parent
						( matchGroupRef "@crescent_city_bb_fab1_lib.crescent_city_bb_fab1(sch_1):\MG_DQ_NEAR_DIMM_NG_M_M_BYTE4\" )
					)
					( Units "uMatchProp" "ns" 1.000000)
					( Status sCSetFlattened )
					( Origin gBackEnd )
				)
			)
			( pinPair "@baseboard_fab2_lib.baseboard_fab2(sch_1):\PP1750\"
				( pinRef "@baseboard_fab2_lib.baseboard_fab2(sch_1):page62_i172:DDR5_DQ(33)" )
				( pinRef "@baseboard_fab2_lib.baseboard_fab2(sch_1):page87_i186:DQ(32)" )
				( attribute "RELATIVE_PROPAGATION_DELAY_SCOPE" "G"
					( Parent
						( matchGroupRef "@baseboard_fab2_lib.baseboard_fab2(sch_1):\MG_DQ-DQS_FAR_DIMM_NG_M_M_BYTE4\" )
					)
					( Status sCSetFlattened )
					( Origin gBackEnd )
				)
				( attribute "RELATIVE_PROPAGATION_DELAY" "0.00 MIL,195.00 MIL"
					( Parent
						( matchGroupRef "@baseboard_fab2_lib.baseboard_fab2(sch_1):\MG_DQ-DQS_FAR_DIMM_NG_M_M_BYTE4\" )
					)
					( Units "uMatchProp" "ns" 1.000000)
					( Status sCSetFlattened )
					( Origin gBackEnd )
				)
				( attribute "RELATIVE_PROPAGATION_DELAY_SCOPE" "G"
					( Parent
						( matchGroupRef "@crescent_city_bb_fab1_lib.crescent_city_bb_fab1(sch_1):\MG_DQ_FAR_DIMM_NG_M_M_BYTE4\" )
					)
					( Status sCSetFlattened )
					( Origin gBackEnd )
				)
				( attribute "RELATIVE_PROPAGATION_DELAY" "-50.00 MIL,50.00 MIL"
					( Parent
						( matchGroupRef "@crescent_city_bb_fab1_lib.crescent_city_bb_fab1(sch_1):\MG_DQ_FAR_DIMM_NG_M_M_BYTE4\" )
					)
					( Units "uMatchProp" "ns" 1.000000)
					( Status sCSetFlattened )
					( Origin gBackEnd )
				)
			)
			( pinPair "@baseboard_fab2_lib.baseboard_fab2(sch_1):\PP1752\"
				( pinRef "@baseboard_fab2_lib.baseboard_fab2(sch_1):page62_i172:DDR5_DQ(33)" )
				( pinRef "@baseboard_fab2_lib.baseboard_fab2(sch_1):page88_i111:DQ(33)" )
				( attribute "RELATIVE_PROPAGATION_DELAY_SCOPE" "G"
					( Parent
						( matchGroupRef "@baseboard_fab2_lib.baseboard_fab2(sch_1):\MG_DQ-DQS_NEAR_DIMM_NG_M_M_BYTE4\" )
					)
					( Status sCSetFlattened )
					( Origin gBackEnd )
				)
				( attribute "RELATIVE_PROPAGATION_DELAY" "0.00 MIL,195.00 MIL"
					( Parent
						( matchGroupRef "@baseboard_fab2_lib.baseboard_fab2(sch_1):\MG_DQ-DQS_NEAR_DIMM_NG_M_M_BYTE4\" )
					)
					( Units "uMatchProp" "ns" 1.000000)
					( Status sCSetFlattened )
					( Origin gBackEnd )
				)
				( attribute "RELATIVE_PROPAGATION_DELAY_SCOPE" "G"
					( Parent
						( matchGroupRef "@crescent_city_bb_fab1_lib.crescent_city_bb_fab1(sch_1):\MG_DQ_NEAR_DIMM_NG_M_M_BYTE4\" )
					)
					( Status sCSetFlattened )
					( Origin gBackEnd )
				)
				( attribute "RELATIVE_PROPAGATION_DELAY" "-50.00 MIL,50.00 MIL"
					( Parent
						( matchGroupRef "@crescent_city_bb_fab1_lib.crescent_city_bb_fab1(sch_1):\MG_DQ_NEAR_DIMM_NG_M_M_BYTE4\" )
					)
					( Units "uMatchProp" "ns" 1.000000)
					( Status sCSetFlattened )
					( Origin gBackEnd )
				)
			)
			( pinPair "@baseboard_fab2_lib.baseboard_fab2(sch_1):\PP1753\"
				( pinRef "@baseboard_fab2_lib.baseboard_fab2(sch_1):page62_i172:DDR5_DQ(34)" )
				( pinRef "@baseboard_fab2_lib.baseboard_fab2(sch_1):page87_i186:DQ(35)" )
				( attribute "RELATIVE_PROPAGATION_DELAY_SCOPE" "G"
					( Parent
						( matchGroupRef "@baseboard_fab2_lib.baseboard_fab2(sch_1):\MG_DQ-DQS_FAR_DIMM_NG_M_M_BYTE4\" )
					)
					( Status sCSetFlattened )
					( Origin gBackEnd )
				)
				( attribute "RELATIVE_PROPAGATION_DELAY" "0.00 MIL,195.00 MIL"
					( Parent
						( matchGroupRef "@baseboard_fab2_lib.baseboard_fab2(sch_1):\MG_DQ-DQS_FAR_DIMM_NG_M_M_BYTE4\" )
					)
					( Units "uMatchProp" "ns" 1.000000)
					( Status sCSetFlattened )
					( Origin gBackEnd )
				)
				( attribute "RELATIVE_PROPAGATION_DELAY_SCOPE" "G"
					( Parent
						( matchGroupRef "@crescent_city_bb_fab1_lib.crescent_city_bb_fab1(sch_1):\MG_DQ_FAR_DIMM_NG_M_M_BYTE4\" )
					)
					( Status sCSetFlattened )
					( Origin gBackEnd )
				)
				( attribute "RELATIVE_PROPAGATION_DELAY" "-50.00 MIL,50.00 MIL"
					( Parent
						( matchGroupRef "@crescent_city_bb_fab1_lib.crescent_city_bb_fab1(sch_1):\MG_DQ_FAR_DIMM_NG_M_M_BYTE4\" )
					)
					( Units "uMatchProp" "ns" 1.000000)
					( Status sCSetFlattened )
					( Origin gBackEnd )
				)
			)
			( pinPair "@baseboard_fab2_lib.baseboard_fab2(sch_1):\PP1755\"
				( pinRef "@baseboard_fab2_lib.baseboard_fab2(sch_1):page62_i172:DDR5_DQ(34)" )
				( pinRef "@baseboard_fab2_lib.baseboard_fab2(sch_1):page88_i111:DQ(34)" )
				( attribute "RELATIVE_PROPAGATION_DELAY_SCOPE" "G"
					( Parent
						( matchGroupRef "@baseboard_fab2_lib.baseboard_fab2(sch_1):\MG_DQ-DQS_NEAR_DIMM_NG_M_M_BYTE4\" )
					)
					( Status sCSetFlattened )
					( Origin gBackEnd )
				)
				( attribute "RELATIVE_PROPAGATION_DELAY" "0.00 MIL,195.00 MIL"
					( Parent
						( matchGroupRef "@baseboard_fab2_lib.baseboard_fab2(sch_1):\MG_DQ-DQS_NEAR_DIMM_NG_M_M_BYTE4\" )
					)
					( Units "uMatchProp" "ns" 1.000000)
					( Status sCSetFlattened )
					( Origin gBackEnd )
				)
				( attribute "RELATIVE_PROPAGATION_DELAY_SCOPE" "G"
					( Parent
						( matchGroupRef "@crescent_city_bb_fab1_lib.crescent_city_bb_fab1(sch_1):\MG_DQ_NEAR_DIMM_NG_M_M_BYTE4\" )
					)
					( Status sCSetFlattened )
					( Origin gBackEnd )
				)
				( attribute "RELATIVE_PROPAGATION_DELAY" "-50.00 MIL,50.00 MIL"
					( Parent
						( matchGroupRef "@crescent_city_bb_fab1_lib.crescent_city_bb_fab1(sch_1):\MG_DQ_NEAR_DIMM_NG_M_M_BYTE4\" )
					)
					( Units "uMatchProp" "ns" 1.000000)
					( Status sCSetFlattened )
					( Origin gBackEnd )
				)
			)
			( pinPair "@baseboard_fab2_lib.baseboard_fab2(sch_1):\PP1756\"
				( pinRef "@baseboard_fab2_lib.baseboard_fab2(sch_1):page62_i172:DDR5_DQ(35)" )
				( pinRef "@baseboard_fab2_lib.baseboard_fab2(sch_1):page87_i186:DQ(34)" )
				( attribute "RELATIVE_PROPAGATION_DELAY_SCOPE" "G"
					( Parent
						( matchGroupRef "@baseboard_fab2_lib.baseboard_fab2(sch_1):\MG_DQ-DQS_FAR_DIMM_NG_M_M_BYTE4\" )
					)
					( Status sCSetFlattened )
					( Origin gBackEnd )
				)
				( attribute "RELATIVE_PROPAGATION_DELAY" "0.00 MIL,195.00 MIL"
					( Parent
						( matchGroupRef "@baseboard_fab2_lib.baseboard_fab2(sch_1):\MG_DQ-DQS_FAR_DIMM_NG_M_M_BYTE4\" )
					)
					( Units "uMatchProp" "ns" 1.000000)
					( Status sCSetFlattened )
					( Origin gBackEnd )
				)
				( attribute "RELATIVE_PROPAGATION_DELAY_SCOPE" "G"
					( Parent
						( matchGroupRef "@crescent_city_bb_fab1_lib.crescent_city_bb_fab1(sch_1):\MG_DQ_FAR_DIMM_NG_M_M_BYTE4\" )
					)
					( Status sCSetFlattened )
					( Origin gBackEnd )
				)
				( attribute "RELATIVE_PROPAGATION_DELAY" "-50.00 MIL,50.00 MIL"
					( Parent
						( matchGroupRef "@crescent_city_bb_fab1_lib.crescent_city_bb_fab1(sch_1):\MG_DQ_FAR_DIMM_NG_M_M_BYTE4\" )
					)
					( Units "uMatchProp" "ns" 1.000000)
					( Status sCSetFlattened )
					( Origin gBackEnd )
				)
			)
			( pinPair "@baseboard_fab2_lib.baseboard_fab2(sch_1):\PP1758\"
				( pinRef "@baseboard_fab2_lib.baseboard_fab2(sch_1):page62_i172:DDR5_DQ(35)" )
				( pinRef "@baseboard_fab2_lib.baseboard_fab2(sch_1):page88_i111:DQ(35)" )
				( attribute "RELATIVE_PROPAGATION_DELAY_SCOPE" "G"
					( Parent
						( matchGroupRef "@baseboard_fab2_lib.baseboard_fab2(sch_1):\MG_DQ-DQS_NEAR_DIMM_NG_M_M_BYTE4\" )
					)
					( Status sCSetFlattened )
					( Origin gBackEnd )
				)
				( attribute "RELATIVE_PROPAGATION_DELAY" "0.00 MIL,195.00 MIL"
					( Parent
						( matchGroupRef "@baseboard_fab2_lib.baseboard_fab2(sch_1):\MG_DQ-DQS_NEAR_DIMM_NG_M_M_BYTE4\" )
					)
					( Units "uMatchProp" "ns" 1.000000)
					( Status sCSetFlattened )
					( Origin gBackEnd )
				)
				( attribute "RELATIVE_PROPAGATION_DELAY_SCOPE" "G"
					( Parent
						( matchGroupRef "@crescent_city_bb_fab1_lib.crescent_city_bb_fab1(sch_1):\MG_DQ_NEAR_DIMM_NG_M_M_BYTE4\" )
					)
					( Origin gBackEnd )
				)
				( attribute "RELATIVE_PROPAGATION_DELAY" "TARGET,TARGET"
					( Parent
						( matchGroupRef "@crescent_city_bb_fab1_lib.crescent_city_bb_fab1(sch_1):\MG_DQ_NEAR_DIMM_NG_M_M_BYTE4\" )
					)
					( Units "uMatchProp" "ns" 1.000000)
					( Origin gBackEnd )
				)
			)
			( pinPair "@baseboard_fab2_lib.baseboard_fab2(sch_1):\PP1759\"
				( pinRef "@baseboard_fab2_lib.baseboard_fab2(sch_1):page62_i172:DDR5_DQ(36)" )
				( pinRef "@baseboard_fab2_lib.baseboard_fab2(sch_1):page87_i186:DQ(37)" )
				( attribute "RELATIVE_PROPAGATION_DELAY_SCOPE" "G"
					( Parent
						( matchGroupRef "@baseboard_fab2_lib.baseboard_fab2(sch_1):\MG_DQ-DQS_FAR_DIMM_NG_M_M_BYTE4\" )
					)
					( Status sCSetFlattened )
					( Origin gBackEnd )
				)
				( attribute "RELATIVE_PROPAGATION_DELAY" "0.00 MIL,195.00 MIL"
					( Parent
						( matchGroupRef "@baseboard_fab2_lib.baseboard_fab2(sch_1):\MG_DQ-DQS_FAR_DIMM_NG_M_M_BYTE4\" )
					)
					( Units "uMatchProp" "ns" 1.000000)
					( Status sCSetFlattened )
					( Origin gBackEnd )
				)
				( attribute "RELATIVE_PROPAGATION_DELAY_SCOPE" "G"
					( Parent
						( matchGroupRef "@crescent_city_bb_fab1_lib.crescent_city_bb_fab1(sch_1):\MG_DQ_FAR_DIMM_NG_M_M_BYTE4\" )
					)
					( Origin gBackEnd )
				)
				( attribute "RELATIVE_PROPAGATION_DELAY" "TARGET,TARGET"
					( Parent
						( matchGroupRef "@crescent_city_bb_fab1_lib.crescent_city_bb_fab1(sch_1):\MG_DQ_FAR_DIMM_NG_M_M_BYTE4\" )
					)
					( Units "uMatchProp" "ns" 1.000000)
					( Origin gBackEnd )
				)
			)
			( pinPair "@baseboard_fab2_lib.baseboard_fab2(sch_1):\PP1761\"
				( pinRef "@baseboard_fab2_lib.baseboard_fab2(sch_1):page62_i172:DDR5_DQ(36)" )
				( pinRef "@baseboard_fab2_lib.baseboard_fab2(sch_1):page88_i111:DQ(36)" )
				( attribute "RELATIVE_PROPAGATION_DELAY_SCOPE" "G"
					( Parent
						( matchGroupRef "@baseboard_fab2_lib.baseboard_fab2(sch_1):\MG_DQ-DQS_NEAR_DIMM_NG_M_M_BYTE4\" )
					)
					( Status sCSetFlattened )
					( Origin gBackEnd )
				)
				( attribute "RELATIVE_PROPAGATION_DELAY" "0.00 MIL,195.00 MIL"
					( Parent
						( matchGroupRef "@baseboard_fab2_lib.baseboard_fab2(sch_1):\MG_DQ-DQS_NEAR_DIMM_NG_M_M_BYTE4\" )
					)
					( Units "uMatchProp" "ns" 1.000000)
					( Status sCSetFlattened )
					( Origin gBackEnd )
				)
				( attribute "RELATIVE_PROPAGATION_DELAY_SCOPE" "G"
					( Parent
						( matchGroupRef "@crescent_city_bb_fab1_lib.crescent_city_bb_fab1(sch_1):\MG_DQ_NEAR_DIMM_NG_M_M_BYTE4\" )
					)
					( Status sCSetFlattened )
					( Origin gBackEnd )
				)
				( attribute "RELATIVE_PROPAGATION_DELAY" "-50.00 MIL,50.00 MIL"
					( Parent
						( matchGroupRef "@crescent_city_bb_fab1_lib.crescent_city_bb_fab1(sch_1):\MG_DQ_NEAR_DIMM_NG_M_M_BYTE4\" )
					)
					( Units "uMatchProp" "ns" 1.000000)
					( Status sCSetFlattened )
					( Origin gBackEnd )
				)
			)
			( pinPair "@baseboard_fab2_lib.baseboard_fab2(sch_1):\PP1762\"
				( pinRef "@baseboard_fab2_lib.baseboard_fab2(sch_1):page62_i172:DDR5_DQ(37)" )
				( pinRef "@baseboard_fab2_lib.baseboard_fab2(sch_1):page87_i186:DQ(36)" )
				( attribute "RELATIVE_PROPAGATION_DELAY_SCOPE" "G"
					( Parent
						( matchGroupRef "@baseboard_fab2_lib.baseboard_fab2(sch_1):\MG_DQ-DQS_FAR_DIMM_NG_M_M_BYTE4\" )
					)
					( Status sCSetFlattened )
					( Origin gBackEnd )
				)
				( attribute "RELATIVE_PROPAGATION_DELAY" "0.00 MIL,195.00 MIL"
					( Parent
						( matchGroupRef "@baseboard_fab2_lib.baseboard_fab2(sch_1):\MG_DQ-DQS_FAR_DIMM_NG_M_M_BYTE4\" )
					)
					( Units "uMatchProp" "ns" 1.000000)
					( Status sCSetFlattened )
					( Origin gBackEnd )
				)
				( attribute "RELATIVE_PROPAGATION_DELAY_SCOPE" "G"
					( Parent
						( matchGroupRef "@crescent_city_bb_fab1_lib.crescent_city_bb_fab1(sch_1):\MG_DQ_FAR_DIMM_NG_M_M_BYTE4\" )
					)
					( Status sCSetFlattened )
					( Origin gBackEnd )
				)
				( attribute "RELATIVE_PROPAGATION_DELAY" "-50.00 MIL,50.00 MIL"
					( Parent
						( matchGroupRef "@crescent_city_bb_fab1_lib.crescent_city_bb_fab1(sch_1):\MG_DQ_FAR_DIMM_NG_M_M_BYTE4\" )
					)
					( Units "uMatchProp" "ns" 1.000000)
					( Status sCSetFlattened )
					( Origin gBackEnd )
				)
			)
			( pinPair "@baseboard_fab2_lib.baseboard_fab2(sch_1):\PP1764\"
				( pinRef "@baseboard_fab2_lib.baseboard_fab2(sch_1):page62_i172:DDR5_DQ(37)" )
				( pinRef "@baseboard_fab2_lib.baseboard_fab2(sch_1):page88_i111:DQ(37)" )
				( attribute "RELATIVE_PROPAGATION_DELAY_SCOPE" "G"
					( Parent
						( matchGroupRef "@baseboard_fab2_lib.baseboard_fab2(sch_1):\MG_DQ-DQS_NEAR_DIMM_NG_M_M_BYTE4\" )
					)
					( Status sCSetFlattened )
					( Origin gBackEnd )
				)
				( attribute "RELATIVE_PROPAGATION_DELAY" "0.00 MIL,195.00 MIL"
					( Parent
						( matchGroupRef "@baseboard_fab2_lib.baseboard_fab2(sch_1):\MG_DQ-DQS_NEAR_DIMM_NG_M_M_BYTE4\" )
					)
					( Units "uMatchProp" "ns" 1.000000)
					( Status sCSetFlattened )
					( Origin gBackEnd )
				)
				( attribute "RELATIVE_PROPAGATION_DELAY_SCOPE" "G"
					( Parent
						( matchGroupRef "@crescent_city_bb_fab1_lib.crescent_city_bb_fab1(sch_1):\MG_DQ_NEAR_DIMM_NG_M_M_BYTE4\" )
					)
					( Status sCSetFlattened )
					( Origin gBackEnd )
				)
				( attribute "RELATIVE_PROPAGATION_DELAY" "-50.00 MIL,50.00 MIL"
					( Parent
						( matchGroupRef "@crescent_city_bb_fab1_lib.crescent_city_bb_fab1(sch_1):\MG_DQ_NEAR_DIMM_NG_M_M_BYTE4\" )
					)
					( Units "uMatchProp" "ns" 1.000000)
					( Status sCSetFlattened )
					( Origin gBackEnd )
				)
			)
			( pinPair "@baseboard_fab2_lib.baseboard_fab2(sch_1):\PP1765\"
				( pinRef "@baseboard_fab2_lib.baseboard_fab2(sch_1):page62_i172:DDR5_DQ(38)" )
				( pinRef "@baseboard_fab2_lib.baseboard_fab2(sch_1):page87_i186:DQ(39)" )
				( attribute "RELATIVE_PROPAGATION_DELAY_SCOPE" "G"
					( Parent
						( matchGroupRef "@baseboard_fab2_lib.baseboard_fab2(sch_1):\MG_DQ-DQS_FAR_DIMM_NG_M_M_BYTE4\" )
					)
					( Status sCSetFlattened )
					( Origin gBackEnd )
				)
				( attribute "RELATIVE_PROPAGATION_DELAY" "0.00 MIL,195.00 MIL"
					( Parent
						( matchGroupRef "@baseboard_fab2_lib.baseboard_fab2(sch_1):\MG_DQ-DQS_FAR_DIMM_NG_M_M_BYTE4\" )
					)
					( Units "uMatchProp" "ns" 1.000000)
					( Status sCSetFlattened )
					( Origin gBackEnd )
				)
				( attribute "RELATIVE_PROPAGATION_DELAY_SCOPE" "G"
					( Parent
						( matchGroupRef "@crescent_city_bb_fab1_lib.crescent_city_bb_fab1(sch_1):\MG_DQ_FAR_DIMM_NG_M_M_BYTE4\" )
					)
					( Status sCSetFlattened )
					( Origin gBackEnd )
				)
				( attribute "RELATIVE_PROPAGATION_DELAY" "-50.00 MIL,50.00 MIL"
					( Parent
						( matchGroupRef "@crescent_city_bb_fab1_lib.crescent_city_bb_fab1(sch_1):\MG_DQ_FAR_DIMM_NG_M_M_BYTE4\" )
					)
					( Units "uMatchProp" "ns" 1.000000)
					( Status sCSetFlattened )
					( Origin gBackEnd )
				)
			)
			( pinPair "@baseboard_fab2_lib.baseboard_fab2(sch_1):\PP1767\"
				( pinRef "@baseboard_fab2_lib.baseboard_fab2(sch_1):page62_i172:DDR5_DQ(38)" )
				( pinRef "@baseboard_fab2_lib.baseboard_fab2(sch_1):page88_i111:DQ(38)" )
				( attribute "RELATIVE_PROPAGATION_DELAY_SCOPE" "G"
					( Parent
						( matchGroupRef "@baseboard_fab2_lib.baseboard_fab2(sch_1):\MG_DQ-DQS_NEAR_DIMM_NG_M_M_BYTE4\" )
					)
					( Status sCSetFlattened )
					( Origin gBackEnd )
				)
				( attribute "RELATIVE_PROPAGATION_DELAY" "0.00 MIL,195.00 MIL"
					( Parent
						( matchGroupRef "@baseboard_fab2_lib.baseboard_fab2(sch_1):\MG_DQ-DQS_NEAR_DIMM_NG_M_M_BYTE4\" )
					)
					( Units "uMatchProp" "ns" 1.000000)
					( Status sCSetFlattened )
					( Origin gBackEnd )
				)
				( attribute "RELATIVE_PROPAGATION_DELAY_SCOPE" "G"
					( Parent
						( matchGroupRef "@crescent_city_bb_fab1_lib.crescent_city_bb_fab1(sch_1):\MG_DQ_NEAR_DIMM_NG_M_M_BYTE4\" )
					)
					( Status sCSetFlattened )
					( Origin gBackEnd )
				)
				( attribute "RELATIVE_PROPAGATION_DELAY" "-50.00 MIL,50.00 MIL"
					( Parent
						( matchGroupRef "@crescent_city_bb_fab1_lib.crescent_city_bb_fab1(sch_1):\MG_DQ_NEAR_DIMM_NG_M_M_BYTE4\" )
					)
					( Units "uMatchProp" "ns" 1.000000)
					( Status sCSetFlattened )
					( Origin gBackEnd )
				)
			)
			( pinPair "@baseboard_fab2_lib.baseboard_fab2(sch_1):\PP1768\"
				( pinRef "@baseboard_fab2_lib.baseboard_fab2(sch_1):page62_i172:DDR5_DQ(39)" )
				( pinRef "@baseboard_fab2_lib.baseboard_fab2(sch_1):page87_i186:DQ(38)" )
				( attribute "RELATIVE_PROPAGATION_DELAY_SCOPE" "G"
					( Parent
						( matchGroupRef "@baseboard_fab2_lib.baseboard_fab2(sch_1):\MG_DQ-DQS_FAR_DIMM_NG_M_M_BYTE4\" )
					)
					( Status sCSetFlattened )
					( Origin gBackEnd )
				)
				( attribute "RELATIVE_PROPAGATION_DELAY" "0.00 MIL,195.00 MIL"
					( Parent
						( matchGroupRef "@baseboard_fab2_lib.baseboard_fab2(sch_1):\MG_DQ-DQS_FAR_DIMM_NG_M_M_BYTE4\" )
					)
					( Units "uMatchProp" "ns" 1.000000)
					( Status sCSetFlattened )
					( Origin gBackEnd )
				)
				( attribute "RELATIVE_PROPAGATION_DELAY_SCOPE" "G"
					( Parent
						( matchGroupRef "@crescent_city_bb_fab1_lib.crescent_city_bb_fab1(sch_1):\MG_DQ_FAR_DIMM_NG_M_M_BYTE4\" )
					)
					( Status sCSetFlattened )
					( Origin gBackEnd )
				)
				( attribute "RELATIVE_PROPAGATION_DELAY" "-50.00 MIL,50.00 MIL"
					( Parent
						( matchGroupRef "@crescent_city_bb_fab1_lib.crescent_city_bb_fab1(sch_1):\MG_DQ_FAR_DIMM_NG_M_M_BYTE4\" )
					)
					( Units "uMatchProp" "ns" 1.000000)
					( Status sCSetFlattened )
					( Origin gBackEnd )
				)
			)
			( pinPair "@baseboard_fab2_lib.baseboard_fab2(sch_1):\PP1770\"
				( pinRef "@baseboard_fab2_lib.baseboard_fab2(sch_1):page62_i172:DDR5_DQ(39)" )
				( pinRef "@baseboard_fab2_lib.baseboard_fab2(sch_1):page88_i111:DQ(39)" )
				( attribute "RELATIVE_PROPAGATION_DELAY_SCOPE" "G"
					( Parent
						( matchGroupRef "@baseboard_fab2_lib.baseboard_fab2(sch_1):\MG_DQ-DQS_NEAR_DIMM_NG_M_M_BYTE4\" )
					)
					( Status sCSetFlattened )
					( Origin gBackEnd )
				)
				( attribute "RELATIVE_PROPAGATION_DELAY" "0.00 MIL,195.00 MIL"
					( Parent
						( matchGroupRef "@baseboard_fab2_lib.baseboard_fab2(sch_1):\MG_DQ-DQS_NEAR_DIMM_NG_M_M_BYTE4\" )
					)
					( Units "uMatchProp" "ns" 1.000000)
					( Status sCSetFlattened )
					( Origin gBackEnd )
				)
				( attribute "RELATIVE_PROPAGATION_DELAY_SCOPE" "G"
					( Parent
						( matchGroupRef "@crescent_city_bb_fab1_lib.crescent_city_bb_fab1(sch_1):\MG_DQ_NEAR_DIMM_NG_M_M_BYTE4\" )
					)
					( Status sCSetFlattened )
					( Origin gBackEnd )
				)
				( attribute "RELATIVE_PROPAGATION_DELAY" "-50.00 MIL,50.00 MIL"
					( Parent
						( matchGroupRef "@crescent_city_bb_fab1_lib.crescent_city_bb_fab1(sch_1):\MG_DQ_NEAR_DIMM_NG_M_M_BYTE4\" )
					)
					( Units "uMatchProp" "ns" 1.000000)
					( Status sCSetFlattened )
					( Origin gBackEnd )
				)
			)
			( pinPair "@baseboard_fab2_lib.baseboard_fab2(sch_1):\PP1723\"
				( pinRef "@baseboard_fab2_lib.baseboard_fab2(sch_1):page62_i172:DDR5_DQ(40)" )
				( pinRef "@baseboard_fab2_lib.baseboard_fab2(sch_1):page87_i186:DQ(41)" )
				( attribute "RELATIVE_PROPAGATION_DELAY_SCOPE" "G"
					( Parent
						( matchGroupRef "@baseboard_fab2_lib.baseboard_fab2(sch_1):\MG_DQ-DQS_FAR_DIMM_NG_M_M_BYTE5\" )
					)
					( Status sCSetFlattened )
					( Origin gBackEnd )
				)
				( attribute "RELATIVE_PROPAGATION_DELAY" "0.00 MIL,195.00 MIL"
					( Parent
						( matchGroupRef "@baseboard_fab2_lib.baseboard_fab2(sch_1):\MG_DQ-DQS_FAR_DIMM_NG_M_M_BYTE5\" )
					)
					( Units "uMatchProp" "ns" 1.000000)
					( Status sCSetFlattened )
					( Origin gBackEnd )
				)
				( attribute "RELATIVE_PROPAGATION_DELAY_SCOPE" "G"
					( Parent
						( matchGroupRef "@baseboard_fab2_lib.baseboard_fab2(sch_1):\MG_DQ_FAR_DIMM_NG_M_M_BYTE5\" )
					)
					( Status sCSetFlattened )
					( Origin gBackEnd )
				)
				( attribute "RELATIVE_PROPAGATION_DELAY" "-50.00 MIL,50.00 MIL"
					( Parent
						( matchGroupRef "@baseboard_fab2_lib.baseboard_fab2(sch_1):\MG_DQ_FAR_DIMM_NG_M_M_BYTE5\" )
					)
					( Units "uMatchProp" "ns" 1.000000)
					( Status sCSetFlattened )
					( Origin gBackEnd )
				)
			)
			( pinPair "@baseboard_fab2_lib.baseboard_fab2(sch_1):\PP1725\"
				( pinRef "@baseboard_fab2_lib.baseboard_fab2(sch_1):page62_i172:DDR5_DQ(40)" )
				( pinRef "@baseboard_fab2_lib.baseboard_fab2(sch_1):page88_i111:DQ(40)" )
				( attribute "RELATIVE_PROPAGATION_DELAY_SCOPE" "G"
					( Parent
						( matchGroupRef "@baseboard_fab2_lib.baseboard_fab2(sch_1):\MG_DQ-DQS_NEAR_DIMM_NG_M_M_BYTE5\" )
					)
					( Status sCSetFlattened )
					( Origin gBackEnd )
				)
				( attribute "RELATIVE_PROPAGATION_DELAY" "0.00 MIL,195.00 MIL"
					( Parent
						( matchGroupRef "@baseboard_fab2_lib.baseboard_fab2(sch_1):\MG_DQ-DQS_NEAR_DIMM_NG_M_M_BYTE5\" )
					)
					( Units "uMatchProp" "ns" 1.000000)
					( Status sCSetFlattened )
					( Origin gBackEnd )
				)
				( attribute "RELATIVE_PROPAGATION_DELAY_SCOPE" "G"
					( Parent
						( matchGroupRef "@crescent_city_bb_fab1_lib.crescent_city_bb_fab1(sch_1):\MG_DQ_NEAR_DIMM_NG_M_M_BYTE5\" )
					)
					( Status sCSetFlattened )
					( Origin gBackEnd )
				)
				( attribute "RELATIVE_PROPAGATION_DELAY" "-50.00 MIL,50.00 MIL"
					( Parent
						( matchGroupRef "@crescent_city_bb_fab1_lib.crescent_city_bb_fab1(sch_1):\MG_DQ_NEAR_DIMM_NG_M_M_BYTE5\" )
					)
					( Units "uMatchProp" "ns" 1.000000)
					( Status sCSetFlattened )
					( Origin gBackEnd )
				)
			)
			( pinPair "@baseboard_fab2_lib.baseboard_fab2(sch_1):\PP1726\"
				( pinRef "@baseboard_fab2_lib.baseboard_fab2(sch_1):page62_i172:DDR5_DQ(41)" )
				( pinRef "@baseboard_fab2_lib.baseboard_fab2(sch_1):page87_i186:DQ(40)" )
				( attribute "RELATIVE_PROPAGATION_DELAY_SCOPE" "G"
					( Parent
						( matchGroupRef "@baseboard_fab2_lib.baseboard_fab2(sch_1):\MG_DQ-DQS_FAR_DIMM_NG_M_M_BYTE5\" )
					)
					( Status sCSetFlattened )
					( Origin gBackEnd )
				)
				( attribute "RELATIVE_PROPAGATION_DELAY" "0.00 MIL,195.00 MIL"
					( Parent
						( matchGroupRef "@baseboard_fab2_lib.baseboard_fab2(sch_1):\MG_DQ-DQS_FAR_DIMM_NG_M_M_BYTE5\" )
					)
					( Units "uMatchProp" "ns" 1.000000)
					( Status sCSetFlattened )
					( Origin gBackEnd )
				)
				( attribute "RELATIVE_PROPAGATION_DELAY_SCOPE" "G"
					( Parent
						( matchGroupRef "@baseboard_fab2_lib.baseboard_fab2(sch_1):\MG_DQ_FAR_DIMM_NG_M_M_BYTE5\" )
					)
					( Status sCSetFlattened )
					( Origin gBackEnd )
				)
				( attribute "RELATIVE_PROPAGATION_DELAY" "-50.00 MIL,50.00 MIL"
					( Parent
						( matchGroupRef "@baseboard_fab2_lib.baseboard_fab2(sch_1):\MG_DQ_FAR_DIMM_NG_M_M_BYTE5\" )
					)
					( Units "uMatchProp" "ns" 1.000000)
					( Status sCSetFlattened )
					( Origin gBackEnd )
				)
			)
			( pinPair "@baseboard_fab2_lib.baseboard_fab2(sch_1):\PP1728\"
				( pinRef "@baseboard_fab2_lib.baseboard_fab2(sch_1):page62_i172:DDR5_DQ(41)" )
				( pinRef "@baseboard_fab2_lib.baseboard_fab2(sch_1):page88_i111:DQ(41)" )
				( attribute "RELATIVE_PROPAGATION_DELAY_SCOPE" "G"
					( Parent
						( matchGroupRef "@baseboard_fab2_lib.baseboard_fab2(sch_1):\MG_DQ-DQS_NEAR_DIMM_NG_M_M_BYTE5\" )
					)
					( Status sCSetFlattened )
					( Origin gBackEnd )
				)
				( attribute "RELATIVE_PROPAGATION_DELAY" "0.00 MIL,195.00 MIL"
					( Parent
						( matchGroupRef "@baseboard_fab2_lib.baseboard_fab2(sch_1):\MG_DQ-DQS_NEAR_DIMM_NG_M_M_BYTE5\" )
					)
					( Units "uMatchProp" "ns" 1.000000)
					( Status sCSetFlattened )
					( Origin gBackEnd )
				)
				( attribute "RELATIVE_PROPAGATION_DELAY_SCOPE" "G"
					( Parent
						( matchGroupRef "@crescent_city_bb_fab1_lib.crescent_city_bb_fab1(sch_1):\MG_DQ_NEAR_DIMM_NG_M_M_BYTE5\" )
					)
					( Status sCSetFlattened )
					( Origin gBackEnd )
				)
				( attribute "RELATIVE_PROPAGATION_DELAY" "-50.00 MIL,50.00 MIL"
					( Parent
						( matchGroupRef "@crescent_city_bb_fab1_lib.crescent_city_bb_fab1(sch_1):\MG_DQ_NEAR_DIMM_NG_M_M_BYTE5\" )
					)
					( Units "uMatchProp" "ns" 1.000000)
					( Status sCSetFlattened )
					( Origin gBackEnd )
				)
			)
			( pinPair "@baseboard_fab2_lib.baseboard_fab2(sch_1):\PP1729\"
				( pinRef "@baseboard_fab2_lib.baseboard_fab2(sch_1):page62_i172:DDR5_DQ(42)" )
				( pinRef "@baseboard_fab2_lib.baseboard_fab2(sch_1):page87_i186:DQ(43)" )
				( attribute "RELATIVE_PROPAGATION_DELAY_SCOPE" "G"
					( Parent
						( matchGroupRef "@baseboard_fab2_lib.baseboard_fab2(sch_1):\MG_DQ-DQS_FAR_DIMM_NG_M_M_BYTE5\" )
					)
					( Status sCSetFlattened )
					( Origin gBackEnd )
				)
				( attribute "RELATIVE_PROPAGATION_DELAY" "0.00 MIL,195.00 MIL"
					( Parent
						( matchGroupRef "@baseboard_fab2_lib.baseboard_fab2(sch_1):\MG_DQ-DQS_FAR_DIMM_NG_M_M_BYTE5\" )
					)
					( Units "uMatchProp" "ns" 1.000000)
					( Status sCSetFlattened )
					( Origin gBackEnd )
				)
				( attribute "RELATIVE_PROPAGATION_DELAY_SCOPE" "G"
					( Parent
						( matchGroupRef "@baseboard_fab2_lib.baseboard_fab2(sch_1):\MG_DQ_FAR_DIMM_NG_M_M_BYTE5\" )
					)
					( Status sCSetFlattened )
					( Origin gBackEnd )
				)
				( attribute "RELATIVE_PROPAGATION_DELAY" "-50.00 MIL,50.00 MIL"
					( Parent
						( matchGroupRef "@baseboard_fab2_lib.baseboard_fab2(sch_1):\MG_DQ_FAR_DIMM_NG_M_M_BYTE5\" )
					)
					( Units "uMatchProp" "ns" 1.000000)
					( Status sCSetFlattened )
					( Origin gBackEnd )
				)
			)
			( pinPair "@baseboard_fab2_lib.baseboard_fab2(sch_1):\PP1731\"
				( pinRef "@baseboard_fab2_lib.baseboard_fab2(sch_1):page62_i172:DDR5_DQ(42)" )
				( pinRef "@baseboard_fab2_lib.baseboard_fab2(sch_1):page88_i111:DQ(42)" )
				( attribute "RELATIVE_PROPAGATION_DELAY_SCOPE" "G"
					( Parent
						( matchGroupRef "@baseboard_fab2_lib.baseboard_fab2(sch_1):\MG_DQ-DQS_NEAR_DIMM_NG_M_M_BYTE5\" )
					)
					( Status sCSetFlattened )
					( Origin gBackEnd )
				)
				( attribute "RELATIVE_PROPAGATION_DELAY" "0.00 MIL,195.00 MIL"
					( Parent
						( matchGroupRef "@baseboard_fab2_lib.baseboard_fab2(sch_1):\MG_DQ-DQS_NEAR_DIMM_NG_M_M_BYTE5\" )
					)
					( Units "uMatchProp" "ns" 1.000000)
					( Status sCSetFlattened )
					( Origin gBackEnd )
				)
				( attribute "RELATIVE_PROPAGATION_DELAY_SCOPE" "G"
					( Parent
						( matchGroupRef "@crescent_city_bb_fab1_lib.crescent_city_bb_fab1(sch_1):\MG_DQ_NEAR_DIMM_NG_M_M_BYTE5\" )
					)
					( Status sCSetFlattened )
					( Origin gBackEnd )
				)
				( attribute "RELATIVE_PROPAGATION_DELAY" "-50.00 MIL,50.00 MIL"
					( Parent
						( matchGroupRef "@crescent_city_bb_fab1_lib.crescent_city_bb_fab1(sch_1):\MG_DQ_NEAR_DIMM_NG_M_M_BYTE5\" )
					)
					( Units "uMatchProp" "ns" 1.000000)
					( Status sCSetFlattened )
					( Origin gBackEnd )
				)
			)
			( pinPair "@baseboard_fab2_lib.baseboard_fab2(sch_1):\PP1732\"
				( pinRef "@baseboard_fab2_lib.baseboard_fab2(sch_1):page62_i172:DDR5_DQ(43)" )
				( pinRef "@baseboard_fab2_lib.baseboard_fab2(sch_1):page87_i186:DQ(42)" )
				( attribute "RELATIVE_PROPAGATION_DELAY_SCOPE" "G"
					( Parent
						( matchGroupRef "@baseboard_fab2_lib.baseboard_fab2(sch_1):\MG_DQ-DQS_FAR_DIMM_NG_M_M_BYTE5\" )
					)
					( Status sCSetFlattened )
					( Origin gBackEnd )
				)
				( attribute "RELATIVE_PROPAGATION_DELAY" "0.00 MIL,195.00 MIL"
					( Parent
						( matchGroupRef "@baseboard_fab2_lib.baseboard_fab2(sch_1):\MG_DQ-DQS_FAR_DIMM_NG_M_M_BYTE5\" )
					)
					( Units "uMatchProp" "ns" 1.000000)
					( Status sCSetFlattened )
					( Origin gBackEnd )
				)
				( attribute "RELATIVE_PROPAGATION_DELAY_SCOPE" "G"
					( Parent
						( matchGroupRef "@baseboard_fab2_lib.baseboard_fab2(sch_1):\MG_DQ_FAR_DIMM_NG_M_M_BYTE5\" )
					)
					( Status sCSetFlattened )
					( Origin gBackEnd )
				)
				( attribute "RELATIVE_PROPAGATION_DELAY" "-50.00 MIL,50.00 MIL"
					( Parent
						( matchGroupRef "@baseboard_fab2_lib.baseboard_fab2(sch_1):\MG_DQ_FAR_DIMM_NG_M_M_BYTE5\" )
					)
					( Units "uMatchProp" "ns" 1.000000)
					( Status sCSetFlattened )
					( Origin gBackEnd )
				)
			)
			( pinPair "@baseboard_fab2_lib.baseboard_fab2(sch_1):\PP1734\"
				( pinRef "@baseboard_fab2_lib.baseboard_fab2(sch_1):page62_i172:DDR5_DQ(43)" )
				( pinRef "@baseboard_fab2_lib.baseboard_fab2(sch_1):page88_i111:DQ(43)" )
				( attribute "RELATIVE_PROPAGATION_DELAY_SCOPE" "G"
					( Parent
						( matchGroupRef "@baseboard_fab2_lib.baseboard_fab2(sch_1):\MG_DQ-DQS_NEAR_DIMM_NG_M_M_BYTE5\" )
					)
					( Status sCSetFlattened )
					( Origin gBackEnd )
				)
				( attribute "RELATIVE_PROPAGATION_DELAY" "0.00 MIL,195.00 MIL"
					( Parent
						( matchGroupRef "@baseboard_fab2_lib.baseboard_fab2(sch_1):\MG_DQ-DQS_NEAR_DIMM_NG_M_M_BYTE5\" )
					)
					( Units "uMatchProp" "ns" 1.000000)
					( Status sCSetFlattened )
					( Origin gBackEnd )
				)
				( attribute "RELATIVE_PROPAGATION_DELAY_SCOPE" "G"
					( Parent
						( matchGroupRef "@crescent_city_bb_fab1_lib.crescent_city_bb_fab1(sch_1):\MG_DQ_NEAR_DIMM_NG_M_M_BYTE5\" )
					)
					( Status sCSetFlattened )
					( Origin gBackEnd )
				)
				( attribute "RELATIVE_PROPAGATION_DELAY" "-50.00 MIL,50.00 MIL"
					( Parent
						( matchGroupRef "@crescent_city_bb_fab1_lib.crescent_city_bb_fab1(sch_1):\MG_DQ_NEAR_DIMM_NG_M_M_BYTE5\" )
					)
					( Units "uMatchProp" "ns" 1.000000)
					( Status sCSetFlattened )
					( Origin gBackEnd )
				)
			)
			( pinPair "@baseboard_fab2_lib.baseboard_fab2(sch_1):\PP1735\"
				( pinRef "@baseboard_fab2_lib.baseboard_fab2(sch_1):page62_i172:DDR5_DQ(44)" )
				( pinRef "@baseboard_fab2_lib.baseboard_fab2(sch_1):page87_i186:DQ(45)" )
				( attribute "RELATIVE_PROPAGATION_DELAY_SCOPE" "G"
					( Parent
						( matchGroupRef "@baseboard_fab2_lib.baseboard_fab2(sch_1):\MG_DQ-DQS_FAR_DIMM_NG_M_M_BYTE5\" )
					)
					( Status sCSetFlattened )
					( Origin gBackEnd )
				)
				( attribute "RELATIVE_PROPAGATION_DELAY" "0.00 MIL,195.00 MIL"
					( Parent
						( matchGroupRef "@baseboard_fab2_lib.baseboard_fab2(sch_1):\MG_DQ-DQS_FAR_DIMM_NG_M_M_BYTE5\" )
					)
					( Units "uMatchProp" "ns" 1.000000)
					( Status sCSetFlattened )
					( Origin gBackEnd )
				)
				( attribute "RELATIVE_PROPAGATION_DELAY_SCOPE" "G"
					( Parent
						( matchGroupRef "@baseboard_fab2_lib.baseboard_fab2(sch_1):\MG_DQ_FAR_DIMM_NG_M_M_BYTE5\" )
					)
					( Status sCSetFlattened )
					( Origin gBackEnd )
				)
				( attribute "RELATIVE_PROPAGATION_DELAY" "-50.00 MIL,50.00 MIL"
					( Parent
						( matchGroupRef "@baseboard_fab2_lib.baseboard_fab2(sch_1):\MG_DQ_FAR_DIMM_NG_M_M_BYTE5\" )
					)
					( Units "uMatchProp" "ns" 1.000000)
					( Status sCSetFlattened )
					( Origin gBackEnd )
				)
			)
			( pinPair "@baseboard_fab2_lib.baseboard_fab2(sch_1):\PP1737\"
				( pinRef "@baseboard_fab2_lib.baseboard_fab2(sch_1):page62_i172:DDR5_DQ(44)" )
				( pinRef "@baseboard_fab2_lib.baseboard_fab2(sch_1):page88_i111:DQ(44)" )
				( attribute "RELATIVE_PROPAGATION_DELAY_SCOPE" "G"
					( Parent
						( matchGroupRef "@baseboard_fab2_lib.baseboard_fab2(sch_1):\MG_DQ-DQS_NEAR_DIMM_NG_M_M_BYTE5\" )
					)
					( Status sCSetFlattened )
					( Origin gBackEnd )
				)
				( attribute "RELATIVE_PROPAGATION_DELAY" "0.00 MIL,195.00 MIL"
					( Parent
						( matchGroupRef "@baseboard_fab2_lib.baseboard_fab2(sch_1):\MG_DQ-DQS_NEAR_DIMM_NG_M_M_BYTE5\" )
					)
					( Units "uMatchProp" "ns" 1.000000)
					( Status sCSetFlattened )
					( Origin gBackEnd )
				)
				( attribute "RELATIVE_PROPAGATION_DELAY_SCOPE" "G"
					( Parent
						( matchGroupRef "@crescent_city_bb_fab1_lib.crescent_city_bb_fab1(sch_1):\MG_DQ_NEAR_DIMM_NG_M_M_BYTE5\" )
					)
					( Status sCSetFlattened )
					( Origin gBackEnd )
				)
				( attribute "RELATIVE_PROPAGATION_DELAY" "-50.00 MIL,50.00 MIL"
					( Parent
						( matchGroupRef "@crescent_city_bb_fab1_lib.crescent_city_bb_fab1(sch_1):\MG_DQ_NEAR_DIMM_NG_M_M_BYTE5\" )
					)
					( Units "uMatchProp" "ns" 1.000000)
					( Status sCSetFlattened )
					( Origin gBackEnd )
				)
			)
			( pinPair "@baseboard_fab2_lib.baseboard_fab2(sch_1):\PP1738\"
				( pinRef "@baseboard_fab2_lib.baseboard_fab2(sch_1):page62_i172:DDR5_DQ(45)" )
				( pinRef "@baseboard_fab2_lib.baseboard_fab2(sch_1):page87_i186:DQ(44)" )
				( attribute "RELATIVE_PROPAGATION_DELAY_SCOPE" "G"
					( Parent
						( matchGroupRef "@baseboard_fab2_lib.baseboard_fab2(sch_1):\MG_DQ-DQS_FAR_DIMM_NG_M_M_BYTE5\" )
					)
					( Status sCSetFlattened )
					( Origin gBackEnd )
				)
				( attribute "RELATIVE_PROPAGATION_DELAY" "0.00 MIL,195.00 MIL"
					( Parent
						( matchGroupRef "@baseboard_fab2_lib.baseboard_fab2(sch_1):\MG_DQ-DQS_FAR_DIMM_NG_M_M_BYTE5\" )
					)
					( Units "uMatchProp" "ns" 1.000000)
					( Status sCSetFlattened )
					( Origin gBackEnd )
				)
				( attribute "RELATIVE_PROPAGATION_DELAY_SCOPE" "G"
					( Parent
						( matchGroupRef "@baseboard_fab2_lib.baseboard_fab2(sch_1):\MG_DQ_FAR_DIMM_NG_M_M_BYTE5\" )
					)
					( Status sCSetFlattened )
					( Origin gBackEnd )
				)
				( attribute "RELATIVE_PROPAGATION_DELAY" "-50.00 MIL,50.00 MIL"
					( Parent
						( matchGroupRef "@baseboard_fab2_lib.baseboard_fab2(sch_1):\MG_DQ_FAR_DIMM_NG_M_M_BYTE5\" )
					)
					( Units "uMatchProp" "ns" 1.000000)
					( Status sCSetFlattened )
					( Origin gBackEnd )
				)
			)
			( pinPair "@baseboard_fab2_lib.baseboard_fab2(sch_1):\PP1740\"
				( pinRef "@baseboard_fab2_lib.baseboard_fab2(sch_1):page62_i172:DDR5_DQ(45)" )
				( pinRef "@baseboard_fab2_lib.baseboard_fab2(sch_1):page88_i111:DQ(45)" )
				( attribute "RELATIVE_PROPAGATION_DELAY_SCOPE" "G"
					( Parent
						( matchGroupRef "@baseboard_fab2_lib.baseboard_fab2(sch_1):\MG_DQ-DQS_NEAR_DIMM_NG_M_M_BYTE5\" )
					)
					( Status sCSetFlattened )
					( Origin gBackEnd )
				)
				( attribute "RELATIVE_PROPAGATION_DELAY" "0.00 MIL,195.00 MIL"
					( Parent
						( matchGroupRef "@baseboard_fab2_lib.baseboard_fab2(sch_1):\MG_DQ-DQS_NEAR_DIMM_NG_M_M_BYTE5\" )
					)
					( Units "uMatchProp" "ns" 1.000000)
					( Status sCSetFlattened )
					( Origin gBackEnd )
				)
				( attribute "RELATIVE_PROPAGATION_DELAY_SCOPE" "G"
					( Parent
						( matchGroupRef "@crescent_city_bb_fab1_lib.crescent_city_bb_fab1(sch_1):\MG_DQ_NEAR_DIMM_NG_M_M_BYTE5\" )
					)
					( Origin gBackEnd )
				)
				( attribute "RELATIVE_PROPAGATION_DELAY" "TARGET,TARGET"
					( Parent
						( matchGroupRef "@crescent_city_bb_fab1_lib.crescent_city_bb_fab1(sch_1):\MG_DQ_NEAR_DIMM_NG_M_M_BYTE5\" )
					)
					( Units "uMatchProp" "ns" 1.000000)
					( Origin gBackEnd )
				)
			)
			( pinPair "@baseboard_fab2_lib.baseboard_fab2(sch_1):\PP1741\"
				( pinRef "@baseboard_fab2_lib.baseboard_fab2(sch_1):page62_i172:DDR5_DQ(46)" )
				( pinRef "@baseboard_fab2_lib.baseboard_fab2(sch_1):page87_i186:DQ(47)" )
				( attribute "RELATIVE_PROPAGATION_DELAY_SCOPE" "G"
					( Parent
						( matchGroupRef "@baseboard_fab2_lib.baseboard_fab2(sch_1):\MG_DQ-DQS_FAR_DIMM_NG_M_M_BYTE5\" )
					)
					( Status sCSetFlattened )
					( Origin gBackEnd )
				)
				( attribute "RELATIVE_PROPAGATION_DELAY" "0.00 MIL,195.00 MIL"
					( Parent
						( matchGroupRef "@baseboard_fab2_lib.baseboard_fab2(sch_1):\MG_DQ-DQS_FAR_DIMM_NG_M_M_BYTE5\" )
					)
					( Units "uMatchProp" "ns" 1.000000)
					( Status sCSetFlattened )
					( Origin gBackEnd )
				)
				( attribute "RELATIVE_PROPAGATION_DELAY_SCOPE" "G"
					( Parent
						( matchGroupRef "@baseboard_fab2_lib.baseboard_fab2(sch_1):\MG_DQ_FAR_DIMM_NG_M_M_BYTE5\" )
					)
					( Status sCSetFlattened )
					( Origin gBackEnd )
				)
				( attribute "RELATIVE_PROPAGATION_DELAY" "-50.00 MIL,50.00 MIL"
					( Parent
						( matchGroupRef "@baseboard_fab2_lib.baseboard_fab2(sch_1):\MG_DQ_FAR_DIMM_NG_M_M_BYTE5\" )
					)
					( Units "uMatchProp" "ns" 1.000000)
					( Status sCSetFlattened )
					( Origin gBackEnd )
				)
			)
			( pinPair "@baseboard_fab2_lib.baseboard_fab2(sch_1):\PP1743\"
				( pinRef "@baseboard_fab2_lib.baseboard_fab2(sch_1):page62_i172:DDR5_DQ(46)" )
				( pinRef "@baseboard_fab2_lib.baseboard_fab2(sch_1):page88_i111:DQ(46)" )
				( attribute "RELATIVE_PROPAGATION_DELAY_SCOPE" "G"
					( Parent
						( matchGroupRef "@baseboard_fab2_lib.baseboard_fab2(sch_1):\MG_DQ-DQS_NEAR_DIMM_NG_M_M_BYTE5\" )
					)
					( Status sCSetFlattened )
					( Origin gBackEnd )
				)
				( attribute "RELATIVE_PROPAGATION_DELAY" "0.00 MIL,195.00 MIL"
					( Parent
						( matchGroupRef "@baseboard_fab2_lib.baseboard_fab2(sch_1):\MG_DQ-DQS_NEAR_DIMM_NG_M_M_BYTE5\" )
					)
					( Units "uMatchProp" "ns" 1.000000)
					( Status sCSetFlattened )
					( Origin gBackEnd )
				)
				( attribute "RELATIVE_PROPAGATION_DELAY_SCOPE" "G"
					( Parent
						( matchGroupRef "@crescent_city_bb_fab1_lib.crescent_city_bb_fab1(sch_1):\MG_DQ_NEAR_DIMM_NG_M_M_BYTE5\" )
					)
					( Status sCSetFlattened )
					( Origin gBackEnd )
				)
				( attribute "RELATIVE_PROPAGATION_DELAY" "-50.00 MIL,50.00 MIL"
					( Parent
						( matchGroupRef "@crescent_city_bb_fab1_lib.crescent_city_bb_fab1(sch_1):\MG_DQ_NEAR_DIMM_NG_M_M_BYTE5\" )
					)
					( Units "uMatchProp" "ns" 1.000000)
					( Status sCSetFlattened )
					( Origin gBackEnd )
				)
			)
			( pinPair "@baseboard_fab2_lib.baseboard_fab2(sch_1):\PP1744\"
				( pinRef "@baseboard_fab2_lib.baseboard_fab2(sch_1):page62_i172:DDR5_DQ(47)" )
				( pinRef "@baseboard_fab2_lib.baseboard_fab2(sch_1):page87_i186:DQ(46)" )
				( attribute "RELATIVE_PROPAGATION_DELAY_SCOPE" "G"
					( Parent
						( matchGroupRef "@baseboard_fab2_lib.baseboard_fab2(sch_1):\MG_DQ-DQS_FAR_DIMM_NG_M_M_BYTE5\" )
					)
					( Status sCSetFlattened )
					( Origin gBackEnd )
				)
				( attribute "RELATIVE_PROPAGATION_DELAY" "0.00 MIL,195.00 MIL"
					( Parent
						( matchGroupRef "@baseboard_fab2_lib.baseboard_fab2(sch_1):\MG_DQ-DQS_FAR_DIMM_NG_M_M_BYTE5\" )
					)
					( Units "uMatchProp" "ns" 1.000000)
					( Status sCSetFlattened )
					( Origin gBackEnd )
				)
				( attribute "RELATIVE_PROPAGATION_DELAY_SCOPE" "G"
					( Parent
						( matchGroupRef "@baseboard_fab2_lib.baseboard_fab2(sch_1):\MG_DQ_FAR_DIMM_NG_M_M_BYTE5\" )
					)
					( Status sCSetFlattened )
					( Origin gBackEnd )
				)
				( attribute "RELATIVE_PROPAGATION_DELAY" "-50.00 MIL,50.00 MIL"
					( Parent
						( matchGroupRef "@baseboard_fab2_lib.baseboard_fab2(sch_1):\MG_DQ_FAR_DIMM_NG_M_M_BYTE5\" )
					)
					( Units "uMatchProp" "ns" 1.000000)
					( Status sCSetFlattened )
					( Origin gBackEnd )
				)
			)
			( pinPair "@baseboard_fab2_lib.baseboard_fab2(sch_1):\PP1746\"
				( pinRef "@baseboard_fab2_lib.baseboard_fab2(sch_1):page62_i172:DDR5_DQ(47)" )
				( pinRef "@baseboard_fab2_lib.baseboard_fab2(sch_1):page88_i111:DQ(47)" )
				( attribute "RELATIVE_PROPAGATION_DELAY_SCOPE" "G"
					( Parent
						( matchGroupRef "@baseboard_fab2_lib.baseboard_fab2(sch_1):\MG_DQ-DQS_NEAR_DIMM_NG_M_M_BYTE5\" )
					)
					( Status sCSetFlattened )
					( Origin gBackEnd )
				)
				( attribute "RELATIVE_PROPAGATION_DELAY" "0.00 MIL,195.00 MIL"
					( Parent
						( matchGroupRef "@baseboard_fab2_lib.baseboard_fab2(sch_1):\MG_DQ-DQS_NEAR_DIMM_NG_M_M_BYTE5\" )
					)
					( Units "uMatchProp" "ns" 1.000000)
					( Status sCSetFlattened )
					( Origin gBackEnd )
				)
				( attribute "RELATIVE_PROPAGATION_DELAY_SCOPE" "G"
					( Parent
						( matchGroupRef "@crescent_city_bb_fab1_lib.crescent_city_bb_fab1(sch_1):\MG_DQ_NEAR_DIMM_NG_M_M_BYTE5\" )
					)
					( Status sCSetFlattened )
					( Origin gBackEnd )
				)
				( attribute "RELATIVE_PROPAGATION_DELAY" "-50.00 MIL,50.00 MIL"
					( Parent
						( matchGroupRef "@crescent_city_bb_fab1_lib.crescent_city_bb_fab1(sch_1):\MG_DQ_NEAR_DIMM_NG_M_M_BYTE5\" )
					)
					( Units "uMatchProp" "ns" 1.000000)
					( Status sCSetFlattened )
					( Origin gBackEnd )
				)
			)
			( pinPair "@baseboard_fab2_lib.baseboard_fab2(sch_1):\PP1699\"
				( pinRef "@baseboard_fab2_lib.baseboard_fab2(sch_1):page62_i172:DDR5_DQ(48)" )
				( pinRef "@baseboard_fab2_lib.baseboard_fab2(sch_1):page87_i186:DQ(49)" )
				( attribute "RELATIVE_PROPAGATION_DELAY_SCOPE" "G"
					( Parent
						( matchGroupRef "@baseboard_fab2_lib.baseboard_fab2(sch_1):\MG_DQ-DQS_FAR_DIMM_NG_M_M_BYTE6\" )
					)
					( Status sCSetFlattened )
					( Origin gBackEnd )
				)
				( attribute "RELATIVE_PROPAGATION_DELAY" "0.00 MIL,195.00 MIL"
					( Parent
						( matchGroupRef "@baseboard_fab2_lib.baseboard_fab2(sch_1):\MG_DQ-DQS_FAR_DIMM_NG_M_M_BYTE6\" )
					)
					( Units "uMatchProp" "ns" 1.000000)
					( Status sCSetFlattened )
					( Origin gBackEnd )
				)
				( attribute "RELATIVE_PROPAGATION_DELAY_SCOPE" "G"
					( Parent
						( matchGroupRef "@baseboard_fab2_lib.baseboard_fab2(sch_1):\MG_DQ_FAR_DIMM_NG_M_M_BYTE6\" )
					)
					( Status sCSetFlattened )
					( Origin gBackEnd )
				)
				( attribute "RELATIVE_PROPAGATION_DELAY" "-50.00 MIL,50.00 MIL"
					( Parent
						( matchGroupRef "@baseboard_fab2_lib.baseboard_fab2(sch_1):\MG_DQ_FAR_DIMM_NG_M_M_BYTE6\" )
					)
					( Units "uMatchProp" "ns" 1.000000)
					( Status sCSetFlattened )
					( Origin gBackEnd )
				)
			)
			( pinPair "@baseboard_fab2_lib.baseboard_fab2(sch_1):\PP1701\"
				( pinRef "@baseboard_fab2_lib.baseboard_fab2(sch_1):page62_i172:DDR5_DQ(48)" )
				( pinRef "@baseboard_fab2_lib.baseboard_fab2(sch_1):page88_i111:DQ(48)" )
				( attribute "RELATIVE_PROPAGATION_DELAY_SCOPE" "G"
					( Parent
						( matchGroupRef "@baseboard_fab2_lib.baseboard_fab2(sch_1):\MG_DQ-DQS_NEAR_DIMM_NG_M_M_BYTE6\" )
					)
					( Status sCSetFlattened )
					( Origin gBackEnd )
				)
				( attribute "RELATIVE_PROPAGATION_DELAY" "0.00 MIL,195.00 MIL"
					( Parent
						( matchGroupRef "@baseboard_fab2_lib.baseboard_fab2(sch_1):\MG_DQ-DQS_NEAR_DIMM_NG_M_M_BYTE6\" )
					)
					( Units "uMatchProp" "ns" 1.000000)
					( Status sCSetFlattened )
					( Origin gBackEnd )
				)
				( attribute "RELATIVE_PROPAGATION_DELAY_SCOPE" "G"
					( Parent
						( matchGroupRef "@crescent_city_bb_fab1_lib.crescent_city_bb_fab1(sch_1):\MG_DQ_NEAR_DIMM_NG_M_M_BYTE6\" )
					)
					( Status sCSetFlattened )
					( Origin gBackEnd )
				)
				( attribute "RELATIVE_PROPAGATION_DELAY" "-50.00 MIL,50.00 MIL"
					( Parent
						( matchGroupRef "@crescent_city_bb_fab1_lib.crescent_city_bb_fab1(sch_1):\MG_DQ_NEAR_DIMM_NG_M_M_BYTE6\" )
					)
					( Units "uMatchProp" "ns" 1.000000)
					( Status sCSetFlattened )
					( Origin gBackEnd )
				)
			)
			( pinPair "@baseboard_fab2_lib.baseboard_fab2(sch_1):\PP1702\"
				( pinRef "@baseboard_fab2_lib.baseboard_fab2(sch_1):page62_i172:DDR5_DQ(49)" )
				( pinRef "@baseboard_fab2_lib.baseboard_fab2(sch_1):page87_i186:DQ(48)" )
				( attribute "RELATIVE_PROPAGATION_DELAY_SCOPE" "G"
					( Parent
						( matchGroupRef "@baseboard_fab2_lib.baseboard_fab2(sch_1):\MG_DQ-DQS_FAR_DIMM_NG_M_M_BYTE6\" )
					)
					( Status sCSetFlattened )
					( Origin gBackEnd )
				)
				( attribute "RELATIVE_PROPAGATION_DELAY" "0.00 MIL,195.00 MIL"
					( Parent
						( matchGroupRef "@baseboard_fab2_lib.baseboard_fab2(sch_1):\MG_DQ-DQS_FAR_DIMM_NG_M_M_BYTE6\" )
					)
					( Units "uMatchProp" "ns" 1.000000)
					( Status sCSetFlattened )
					( Origin gBackEnd )
				)
				( attribute "RELATIVE_PROPAGATION_DELAY_SCOPE" "G"
					( Parent
						( matchGroupRef "@baseboard_fab2_lib.baseboard_fab2(sch_1):\MG_DQ_FAR_DIMM_NG_M_M_BYTE6\" )
					)
					( Status sCSetFlattened )
					( Origin gBackEnd )
				)
				( attribute "RELATIVE_PROPAGATION_DELAY" "-50.00 MIL,50.00 MIL"
					( Parent
						( matchGroupRef "@baseboard_fab2_lib.baseboard_fab2(sch_1):\MG_DQ_FAR_DIMM_NG_M_M_BYTE6\" )
					)
					( Units "uMatchProp" "ns" 1.000000)
					( Status sCSetFlattened )
					( Origin gBackEnd )
				)
			)
			( pinPair "@baseboard_fab2_lib.baseboard_fab2(sch_1):\PP1704\"
				( pinRef "@baseboard_fab2_lib.baseboard_fab2(sch_1):page62_i172:DDR5_DQ(49)" )
				( pinRef "@baseboard_fab2_lib.baseboard_fab2(sch_1):page88_i111:DQ(49)" )
				( attribute "RELATIVE_PROPAGATION_DELAY_SCOPE" "G"
					( Parent
						( matchGroupRef "@baseboard_fab2_lib.baseboard_fab2(sch_1):\MG_DQ-DQS_NEAR_DIMM_NG_M_M_BYTE6\" )
					)
					( Status sCSetFlattened )
					( Origin gBackEnd )
				)
				( attribute "RELATIVE_PROPAGATION_DELAY" "0.00 MIL,195.00 MIL"
					( Parent
						( matchGroupRef "@baseboard_fab2_lib.baseboard_fab2(sch_1):\MG_DQ-DQS_NEAR_DIMM_NG_M_M_BYTE6\" )
					)
					( Units "uMatchProp" "ns" 1.000000)
					( Status sCSetFlattened )
					( Origin gBackEnd )
				)
				( attribute "RELATIVE_PROPAGATION_DELAY_SCOPE" "G"
					( Parent
						( matchGroupRef "@crescent_city_bb_fab1_lib.crescent_city_bb_fab1(sch_1):\MG_DQ_NEAR_DIMM_NG_M_M_BYTE6\" )
					)
					( Origin gBackEnd )
				)
				( attribute "RELATIVE_PROPAGATION_DELAY" "TARGET,TARGET"
					( Parent
						( matchGroupRef "@crescent_city_bb_fab1_lib.crescent_city_bb_fab1(sch_1):\MG_DQ_NEAR_DIMM_NG_M_M_BYTE6\" )
					)
					( Units "uMatchProp" "ns" 1.000000)
					( Origin gBackEnd )
				)
			)
			( pinPair "@baseboard_fab2_lib.baseboard_fab2(sch_1):\PP1705\"
				( pinRef "@baseboard_fab2_lib.baseboard_fab2(sch_1):page62_i172:DDR5_DQ(50)" )
				( pinRef "@baseboard_fab2_lib.baseboard_fab2(sch_1):page87_i186:DQ(51)" )
				( attribute "RELATIVE_PROPAGATION_DELAY_SCOPE" "G"
					( Parent
						( matchGroupRef "@baseboard_fab2_lib.baseboard_fab2(sch_1):\MG_DQ-DQS_FAR_DIMM_NG_M_M_BYTE6\" )
					)
					( Status sCSetFlattened )
					( Origin gBackEnd )
				)
				( attribute "RELATIVE_PROPAGATION_DELAY" "0.00 MIL,195.00 MIL"
					( Parent
						( matchGroupRef "@baseboard_fab2_lib.baseboard_fab2(sch_1):\MG_DQ-DQS_FAR_DIMM_NG_M_M_BYTE6\" )
					)
					( Units "uMatchProp" "ns" 1.000000)
					( Status sCSetFlattened )
					( Origin gBackEnd )
				)
				( attribute "RELATIVE_PROPAGATION_DELAY_SCOPE" "G"
					( Parent
						( matchGroupRef "@baseboard_fab2_lib.baseboard_fab2(sch_1):\MG_DQ_FAR_DIMM_NG_M_M_BYTE6\" )
					)
					( Status sCSetFlattened )
					( Origin gBackEnd )
				)
				( attribute "RELATIVE_PROPAGATION_DELAY" "-50.00 MIL,50.00 MIL"
					( Parent
						( matchGroupRef "@baseboard_fab2_lib.baseboard_fab2(sch_1):\MG_DQ_FAR_DIMM_NG_M_M_BYTE6\" )
					)
					( Units "uMatchProp" "ns" 1.000000)
					( Status sCSetFlattened )
					( Origin gBackEnd )
				)
			)
			( pinPair "@baseboard_fab2_lib.baseboard_fab2(sch_1):\PP1707\"
				( pinRef "@baseboard_fab2_lib.baseboard_fab2(sch_1):page62_i172:DDR5_DQ(50)" )
				( pinRef "@baseboard_fab2_lib.baseboard_fab2(sch_1):page88_i111:DQ(50)" )
				( attribute "RELATIVE_PROPAGATION_DELAY_SCOPE" "G"
					( Parent
						( matchGroupRef "@baseboard_fab2_lib.baseboard_fab2(sch_1):\MG_DQ-DQS_NEAR_DIMM_NG_M_M_BYTE6\" )
					)
					( Status sCSetFlattened )
					( Origin gBackEnd )
				)
				( attribute "RELATIVE_PROPAGATION_DELAY" "0.00 MIL,195.00 MIL"
					( Parent
						( matchGroupRef "@baseboard_fab2_lib.baseboard_fab2(sch_1):\MG_DQ-DQS_NEAR_DIMM_NG_M_M_BYTE6\" )
					)
					( Units "uMatchProp" "ns" 1.000000)
					( Status sCSetFlattened )
					( Origin gBackEnd )
				)
				( attribute "RELATIVE_PROPAGATION_DELAY_SCOPE" "G"
					( Parent
						( matchGroupRef "@crescent_city_bb_fab1_lib.crescent_city_bb_fab1(sch_1):\MG_DQ_NEAR_DIMM_NG_M_M_BYTE6\" )
					)
					( Status sCSetFlattened )
					( Origin gBackEnd )
				)
				( attribute "RELATIVE_PROPAGATION_DELAY" "-50.00 MIL,50.00 MIL"
					( Parent
						( matchGroupRef "@crescent_city_bb_fab1_lib.crescent_city_bb_fab1(sch_1):\MG_DQ_NEAR_DIMM_NG_M_M_BYTE6\" )
					)
					( Units "uMatchProp" "ns" 1.000000)
					( Status sCSetFlattened )
					( Origin gBackEnd )
				)
			)
			( pinPair "@baseboard_fab2_lib.baseboard_fab2(sch_1):\PP1708\"
				( pinRef "@baseboard_fab2_lib.baseboard_fab2(sch_1):page62_i172:DDR5_DQ(51)" )
				( pinRef "@baseboard_fab2_lib.baseboard_fab2(sch_1):page87_i186:DQ(50)" )
				( attribute "RELATIVE_PROPAGATION_DELAY_SCOPE" "G"
					( Parent
						( matchGroupRef "@baseboard_fab2_lib.baseboard_fab2(sch_1):\MG_DQ-DQS_FAR_DIMM_NG_M_M_BYTE6\" )
					)
					( Status sCSetFlattened )
					( Origin gBackEnd )
				)
				( attribute "RELATIVE_PROPAGATION_DELAY" "0.00 MIL,195.00 MIL"
					( Parent
						( matchGroupRef "@baseboard_fab2_lib.baseboard_fab2(sch_1):\MG_DQ-DQS_FAR_DIMM_NG_M_M_BYTE6\" )
					)
					( Units "uMatchProp" "ns" 1.000000)
					( Status sCSetFlattened )
					( Origin gBackEnd )
				)
				( attribute "RELATIVE_PROPAGATION_DELAY_SCOPE" "G"
					( Parent
						( matchGroupRef "@baseboard_fab2_lib.baseboard_fab2(sch_1):\MG_DQ_FAR_DIMM_NG_M_M_BYTE6\" )
					)
					( Status sCSetFlattened )
					( Origin gBackEnd )
				)
				( attribute "RELATIVE_PROPAGATION_DELAY" "-50.00 MIL,50.00 MIL"
					( Parent
						( matchGroupRef "@baseboard_fab2_lib.baseboard_fab2(sch_1):\MG_DQ_FAR_DIMM_NG_M_M_BYTE6\" )
					)
					( Units "uMatchProp" "ns" 1.000000)
					( Status sCSetFlattened )
					( Origin gBackEnd )
				)
			)
			( pinPair "@baseboard_fab2_lib.baseboard_fab2(sch_1):\PP1710\"
				( pinRef "@baseboard_fab2_lib.baseboard_fab2(sch_1):page62_i172:DDR5_DQ(51)" )
				( pinRef "@baseboard_fab2_lib.baseboard_fab2(sch_1):page88_i111:DQ(51)" )
				( attribute "RELATIVE_PROPAGATION_DELAY_SCOPE" "G"
					( Parent
						( matchGroupRef "@baseboard_fab2_lib.baseboard_fab2(sch_1):\MG_DQ-DQS_NEAR_DIMM_NG_M_M_BYTE6\" )
					)
					( Status sCSetFlattened )
					( Origin gBackEnd )
				)
				( attribute "RELATIVE_PROPAGATION_DELAY" "0.00 MIL,195.00 MIL"
					( Parent
						( matchGroupRef "@baseboard_fab2_lib.baseboard_fab2(sch_1):\MG_DQ-DQS_NEAR_DIMM_NG_M_M_BYTE6\" )
					)
					( Units "uMatchProp" "ns" 1.000000)
					( Status sCSetFlattened )
					( Origin gBackEnd )
				)
				( attribute "RELATIVE_PROPAGATION_DELAY_SCOPE" "G"
					( Parent
						( matchGroupRef "@crescent_city_bb_fab1_lib.crescent_city_bb_fab1(sch_1):\MG_DQ_NEAR_DIMM_NG_M_M_BYTE6\" )
					)
					( Status sCSetFlattened )
					( Origin gBackEnd )
				)
				( attribute "RELATIVE_PROPAGATION_DELAY" "-50.00 MIL,50.00 MIL"
					( Parent
						( matchGroupRef "@crescent_city_bb_fab1_lib.crescent_city_bb_fab1(sch_1):\MG_DQ_NEAR_DIMM_NG_M_M_BYTE6\" )
					)
					( Units "uMatchProp" "ns" 1.000000)
					( Status sCSetFlattened )
					( Origin gBackEnd )
				)
			)
			( pinPair "@baseboard_fab2_lib.baseboard_fab2(sch_1):\PP1711\"
				( pinRef "@baseboard_fab2_lib.baseboard_fab2(sch_1):page62_i172:DDR5_DQ(52)" )
				( pinRef "@baseboard_fab2_lib.baseboard_fab2(sch_1):page87_i186:DQ(53)" )
				( attribute "RELATIVE_PROPAGATION_DELAY_SCOPE" "G"
					( Parent
						( matchGroupRef "@baseboard_fab2_lib.baseboard_fab2(sch_1):\MG_DQ-DQS_FAR_DIMM_NG_M_M_BYTE6\" )
					)
					( Status sCSetFlattened )
					( Origin gBackEnd )
				)
				( attribute "RELATIVE_PROPAGATION_DELAY" "0.00 MIL,195.00 MIL"
					( Parent
						( matchGroupRef "@baseboard_fab2_lib.baseboard_fab2(sch_1):\MG_DQ-DQS_FAR_DIMM_NG_M_M_BYTE6\" )
					)
					( Units "uMatchProp" "ns" 1.000000)
					( Status sCSetFlattened )
					( Origin gBackEnd )
				)
				( attribute "RELATIVE_PROPAGATION_DELAY_SCOPE" "G"
					( Parent
						( matchGroupRef "@baseboard_fab2_lib.baseboard_fab2(sch_1):\MG_DQ_FAR_DIMM_NG_M_M_BYTE6\" )
					)
					( Status sCSetFlattened )
					( Origin gBackEnd )
				)
				( attribute "RELATIVE_PROPAGATION_DELAY" "-50.00 MIL,50.00 MIL"
					( Parent
						( matchGroupRef "@baseboard_fab2_lib.baseboard_fab2(sch_1):\MG_DQ_FAR_DIMM_NG_M_M_BYTE6\" )
					)
					( Units "uMatchProp" "ns" 1.000000)
					( Status sCSetFlattened )
					( Origin gBackEnd )
				)
			)
			( pinPair "@baseboard_fab2_lib.baseboard_fab2(sch_1):\PP1713\"
				( pinRef "@baseboard_fab2_lib.baseboard_fab2(sch_1):page62_i172:DDR5_DQ(52)" )
				( pinRef "@baseboard_fab2_lib.baseboard_fab2(sch_1):page88_i111:DQ(52)" )
				( attribute "RELATIVE_PROPAGATION_DELAY_SCOPE" "G"
					( Parent
						( matchGroupRef "@baseboard_fab2_lib.baseboard_fab2(sch_1):\MG_DQ-DQS_NEAR_DIMM_NG_M_M_BYTE6\" )
					)
					( Status sCSetFlattened )
					( Origin gBackEnd )
				)
				( attribute "RELATIVE_PROPAGATION_DELAY" "0.00 MIL,195.00 MIL"
					( Parent
						( matchGroupRef "@baseboard_fab2_lib.baseboard_fab2(sch_1):\MG_DQ-DQS_NEAR_DIMM_NG_M_M_BYTE6\" )
					)
					( Units "uMatchProp" "ns" 1.000000)
					( Status sCSetFlattened )
					( Origin gBackEnd )
				)
				( attribute "RELATIVE_PROPAGATION_DELAY_SCOPE" "G"
					( Parent
						( matchGroupRef "@crescent_city_bb_fab1_lib.crescent_city_bb_fab1(sch_1):\MG_DQ_NEAR_DIMM_NG_M_M_BYTE6\" )
					)
					( Status sCSetFlattened )
					( Origin gBackEnd )
				)
				( attribute "RELATIVE_PROPAGATION_DELAY" "-50.00 MIL,50.00 MIL"
					( Parent
						( matchGroupRef "@crescent_city_bb_fab1_lib.crescent_city_bb_fab1(sch_1):\MG_DQ_NEAR_DIMM_NG_M_M_BYTE6\" )
					)
					( Units "uMatchProp" "ns" 1.000000)
					( Status sCSetFlattened )
					( Origin gBackEnd )
				)
			)
			( pinPair "@baseboard_fab2_lib.baseboard_fab2(sch_1):\PP1714\"
				( pinRef "@baseboard_fab2_lib.baseboard_fab2(sch_1):page62_i172:DDR5_DQ(53)" )
				( pinRef "@baseboard_fab2_lib.baseboard_fab2(sch_1):page87_i186:DQ(52)" )
				( attribute "RELATIVE_PROPAGATION_DELAY_SCOPE" "G"
					( Parent
						( matchGroupRef "@baseboard_fab2_lib.baseboard_fab2(sch_1):\MG_DQ-DQS_FAR_DIMM_NG_M_M_BYTE6\" )
					)
					( Status sCSetFlattened )
					( Origin gBackEnd )
				)
				( attribute "RELATIVE_PROPAGATION_DELAY" "0.00 MIL,195.00 MIL"
					( Parent
						( matchGroupRef "@baseboard_fab2_lib.baseboard_fab2(sch_1):\MG_DQ-DQS_FAR_DIMM_NG_M_M_BYTE6\" )
					)
					( Units "uMatchProp" "ns" 1.000000)
					( Status sCSetFlattened )
					( Origin gBackEnd )
				)
				( attribute "RELATIVE_PROPAGATION_DELAY_SCOPE" "G"
					( Parent
						( matchGroupRef "@baseboard_fab2_lib.baseboard_fab2(sch_1):\MG_DQ_FAR_DIMM_NG_M_M_BYTE6\" )
					)
					( Status sCSetFlattened )
					( Origin gBackEnd )
				)
				( attribute "RELATIVE_PROPAGATION_DELAY" "-50.00 MIL,50.00 MIL"
					( Parent
						( matchGroupRef "@baseboard_fab2_lib.baseboard_fab2(sch_1):\MG_DQ_FAR_DIMM_NG_M_M_BYTE6\" )
					)
					( Units "uMatchProp" "ns" 1.000000)
					( Status sCSetFlattened )
					( Origin gBackEnd )
				)
			)
			( pinPair "@baseboard_fab2_lib.baseboard_fab2(sch_1):\PP1716\"
				( pinRef "@baseboard_fab2_lib.baseboard_fab2(sch_1):page62_i172:DDR5_DQ(53)" )
				( pinRef "@baseboard_fab2_lib.baseboard_fab2(sch_1):page88_i111:DQ(53)" )
				( attribute "RELATIVE_PROPAGATION_DELAY_SCOPE" "G"
					( Parent
						( matchGroupRef "@baseboard_fab2_lib.baseboard_fab2(sch_1):\MG_DQ-DQS_NEAR_DIMM_NG_M_M_BYTE6\" )
					)
					( Status sCSetFlattened )
					( Origin gBackEnd )
				)
				( attribute "RELATIVE_PROPAGATION_DELAY" "0.00 MIL,195.00 MIL"
					( Parent
						( matchGroupRef "@baseboard_fab2_lib.baseboard_fab2(sch_1):\MG_DQ-DQS_NEAR_DIMM_NG_M_M_BYTE6\" )
					)
					( Units "uMatchProp" "ns" 1.000000)
					( Status sCSetFlattened )
					( Origin gBackEnd )
				)
				( attribute "RELATIVE_PROPAGATION_DELAY_SCOPE" "G"
					( Parent
						( matchGroupRef "@crescent_city_bb_fab1_lib.crescent_city_bb_fab1(sch_1):\MG_DQ_NEAR_DIMM_NG_M_M_BYTE6\" )
					)
					( Status sCSetFlattened )
					( Origin gBackEnd )
				)
				( attribute "RELATIVE_PROPAGATION_DELAY" "-50.00 MIL,50.00 MIL"
					( Parent
						( matchGroupRef "@crescent_city_bb_fab1_lib.crescent_city_bb_fab1(sch_1):\MG_DQ_NEAR_DIMM_NG_M_M_BYTE6\" )
					)
					( Units "uMatchProp" "ns" 1.000000)
					( Status sCSetFlattened )
					( Origin gBackEnd )
				)
			)
			( pinPair "@baseboard_fab2_lib.baseboard_fab2(sch_1):\PP1717\"
				( pinRef "@baseboard_fab2_lib.baseboard_fab2(sch_1):page62_i172:DDR5_DQ(54)" )
				( pinRef "@baseboard_fab2_lib.baseboard_fab2(sch_1):page87_i186:DQ(55)" )
				( attribute "RELATIVE_PROPAGATION_DELAY_SCOPE" "G"
					( Parent
						( matchGroupRef "@baseboard_fab2_lib.baseboard_fab2(sch_1):\MG_DQ-DQS_FAR_DIMM_NG_M_M_BYTE6\" )
					)
					( Status sCSetFlattened )
					( Origin gBackEnd )
				)
				( attribute "RELATIVE_PROPAGATION_DELAY" "0.00 MIL,195.00 MIL"
					( Parent
						( matchGroupRef "@baseboard_fab2_lib.baseboard_fab2(sch_1):\MG_DQ-DQS_FAR_DIMM_NG_M_M_BYTE6\" )
					)
					( Units "uMatchProp" "ns" 1.000000)
					( Status sCSetFlattened )
					( Origin gBackEnd )
				)
				( attribute "RELATIVE_PROPAGATION_DELAY_SCOPE" "G"
					( Parent
						( matchGroupRef "@baseboard_fab2_lib.baseboard_fab2(sch_1):\MG_DQ_FAR_DIMM_NG_M_M_BYTE6\" )
					)
					( Status sCSetFlattened )
					( Origin gBackEnd )
				)
				( attribute "RELATIVE_PROPAGATION_DELAY" "-50.00 MIL,50.00 MIL"
					( Parent
						( matchGroupRef "@baseboard_fab2_lib.baseboard_fab2(sch_1):\MG_DQ_FAR_DIMM_NG_M_M_BYTE6\" )
					)
					( Units "uMatchProp" "ns" 1.000000)
					( Status sCSetFlattened )
					( Origin gBackEnd )
				)
			)
			( pinPair "@baseboard_fab2_lib.baseboard_fab2(sch_1):\PP1719\"
				( pinRef "@baseboard_fab2_lib.baseboard_fab2(sch_1):page62_i172:DDR5_DQ(54)" )
				( pinRef "@baseboard_fab2_lib.baseboard_fab2(sch_1):page88_i111:DQ(54)" )
				( attribute "RELATIVE_PROPAGATION_DELAY_SCOPE" "G"
					( Parent
						( matchGroupRef "@baseboard_fab2_lib.baseboard_fab2(sch_1):\MG_DQ-DQS_NEAR_DIMM_NG_M_M_BYTE6\" )
					)
					( Status sCSetFlattened )
					( Origin gBackEnd )
				)
				( attribute "RELATIVE_PROPAGATION_DELAY" "0.00 MIL,195.00 MIL"
					( Parent
						( matchGroupRef "@baseboard_fab2_lib.baseboard_fab2(sch_1):\MG_DQ-DQS_NEAR_DIMM_NG_M_M_BYTE6\" )
					)
					( Units "uMatchProp" "ns" 1.000000)
					( Status sCSetFlattened )
					( Origin gBackEnd )
				)
				( attribute "RELATIVE_PROPAGATION_DELAY_SCOPE" "G"
					( Parent
						( matchGroupRef "@crescent_city_bb_fab1_lib.crescent_city_bb_fab1(sch_1):\MG_DQ_NEAR_DIMM_NG_M_M_BYTE6\" )
					)
					( Status sCSetFlattened )
					( Origin gBackEnd )
				)
				( attribute "RELATIVE_PROPAGATION_DELAY" "-50.00 MIL,50.00 MIL"
					( Parent
						( matchGroupRef "@crescent_city_bb_fab1_lib.crescent_city_bb_fab1(sch_1):\MG_DQ_NEAR_DIMM_NG_M_M_BYTE6\" )
					)
					( Units "uMatchProp" "ns" 1.000000)
					( Status sCSetFlattened )
					( Origin gBackEnd )
				)
			)
			( pinPair "@baseboard_fab2_lib.baseboard_fab2(sch_1):\PP1720\"
				( pinRef "@baseboard_fab2_lib.baseboard_fab2(sch_1):page62_i172:DDR5_DQ(55)" )
				( pinRef "@baseboard_fab2_lib.baseboard_fab2(sch_1):page87_i186:DQ(54)" )
				( attribute "RELATIVE_PROPAGATION_DELAY_SCOPE" "G"
					( Parent
						( matchGroupRef "@baseboard_fab2_lib.baseboard_fab2(sch_1):\MG_DQ-DQS_FAR_DIMM_NG_M_M_BYTE6\" )
					)
					( Status sCSetFlattened )
					( Origin gBackEnd )
				)
				( attribute "RELATIVE_PROPAGATION_DELAY" "0.00 MIL,195.00 MIL"
					( Parent
						( matchGroupRef "@baseboard_fab2_lib.baseboard_fab2(sch_1):\MG_DQ-DQS_FAR_DIMM_NG_M_M_BYTE6\" )
					)
					( Units "uMatchProp" "ns" 1.000000)
					( Status sCSetFlattened )
					( Origin gBackEnd )
				)
				( attribute "RELATIVE_PROPAGATION_DELAY_SCOPE" "G"
					( Parent
						( matchGroupRef "@baseboard_fab2_lib.baseboard_fab2(sch_1):\MG_DQ_FAR_DIMM_NG_M_M_BYTE6\" )
					)
					( Status sCSetFlattened )
					( Origin gBackEnd )
				)
				( attribute "RELATIVE_PROPAGATION_DELAY" "-50.00 MIL,50.00 MIL"
					( Parent
						( matchGroupRef "@baseboard_fab2_lib.baseboard_fab2(sch_1):\MG_DQ_FAR_DIMM_NG_M_M_BYTE6\" )
					)
					( Units "uMatchProp" "ns" 1.000000)
					( Status sCSetFlattened )
					( Origin gBackEnd )
				)
			)
			( pinPair "@baseboard_fab2_lib.baseboard_fab2(sch_1):\PP1722\"
				( pinRef "@baseboard_fab2_lib.baseboard_fab2(sch_1):page62_i172:DDR5_DQ(55)" )
				( pinRef "@baseboard_fab2_lib.baseboard_fab2(sch_1):page88_i111:DQ(55)" )
				( attribute "RELATIVE_PROPAGATION_DELAY_SCOPE" "G"
					( Parent
						( matchGroupRef "@baseboard_fab2_lib.baseboard_fab2(sch_1):\MG_DQ-DQS_NEAR_DIMM_NG_M_M_BYTE6\" )
					)
					( Status sCSetFlattened )
					( Origin gBackEnd )
				)
				( attribute "RELATIVE_PROPAGATION_DELAY" "0.00 MIL,195.00 MIL"
					( Parent
						( matchGroupRef "@baseboard_fab2_lib.baseboard_fab2(sch_1):\MG_DQ-DQS_NEAR_DIMM_NG_M_M_BYTE6\" )
					)
					( Units "uMatchProp" "ns" 1.000000)
					( Status sCSetFlattened )
					( Origin gBackEnd )
				)
				( attribute "RELATIVE_PROPAGATION_DELAY_SCOPE" "G"
					( Parent
						( matchGroupRef "@crescent_city_bb_fab1_lib.crescent_city_bb_fab1(sch_1):\MG_DQ_NEAR_DIMM_NG_M_M_BYTE6\" )
					)
					( Status sCSetFlattened )
					( Origin gBackEnd )
				)
				( attribute "RELATIVE_PROPAGATION_DELAY" "-50.00 MIL,50.00 MIL"
					( Parent
						( matchGroupRef "@crescent_city_bb_fab1_lib.crescent_city_bb_fab1(sch_1):\MG_DQ_NEAR_DIMM_NG_M_M_BYTE6\" )
					)
					( Units "uMatchProp" "ns" 1.000000)
					( Status sCSetFlattened )
					( Origin gBackEnd )
				)
			)
			( pinPair "@baseboard_fab2_lib.baseboard_fab2(sch_1):\PP1675\"
				( pinRef "@baseboard_fab2_lib.baseboard_fab2(sch_1):page62_i172:DDR5_DQ(56)" )
				( pinRef "@baseboard_fab2_lib.baseboard_fab2(sch_1):page87_i186:DQ(57)" )
				( attribute "RELATIVE_PROPAGATION_DELAY_SCOPE" "G"
					( Parent
						( matchGroupRef "@baseboard_fab2_lib.baseboard_fab2(sch_1):\MG_DQ-DQS_FAR_DIMM_NG_M_M_BYTE7\" )
					)
					( Status sCSetFlattened )
					( Origin gBackEnd )
				)
				( attribute "RELATIVE_PROPAGATION_DELAY" "0.00 MIL,195.00 MIL"
					( Parent
						( matchGroupRef "@baseboard_fab2_lib.baseboard_fab2(sch_1):\MG_DQ-DQS_FAR_DIMM_NG_M_M_BYTE7\" )
					)
					( Units "uMatchProp" "ns" 1.000000)
					( Status sCSetFlattened )
					( Origin gBackEnd )
				)
				( attribute "RELATIVE_PROPAGATION_DELAY_SCOPE" "G"
					( Parent
						( matchGroupRef "@crescent_city_bb_fab1_lib.crescent_city_bb_fab1(sch_1):\MG_DQ_FAR_DIMM_NG_M_M_BYTE7\" )
					)
					( Status sCSetFlattened )
					( Origin gBackEnd )
				)
				( attribute "RELATIVE_PROPAGATION_DELAY" "-50.00 MIL,50.00 MIL"
					( Parent
						( matchGroupRef "@crescent_city_bb_fab1_lib.crescent_city_bb_fab1(sch_1):\MG_DQ_FAR_DIMM_NG_M_M_BYTE7\" )
					)
					( Units "uMatchProp" "ns" 1.000000)
					( Status sCSetFlattened )
					( Origin gBackEnd )
				)
			)
			( pinPair "@baseboard_fab2_lib.baseboard_fab2(sch_1):\PP1677\"
				( pinRef "@baseboard_fab2_lib.baseboard_fab2(sch_1):page62_i172:DDR5_DQ(56)" )
				( pinRef "@baseboard_fab2_lib.baseboard_fab2(sch_1):page88_i111:DQ(56)" )
				( attribute "RELATIVE_PROPAGATION_DELAY_SCOPE" "G"
					( Parent
						( matchGroupRef "@baseboard_fab2_lib.baseboard_fab2(sch_1):\MG_DQ-DQS_NEAR_DIMM_NG_M_M_BYTE7\" )
					)
					( Status sCSetFlattened )
					( Origin gBackEnd )
				)
				( attribute "RELATIVE_PROPAGATION_DELAY" "0.00 MIL,195.00 MIL"
					( Parent
						( matchGroupRef "@baseboard_fab2_lib.baseboard_fab2(sch_1):\MG_DQ-DQS_NEAR_DIMM_NG_M_M_BYTE7\" )
					)
					( Units "uMatchProp" "ns" 1.000000)
					( Status sCSetFlattened )
					( Origin gBackEnd )
				)
				( attribute "RELATIVE_PROPAGATION_DELAY_SCOPE" "G"
					( Parent
						( matchGroupRef "@crescent_city_bb_fab1_lib.crescent_city_bb_fab1(sch_1):\MG_DQ_NEAR_DIMM_NG_M_M_BYTE7\" )
					)
					( Status sCSetFlattened )
					( Origin gBackEnd )
				)
				( attribute "RELATIVE_PROPAGATION_DELAY" "-50.00 MIL,50.00 MIL"
					( Parent
						( matchGroupRef "@crescent_city_bb_fab1_lib.crescent_city_bb_fab1(sch_1):\MG_DQ_NEAR_DIMM_NG_M_M_BYTE7\" )
					)
					( Units "uMatchProp" "ns" 1.000000)
					( Status sCSetFlattened )
					( Origin gBackEnd )
				)
			)
			( pinPair "@baseboard_fab2_lib.baseboard_fab2(sch_1):\PP1678\"
				( pinRef "@baseboard_fab2_lib.baseboard_fab2(sch_1):page62_i172:DDR5_DQ(57)" )
				( pinRef "@baseboard_fab2_lib.baseboard_fab2(sch_1):page87_i186:DQ(56)" )
				( attribute "RELATIVE_PROPAGATION_DELAY_SCOPE" "G"
					( Parent
						( matchGroupRef "@baseboard_fab2_lib.baseboard_fab2(sch_1):\MG_DQ-DQS_FAR_DIMM_NG_M_M_BYTE7\" )
					)
					( Status sCSetFlattened )
					( Origin gBackEnd )
				)
				( attribute "RELATIVE_PROPAGATION_DELAY" "0.00 MIL,195.00 MIL"
					( Parent
						( matchGroupRef "@baseboard_fab2_lib.baseboard_fab2(sch_1):\MG_DQ-DQS_FAR_DIMM_NG_M_M_BYTE7\" )
					)
					( Units "uMatchProp" "ns" 1.000000)
					( Status sCSetFlattened )
					( Origin gBackEnd )
				)
				( attribute "RELATIVE_PROPAGATION_DELAY_SCOPE" "G"
					( Parent
						( matchGroupRef "@crescent_city_bb_fab1_lib.crescent_city_bb_fab1(sch_1):\MG_DQ_FAR_DIMM_NG_M_M_BYTE7\" )
					)
					( Status sCSetFlattened )
					( Origin gBackEnd )
				)
				( attribute "RELATIVE_PROPAGATION_DELAY" "-50.00 MIL,50.00 MIL"
					( Parent
						( matchGroupRef "@crescent_city_bb_fab1_lib.crescent_city_bb_fab1(sch_1):\MG_DQ_FAR_DIMM_NG_M_M_BYTE7\" )
					)
					( Units "uMatchProp" "ns" 1.000000)
					( Status sCSetFlattened )
					( Origin gBackEnd )
				)
			)
			( pinPair "@baseboard_fab2_lib.baseboard_fab2(sch_1):\PP1680\"
				( pinRef "@baseboard_fab2_lib.baseboard_fab2(sch_1):page62_i172:DDR5_DQ(57)" )
				( pinRef "@baseboard_fab2_lib.baseboard_fab2(sch_1):page88_i111:DQ(57)" )
				( attribute "RELATIVE_PROPAGATION_DELAY_SCOPE" "G"
					( Parent
						( matchGroupRef "@baseboard_fab2_lib.baseboard_fab2(sch_1):\MG_DQ-DQS_NEAR_DIMM_NG_M_M_BYTE7\" )
					)
					( Status sCSetFlattened )
					( Origin gBackEnd )
				)
				( attribute "RELATIVE_PROPAGATION_DELAY" "0.00 MIL,195.00 MIL"
					( Parent
						( matchGroupRef "@baseboard_fab2_lib.baseboard_fab2(sch_1):\MG_DQ-DQS_NEAR_DIMM_NG_M_M_BYTE7\" )
					)
					( Units "uMatchProp" "ns" 1.000000)
					( Status sCSetFlattened )
					( Origin gBackEnd )
				)
				( attribute "RELATIVE_PROPAGATION_DELAY_SCOPE" "G"
					( Parent
						( matchGroupRef "@crescent_city_bb_fab1_lib.crescent_city_bb_fab1(sch_1):\MG_DQ_NEAR_DIMM_NG_M_M_BYTE7\" )
					)
					( Status sCSetFlattened )
					( Origin gBackEnd )
				)
				( attribute "RELATIVE_PROPAGATION_DELAY" "-50.00 MIL,50.00 MIL"
					( Parent
						( matchGroupRef "@crescent_city_bb_fab1_lib.crescent_city_bb_fab1(sch_1):\MG_DQ_NEAR_DIMM_NG_M_M_BYTE7\" )
					)
					( Units "uMatchProp" "ns" 1.000000)
					( Status sCSetFlattened )
					( Origin gBackEnd )
				)
			)
			( pinPair "@baseboard_fab2_lib.baseboard_fab2(sch_1):\PP1681\"
				( pinRef "@baseboard_fab2_lib.baseboard_fab2(sch_1):page62_i172:DDR5_DQ(58)" )
				( pinRef "@baseboard_fab2_lib.baseboard_fab2(sch_1):page87_i186:DQ(59)" )
				( attribute "RELATIVE_PROPAGATION_DELAY_SCOPE" "G"
					( Parent
						( matchGroupRef "@baseboard_fab2_lib.baseboard_fab2(sch_1):\MG_DQ-DQS_FAR_DIMM_NG_M_M_BYTE7\" )
					)
					( Status sCSetFlattened )
					( Origin gBackEnd )
				)
				( attribute "RELATIVE_PROPAGATION_DELAY" "0.00 MIL,195.00 MIL"
					( Parent
						( matchGroupRef "@baseboard_fab2_lib.baseboard_fab2(sch_1):\MG_DQ-DQS_FAR_DIMM_NG_M_M_BYTE7\" )
					)
					( Units "uMatchProp" "ns" 1.000000)
					( Status sCSetFlattened )
					( Origin gBackEnd )
				)
				( attribute "RELATIVE_PROPAGATION_DELAY_SCOPE" "G"
					( Parent
						( matchGroupRef "@crescent_city_bb_fab1_lib.crescent_city_bb_fab1(sch_1):\MG_DQ_FAR_DIMM_NG_M_M_BYTE7\" )
					)
					( Status sCSetFlattened )
					( Origin gBackEnd )
				)
				( attribute "RELATIVE_PROPAGATION_DELAY" "-50.00 MIL,50.00 MIL"
					( Parent
						( matchGroupRef "@crescent_city_bb_fab1_lib.crescent_city_bb_fab1(sch_1):\MG_DQ_FAR_DIMM_NG_M_M_BYTE7\" )
					)
					( Units "uMatchProp" "ns" 1.000000)
					( Status sCSetFlattened )
					( Origin gBackEnd )
				)
			)
			( pinPair "@baseboard_fab2_lib.baseboard_fab2(sch_1):\PP1683\"
				( pinRef "@baseboard_fab2_lib.baseboard_fab2(sch_1):page62_i172:DDR5_DQ(58)" )
				( pinRef "@baseboard_fab2_lib.baseboard_fab2(sch_1):page88_i111:DQ(58)" )
				( attribute "RELATIVE_PROPAGATION_DELAY_SCOPE" "G"
					( Parent
						( matchGroupRef "@baseboard_fab2_lib.baseboard_fab2(sch_1):\MG_DQ-DQS_NEAR_DIMM_NG_M_M_BYTE7\" )
					)
					( Status sCSetFlattened )
					( Origin gBackEnd )
				)
				( attribute "RELATIVE_PROPAGATION_DELAY" "0.00 MIL,195.00 MIL"
					( Parent
						( matchGroupRef "@baseboard_fab2_lib.baseboard_fab2(sch_1):\MG_DQ-DQS_NEAR_DIMM_NG_M_M_BYTE7\" )
					)
					( Units "uMatchProp" "ns" 1.000000)
					( Status sCSetFlattened )
					( Origin gBackEnd )
				)
				( attribute "RELATIVE_PROPAGATION_DELAY_SCOPE" "G"
					( Parent
						( matchGroupRef "@crescent_city_bb_fab1_lib.crescent_city_bb_fab1(sch_1):\MG_DQ_NEAR_DIMM_NG_M_M_BYTE7\" )
					)
					( Status sCSetFlattened )
					( Origin gBackEnd )
				)
				( attribute "RELATIVE_PROPAGATION_DELAY" "-50.00 MIL,50.00 MIL"
					( Parent
						( matchGroupRef "@crescent_city_bb_fab1_lib.crescent_city_bb_fab1(sch_1):\MG_DQ_NEAR_DIMM_NG_M_M_BYTE7\" )
					)
					( Units "uMatchProp" "ns" 1.000000)
					( Status sCSetFlattened )
					( Origin gBackEnd )
				)
			)
			( pinPair "@baseboard_fab2_lib.baseboard_fab2(sch_1):\PP1684\"
				( pinRef "@baseboard_fab2_lib.baseboard_fab2(sch_1):page62_i172:DDR5_DQ(59)" )
				( pinRef "@baseboard_fab2_lib.baseboard_fab2(sch_1):page87_i186:DQ(58)" )
				( attribute "RELATIVE_PROPAGATION_DELAY_SCOPE" "G"
					( Parent
						( matchGroupRef "@baseboard_fab2_lib.baseboard_fab2(sch_1):\MG_DQ-DQS_FAR_DIMM_NG_M_M_BYTE7\" )
					)
					( Status sCSetFlattened )
					( Origin gBackEnd )
				)
				( attribute "RELATIVE_PROPAGATION_DELAY" "0.00 MIL,195.00 MIL"
					( Parent
						( matchGroupRef "@baseboard_fab2_lib.baseboard_fab2(sch_1):\MG_DQ-DQS_FAR_DIMM_NG_M_M_BYTE7\" )
					)
					( Units "uMatchProp" "ns" 1.000000)
					( Status sCSetFlattened )
					( Origin gBackEnd )
				)
				( attribute "RELATIVE_PROPAGATION_DELAY_SCOPE" "G"
					( Parent
						( matchGroupRef "@crescent_city_bb_fab1_lib.crescent_city_bb_fab1(sch_1):\MG_DQ_FAR_DIMM_NG_M_M_BYTE7\" )
					)
					( Status sCSetFlattened )
					( Origin gBackEnd )
				)
				( attribute "RELATIVE_PROPAGATION_DELAY" "-50.00 MIL,50.00 MIL"
					( Parent
						( matchGroupRef "@crescent_city_bb_fab1_lib.crescent_city_bb_fab1(sch_1):\MG_DQ_FAR_DIMM_NG_M_M_BYTE7\" )
					)
					( Units "uMatchProp" "ns" 1.000000)
					( Status sCSetFlattened )
					( Origin gBackEnd )
				)
			)
			( pinPair "@baseboard_fab2_lib.baseboard_fab2(sch_1):\PP1686\"
				( pinRef "@baseboard_fab2_lib.baseboard_fab2(sch_1):page62_i172:DDR5_DQ(59)" )
				( pinRef "@baseboard_fab2_lib.baseboard_fab2(sch_1):page88_i111:DQ(59)" )
				( attribute "RELATIVE_PROPAGATION_DELAY_SCOPE" "G"
					( Parent
						( matchGroupRef "@baseboard_fab2_lib.baseboard_fab2(sch_1):\MG_DQ-DQS_NEAR_DIMM_NG_M_M_BYTE7\" )
					)
					( Status sCSetFlattened )
					( Origin gBackEnd )
				)
				( attribute "RELATIVE_PROPAGATION_DELAY" "0.00 MIL,195.00 MIL"
					( Parent
						( matchGroupRef "@baseboard_fab2_lib.baseboard_fab2(sch_1):\MG_DQ-DQS_NEAR_DIMM_NG_M_M_BYTE7\" )
					)
					( Units "uMatchProp" "ns" 1.000000)
					( Status sCSetFlattened )
					( Origin gBackEnd )
				)
				( attribute "RELATIVE_PROPAGATION_DELAY_SCOPE" "G"
					( Parent
						( matchGroupRef "@crescent_city_bb_fab1_lib.crescent_city_bb_fab1(sch_1):\MG_DQ_NEAR_DIMM_NG_M_M_BYTE7\" )
					)
					( Status sCSetFlattened )
					( Origin gBackEnd )
				)
				( attribute "RELATIVE_PROPAGATION_DELAY" "-50.00 MIL,50.00 MIL"
					( Parent
						( matchGroupRef "@crescent_city_bb_fab1_lib.crescent_city_bb_fab1(sch_1):\MG_DQ_NEAR_DIMM_NG_M_M_BYTE7\" )
					)
					( Units "uMatchProp" "ns" 1.000000)
					( Status sCSetFlattened )
					( Origin gBackEnd )
				)
			)
			( pinPair "@baseboard_fab2_lib.baseboard_fab2(sch_1):\PP1687\"
				( pinRef "@baseboard_fab2_lib.baseboard_fab2(sch_1):page62_i172:DDR5_DQ(60)" )
				( pinRef "@baseboard_fab2_lib.baseboard_fab2(sch_1):page87_i186:DQ(61)" )
				( attribute "RELATIVE_PROPAGATION_DELAY_SCOPE" "G"
					( Parent
						( matchGroupRef "@baseboard_fab2_lib.baseboard_fab2(sch_1):\MG_DQ-DQS_FAR_DIMM_NG_M_M_BYTE7\" )
					)
					( Status sCSetFlattened )
					( Origin gBackEnd )
				)
				( attribute "RELATIVE_PROPAGATION_DELAY" "0.00 MIL,195.00 MIL"
					( Parent
						( matchGroupRef "@baseboard_fab2_lib.baseboard_fab2(sch_1):\MG_DQ-DQS_FAR_DIMM_NG_M_M_BYTE7\" )
					)
					( Units "uMatchProp" "ns" 1.000000)
					( Status sCSetFlattened )
					( Origin gBackEnd )
				)
				( attribute "RELATIVE_PROPAGATION_DELAY_SCOPE" "G"
					( Parent
						( matchGroupRef "@crescent_city_bb_fab1_lib.crescent_city_bb_fab1(sch_1):\MG_DQ_FAR_DIMM_NG_M_M_BYTE7\" )
					)
					( Origin gBackEnd )
				)
				( attribute "RELATIVE_PROPAGATION_DELAY" "TARGET,TARGET"
					( Parent
						( matchGroupRef "@crescent_city_bb_fab1_lib.crescent_city_bb_fab1(sch_1):\MG_DQ_FAR_DIMM_NG_M_M_BYTE7\" )
					)
					( Units "uMatchProp" "ns" 1.000000)
					( Origin gBackEnd )
				)
			)
			( pinPair "@baseboard_fab2_lib.baseboard_fab2(sch_1):\PP1689\"
				( pinRef "@baseboard_fab2_lib.baseboard_fab2(sch_1):page62_i172:DDR5_DQ(60)" )
				( pinRef "@baseboard_fab2_lib.baseboard_fab2(sch_1):page88_i111:DQ(60)" )
				( attribute "RELATIVE_PROPAGATION_DELAY_SCOPE" "G"
					( Parent
						( matchGroupRef "@baseboard_fab2_lib.baseboard_fab2(sch_1):\MG_DQ-DQS_NEAR_DIMM_NG_M_M_BYTE7\" )
					)
					( Status sCSetFlattened )
					( Origin gBackEnd )
				)
				( attribute "RELATIVE_PROPAGATION_DELAY" "0.00 MIL,195.00 MIL"
					( Parent
						( matchGroupRef "@baseboard_fab2_lib.baseboard_fab2(sch_1):\MG_DQ-DQS_NEAR_DIMM_NG_M_M_BYTE7\" )
					)
					( Units "uMatchProp" "ns" 1.000000)
					( Status sCSetFlattened )
					( Origin gBackEnd )
				)
				( attribute "RELATIVE_PROPAGATION_DELAY_SCOPE" "G"
					( Parent
						( matchGroupRef "@crescent_city_bb_fab1_lib.crescent_city_bb_fab1(sch_1):\MG_DQ_NEAR_DIMM_NG_M_M_BYTE7\" )
					)
					( Origin gBackEnd )
				)
				( attribute "RELATIVE_PROPAGATION_DELAY" "TARGET,TARGET"
					( Parent
						( matchGroupRef "@crescent_city_bb_fab1_lib.crescent_city_bb_fab1(sch_1):\MG_DQ_NEAR_DIMM_NG_M_M_BYTE7\" )
					)
					( Units "uMatchProp" "ns" 1.000000)
					( Origin gBackEnd )
				)
			)
			( pinPair "@baseboard_fab2_lib.baseboard_fab2(sch_1):\PP1690\"
				( pinRef "@baseboard_fab2_lib.baseboard_fab2(sch_1):page62_i172:DDR5_DQ(61)" )
				( pinRef "@baseboard_fab2_lib.baseboard_fab2(sch_1):page87_i186:DQ(60)" )
				( attribute "RELATIVE_PROPAGATION_DELAY_SCOPE" "G"
					( Parent
						( matchGroupRef "@baseboard_fab2_lib.baseboard_fab2(sch_1):\MG_DQ-DQS_FAR_DIMM_NG_M_M_BYTE7\" )
					)
					( Status sCSetFlattened )
					( Origin gBackEnd )
				)
				( attribute "RELATIVE_PROPAGATION_DELAY" "0.00 MIL,195.00 MIL"
					( Parent
						( matchGroupRef "@baseboard_fab2_lib.baseboard_fab2(sch_1):\MG_DQ-DQS_FAR_DIMM_NG_M_M_BYTE7\" )
					)
					( Units "uMatchProp" "ns" 1.000000)
					( Status sCSetFlattened )
					( Origin gBackEnd )
				)
				( attribute "RELATIVE_PROPAGATION_DELAY_SCOPE" "G"
					( Parent
						( matchGroupRef "@crescent_city_bb_fab1_lib.crescent_city_bb_fab1(sch_1):\MG_DQ_FAR_DIMM_NG_M_M_BYTE7\" )
					)
					( Status sCSetFlattened )
					( Origin gBackEnd )
				)
				( attribute "RELATIVE_PROPAGATION_DELAY" "-50.00 MIL,50.00 MIL"
					( Parent
						( matchGroupRef "@crescent_city_bb_fab1_lib.crescent_city_bb_fab1(sch_1):\MG_DQ_FAR_DIMM_NG_M_M_BYTE7\" )
					)
					( Units "uMatchProp" "ns" 1.000000)
					( Status sCSetFlattened )
					( Origin gBackEnd )
				)
			)
			( pinPair "@baseboard_fab2_lib.baseboard_fab2(sch_1):\PP1692\"
				( pinRef "@baseboard_fab2_lib.baseboard_fab2(sch_1):page62_i172:DDR5_DQ(61)" )
				( pinRef "@baseboard_fab2_lib.baseboard_fab2(sch_1):page88_i111:DQ(61)" )
				( attribute "RELATIVE_PROPAGATION_DELAY_SCOPE" "G"
					( Parent
						( matchGroupRef "@baseboard_fab2_lib.baseboard_fab2(sch_1):\MG_DQ-DQS_NEAR_DIMM_NG_M_M_BYTE7\" )
					)
					( Status sCSetFlattened )
					( Origin gBackEnd )
				)
				( attribute "RELATIVE_PROPAGATION_DELAY" "0.00 MIL,195.00 MIL"
					( Parent
						( matchGroupRef "@baseboard_fab2_lib.baseboard_fab2(sch_1):\MG_DQ-DQS_NEAR_DIMM_NG_M_M_BYTE7\" )
					)
					( Units "uMatchProp" "ns" 1.000000)
					( Status sCSetFlattened )
					( Origin gBackEnd )
				)
				( attribute "RELATIVE_PROPAGATION_DELAY_SCOPE" "G"
					( Parent
						( matchGroupRef "@crescent_city_bb_fab1_lib.crescent_city_bb_fab1(sch_1):\MG_DQ_NEAR_DIMM_NG_M_M_BYTE7\" )
					)
					( Status sCSetFlattened )
					( Origin gBackEnd )
				)
				( attribute "RELATIVE_PROPAGATION_DELAY" "-50.00 MIL,50.00 MIL"
					( Parent
						( matchGroupRef "@crescent_city_bb_fab1_lib.crescent_city_bb_fab1(sch_1):\MG_DQ_NEAR_DIMM_NG_M_M_BYTE7\" )
					)
					( Units "uMatchProp" "ns" 1.000000)
					( Status sCSetFlattened )
					( Origin gBackEnd )
				)
			)
			( pinPair "@baseboard_fab2_lib.baseboard_fab2(sch_1):\PP1693\"
				( pinRef "@baseboard_fab2_lib.baseboard_fab2(sch_1):page62_i172:DDR5_DQ(62)" )
				( pinRef "@baseboard_fab2_lib.baseboard_fab2(sch_1):page87_i186:DQ(63)" )
				( attribute "RELATIVE_PROPAGATION_DELAY_SCOPE" "G"
					( Parent
						( matchGroupRef "@baseboard_fab2_lib.baseboard_fab2(sch_1):\MG_DQ-DQS_FAR_DIMM_NG_M_M_BYTE7\" )
					)
					( Status sCSetFlattened )
					( Origin gBackEnd )
				)
				( attribute "RELATIVE_PROPAGATION_DELAY" "0.00 MIL,195.00 MIL"
					( Parent
						( matchGroupRef "@baseboard_fab2_lib.baseboard_fab2(sch_1):\MG_DQ-DQS_FAR_DIMM_NG_M_M_BYTE7\" )
					)
					( Units "uMatchProp" "ns" 1.000000)
					( Status sCSetFlattened )
					( Origin gBackEnd )
				)
				( attribute "RELATIVE_PROPAGATION_DELAY_SCOPE" "G"
					( Parent
						( matchGroupRef "@crescent_city_bb_fab1_lib.crescent_city_bb_fab1(sch_1):\MG_DQ_FAR_DIMM_NG_M_M_BYTE7\" )
					)
					( Status sCSetFlattened )
					( Origin gBackEnd )
				)
				( attribute "RELATIVE_PROPAGATION_DELAY" "-50.00 MIL,50.00 MIL"
					( Parent
						( matchGroupRef "@crescent_city_bb_fab1_lib.crescent_city_bb_fab1(sch_1):\MG_DQ_FAR_DIMM_NG_M_M_BYTE7\" )
					)
					( Units "uMatchProp" "ns" 1.000000)
					( Status sCSetFlattened )
					( Origin gBackEnd )
				)
			)
			( pinPair "@baseboard_fab2_lib.baseboard_fab2(sch_1):\PP1694\"
				( pinRef "@baseboard_fab2_lib.baseboard_fab2(sch_1):page88_i111:DQ(62)" )
				( pinRef "@baseboard_fab2_lib.baseboard_fab2(sch_1):page62_i172:DDR5_DQ(62)" )
				( attribute "RELATIVE_PROPAGATION_DELAY_SCOPE" "G"
					( Parent
						( matchGroupRef "@baseboard_fab2_lib.baseboard_fab2(sch_1):\MG_DQ-DQS_NEAR_DIMM_NG_M_M_BYTE7\" )
					)
					( Status sCSetFlattened )
					( Origin gBackEnd )
				)
				( attribute "RELATIVE_PROPAGATION_DELAY" "0.00 MIL,195.00 MIL"
					( Parent
						( matchGroupRef "@baseboard_fab2_lib.baseboard_fab2(sch_1):\MG_DQ-DQS_NEAR_DIMM_NG_M_M_BYTE7\" )
					)
					( Units "uMatchProp" "ns" 1.000000)
					( Status sCSetFlattened )
					( Origin gBackEnd )
				)
				( attribute "RELATIVE_PROPAGATION_DELAY_SCOPE" "G"
					( Parent
						( matchGroupRef "@crescent_city_bb_fab1_lib.crescent_city_bb_fab1(sch_1):\MG_DQ_NEAR_DIMM_NG_M_M_BYTE7\" )
					)
					( Status sCSetFlattened )
					( Origin gBackEnd )
				)
				( attribute "RELATIVE_PROPAGATION_DELAY" "-50.00 MIL,50.00 MIL"
					( Parent
						( matchGroupRef "@crescent_city_bb_fab1_lib.crescent_city_bb_fab1(sch_1):\MG_DQ_NEAR_DIMM_NG_M_M_BYTE7\" )
					)
					( Units "uMatchProp" "ns" 1.000000)
					( Status sCSetFlattened )
					( Origin gBackEnd )
				)
			)
			( pinPair "@baseboard_fab2_lib.baseboard_fab2(sch_1):\PP1696\"
				( pinRef "@baseboard_fab2_lib.baseboard_fab2(sch_1):page62_i172:DDR5_DQ(63)" )
				( pinRef "@baseboard_fab2_lib.baseboard_fab2(sch_1):page87_i186:DQ(62)" )
				( attribute "RELATIVE_PROPAGATION_DELAY_SCOPE" "G"
					( Parent
						( matchGroupRef "@baseboard_fab2_lib.baseboard_fab2(sch_1):\MG_DQ-DQS_FAR_DIMM_NG_M_M_BYTE7\" )
					)
					( Status sCSetFlattened )
					( Origin gBackEnd )
				)
				( attribute "RELATIVE_PROPAGATION_DELAY" "0.00 MIL,195.00 MIL"
					( Parent
						( matchGroupRef "@baseboard_fab2_lib.baseboard_fab2(sch_1):\MG_DQ-DQS_FAR_DIMM_NG_M_M_BYTE7\" )
					)
					( Units "uMatchProp" "ns" 1.000000)
					( Status sCSetFlattened )
					( Origin gBackEnd )
				)
				( attribute "RELATIVE_PROPAGATION_DELAY_SCOPE" "G"
					( Parent
						( matchGroupRef "@crescent_city_bb_fab1_lib.crescent_city_bb_fab1(sch_1):\MG_DQ_FAR_DIMM_NG_M_M_BYTE7\" )
					)
					( Status sCSetFlattened )
					( Origin gBackEnd )
				)
				( attribute "RELATIVE_PROPAGATION_DELAY" "-50.00 MIL,50.00 MIL"
					( Parent
						( matchGroupRef "@crescent_city_bb_fab1_lib.crescent_city_bb_fab1(sch_1):\MG_DQ_FAR_DIMM_NG_M_M_BYTE7\" )
					)
					( Units "uMatchProp" "ns" 1.000000)
					( Status sCSetFlattened )
					( Origin gBackEnd )
				)
			)
			( pinPair "@baseboard_fab2_lib.baseboard_fab2(sch_1):\PP1698\"
				( pinRef "@baseboard_fab2_lib.baseboard_fab2(sch_1):page62_i172:DDR5_DQ(63)" )
				( pinRef "@baseboard_fab2_lib.baseboard_fab2(sch_1):page88_i111:DQ(63)" )
				( attribute "RELATIVE_PROPAGATION_DELAY_SCOPE" "G"
					( Parent
						( matchGroupRef "@baseboard_fab2_lib.baseboard_fab2(sch_1):\MG_DQ-DQS_NEAR_DIMM_NG_M_M_BYTE7\" )
					)
					( Status sCSetFlattened )
					( Origin gBackEnd )
				)
				( attribute "RELATIVE_PROPAGATION_DELAY" "0.00 MIL,195.00 MIL"
					( Parent
						( matchGroupRef "@baseboard_fab2_lib.baseboard_fab2(sch_1):\MG_DQ-DQS_NEAR_DIMM_NG_M_M_BYTE7\" )
					)
					( Units "uMatchProp" "ns" 1.000000)
					( Status sCSetFlattened )
					( Origin gBackEnd )
				)
				( attribute "RELATIVE_PROPAGATION_DELAY_SCOPE" "G"
					( Parent
						( matchGroupRef "@crescent_city_bb_fab1_lib.crescent_city_bb_fab1(sch_1):\MG_DQ_NEAR_DIMM_NG_M_M_BYTE7\" )
					)
					( Status sCSetFlattened )
					( Origin gBackEnd )
				)
				( attribute "RELATIVE_PROPAGATION_DELAY" "-50.00 MIL,50.00 MIL"
					( Parent
						( matchGroupRef "@crescent_city_bb_fab1_lib.crescent_city_bb_fab1(sch_1):\MG_DQ_NEAR_DIMM_NG_M_M_BYTE7\" )
					)
					( Units "uMatchProp" "ns" 1.000000)
					( Status sCSetFlattened )
					( Origin gBackEnd )
				)
			)
			( pinPair "@baseboard_fab2_lib.baseboard_fab2(sch_1):\PP5091\"
				( pinRef "@baseboard_fab2_lib.baseboard_fab2(sch_1):page24_i172:DDR1_DQ(0)" )
				( pinRef "@baseboard_fab2_lib.baseboard_fab2(sch_1):page45_i111:DQ(1)" )
				( attribute "RELATIVE_PROPAGATION_DELAY_SCOPE" "G"
					( Parent
						( matchGroupRef "@baseboard_fab2_lib.baseboard_fab2(sch_1):\MG_DQ-DQS_FAR_DIMM_NG_M_B_BYTE0\" )
					)
					( Status sCSetFlattened )
					( Origin gBackEnd )
				)
				( attribute "RELATIVE_PROPAGATION_DELAY" "0.00 MIL,195.00 MIL"
					( Parent
						( matchGroupRef "@baseboard_fab2_lib.baseboard_fab2(sch_1):\MG_DQ-DQS_FAR_DIMM_NG_M_B_BYTE0\" )
					)
					( Units "uMatchProp" "ns" 1.000000)
					( Status sCSetFlattened )
					( Origin gBackEnd )
				)
				( attribute "RELATIVE_PROPAGATION_DELAY_SCOPE" "G"
					( Parent
						( matchGroupRef "@baseboard_fab2_lib.baseboard_fab2(sch_1):\MG_DQ_FAR_DIMM_NG_M_B_BYTE0\" )
					)
					( Status sCSetFlattened )
					( Origin gBackEnd )
				)
				( attribute "RELATIVE_PROPAGATION_DELAY" "-50.00 MIL,50.00 MIL"
					( Parent
						( matchGroupRef "@baseboard_fab2_lib.baseboard_fab2(sch_1):\MG_DQ_FAR_DIMM_NG_M_B_BYTE0\" )
					)
					( Units "uMatchProp" "ns" 1.000000)
					( Status sCSetFlattened )
					( Origin gBackEnd )
				)
			)
			( pinPair "@baseboard_fab2_lib.baseboard_fab2(sch_1):\PP5093\"
				( pinRef "@baseboard_fab2_lib.baseboard_fab2(sch_1):page24_i172:DDR1_DQ(0)" )
				( pinRef "@baseboard_fab2_lib.baseboard_fab2(sch_1):page46_i14:DQ(0)" )
				( attribute "RELATIVE_PROPAGATION_DELAY_SCOPE" "G"
					( Parent
						( matchGroupRef "@baseboard_fab2_lib.baseboard_fab2(sch_1):\MG_DQ-DQS_NEAR_DIMM_NG_M_B_BYTE0\" )
					)
					( Status sCSetFlattened )
					( Origin gBackEnd )
				)
				( attribute "RELATIVE_PROPAGATION_DELAY" "0.00 MIL,195.00 MIL"
					( Parent
						( matchGroupRef "@baseboard_fab2_lib.baseboard_fab2(sch_1):\MG_DQ-DQS_NEAR_DIMM_NG_M_B_BYTE0\" )
					)
					( Units "uMatchProp" "ns" 1.000000)
					( Status sCSetFlattened )
					( Origin gBackEnd )
				)
				( attribute "RELATIVE_PROPAGATION_DELAY_SCOPE" "G"
					( Parent
						( matchGroupRef "@baseboard_fab2_lib.baseboard_fab2(sch_1):\MG_DQ_NEAR_DIMM_NG_M_B_BYTE0\" )
					)
					( Status sCSetFlattened )
					( Origin gBackEnd )
				)
				( attribute "RELATIVE_PROPAGATION_DELAY" "-50.00 MIL,50.00 MIL"
					( Parent
						( matchGroupRef "@baseboard_fab2_lib.baseboard_fab2(sch_1):\MG_DQ_NEAR_DIMM_NG_M_B_BYTE0\" )
					)
					( Units "uMatchProp" "ns" 1.000000)
					( Status sCSetFlattened )
					( Origin gBackEnd )
				)
			)
			( pinPair "@baseboard_fab2_lib.baseboard_fab2(sch_1):\PP5094\"
				( pinRef "@baseboard_fab2_lib.baseboard_fab2(sch_1):page24_i172:DDR1_DQ(1)" )
				( pinRef "@baseboard_fab2_lib.baseboard_fab2(sch_1):page45_i111:DQ(0)" )
				( attribute "RELATIVE_PROPAGATION_DELAY_SCOPE" "G"
					( Parent
						( matchGroupRef "@baseboard_fab2_lib.baseboard_fab2(sch_1):\MG_DQ-DQS_FAR_DIMM_NG_M_B_BYTE0\" )
					)
					( Status sCSetFlattened )
					( Origin gBackEnd )
				)
				( attribute "RELATIVE_PROPAGATION_DELAY" "0.00 MIL,195.00 MIL"
					( Parent
						( matchGroupRef "@baseboard_fab2_lib.baseboard_fab2(sch_1):\MG_DQ-DQS_FAR_DIMM_NG_M_B_BYTE0\" )
					)
					( Units "uMatchProp" "ns" 1.000000)
					( Status sCSetFlattened )
					( Origin gBackEnd )
				)
				( attribute "RELATIVE_PROPAGATION_DELAY_SCOPE" "G"
					( Parent
						( matchGroupRef "@baseboard_fab2_lib.baseboard_fab2(sch_1):\MG_DQ_FAR_DIMM_NG_M_B_BYTE0\" )
					)
					( Status sCSetFlattened )
					( Origin gBackEnd )
				)
				( attribute "RELATIVE_PROPAGATION_DELAY" "-50.00 MIL,50.00 MIL"
					( Parent
						( matchGroupRef "@baseboard_fab2_lib.baseboard_fab2(sch_1):\MG_DQ_FAR_DIMM_NG_M_B_BYTE0\" )
					)
					( Units "uMatchProp" "ns" 1.000000)
					( Status sCSetFlattened )
					( Origin gBackEnd )
				)
			)
			( pinPair "@baseboard_fab2_lib.baseboard_fab2(sch_1):\PP5096\"
				( pinRef "@baseboard_fab2_lib.baseboard_fab2(sch_1):page24_i172:DDR1_DQ(1)" )
				( pinRef "@baseboard_fab2_lib.baseboard_fab2(sch_1):page46_i14:DQ(1)" )
				( attribute "RELATIVE_PROPAGATION_DELAY_SCOPE" "G"
					( Parent
						( matchGroupRef "@baseboard_fab2_lib.baseboard_fab2(sch_1):\MG_DQ-DQS_NEAR_DIMM_NG_M_B_BYTE0\" )
					)
					( Status sCSetFlattened )
					( Origin gBackEnd )
				)
				( attribute "RELATIVE_PROPAGATION_DELAY" "0.00 MIL,195.00 MIL"
					( Parent
						( matchGroupRef "@baseboard_fab2_lib.baseboard_fab2(sch_1):\MG_DQ-DQS_NEAR_DIMM_NG_M_B_BYTE0\" )
					)
					( Units "uMatchProp" "ns" 1.000000)
					( Status sCSetFlattened )
					( Origin gBackEnd )
				)
				( attribute "RELATIVE_PROPAGATION_DELAY_SCOPE" "G"
					( Parent
						( matchGroupRef "@baseboard_fab2_lib.baseboard_fab2(sch_1):\MG_DQ_NEAR_DIMM_NG_M_B_BYTE0\" )
					)
					( Status sCSetFlattened )
					( Origin gBackEnd )
				)
				( attribute "RELATIVE_PROPAGATION_DELAY" "-50.00 MIL,50.00 MIL"
					( Parent
						( matchGroupRef "@baseboard_fab2_lib.baseboard_fab2(sch_1):\MG_DQ_NEAR_DIMM_NG_M_B_BYTE0\" )
					)
					( Units "uMatchProp" "ns" 1.000000)
					( Status sCSetFlattened )
					( Origin gBackEnd )
				)
			)
			( pinPair "@baseboard_fab2_lib.baseboard_fab2(sch_1):\PP5097\"
				( pinRef "@baseboard_fab2_lib.baseboard_fab2(sch_1):page24_i172:DDR1_DQ(2)" )
				( pinRef "@baseboard_fab2_lib.baseboard_fab2(sch_1):page45_i111:DQ(3)" )
				( attribute "RELATIVE_PROPAGATION_DELAY_SCOPE" "G"
					( Parent
						( matchGroupRef "@baseboard_fab2_lib.baseboard_fab2(sch_1):\MG_DQ-DQS_FAR_DIMM_NG_M_B_BYTE0\" )
					)
					( Status sCSetFlattened )
					( Origin gBackEnd )
				)
				( attribute "RELATIVE_PROPAGATION_DELAY" "0.00 MIL,195.00 MIL"
					( Parent
						( matchGroupRef "@baseboard_fab2_lib.baseboard_fab2(sch_1):\MG_DQ-DQS_FAR_DIMM_NG_M_B_BYTE0\" )
					)
					( Units "uMatchProp" "ns" 1.000000)
					( Status sCSetFlattened )
					( Origin gBackEnd )
				)
				( attribute "RELATIVE_PROPAGATION_DELAY_SCOPE" "G"
					( Parent
						( matchGroupRef "@baseboard_fab2_lib.baseboard_fab2(sch_1):\MG_DQ_FAR_DIMM_NG_M_B_BYTE0\" )
					)
					( Status sCSetFlattened )
					( Origin gBackEnd )
				)
				( attribute "RELATIVE_PROPAGATION_DELAY" "-50.00 MIL,50.00 MIL"
					( Parent
						( matchGroupRef "@baseboard_fab2_lib.baseboard_fab2(sch_1):\MG_DQ_FAR_DIMM_NG_M_B_BYTE0\" )
					)
					( Units "uMatchProp" "ns" 1.000000)
					( Status sCSetFlattened )
					( Origin gBackEnd )
				)
			)
			( pinPair "@baseboard_fab2_lib.baseboard_fab2(sch_1):\PP5099\"
				( pinRef "@baseboard_fab2_lib.baseboard_fab2(sch_1):page24_i172:DDR1_DQ(2)" )
				( pinRef "@baseboard_fab2_lib.baseboard_fab2(sch_1):page46_i14:DQ(2)" )
				( attribute "RELATIVE_PROPAGATION_DELAY_SCOPE" "G"
					( Parent
						( matchGroupRef "@baseboard_fab2_lib.baseboard_fab2(sch_1):\MG_DQ-DQS_NEAR_DIMM_NG_M_B_BYTE0\" )
					)
					( Status sCSetFlattened )
					( Origin gBackEnd )
				)
				( attribute "RELATIVE_PROPAGATION_DELAY" "0.00 MIL,195.00 MIL"
					( Parent
						( matchGroupRef "@baseboard_fab2_lib.baseboard_fab2(sch_1):\MG_DQ-DQS_NEAR_DIMM_NG_M_B_BYTE0\" )
					)
					( Units "uMatchProp" "ns" 1.000000)
					( Status sCSetFlattened )
					( Origin gBackEnd )
				)
				( attribute "RELATIVE_PROPAGATION_DELAY_SCOPE" "G"
					( Parent
						( matchGroupRef "@baseboard_fab2_lib.baseboard_fab2(sch_1):\MG_DQ_NEAR_DIMM_NG_M_B_BYTE0\" )
					)
					( Status sCSetFlattened )
					( Origin gBackEnd )
				)
				( attribute "RELATIVE_PROPAGATION_DELAY" "-50.00 MIL,50.00 MIL"
					( Parent
						( matchGroupRef "@baseboard_fab2_lib.baseboard_fab2(sch_1):\MG_DQ_NEAR_DIMM_NG_M_B_BYTE0\" )
					)
					( Units "uMatchProp" "ns" 1.000000)
					( Status sCSetFlattened )
					( Origin gBackEnd )
				)
			)
			( pinPair "@baseboard_fab2_lib.baseboard_fab2(sch_1):\PP5100\"
				( pinRef "@baseboard_fab2_lib.baseboard_fab2(sch_1):page24_i172:DDR1_DQ(3)" )
				( pinRef "@baseboard_fab2_lib.baseboard_fab2(sch_1):page45_i111:DQ(2)" )
				( attribute "RELATIVE_PROPAGATION_DELAY_SCOPE" "G"
					( Parent
						( matchGroupRef "@baseboard_fab2_lib.baseboard_fab2(sch_1):\MG_DQ-DQS_FAR_DIMM_NG_M_B_BYTE0\" )
					)
					( Status sCSetFlattened )
					( Origin gBackEnd )
				)
				( attribute "RELATIVE_PROPAGATION_DELAY" "0.00 MIL,195.00 MIL"
					( Parent
						( matchGroupRef "@baseboard_fab2_lib.baseboard_fab2(sch_1):\MG_DQ-DQS_FAR_DIMM_NG_M_B_BYTE0\" )
					)
					( Units "uMatchProp" "ns" 1.000000)
					( Status sCSetFlattened )
					( Origin gBackEnd )
				)
				( attribute "RELATIVE_PROPAGATION_DELAY_SCOPE" "G"
					( Parent
						( matchGroupRef "@baseboard_fab2_lib.baseboard_fab2(sch_1):\MG_DQ_FAR_DIMM_NG_M_B_BYTE0\" )
					)
					( Status sCSetFlattened )
					( Origin gBackEnd )
				)
				( attribute "RELATIVE_PROPAGATION_DELAY" "-50.00 MIL,50.00 MIL"
					( Parent
						( matchGroupRef "@baseboard_fab2_lib.baseboard_fab2(sch_1):\MG_DQ_FAR_DIMM_NG_M_B_BYTE0\" )
					)
					( Units "uMatchProp" "ns" 1.000000)
					( Status sCSetFlattened )
					( Origin gBackEnd )
				)
			)
			( pinPair "@baseboard_fab2_lib.baseboard_fab2(sch_1):\PP5102\"
				( pinRef "@baseboard_fab2_lib.baseboard_fab2(sch_1):page24_i172:DDR1_DQ(3)" )
				( pinRef "@baseboard_fab2_lib.baseboard_fab2(sch_1):page46_i14:DQ(3)" )
				( attribute "RELATIVE_PROPAGATION_DELAY_SCOPE" "G"
					( Parent
						( matchGroupRef "@baseboard_fab2_lib.baseboard_fab2(sch_1):\MG_DQ-DQS_NEAR_DIMM_NG_M_B_BYTE0\" )
					)
					( Status sCSetFlattened )
					( Origin gBackEnd )
				)
				( attribute "RELATIVE_PROPAGATION_DELAY" "0.00 MIL,195.00 MIL"
					( Parent
						( matchGroupRef "@baseboard_fab2_lib.baseboard_fab2(sch_1):\MG_DQ-DQS_NEAR_DIMM_NG_M_B_BYTE0\" )
					)
					( Units "uMatchProp" "ns" 1.000000)
					( Status sCSetFlattened )
					( Origin gBackEnd )
				)
				( attribute "RELATIVE_PROPAGATION_DELAY_SCOPE" "G"
					( Parent
						( matchGroupRef "@baseboard_fab2_lib.baseboard_fab2(sch_1):\MG_DQ_NEAR_DIMM_NG_M_B_BYTE0\" )
					)
					( Status sCSetFlattened )
					( Origin gBackEnd )
				)
				( attribute "RELATIVE_PROPAGATION_DELAY" "-50.00 MIL,50.00 MIL"
					( Parent
						( matchGroupRef "@baseboard_fab2_lib.baseboard_fab2(sch_1):\MG_DQ_NEAR_DIMM_NG_M_B_BYTE0\" )
					)
					( Units "uMatchProp" "ns" 1.000000)
					( Status sCSetFlattened )
					( Origin gBackEnd )
				)
			)
			( pinPair "@baseboard_fab2_lib.baseboard_fab2(sch_1):\PP5103\"
				( pinRef "@baseboard_fab2_lib.baseboard_fab2(sch_1):page24_i172:DDR1_DQ(4)" )
				( pinRef "@baseboard_fab2_lib.baseboard_fab2(sch_1):page45_i111:DQ(5)" )
				( attribute "RELATIVE_PROPAGATION_DELAY_SCOPE" "G"
					( Parent
						( matchGroupRef "@baseboard_fab2_lib.baseboard_fab2(sch_1):\MG_DQ-DQS_FAR_DIMM_NG_M_B_BYTE0\" )
					)
					( Status sCSetFlattened )
					( Origin gBackEnd )
				)
				( attribute "RELATIVE_PROPAGATION_DELAY" "0.00 MIL,195.00 MIL"
					( Parent
						( matchGroupRef "@baseboard_fab2_lib.baseboard_fab2(sch_1):\MG_DQ-DQS_FAR_DIMM_NG_M_B_BYTE0\" )
					)
					( Units "uMatchProp" "ns" 1.000000)
					( Status sCSetFlattened )
					( Origin gBackEnd )
				)
				( attribute "RELATIVE_PROPAGATION_DELAY_SCOPE" "G"
					( Parent
						( matchGroupRef "@baseboard_fab2_lib.baseboard_fab2(sch_1):\MG_DQ_FAR_DIMM_NG_M_B_BYTE0\" )
					)
					( Status sCSetFlattened )
					( Origin gBackEnd )
				)
				( attribute "RELATIVE_PROPAGATION_DELAY" "-50.00 MIL,50.00 MIL"
					( Parent
						( matchGroupRef "@baseboard_fab2_lib.baseboard_fab2(sch_1):\MG_DQ_FAR_DIMM_NG_M_B_BYTE0\" )
					)
					( Units "uMatchProp" "ns" 1.000000)
					( Status sCSetFlattened )
					( Origin gBackEnd )
				)
			)
			( pinPair "@baseboard_fab2_lib.baseboard_fab2(sch_1):\PP5105\"
				( pinRef "@baseboard_fab2_lib.baseboard_fab2(sch_1):page24_i172:DDR1_DQ(4)" )
				( pinRef "@baseboard_fab2_lib.baseboard_fab2(sch_1):page46_i14:DQ(4)" )
				( attribute "RELATIVE_PROPAGATION_DELAY_SCOPE" "G"
					( Parent
						( matchGroupRef "@baseboard_fab2_lib.baseboard_fab2(sch_1):\MG_DQ-DQS_NEAR_DIMM_NG_M_B_BYTE0\" )
					)
					( Status sCSetFlattened )
					( Origin gBackEnd )
				)
				( attribute "RELATIVE_PROPAGATION_DELAY" "0.00 MIL,195.00 MIL"
					( Parent
						( matchGroupRef "@baseboard_fab2_lib.baseboard_fab2(sch_1):\MG_DQ-DQS_NEAR_DIMM_NG_M_B_BYTE0\" )
					)
					( Units "uMatchProp" "ns" 1.000000)
					( Status sCSetFlattened )
					( Origin gBackEnd )
				)
				( attribute "RELATIVE_PROPAGATION_DELAY_SCOPE" "G"
					( Parent
						( matchGroupRef "@baseboard_fab2_lib.baseboard_fab2(sch_1):\MG_DQ_NEAR_DIMM_NG_M_B_BYTE0\" )
					)
					( Status sCSetFlattened )
					( Origin gBackEnd )
				)
				( attribute "RELATIVE_PROPAGATION_DELAY" "-50.00 MIL,50.00 MIL"
					( Parent
						( matchGroupRef "@baseboard_fab2_lib.baseboard_fab2(sch_1):\MG_DQ_NEAR_DIMM_NG_M_B_BYTE0\" )
					)
					( Units "uMatchProp" "ns" 1.000000)
					( Status sCSetFlattened )
					( Origin gBackEnd )
				)
			)
			( pinPair "@baseboard_fab2_lib.baseboard_fab2(sch_1):\PP5106\"
				( pinRef "@baseboard_fab2_lib.baseboard_fab2(sch_1):page24_i172:DDR1_DQ(5)" )
				( pinRef "@baseboard_fab2_lib.baseboard_fab2(sch_1):page45_i111:DQ(4)" )
				( attribute "RELATIVE_PROPAGATION_DELAY_SCOPE" "G"
					( Parent
						( matchGroupRef "@baseboard_fab2_lib.baseboard_fab2(sch_1):\MG_DQ-DQS_FAR_DIMM_NG_M_B_BYTE0\" )
					)
					( Status sCSetFlattened )
					( Origin gBackEnd )
				)
				( attribute "RELATIVE_PROPAGATION_DELAY" "0.00 MIL,195.00 MIL"
					( Parent
						( matchGroupRef "@baseboard_fab2_lib.baseboard_fab2(sch_1):\MG_DQ-DQS_FAR_DIMM_NG_M_B_BYTE0\" )
					)
					( Units "uMatchProp" "ns" 1.000000)
					( Status sCSetFlattened )
					( Origin gBackEnd )
				)
				( attribute "RELATIVE_PROPAGATION_DELAY_SCOPE" "G"
					( Parent
						( matchGroupRef "@baseboard_fab2_lib.baseboard_fab2(sch_1):\MG_DQ_FAR_DIMM_NG_M_B_BYTE0\" )
					)
					( Status sCSetFlattened )
					( Origin gBackEnd )
				)
				( attribute "RELATIVE_PROPAGATION_DELAY" "-50.00 MIL,50.00 MIL"
					( Parent
						( matchGroupRef "@baseboard_fab2_lib.baseboard_fab2(sch_1):\MG_DQ_FAR_DIMM_NG_M_B_BYTE0\" )
					)
					( Units "uMatchProp" "ns" 1.000000)
					( Status sCSetFlattened )
					( Origin gBackEnd )
				)
			)
			( pinPair "@baseboard_fab2_lib.baseboard_fab2(sch_1):\PP5108\"
				( pinRef "@baseboard_fab2_lib.baseboard_fab2(sch_1):page24_i172:DDR1_DQ(5)" )
				( pinRef "@baseboard_fab2_lib.baseboard_fab2(sch_1):page46_i14:DQ(5)" )
				( attribute "RELATIVE_PROPAGATION_DELAY_SCOPE" "G"
					( Parent
						( matchGroupRef "@baseboard_fab2_lib.baseboard_fab2(sch_1):\MG_DQ-DQS_NEAR_DIMM_NG_M_B_BYTE0\" )
					)
					( Status sCSetFlattened )
					( Origin gBackEnd )
				)
				( attribute "RELATIVE_PROPAGATION_DELAY" "0.00 MIL,195.00 MIL"
					( Parent
						( matchGroupRef "@baseboard_fab2_lib.baseboard_fab2(sch_1):\MG_DQ-DQS_NEAR_DIMM_NG_M_B_BYTE0\" )
					)
					( Units "uMatchProp" "ns" 1.000000)
					( Status sCSetFlattened )
					( Origin gBackEnd )
				)
				( attribute "RELATIVE_PROPAGATION_DELAY_SCOPE" "G"
					( Parent
						( matchGroupRef "@baseboard_fab2_lib.baseboard_fab2(sch_1):\MG_DQ_NEAR_DIMM_NG_M_B_BYTE0\" )
					)
					( Status sCSetFlattened )
					( Origin gBackEnd )
				)
				( attribute "RELATIVE_PROPAGATION_DELAY" "-50.00 MIL,50.00 MIL"
					( Parent
						( matchGroupRef "@baseboard_fab2_lib.baseboard_fab2(sch_1):\MG_DQ_NEAR_DIMM_NG_M_B_BYTE0\" )
					)
					( Units "uMatchProp" "ns" 1.000000)
					( Status sCSetFlattened )
					( Origin gBackEnd )
				)
			)
			( pinPair "@baseboard_fab2_lib.baseboard_fab2(sch_1):\PP5109\"
				( pinRef "@baseboard_fab2_lib.baseboard_fab2(sch_1):page24_i172:DDR1_DQ(6)" )
				( pinRef "@baseboard_fab2_lib.baseboard_fab2(sch_1):page45_i111:DQ(7)" )
				( attribute "RELATIVE_PROPAGATION_DELAY_SCOPE" "G"
					( Parent
						( matchGroupRef "@baseboard_fab2_lib.baseboard_fab2(sch_1):\MG_DQ-DQS_FAR_DIMM_NG_M_B_BYTE0\" )
					)
					( Status sCSetFlattened )
					( Origin gBackEnd )
				)
				( attribute "RELATIVE_PROPAGATION_DELAY" "0.00 MIL,195.00 MIL"
					( Parent
						( matchGroupRef "@baseboard_fab2_lib.baseboard_fab2(sch_1):\MG_DQ-DQS_FAR_DIMM_NG_M_B_BYTE0\" )
					)
					( Units "uMatchProp" "ns" 1.000000)
					( Status sCSetFlattened )
					( Origin gBackEnd )
				)
				( attribute "RELATIVE_PROPAGATION_DELAY_SCOPE" "G"
					( Parent
						( matchGroupRef "@baseboard_fab2_lib.baseboard_fab2(sch_1):\MG_DQ_FAR_DIMM_NG_M_B_BYTE0\" )
					)
					( Status sCSetFlattened )
					( Origin gBackEnd )
				)
				( attribute "RELATIVE_PROPAGATION_DELAY" "-50.00 MIL,50.00 MIL"
					( Parent
						( matchGroupRef "@baseboard_fab2_lib.baseboard_fab2(sch_1):\MG_DQ_FAR_DIMM_NG_M_B_BYTE0\" )
					)
					( Units "uMatchProp" "ns" 1.000000)
					( Status sCSetFlattened )
					( Origin gBackEnd )
				)
			)
			( pinPair "@baseboard_fab2_lib.baseboard_fab2(sch_1):\PP5111\"
				( pinRef "@baseboard_fab2_lib.baseboard_fab2(sch_1):page24_i172:DDR1_DQ(6)" )
				( pinRef "@baseboard_fab2_lib.baseboard_fab2(sch_1):page46_i14:DQ(6)" )
				( attribute "RELATIVE_PROPAGATION_DELAY_SCOPE" "G"
					( Parent
						( matchGroupRef "@baseboard_fab2_lib.baseboard_fab2(sch_1):\MG_DQ-DQS_NEAR_DIMM_NG_M_B_BYTE0\" )
					)
					( Status sCSetFlattened )
					( Origin gBackEnd )
				)
				( attribute "RELATIVE_PROPAGATION_DELAY" "0.00 MIL,195.00 MIL"
					( Parent
						( matchGroupRef "@baseboard_fab2_lib.baseboard_fab2(sch_1):\MG_DQ-DQS_NEAR_DIMM_NG_M_B_BYTE0\" )
					)
					( Units "uMatchProp" "ns" 1.000000)
					( Status sCSetFlattened )
					( Origin gBackEnd )
				)
				( attribute "RELATIVE_PROPAGATION_DELAY_SCOPE" "G"
					( Parent
						( matchGroupRef "@baseboard_fab2_lib.baseboard_fab2(sch_1):\MG_DQ_NEAR_DIMM_NG_M_B_BYTE0\" )
					)
					( Status sCSetFlattened )
					( Origin gBackEnd )
				)
				( attribute "RELATIVE_PROPAGATION_DELAY" "-50.00 MIL,50.00 MIL"
					( Parent
						( matchGroupRef "@baseboard_fab2_lib.baseboard_fab2(sch_1):\MG_DQ_NEAR_DIMM_NG_M_B_BYTE0\" )
					)
					( Units "uMatchProp" "ns" 1.000000)
					( Status sCSetFlattened )
					( Origin gBackEnd )
				)
			)
			( pinPair "@baseboard_fab2_lib.baseboard_fab2(sch_1):\PP5112\"
				( pinRef "@baseboard_fab2_lib.baseboard_fab2(sch_1):page24_i172:DDR1_DQ(7)" )
				( pinRef "@baseboard_fab2_lib.baseboard_fab2(sch_1):page45_i111:DQ(6)" )
				( attribute "RELATIVE_PROPAGATION_DELAY_SCOPE" "G"
					( Parent
						( matchGroupRef "@baseboard_fab2_lib.baseboard_fab2(sch_1):\MG_DQ-DQS_FAR_DIMM_NG_M_B_BYTE0\" )
					)
					( Status sCSetFlattened )
					( Origin gBackEnd )
				)
				( attribute "RELATIVE_PROPAGATION_DELAY" "0.00 MIL,195.00 MIL"
					( Parent
						( matchGroupRef "@baseboard_fab2_lib.baseboard_fab2(sch_1):\MG_DQ-DQS_FAR_DIMM_NG_M_B_BYTE0\" )
					)
					( Units "uMatchProp" "ns" 1.000000)
					( Status sCSetFlattened )
					( Origin gBackEnd )
				)
				( attribute "RELATIVE_PROPAGATION_DELAY_SCOPE" "G"
					( Parent
						( matchGroupRef "@baseboard_fab2_lib.baseboard_fab2(sch_1):\MG_DQ_FAR_DIMM_NG_M_B_BYTE0\" )
					)
					( Status sCSetFlattened )
					( Origin gBackEnd )
				)
				( attribute "RELATIVE_PROPAGATION_DELAY" "-50.00 MIL,50.00 MIL"
					( Parent
						( matchGroupRef "@baseboard_fab2_lib.baseboard_fab2(sch_1):\MG_DQ_FAR_DIMM_NG_M_B_BYTE0\" )
					)
					( Units "uMatchProp" "ns" 1.000000)
					( Status sCSetFlattened )
					( Origin gBackEnd )
				)
			)
			( pinPair "@baseboard_fab2_lib.baseboard_fab2(sch_1):\PP5114\"
				( pinRef "@baseboard_fab2_lib.baseboard_fab2(sch_1):page24_i172:DDR1_DQ(7)" )
				( pinRef "@baseboard_fab2_lib.baseboard_fab2(sch_1):page46_i14:DQ(7)" )
				( attribute "RELATIVE_PROPAGATION_DELAY_SCOPE" "G"
					( Parent
						( matchGroupRef "@baseboard_fab2_lib.baseboard_fab2(sch_1):\MG_DQ-DQS_NEAR_DIMM_NG_M_B_BYTE0\" )
					)
					( Status sCSetFlattened )
					( Origin gBackEnd )
				)
				( attribute "RELATIVE_PROPAGATION_DELAY" "0.00 MIL,195.00 MIL"
					( Parent
						( matchGroupRef "@baseboard_fab2_lib.baseboard_fab2(sch_1):\MG_DQ-DQS_NEAR_DIMM_NG_M_B_BYTE0\" )
					)
					( Units "uMatchProp" "ns" 1.000000)
					( Status sCSetFlattened )
					( Origin gBackEnd )
				)
				( attribute "RELATIVE_PROPAGATION_DELAY_SCOPE" "G"
					( Parent
						( matchGroupRef "@baseboard_fab2_lib.baseboard_fab2(sch_1):\MG_DQ_NEAR_DIMM_NG_M_B_BYTE0\" )
					)
					( Status sCSetFlattened )
					( Origin gBackEnd )
				)
				( attribute "RELATIVE_PROPAGATION_DELAY" "-50.00 MIL,50.00 MIL"
					( Parent
						( matchGroupRef "@baseboard_fab2_lib.baseboard_fab2(sch_1):\MG_DQ_NEAR_DIMM_NG_M_B_BYTE0\" )
					)
					( Units "uMatchProp" "ns" 1.000000)
					( Status sCSetFlattened )
					( Origin gBackEnd )
				)
			)
			( pinPair "@baseboard_fab2_lib.baseboard_fab2(sch_1):\PP5067\"
				( pinRef "@baseboard_fab2_lib.baseboard_fab2(sch_1):page24_i172:DDR1_DQ(8)" )
				( pinRef "@baseboard_fab2_lib.baseboard_fab2(sch_1):page45_i111:DQ(9)" )
				( attribute "RELATIVE_PROPAGATION_DELAY_SCOPE" "G"
					( Parent
						( matchGroupRef "@baseboard_fab2_lib.baseboard_fab2(sch_1):\MG_DQ-DQS_FAR_DIMM_NG_M_B_BYTE1\" )
					)
					( Status sCSetFlattened )
					( Origin gBackEnd )
				)
				( attribute "RELATIVE_PROPAGATION_DELAY" "0.00 MIL,195.00 MIL"
					( Parent
						( matchGroupRef "@baseboard_fab2_lib.baseboard_fab2(sch_1):\MG_DQ-DQS_FAR_DIMM_NG_M_B_BYTE1\" )
					)
					( Units "uMatchProp" "ns" 1.000000)
					( Status sCSetFlattened )
					( Origin gBackEnd )
				)
				( attribute "RELATIVE_PROPAGATION_DELAY_SCOPE" "G"
					( Parent
						( matchGroupRef "@baseboard_fab2_lib.baseboard_fab2(sch_1):\MG_DQ_FAR_DIMM_NG_M_B_BYTE1\" )
					)
					( Status sCSetFlattened )
					( Origin gBackEnd )
				)
				( attribute "RELATIVE_PROPAGATION_DELAY" "-50.00 MIL,50.00 MIL"
					( Parent
						( matchGroupRef "@baseboard_fab2_lib.baseboard_fab2(sch_1):\MG_DQ_FAR_DIMM_NG_M_B_BYTE1\" )
					)
					( Units "uMatchProp" "ns" 1.000000)
					( Status sCSetFlattened )
					( Origin gBackEnd )
				)
			)
			( pinPair "@baseboard_fab2_lib.baseboard_fab2(sch_1):\PP5069\"
				( pinRef "@baseboard_fab2_lib.baseboard_fab2(sch_1):page24_i172:DDR1_DQ(8)" )
				( pinRef "@baseboard_fab2_lib.baseboard_fab2(sch_1):page46_i14:DQ(8)" )
				( attribute "RELATIVE_PROPAGATION_DELAY_SCOPE" "G"
					( Parent
						( matchGroupRef "@baseboard_fab2_lib.baseboard_fab2(sch_1):\MG_DQ-DQS_NEAR_DIMM_NG_M_B_BYTE1\" )
					)
					( Status sCSetFlattened )
					( Origin gBackEnd )
				)
				( attribute "RELATIVE_PROPAGATION_DELAY" "0.00 MIL,195.00 MIL"
					( Parent
						( matchGroupRef "@baseboard_fab2_lib.baseboard_fab2(sch_1):\MG_DQ-DQS_NEAR_DIMM_NG_M_B_BYTE1\" )
					)
					( Units "uMatchProp" "ns" 1.000000)
					( Status sCSetFlattened )
					( Origin gBackEnd )
				)
				( attribute "RELATIVE_PROPAGATION_DELAY_SCOPE" "G"
					( Parent
						( matchGroupRef "@baseboard_fab2_lib.baseboard_fab2(sch_1):\MG_DQ_NEAR_DIMM_NG_M_B_BYTE1\" )
					)
					( Status sCSetFlattened )
					( Origin gBackEnd )
				)
				( attribute "RELATIVE_PROPAGATION_DELAY" "-50.00 MIL,50.00 MIL"
					( Parent
						( matchGroupRef "@baseboard_fab2_lib.baseboard_fab2(sch_1):\MG_DQ_NEAR_DIMM_NG_M_B_BYTE1\" )
					)
					( Units "uMatchProp" "ns" 1.000000)
					( Status sCSetFlattened )
					( Origin gBackEnd )
				)
			)
			( pinPair "@baseboard_fab2_lib.baseboard_fab2(sch_1):\PP5070\"
				( pinRef "@baseboard_fab2_lib.baseboard_fab2(sch_1):page24_i172:DDR1_DQ(9)" )
				( pinRef "@baseboard_fab2_lib.baseboard_fab2(sch_1):page45_i111:DQ(8)" )
				( attribute "RELATIVE_PROPAGATION_DELAY_SCOPE" "G"
					( Parent
						( matchGroupRef "@baseboard_fab2_lib.baseboard_fab2(sch_1):\MG_DQ-DQS_FAR_DIMM_NG_M_B_BYTE1\" )
					)
					( Status sCSetFlattened )
					( Origin gBackEnd )
				)
				( attribute "RELATIVE_PROPAGATION_DELAY" "0.00 MIL,195.00 MIL"
					( Parent
						( matchGroupRef "@baseboard_fab2_lib.baseboard_fab2(sch_1):\MG_DQ-DQS_FAR_DIMM_NG_M_B_BYTE1\" )
					)
					( Units "uMatchProp" "ns" 1.000000)
					( Status sCSetFlattened )
					( Origin gBackEnd )
				)
				( attribute "RELATIVE_PROPAGATION_DELAY_SCOPE" "G"
					( Parent
						( matchGroupRef "@baseboard_fab2_lib.baseboard_fab2(sch_1):\MG_DQ_FAR_DIMM_NG_M_B_BYTE1\" )
					)
					( Status sCSetFlattened )
					( Origin gBackEnd )
				)
				( attribute "RELATIVE_PROPAGATION_DELAY" "-50.00 MIL,50.00 MIL"
					( Parent
						( matchGroupRef "@baseboard_fab2_lib.baseboard_fab2(sch_1):\MG_DQ_FAR_DIMM_NG_M_B_BYTE1\" )
					)
					( Units "uMatchProp" "ns" 1.000000)
					( Status sCSetFlattened )
					( Origin gBackEnd )
				)
			)
			( pinPair "@baseboard_fab2_lib.baseboard_fab2(sch_1):\PP5072\"
				( pinRef "@baseboard_fab2_lib.baseboard_fab2(sch_1):page24_i172:DDR1_DQ(9)" )
				( pinRef "@baseboard_fab2_lib.baseboard_fab2(sch_1):page46_i14:DQ(9)" )
				( attribute "RELATIVE_PROPAGATION_DELAY_SCOPE" "G"
					( Parent
						( matchGroupRef "@baseboard_fab2_lib.baseboard_fab2(sch_1):\MG_DQ-DQS_NEAR_DIMM_NG_M_B_BYTE1\" )
					)
					( Status sCSetFlattened )
					( Origin gBackEnd )
				)
				( attribute "RELATIVE_PROPAGATION_DELAY" "0.00 MIL,195.00 MIL"
					( Parent
						( matchGroupRef "@baseboard_fab2_lib.baseboard_fab2(sch_1):\MG_DQ-DQS_NEAR_DIMM_NG_M_B_BYTE1\" )
					)
					( Units "uMatchProp" "ns" 1.000000)
					( Status sCSetFlattened )
					( Origin gBackEnd )
				)
				( attribute "RELATIVE_PROPAGATION_DELAY_SCOPE" "G"
					( Parent
						( matchGroupRef "@baseboard_fab2_lib.baseboard_fab2(sch_1):\MG_DQ_NEAR_DIMM_NG_M_B_BYTE1\" )
					)
					( Status sCSetFlattened )
					( Origin gBackEnd )
				)
				( attribute "RELATIVE_PROPAGATION_DELAY" "-50.00 MIL,50.00 MIL"
					( Parent
						( matchGroupRef "@baseboard_fab2_lib.baseboard_fab2(sch_1):\MG_DQ_NEAR_DIMM_NG_M_B_BYTE1\" )
					)
					( Units "uMatchProp" "ns" 1.000000)
					( Status sCSetFlattened )
					( Origin gBackEnd )
				)
			)
			( pinPair "@baseboard_fab2_lib.baseboard_fab2(sch_1):\PP5073\"
				( pinRef "@baseboard_fab2_lib.baseboard_fab2(sch_1):page24_i172:DDR1_DQ(10)" )
				( pinRef "@baseboard_fab2_lib.baseboard_fab2(sch_1):page45_i111:DQ(11)" )
				( attribute "RELATIVE_PROPAGATION_DELAY_SCOPE" "G"
					( Parent
						( matchGroupRef "@baseboard_fab2_lib.baseboard_fab2(sch_1):\MG_DQ-DQS_FAR_DIMM_NG_M_B_BYTE1\" )
					)
					( Status sCSetFlattened )
					( Origin gBackEnd )
				)
				( attribute "RELATIVE_PROPAGATION_DELAY" "0.00 MIL,195.00 MIL"
					( Parent
						( matchGroupRef "@baseboard_fab2_lib.baseboard_fab2(sch_1):\MG_DQ-DQS_FAR_DIMM_NG_M_B_BYTE1\" )
					)
					( Units "uMatchProp" "ns" 1.000000)
					( Status sCSetFlattened )
					( Origin gBackEnd )
				)
				( attribute "RELATIVE_PROPAGATION_DELAY_SCOPE" "G"
					( Parent
						( matchGroupRef "@baseboard_fab2_lib.baseboard_fab2(sch_1):\MG_DQ_FAR_DIMM_NG_M_B_BYTE1\" )
					)
					( Status sCSetFlattened )
					( Origin gBackEnd )
				)
				( attribute "RELATIVE_PROPAGATION_DELAY" "-50.00 MIL,50.00 MIL"
					( Parent
						( matchGroupRef "@baseboard_fab2_lib.baseboard_fab2(sch_1):\MG_DQ_FAR_DIMM_NG_M_B_BYTE1\" )
					)
					( Units "uMatchProp" "ns" 1.000000)
					( Status sCSetFlattened )
					( Origin gBackEnd )
				)
			)
			( pinPair "@baseboard_fab2_lib.baseboard_fab2(sch_1):\PP5075\"
				( pinRef "@baseboard_fab2_lib.baseboard_fab2(sch_1):page24_i172:DDR1_DQ(10)" )
				( pinRef "@baseboard_fab2_lib.baseboard_fab2(sch_1):page46_i14:DQ(10)" )
				( attribute "RELATIVE_PROPAGATION_DELAY_SCOPE" "G"
					( Parent
						( matchGroupRef "@baseboard_fab2_lib.baseboard_fab2(sch_1):\MG_DQ-DQS_NEAR_DIMM_NG_M_B_BYTE1\" )
					)
					( Status sCSetFlattened )
					( Origin gBackEnd )
				)
				( attribute "RELATIVE_PROPAGATION_DELAY" "0.00 MIL,195.00 MIL"
					( Parent
						( matchGroupRef "@baseboard_fab2_lib.baseboard_fab2(sch_1):\MG_DQ-DQS_NEAR_DIMM_NG_M_B_BYTE1\" )
					)
					( Units "uMatchProp" "ns" 1.000000)
					( Status sCSetFlattened )
					( Origin gBackEnd )
				)
				( attribute "RELATIVE_PROPAGATION_DELAY_SCOPE" "G"
					( Parent
						( matchGroupRef "@baseboard_fab2_lib.baseboard_fab2(sch_1):\MG_DQ_NEAR_DIMM_NG_M_B_BYTE1\" )
					)
					( Status sCSetFlattened )
					( Origin gBackEnd )
				)
				( attribute "RELATIVE_PROPAGATION_DELAY" "-50.00 MIL,50.00 MIL"
					( Parent
						( matchGroupRef "@baseboard_fab2_lib.baseboard_fab2(sch_1):\MG_DQ_NEAR_DIMM_NG_M_B_BYTE1\" )
					)
					( Units "uMatchProp" "ns" 1.000000)
					( Status sCSetFlattened )
					( Origin gBackEnd )
				)
			)
			( pinPair "@baseboard_fab2_lib.baseboard_fab2(sch_1):\PP5076\"
				( pinRef "@baseboard_fab2_lib.baseboard_fab2(sch_1):page24_i172:DDR1_DQ(11)" )
				( pinRef "@baseboard_fab2_lib.baseboard_fab2(sch_1):page45_i111:DQ(10)" )
				( attribute "RELATIVE_PROPAGATION_DELAY_SCOPE" "G"
					( Parent
						( matchGroupRef "@baseboard_fab2_lib.baseboard_fab2(sch_1):\MG_DQ-DQS_FAR_DIMM_NG_M_B_BYTE1\" )
					)
					( Status sCSetFlattened )
					( Origin gBackEnd )
				)
				( attribute "RELATIVE_PROPAGATION_DELAY" "0.00 MIL,195.00 MIL"
					( Parent
						( matchGroupRef "@baseboard_fab2_lib.baseboard_fab2(sch_1):\MG_DQ-DQS_FAR_DIMM_NG_M_B_BYTE1\" )
					)
					( Units "uMatchProp" "ns" 1.000000)
					( Status sCSetFlattened )
					( Origin gBackEnd )
				)
				( attribute "RELATIVE_PROPAGATION_DELAY_SCOPE" "G"
					( Parent
						( matchGroupRef "@baseboard_fab2_lib.baseboard_fab2(sch_1):\MG_DQ_FAR_DIMM_NG_M_B_BYTE1\" )
					)
					( Status sCSetFlattened )
					( Origin gBackEnd )
				)
				( attribute "RELATIVE_PROPAGATION_DELAY" "-50.00 MIL,50.00 MIL"
					( Parent
						( matchGroupRef "@baseboard_fab2_lib.baseboard_fab2(sch_1):\MG_DQ_FAR_DIMM_NG_M_B_BYTE1\" )
					)
					( Units "uMatchProp" "ns" 1.000000)
					( Status sCSetFlattened )
					( Origin gBackEnd )
				)
			)
			( pinPair "@baseboard_fab2_lib.baseboard_fab2(sch_1):\PP5078\"
				( pinRef "@baseboard_fab2_lib.baseboard_fab2(sch_1):page24_i172:DDR1_DQ(11)" )
				( pinRef "@baseboard_fab2_lib.baseboard_fab2(sch_1):page46_i14:DQ(11)" )
				( attribute "RELATIVE_PROPAGATION_DELAY_SCOPE" "G"
					( Parent
						( matchGroupRef "@baseboard_fab2_lib.baseboard_fab2(sch_1):\MG_DQ-DQS_NEAR_DIMM_NG_M_B_BYTE1\" )
					)
					( Status sCSetFlattened )
					( Origin gBackEnd )
				)
				( attribute "RELATIVE_PROPAGATION_DELAY" "0.00 MIL,195.00 MIL"
					( Parent
						( matchGroupRef "@baseboard_fab2_lib.baseboard_fab2(sch_1):\MG_DQ-DQS_NEAR_DIMM_NG_M_B_BYTE1\" )
					)
					( Units "uMatchProp" "ns" 1.000000)
					( Status sCSetFlattened )
					( Origin gBackEnd )
				)
				( attribute "RELATIVE_PROPAGATION_DELAY_SCOPE" "G"
					( Parent
						( matchGroupRef "@baseboard_fab2_lib.baseboard_fab2(sch_1):\MG_DQ_NEAR_DIMM_NG_M_B_BYTE1\" )
					)
					( Status sCSetFlattened )
					( Origin gBackEnd )
				)
				( attribute "RELATIVE_PROPAGATION_DELAY" "-50.00 MIL,50.00 MIL"
					( Parent
						( matchGroupRef "@baseboard_fab2_lib.baseboard_fab2(sch_1):\MG_DQ_NEAR_DIMM_NG_M_B_BYTE1\" )
					)
					( Units "uMatchProp" "ns" 1.000000)
					( Status sCSetFlattened )
					( Origin gBackEnd )
				)
			)
			( pinPair "@baseboard_fab2_lib.baseboard_fab2(sch_1):\PP5079\"
				( pinRef "@baseboard_fab2_lib.baseboard_fab2(sch_1):page24_i172:DDR1_DQ(12)" )
				( pinRef "@baseboard_fab2_lib.baseboard_fab2(sch_1):page45_i111:DQ(13)" )
				( attribute "RELATIVE_PROPAGATION_DELAY_SCOPE" "G"
					( Parent
						( matchGroupRef "@baseboard_fab2_lib.baseboard_fab2(sch_1):\MG_DQ-DQS_FAR_DIMM_NG_M_B_BYTE1\" )
					)
					( Status sCSetFlattened )
					( Origin gBackEnd )
				)
				( attribute "RELATIVE_PROPAGATION_DELAY" "0.00 MIL,195.00 MIL"
					( Parent
						( matchGroupRef "@baseboard_fab2_lib.baseboard_fab2(sch_1):\MG_DQ-DQS_FAR_DIMM_NG_M_B_BYTE1\" )
					)
					( Units "uMatchProp" "ns" 1.000000)
					( Status sCSetFlattened )
					( Origin gBackEnd )
				)
				( attribute "RELATIVE_PROPAGATION_DELAY_SCOPE" "G"
					( Parent
						( matchGroupRef "@baseboard_fab2_lib.baseboard_fab2(sch_1):\MG_DQ_FAR_DIMM_NG_M_B_BYTE1\" )
					)
					( Status sCSetFlattened )
					( Origin gBackEnd )
				)
				( attribute "RELATIVE_PROPAGATION_DELAY" "-50.00 MIL,50.00 MIL"
					( Parent
						( matchGroupRef "@baseboard_fab2_lib.baseboard_fab2(sch_1):\MG_DQ_FAR_DIMM_NG_M_B_BYTE1\" )
					)
					( Units "uMatchProp" "ns" 1.000000)
					( Status sCSetFlattened )
					( Origin gBackEnd )
				)
			)
			( pinPair "@baseboard_fab2_lib.baseboard_fab2(sch_1):\PP5081\"
				( pinRef "@baseboard_fab2_lib.baseboard_fab2(sch_1):page24_i172:DDR1_DQ(12)" )
				( pinRef "@baseboard_fab2_lib.baseboard_fab2(sch_1):page46_i14:DQ(12)" )
				( attribute "RELATIVE_PROPAGATION_DELAY_SCOPE" "G"
					( Parent
						( matchGroupRef "@baseboard_fab2_lib.baseboard_fab2(sch_1):\MG_DQ-DQS_NEAR_DIMM_NG_M_B_BYTE1\" )
					)
					( Status sCSetFlattened )
					( Origin gBackEnd )
				)
				( attribute "RELATIVE_PROPAGATION_DELAY" "0.00 MIL,195.00 MIL"
					( Parent
						( matchGroupRef "@baseboard_fab2_lib.baseboard_fab2(sch_1):\MG_DQ-DQS_NEAR_DIMM_NG_M_B_BYTE1\" )
					)
					( Units "uMatchProp" "ns" 1.000000)
					( Status sCSetFlattened )
					( Origin gBackEnd )
				)
				( attribute "RELATIVE_PROPAGATION_DELAY_SCOPE" "G"
					( Parent
						( matchGroupRef "@baseboard_fab2_lib.baseboard_fab2(sch_1):\MG_DQ_NEAR_DIMM_NG_M_B_BYTE1\" )
					)
					( Status sCSetFlattened )
					( Origin gBackEnd )
				)
				( attribute "RELATIVE_PROPAGATION_DELAY" "-50.00 MIL,50.00 MIL"
					( Parent
						( matchGroupRef "@baseboard_fab2_lib.baseboard_fab2(sch_1):\MG_DQ_NEAR_DIMM_NG_M_B_BYTE1\" )
					)
					( Units "uMatchProp" "ns" 1.000000)
					( Status sCSetFlattened )
					( Origin gBackEnd )
				)
			)
			( pinPair "@baseboard_fab2_lib.baseboard_fab2(sch_1):\PP5082\"
				( pinRef "@baseboard_fab2_lib.baseboard_fab2(sch_1):page24_i172:DDR1_DQ(13)" )
				( pinRef "@baseboard_fab2_lib.baseboard_fab2(sch_1):page45_i111:DQ(12)" )
				( attribute "RELATIVE_PROPAGATION_DELAY_SCOPE" "G"
					( Parent
						( matchGroupRef "@baseboard_fab2_lib.baseboard_fab2(sch_1):\MG_DQ-DQS_FAR_DIMM_NG_M_B_BYTE1\" )
					)
					( Status sCSetFlattened )
					( Origin gBackEnd )
				)
				( attribute "RELATIVE_PROPAGATION_DELAY" "0.00 MIL,195.00 MIL"
					( Parent
						( matchGroupRef "@baseboard_fab2_lib.baseboard_fab2(sch_1):\MG_DQ-DQS_FAR_DIMM_NG_M_B_BYTE1\" )
					)
					( Units "uMatchProp" "ns" 1.000000)
					( Status sCSetFlattened )
					( Origin gBackEnd )
				)
				( attribute "RELATIVE_PROPAGATION_DELAY_SCOPE" "G"
					( Parent
						( matchGroupRef "@baseboard_fab2_lib.baseboard_fab2(sch_1):\MG_DQ_FAR_DIMM_NG_M_B_BYTE1\" )
					)
					( Status sCSetFlattened )
					( Origin gBackEnd )
				)
				( attribute "RELATIVE_PROPAGATION_DELAY" "-50.00 MIL,50.00 MIL"
					( Parent
						( matchGroupRef "@baseboard_fab2_lib.baseboard_fab2(sch_1):\MG_DQ_FAR_DIMM_NG_M_B_BYTE1\" )
					)
					( Units "uMatchProp" "ns" 1.000000)
					( Status sCSetFlattened )
					( Origin gBackEnd )
				)
			)
			( pinPair "@baseboard_fab2_lib.baseboard_fab2(sch_1):\PP5084\"
				( pinRef "@baseboard_fab2_lib.baseboard_fab2(sch_1):page24_i172:DDR1_DQ(13)" )
				( pinRef "@baseboard_fab2_lib.baseboard_fab2(sch_1):page46_i14:DQ(13)" )
				( attribute "RELATIVE_PROPAGATION_DELAY_SCOPE" "G"
					( Parent
						( matchGroupRef "@baseboard_fab2_lib.baseboard_fab2(sch_1):\MG_DQ-DQS_NEAR_DIMM_NG_M_B_BYTE1\" )
					)
					( Status sCSetFlattened )
					( Origin gBackEnd )
				)
				( attribute "RELATIVE_PROPAGATION_DELAY" "0.00 MIL,195.00 MIL"
					( Parent
						( matchGroupRef "@baseboard_fab2_lib.baseboard_fab2(sch_1):\MG_DQ-DQS_NEAR_DIMM_NG_M_B_BYTE1\" )
					)
					( Units "uMatchProp" "ns" 1.000000)
					( Status sCSetFlattened )
					( Origin gBackEnd )
				)
				( attribute "RELATIVE_PROPAGATION_DELAY_SCOPE" "G"
					( Parent
						( matchGroupRef "@baseboard_fab2_lib.baseboard_fab2(sch_1):\MG_DQ_NEAR_DIMM_NG_M_B_BYTE1\" )
					)
					( Status sCSetFlattened )
					( Origin gBackEnd )
				)
				( attribute "RELATIVE_PROPAGATION_DELAY" "-50.00 MIL,50.00 MIL"
					( Parent
						( matchGroupRef "@baseboard_fab2_lib.baseboard_fab2(sch_1):\MG_DQ_NEAR_DIMM_NG_M_B_BYTE1\" )
					)
					( Units "uMatchProp" "ns" 1.000000)
					( Status sCSetFlattened )
					( Origin gBackEnd )
				)
			)
			( pinPair "@baseboard_fab2_lib.baseboard_fab2(sch_1):\PP5085\"
				( pinRef "@baseboard_fab2_lib.baseboard_fab2(sch_1):page24_i172:DDR1_DQ(14)" )
				( pinRef "@baseboard_fab2_lib.baseboard_fab2(sch_1):page45_i111:DQ(15)" )
				( attribute "RELATIVE_PROPAGATION_DELAY_SCOPE" "G"
					( Parent
						( matchGroupRef "@baseboard_fab2_lib.baseboard_fab2(sch_1):\MG_DQ-DQS_FAR_DIMM_NG_M_B_BYTE1\" )
					)
					( Status sCSetFlattened )
					( Origin gBackEnd )
				)
				( attribute "RELATIVE_PROPAGATION_DELAY" "0.00 MIL,195.00 MIL"
					( Parent
						( matchGroupRef "@baseboard_fab2_lib.baseboard_fab2(sch_1):\MG_DQ-DQS_FAR_DIMM_NG_M_B_BYTE1\" )
					)
					( Units "uMatchProp" "ns" 1.000000)
					( Status sCSetFlattened )
					( Origin gBackEnd )
				)
				( attribute "RELATIVE_PROPAGATION_DELAY_SCOPE" "G"
					( Parent
						( matchGroupRef "@baseboard_fab2_lib.baseboard_fab2(sch_1):\MG_DQ_FAR_DIMM_NG_M_B_BYTE1\" )
					)
					( Status sCSetFlattened )
					( Origin gBackEnd )
				)
				( attribute "RELATIVE_PROPAGATION_DELAY" "-50.00 MIL,50.00 MIL"
					( Parent
						( matchGroupRef "@baseboard_fab2_lib.baseboard_fab2(sch_1):\MG_DQ_FAR_DIMM_NG_M_B_BYTE1\" )
					)
					( Units "uMatchProp" "ns" 1.000000)
					( Status sCSetFlattened )
					( Origin gBackEnd )
				)
			)
			( pinPair "@baseboard_fab2_lib.baseboard_fab2(sch_1):\PP5087\"
				( pinRef "@baseboard_fab2_lib.baseboard_fab2(sch_1):page24_i172:DDR1_DQ(14)" )
				( pinRef "@baseboard_fab2_lib.baseboard_fab2(sch_1):page46_i14:DQ(14)" )
				( attribute "RELATIVE_PROPAGATION_DELAY_SCOPE" "G"
					( Parent
						( matchGroupRef "@baseboard_fab2_lib.baseboard_fab2(sch_1):\MG_DQ-DQS_NEAR_DIMM_NG_M_B_BYTE1\" )
					)
					( Status sCSetFlattened )
					( Origin gBackEnd )
				)
				( attribute "RELATIVE_PROPAGATION_DELAY" "0.00 MIL,195.00 MIL"
					( Parent
						( matchGroupRef "@baseboard_fab2_lib.baseboard_fab2(sch_1):\MG_DQ-DQS_NEAR_DIMM_NG_M_B_BYTE1\" )
					)
					( Units "uMatchProp" "ns" 1.000000)
					( Status sCSetFlattened )
					( Origin gBackEnd )
				)
				( attribute "RELATIVE_PROPAGATION_DELAY_SCOPE" "G"
					( Parent
						( matchGroupRef "@baseboard_fab2_lib.baseboard_fab2(sch_1):\MG_DQ_NEAR_DIMM_NG_M_B_BYTE1\" )
					)
					( Status sCSetFlattened )
					( Origin gBackEnd )
				)
				( attribute "RELATIVE_PROPAGATION_DELAY" "-50.00 MIL,50.00 MIL"
					( Parent
						( matchGroupRef "@baseboard_fab2_lib.baseboard_fab2(sch_1):\MG_DQ_NEAR_DIMM_NG_M_B_BYTE1\" )
					)
					( Units "uMatchProp" "ns" 1.000000)
					( Status sCSetFlattened )
					( Origin gBackEnd )
				)
			)
			( pinPair "@baseboard_fab2_lib.baseboard_fab2(sch_1):\PP5088\"
				( pinRef "@baseboard_fab2_lib.baseboard_fab2(sch_1):page24_i172:DDR1_DQ(15)" )
				( pinRef "@baseboard_fab2_lib.baseboard_fab2(sch_1):page45_i111:DQ(14)" )
				( attribute "RELATIVE_PROPAGATION_DELAY_SCOPE" "G"
					( Parent
						( matchGroupRef "@baseboard_fab2_lib.baseboard_fab2(sch_1):\MG_DQ-DQS_FAR_DIMM_NG_M_B_BYTE1\" )
					)
					( Status sCSetFlattened )
					( Origin gBackEnd )
				)
				( attribute "RELATIVE_PROPAGATION_DELAY" "0.00 MIL,195.00 MIL"
					( Parent
						( matchGroupRef "@baseboard_fab2_lib.baseboard_fab2(sch_1):\MG_DQ-DQS_FAR_DIMM_NG_M_B_BYTE1\" )
					)
					( Units "uMatchProp" "ns" 1.000000)
					( Status sCSetFlattened )
					( Origin gBackEnd )
				)
				( attribute "RELATIVE_PROPAGATION_DELAY_SCOPE" "G"
					( Parent
						( matchGroupRef "@baseboard_fab2_lib.baseboard_fab2(sch_1):\MG_DQ_FAR_DIMM_NG_M_B_BYTE1\" )
					)
					( Status sCSetFlattened )
					( Origin gBackEnd )
				)
				( attribute "RELATIVE_PROPAGATION_DELAY" "-50.00 MIL,50.00 MIL"
					( Parent
						( matchGroupRef "@baseboard_fab2_lib.baseboard_fab2(sch_1):\MG_DQ_FAR_DIMM_NG_M_B_BYTE1\" )
					)
					( Units "uMatchProp" "ns" 1.000000)
					( Status sCSetFlattened )
					( Origin gBackEnd )
				)
			)
			( pinPair "@baseboard_fab2_lib.baseboard_fab2(sch_1):\PP5090\"
				( pinRef "@baseboard_fab2_lib.baseboard_fab2(sch_1):page24_i172:DDR1_DQ(15)" )
				( pinRef "@baseboard_fab2_lib.baseboard_fab2(sch_1):page46_i14:DQ(15)" )
				( attribute "RELATIVE_PROPAGATION_DELAY_SCOPE" "G"
					( Parent
						( matchGroupRef "@baseboard_fab2_lib.baseboard_fab2(sch_1):\MG_DQ-DQS_NEAR_DIMM_NG_M_B_BYTE1\" )
					)
					( Status sCSetFlattened )
					( Origin gBackEnd )
				)
				( attribute "RELATIVE_PROPAGATION_DELAY" "0.00 MIL,195.00 MIL"
					( Parent
						( matchGroupRef "@baseboard_fab2_lib.baseboard_fab2(sch_1):\MG_DQ-DQS_NEAR_DIMM_NG_M_B_BYTE1\" )
					)
					( Units "uMatchProp" "ns" 1.000000)
					( Status sCSetFlattened )
					( Origin gBackEnd )
				)
				( attribute "RELATIVE_PROPAGATION_DELAY_SCOPE" "G"
					( Parent
						( matchGroupRef "@baseboard_fab2_lib.baseboard_fab2(sch_1):\MG_DQ_NEAR_DIMM_NG_M_B_BYTE1\" )
					)
					( Status sCSetFlattened )
					( Origin gBackEnd )
				)
				( attribute "RELATIVE_PROPAGATION_DELAY" "-50.00 MIL,50.00 MIL"
					( Parent
						( matchGroupRef "@baseboard_fab2_lib.baseboard_fab2(sch_1):\MG_DQ_NEAR_DIMM_NG_M_B_BYTE1\" )
					)
					( Units "uMatchProp" "ns" 1.000000)
					( Status sCSetFlattened )
					( Origin gBackEnd )
				)
			)
			( pinPair "@baseboard_fab2_lib.baseboard_fab2(sch_1):\PP5043\"
				( pinRef "@baseboard_fab2_lib.baseboard_fab2(sch_1):page24_i172:DDR1_DQ(16)" )
				( pinRef "@baseboard_fab2_lib.baseboard_fab2(sch_1):page45_i111:DQ(17)" )
				( attribute "RELATIVE_PROPAGATION_DELAY_SCOPE" "G"
					( Parent
						( matchGroupRef "@baseboard_fab2_lib.baseboard_fab2(sch_1):\MG_DQ-DQS_FAR_DIMM_NG_M_B_BYTE2\" )
					)
					( Status sCSetFlattened )
					( Origin gBackEnd )
				)
				( attribute "RELATIVE_PROPAGATION_DELAY" "0.00 MIL,195.00 MIL"
					( Parent
						( matchGroupRef "@baseboard_fab2_lib.baseboard_fab2(sch_1):\MG_DQ-DQS_FAR_DIMM_NG_M_B_BYTE2\" )
					)
					( Units "uMatchProp" "ns" 1.000000)
					( Status sCSetFlattened )
					( Origin gBackEnd )
				)
				( attribute "RELATIVE_PROPAGATION_DELAY_SCOPE" "G"
					( Parent
						( matchGroupRef "@baseboard_fab2_lib.baseboard_fab2(sch_1):\MG_DQ_FAR_DIMM_NG_M_B_BYTE2\" )
					)
					( Status sCSetFlattened )
					( Origin gBackEnd )
				)
				( attribute "RELATIVE_PROPAGATION_DELAY" "-50.00 MIL,50.00 MIL"
					( Parent
						( matchGroupRef "@baseboard_fab2_lib.baseboard_fab2(sch_1):\MG_DQ_FAR_DIMM_NG_M_B_BYTE2\" )
					)
					( Units "uMatchProp" "ns" 1.000000)
					( Status sCSetFlattened )
					( Origin gBackEnd )
				)
			)
			( pinPair "@baseboard_fab2_lib.baseboard_fab2(sch_1):\PP5045\"
				( pinRef "@baseboard_fab2_lib.baseboard_fab2(sch_1):page24_i172:DDR1_DQ(16)" )
				( pinRef "@baseboard_fab2_lib.baseboard_fab2(sch_1):page46_i14:DQ(16)" )
				( attribute "RELATIVE_PROPAGATION_DELAY_SCOPE" "G"
					( Parent
						( matchGroupRef "@baseboard_fab2_lib.baseboard_fab2(sch_1):\MG_DQ-DQS_NEAR_DIMM_NG_M_B_BYTE2\" )
					)
					( Status sCSetFlattened )
					( Origin gBackEnd )
				)
				( attribute "RELATIVE_PROPAGATION_DELAY" "0.00 MIL,195.00 MIL"
					( Parent
						( matchGroupRef "@baseboard_fab2_lib.baseboard_fab2(sch_1):\MG_DQ-DQS_NEAR_DIMM_NG_M_B_BYTE2\" )
					)
					( Units "uMatchProp" "ns" 1.000000)
					( Status sCSetFlattened )
					( Origin gBackEnd )
				)
				( attribute "RELATIVE_PROPAGATION_DELAY_SCOPE" "G"
					( Parent
						( matchGroupRef "@baseboard_fab2_lib.baseboard_fab2(sch_1):\MG_DQ_NEAR_DIMM_NG_M_B_BYTE2\" )
					)
					( Status sCSetFlattened )
					( Origin gBackEnd )
				)
				( attribute "RELATIVE_PROPAGATION_DELAY" "-50.00 MIL,50.00 MIL"
					( Parent
						( matchGroupRef "@baseboard_fab2_lib.baseboard_fab2(sch_1):\MG_DQ_NEAR_DIMM_NG_M_B_BYTE2\" )
					)
					( Units "uMatchProp" "ns" 1.000000)
					( Status sCSetFlattened )
					( Origin gBackEnd )
				)
			)
			( pinPair "@baseboard_fab2_lib.baseboard_fab2(sch_1):\PP5046\"
				( pinRef "@baseboard_fab2_lib.baseboard_fab2(sch_1):page24_i172:DDR1_DQ(17)" )
				( pinRef "@baseboard_fab2_lib.baseboard_fab2(sch_1):page45_i111:DQ(16)" )
				( attribute "RELATIVE_PROPAGATION_DELAY_SCOPE" "G"
					( Parent
						( matchGroupRef "@baseboard_fab2_lib.baseboard_fab2(sch_1):\MG_DQ-DQS_FAR_DIMM_NG_M_B_BYTE2\" )
					)
					( Status sCSetFlattened )
					( Origin gBackEnd )
				)
				( attribute "RELATIVE_PROPAGATION_DELAY" "0.00 MIL,195.00 MIL"
					( Parent
						( matchGroupRef "@baseboard_fab2_lib.baseboard_fab2(sch_1):\MG_DQ-DQS_FAR_DIMM_NG_M_B_BYTE2\" )
					)
					( Units "uMatchProp" "ns" 1.000000)
					( Status sCSetFlattened )
					( Origin gBackEnd )
				)
				( attribute "RELATIVE_PROPAGATION_DELAY_SCOPE" "G"
					( Parent
						( matchGroupRef "@baseboard_fab2_lib.baseboard_fab2(sch_1):\MG_DQ_FAR_DIMM_NG_M_B_BYTE2\" )
					)
					( Status sCSetFlattened )
					( Origin gBackEnd )
				)
				( attribute "RELATIVE_PROPAGATION_DELAY" "-50.00 MIL,50.00 MIL"
					( Parent
						( matchGroupRef "@baseboard_fab2_lib.baseboard_fab2(sch_1):\MG_DQ_FAR_DIMM_NG_M_B_BYTE2\" )
					)
					( Units "uMatchProp" "ns" 1.000000)
					( Status sCSetFlattened )
					( Origin gBackEnd )
				)
			)
			( pinPair "@baseboard_fab2_lib.baseboard_fab2(sch_1):\PP5048\"
				( pinRef "@baseboard_fab2_lib.baseboard_fab2(sch_1):page24_i172:DDR1_DQ(17)" )
				( pinRef "@baseboard_fab2_lib.baseboard_fab2(sch_1):page46_i14:DQ(17)" )
				( attribute "RELATIVE_PROPAGATION_DELAY_SCOPE" "G"
					( Parent
						( matchGroupRef "@baseboard_fab2_lib.baseboard_fab2(sch_1):\MG_DQ-DQS_NEAR_DIMM_NG_M_B_BYTE2\" )
					)
					( Status sCSetFlattened )
					( Origin gBackEnd )
				)
				( attribute "RELATIVE_PROPAGATION_DELAY" "0.00 MIL,195.00 MIL"
					( Parent
						( matchGroupRef "@baseboard_fab2_lib.baseboard_fab2(sch_1):\MG_DQ-DQS_NEAR_DIMM_NG_M_B_BYTE2\" )
					)
					( Units "uMatchProp" "ns" 1.000000)
					( Status sCSetFlattened )
					( Origin gBackEnd )
				)
				( attribute "RELATIVE_PROPAGATION_DELAY_SCOPE" "G"
					( Parent
						( matchGroupRef "@baseboard_fab2_lib.baseboard_fab2(sch_1):\MG_DQ_NEAR_DIMM_NG_M_B_BYTE2\" )
					)
					( Status sCSetFlattened )
					( Origin gBackEnd )
				)
				( attribute "RELATIVE_PROPAGATION_DELAY" "-50.00 MIL,50.00 MIL"
					( Parent
						( matchGroupRef "@baseboard_fab2_lib.baseboard_fab2(sch_1):\MG_DQ_NEAR_DIMM_NG_M_B_BYTE2\" )
					)
					( Units "uMatchProp" "ns" 1.000000)
					( Status sCSetFlattened )
					( Origin gBackEnd )
				)
			)
			( pinPair "@baseboard_fab2_lib.baseboard_fab2(sch_1):\PP5049\"
				( pinRef "@baseboard_fab2_lib.baseboard_fab2(sch_1):page24_i172:DDR1_DQ(18)" )
				( pinRef "@baseboard_fab2_lib.baseboard_fab2(sch_1):page45_i111:DQ(19)" )
				( attribute "RELATIVE_PROPAGATION_DELAY_SCOPE" "G"
					( Parent
						( matchGroupRef "@baseboard_fab2_lib.baseboard_fab2(sch_1):\MG_DQ-DQS_FAR_DIMM_NG_M_B_BYTE2\" )
					)
					( Status sCSetFlattened )
					( Origin gBackEnd )
				)
				( attribute "RELATIVE_PROPAGATION_DELAY" "0.00 MIL,195.00 MIL"
					( Parent
						( matchGroupRef "@baseboard_fab2_lib.baseboard_fab2(sch_1):\MG_DQ-DQS_FAR_DIMM_NG_M_B_BYTE2\" )
					)
					( Units "uMatchProp" "ns" 1.000000)
					( Status sCSetFlattened )
					( Origin gBackEnd )
				)
				( attribute "RELATIVE_PROPAGATION_DELAY_SCOPE" "G"
					( Parent
						( matchGroupRef "@baseboard_fab2_lib.baseboard_fab2(sch_1):\MG_DQ_FAR_DIMM_NG_M_B_BYTE2\" )
					)
					( Status sCSetFlattened )
					( Origin gBackEnd )
				)
				( attribute "RELATIVE_PROPAGATION_DELAY" "-50.00 MIL,50.00 MIL"
					( Parent
						( matchGroupRef "@baseboard_fab2_lib.baseboard_fab2(sch_1):\MG_DQ_FAR_DIMM_NG_M_B_BYTE2\" )
					)
					( Units "uMatchProp" "ns" 1.000000)
					( Status sCSetFlattened )
					( Origin gBackEnd )
				)
			)
			( pinPair "@baseboard_fab2_lib.baseboard_fab2(sch_1):\PP5051\"
				( pinRef "@baseboard_fab2_lib.baseboard_fab2(sch_1):page24_i172:DDR1_DQ(18)" )
				( pinRef "@baseboard_fab2_lib.baseboard_fab2(sch_1):page46_i14:DQ(18)" )
				( attribute "RELATIVE_PROPAGATION_DELAY_SCOPE" "G"
					( Parent
						( matchGroupRef "@baseboard_fab2_lib.baseboard_fab2(sch_1):\MG_DQ-DQS_NEAR_DIMM_NG_M_B_BYTE2\" )
					)
					( Status sCSetFlattened )
					( Origin gBackEnd )
				)
				( attribute "RELATIVE_PROPAGATION_DELAY" "0.00 MIL,195.00 MIL"
					( Parent
						( matchGroupRef "@baseboard_fab2_lib.baseboard_fab2(sch_1):\MG_DQ-DQS_NEAR_DIMM_NG_M_B_BYTE2\" )
					)
					( Units "uMatchProp" "ns" 1.000000)
					( Status sCSetFlattened )
					( Origin gBackEnd )
				)
				( attribute "RELATIVE_PROPAGATION_DELAY_SCOPE" "G"
					( Parent
						( matchGroupRef "@baseboard_fab2_lib.baseboard_fab2(sch_1):\MG_DQ_NEAR_DIMM_NG_M_B_BYTE2\" )
					)
					( Status sCSetFlattened )
					( Origin gBackEnd )
				)
				( attribute "RELATIVE_PROPAGATION_DELAY" "-50.00 MIL,50.00 MIL"
					( Parent
						( matchGroupRef "@baseboard_fab2_lib.baseboard_fab2(sch_1):\MG_DQ_NEAR_DIMM_NG_M_B_BYTE2\" )
					)
					( Units "uMatchProp" "ns" 1.000000)
					( Status sCSetFlattened )
					( Origin gBackEnd )
				)
			)
			( pinPair "@baseboard_fab2_lib.baseboard_fab2(sch_1):\PP5052\"
				( pinRef "@baseboard_fab2_lib.baseboard_fab2(sch_1):page24_i172:DDR1_DQ(19)" )
				( pinRef "@baseboard_fab2_lib.baseboard_fab2(sch_1):page45_i111:DQ(18)" )
				( attribute "RELATIVE_PROPAGATION_DELAY_SCOPE" "G"
					( Parent
						( matchGroupRef "@baseboard_fab2_lib.baseboard_fab2(sch_1):\MG_DQ-DQS_FAR_DIMM_NG_M_B_BYTE2\" )
					)
					( Status sCSetFlattened )
					( Origin gBackEnd )
				)
				( attribute "RELATIVE_PROPAGATION_DELAY" "0.00 MIL,195.00 MIL"
					( Parent
						( matchGroupRef "@baseboard_fab2_lib.baseboard_fab2(sch_1):\MG_DQ-DQS_FAR_DIMM_NG_M_B_BYTE2\" )
					)
					( Units "uMatchProp" "ns" 1.000000)
					( Status sCSetFlattened )
					( Origin gBackEnd )
				)
				( attribute "RELATIVE_PROPAGATION_DELAY_SCOPE" "G"
					( Parent
						( matchGroupRef "@baseboard_fab2_lib.baseboard_fab2(sch_1):\MG_DQ_FAR_DIMM_NG_M_B_BYTE2\" )
					)
					( Status sCSetFlattened )
					( Origin gBackEnd )
				)
				( attribute "RELATIVE_PROPAGATION_DELAY" "-50.00 MIL,50.00 MIL"
					( Parent
						( matchGroupRef "@baseboard_fab2_lib.baseboard_fab2(sch_1):\MG_DQ_FAR_DIMM_NG_M_B_BYTE2\" )
					)
					( Units "uMatchProp" "ns" 1.000000)
					( Status sCSetFlattened )
					( Origin gBackEnd )
				)
			)
			( pinPair "@baseboard_fab2_lib.baseboard_fab2(sch_1):\PP5054\"
				( pinRef "@baseboard_fab2_lib.baseboard_fab2(sch_1):page24_i172:DDR1_DQ(19)" )
				( pinRef "@baseboard_fab2_lib.baseboard_fab2(sch_1):page46_i14:DQ(19)" )
				( attribute "RELATIVE_PROPAGATION_DELAY_SCOPE" "G"
					( Parent
						( matchGroupRef "@baseboard_fab2_lib.baseboard_fab2(sch_1):\MG_DQ-DQS_NEAR_DIMM_NG_M_B_BYTE2\" )
					)
					( Status sCSetFlattened )
					( Origin gBackEnd )
				)
				( attribute "RELATIVE_PROPAGATION_DELAY" "0.00 MIL,195.00 MIL"
					( Parent
						( matchGroupRef "@baseboard_fab2_lib.baseboard_fab2(sch_1):\MG_DQ-DQS_NEAR_DIMM_NG_M_B_BYTE2\" )
					)
					( Units "uMatchProp" "ns" 1.000000)
					( Status sCSetFlattened )
					( Origin gBackEnd )
				)
				( attribute "RELATIVE_PROPAGATION_DELAY_SCOPE" "G"
					( Parent
						( matchGroupRef "@baseboard_fab2_lib.baseboard_fab2(sch_1):\MG_DQ_NEAR_DIMM_NG_M_B_BYTE2\" )
					)
					( Status sCSetFlattened )
					( Origin gBackEnd )
				)
				( attribute "RELATIVE_PROPAGATION_DELAY" "-50.00 MIL,50.00 MIL"
					( Parent
						( matchGroupRef "@baseboard_fab2_lib.baseboard_fab2(sch_1):\MG_DQ_NEAR_DIMM_NG_M_B_BYTE2\" )
					)
					( Units "uMatchProp" "ns" 1.000000)
					( Status sCSetFlattened )
					( Origin gBackEnd )
				)
			)
			( pinPair "@baseboard_fab2_lib.baseboard_fab2(sch_1):\PP5055\"
				( pinRef "@baseboard_fab2_lib.baseboard_fab2(sch_1):page24_i172:DDR1_DQ(20)" )
				( pinRef "@baseboard_fab2_lib.baseboard_fab2(sch_1):page45_i111:DQ(21)" )
				( attribute "RELATIVE_PROPAGATION_DELAY_SCOPE" "G"
					( Parent
						( matchGroupRef "@baseboard_fab2_lib.baseboard_fab2(sch_1):\MG_DQ-DQS_FAR_DIMM_NG_M_B_BYTE2\" )
					)
					( Status sCSetFlattened )
					( Origin gBackEnd )
				)
				( attribute "RELATIVE_PROPAGATION_DELAY" "0.00 MIL,195.00 MIL"
					( Parent
						( matchGroupRef "@baseboard_fab2_lib.baseboard_fab2(sch_1):\MG_DQ-DQS_FAR_DIMM_NG_M_B_BYTE2\" )
					)
					( Units "uMatchProp" "ns" 1.000000)
					( Status sCSetFlattened )
					( Origin gBackEnd )
				)
				( attribute "RELATIVE_PROPAGATION_DELAY_SCOPE" "G"
					( Parent
						( matchGroupRef "@baseboard_fab2_lib.baseboard_fab2(sch_1):\MG_DQ_FAR_DIMM_NG_M_B_BYTE2\" )
					)
					( Status sCSetFlattened )
					( Origin gBackEnd )
				)
				( attribute "RELATIVE_PROPAGATION_DELAY" "-50.00 MIL,50.00 MIL"
					( Parent
						( matchGroupRef "@baseboard_fab2_lib.baseboard_fab2(sch_1):\MG_DQ_FAR_DIMM_NG_M_B_BYTE2\" )
					)
					( Units "uMatchProp" "ns" 1.000000)
					( Status sCSetFlattened )
					( Origin gBackEnd )
				)
			)
			( pinPair "@baseboard_fab2_lib.baseboard_fab2(sch_1):\PP5057\"
				( pinRef "@baseboard_fab2_lib.baseboard_fab2(sch_1):page24_i172:DDR1_DQ(20)" )
				( pinRef "@baseboard_fab2_lib.baseboard_fab2(sch_1):page46_i14:DQ(20)" )
				( attribute "RELATIVE_PROPAGATION_DELAY_SCOPE" "G"
					( Parent
						( matchGroupRef "@baseboard_fab2_lib.baseboard_fab2(sch_1):\MG_DQ-DQS_NEAR_DIMM_NG_M_B_BYTE2\" )
					)
					( Status sCSetFlattened )
					( Origin gBackEnd )
				)
				( attribute "RELATIVE_PROPAGATION_DELAY" "0.00 MIL,195.00 MIL"
					( Parent
						( matchGroupRef "@baseboard_fab2_lib.baseboard_fab2(sch_1):\MG_DQ-DQS_NEAR_DIMM_NG_M_B_BYTE2\" )
					)
					( Units "uMatchProp" "ns" 1.000000)
					( Status sCSetFlattened )
					( Origin gBackEnd )
				)
				( attribute "RELATIVE_PROPAGATION_DELAY_SCOPE" "G"
					( Parent
						( matchGroupRef "@baseboard_fab2_lib.baseboard_fab2(sch_1):\MG_DQ_NEAR_DIMM_NG_M_B_BYTE2\" )
					)
					( Status sCSetFlattened )
					( Origin gBackEnd )
				)
				( attribute "RELATIVE_PROPAGATION_DELAY" "-50.00 MIL,50.00 MIL"
					( Parent
						( matchGroupRef "@baseboard_fab2_lib.baseboard_fab2(sch_1):\MG_DQ_NEAR_DIMM_NG_M_B_BYTE2\" )
					)
					( Units "uMatchProp" "ns" 1.000000)
					( Status sCSetFlattened )
					( Origin gBackEnd )
				)
			)
			( pinPair "@baseboard_fab2_lib.baseboard_fab2(sch_1):\PP5058\"
				( pinRef "@baseboard_fab2_lib.baseboard_fab2(sch_1):page24_i172:DDR1_DQ(21)" )
				( pinRef "@baseboard_fab2_lib.baseboard_fab2(sch_1):page45_i111:DQ(20)" )
				( attribute "RELATIVE_PROPAGATION_DELAY_SCOPE" "G"
					( Parent
						( matchGroupRef "@baseboard_fab2_lib.baseboard_fab2(sch_1):\MG_DQ-DQS_FAR_DIMM_NG_M_B_BYTE2\" )
					)
					( Status sCSetFlattened )
					( Origin gBackEnd )
				)
				( attribute "RELATIVE_PROPAGATION_DELAY" "0.00 MIL,195.00 MIL"
					( Parent
						( matchGroupRef "@baseboard_fab2_lib.baseboard_fab2(sch_1):\MG_DQ-DQS_FAR_DIMM_NG_M_B_BYTE2\" )
					)
					( Units "uMatchProp" "ns" 1.000000)
					( Status sCSetFlattened )
					( Origin gBackEnd )
				)
				( attribute "RELATIVE_PROPAGATION_DELAY_SCOPE" "G"
					( Parent
						( matchGroupRef "@baseboard_fab2_lib.baseboard_fab2(sch_1):\MG_DQ_FAR_DIMM_NG_M_B_BYTE2\" )
					)
					( Status sCSetFlattened )
					( Origin gBackEnd )
				)
				( attribute "RELATIVE_PROPAGATION_DELAY" "-50.00 MIL,50.00 MIL"
					( Parent
						( matchGroupRef "@baseboard_fab2_lib.baseboard_fab2(sch_1):\MG_DQ_FAR_DIMM_NG_M_B_BYTE2\" )
					)
					( Units "uMatchProp" "ns" 1.000000)
					( Status sCSetFlattened )
					( Origin gBackEnd )
				)
			)
			( pinPair "@baseboard_fab2_lib.baseboard_fab2(sch_1):\PP5060\"
				( pinRef "@baseboard_fab2_lib.baseboard_fab2(sch_1):page24_i172:DDR1_DQ(21)" )
				( pinRef "@baseboard_fab2_lib.baseboard_fab2(sch_1):page46_i14:DQ(21)" )
				( attribute "RELATIVE_PROPAGATION_DELAY_SCOPE" "G"
					( Parent
						( matchGroupRef "@baseboard_fab2_lib.baseboard_fab2(sch_1):\MG_DQ-DQS_NEAR_DIMM_NG_M_B_BYTE2\" )
					)
					( Status sCSetFlattened )
					( Origin gBackEnd )
				)
				( attribute "RELATIVE_PROPAGATION_DELAY" "0.00 MIL,195.00 MIL"
					( Parent
						( matchGroupRef "@baseboard_fab2_lib.baseboard_fab2(sch_1):\MG_DQ-DQS_NEAR_DIMM_NG_M_B_BYTE2\" )
					)
					( Units "uMatchProp" "ns" 1.000000)
					( Status sCSetFlattened )
					( Origin gBackEnd )
				)
				( attribute "RELATIVE_PROPAGATION_DELAY_SCOPE" "G"
					( Parent
						( matchGroupRef "@baseboard_fab2_lib.baseboard_fab2(sch_1):\MG_DQ_NEAR_DIMM_NG_M_B_BYTE2\" )
					)
					( Status sCSetFlattened )
					( Origin gBackEnd )
				)
				( attribute "RELATIVE_PROPAGATION_DELAY" "-50.00 MIL,50.00 MIL"
					( Parent
						( matchGroupRef "@baseboard_fab2_lib.baseboard_fab2(sch_1):\MG_DQ_NEAR_DIMM_NG_M_B_BYTE2\" )
					)
					( Units "uMatchProp" "ns" 1.000000)
					( Status sCSetFlattened )
					( Origin gBackEnd )
				)
			)
			( pinPair "@baseboard_fab2_lib.baseboard_fab2(sch_1):\PP5061\"
				( pinRef "@baseboard_fab2_lib.baseboard_fab2(sch_1):page24_i172:DDR1_DQ(22)" )
				( pinRef "@baseboard_fab2_lib.baseboard_fab2(sch_1):page45_i111:DQ(23)" )
				( attribute "RELATIVE_PROPAGATION_DELAY_SCOPE" "G"
					( Parent
						( matchGroupRef "@baseboard_fab2_lib.baseboard_fab2(sch_1):\MG_DQ-DQS_FAR_DIMM_NG_M_B_BYTE2\" )
					)
					( Status sCSetFlattened )
					( Origin gBackEnd )
				)
				( attribute "RELATIVE_PROPAGATION_DELAY" "0.00 MIL,195.00 MIL"
					( Parent
						( matchGroupRef "@baseboard_fab2_lib.baseboard_fab2(sch_1):\MG_DQ-DQS_FAR_DIMM_NG_M_B_BYTE2\" )
					)
					( Units "uMatchProp" "ns" 1.000000)
					( Status sCSetFlattened )
					( Origin gBackEnd )
				)
				( attribute "RELATIVE_PROPAGATION_DELAY_SCOPE" "G"
					( Parent
						( matchGroupRef "@baseboard_fab2_lib.baseboard_fab2(sch_1):\MG_DQ_FAR_DIMM_NG_M_B_BYTE2\" )
					)
					( Status sCSetFlattened )
					( Origin gBackEnd )
				)
				( attribute "RELATIVE_PROPAGATION_DELAY" "-50.00 MIL,50.00 MIL"
					( Parent
						( matchGroupRef "@baseboard_fab2_lib.baseboard_fab2(sch_1):\MG_DQ_FAR_DIMM_NG_M_B_BYTE2\" )
					)
					( Units "uMatchProp" "ns" 1.000000)
					( Status sCSetFlattened )
					( Origin gBackEnd )
				)
			)
			( pinPair "@baseboard_fab2_lib.baseboard_fab2(sch_1):\PP5063\"
				( pinRef "@baseboard_fab2_lib.baseboard_fab2(sch_1):page24_i172:DDR1_DQ(22)" )
				( pinRef "@baseboard_fab2_lib.baseboard_fab2(sch_1):page46_i14:DQ(22)" )
				( attribute "RELATIVE_PROPAGATION_DELAY_SCOPE" "G"
					( Parent
						( matchGroupRef "@baseboard_fab2_lib.baseboard_fab2(sch_1):\MG_DQ-DQS_NEAR_DIMM_NG_M_B_BYTE2\" )
					)
					( Status sCSetFlattened )
					( Origin gBackEnd )
				)
				( attribute "RELATIVE_PROPAGATION_DELAY" "0.00 MIL,195.00 MIL"
					( Parent
						( matchGroupRef "@baseboard_fab2_lib.baseboard_fab2(sch_1):\MG_DQ-DQS_NEAR_DIMM_NG_M_B_BYTE2\" )
					)
					( Units "uMatchProp" "ns" 1.000000)
					( Status sCSetFlattened )
					( Origin gBackEnd )
				)
				( attribute "RELATIVE_PROPAGATION_DELAY_SCOPE" "G"
					( Parent
						( matchGroupRef "@baseboard_fab2_lib.baseboard_fab2(sch_1):\MG_DQ_NEAR_DIMM_NG_M_B_BYTE2\" )
					)
					( Status sCSetFlattened )
					( Origin gBackEnd )
				)
				( attribute "RELATIVE_PROPAGATION_DELAY" "-50.00 MIL,50.00 MIL"
					( Parent
						( matchGroupRef "@baseboard_fab2_lib.baseboard_fab2(sch_1):\MG_DQ_NEAR_DIMM_NG_M_B_BYTE2\" )
					)
					( Units "uMatchProp" "ns" 1.000000)
					( Status sCSetFlattened )
					( Origin gBackEnd )
				)
			)
			( pinPair "@baseboard_fab2_lib.baseboard_fab2(sch_1):\PP5064\"
				( pinRef "@baseboard_fab2_lib.baseboard_fab2(sch_1):page24_i172:DDR1_DQ(23)" )
				( pinRef "@baseboard_fab2_lib.baseboard_fab2(sch_1):page45_i111:DQ(22)" )
				( attribute "RELATIVE_PROPAGATION_DELAY_SCOPE" "G"
					( Parent
						( matchGroupRef "@baseboard_fab2_lib.baseboard_fab2(sch_1):\MG_DQ-DQS_FAR_DIMM_NG_M_B_BYTE2\" )
					)
					( Status sCSetFlattened )
					( Origin gBackEnd )
				)
				( attribute "RELATIVE_PROPAGATION_DELAY" "0.00 MIL,195.00 MIL"
					( Parent
						( matchGroupRef "@baseboard_fab2_lib.baseboard_fab2(sch_1):\MG_DQ-DQS_FAR_DIMM_NG_M_B_BYTE2\" )
					)
					( Units "uMatchProp" "ns" 1.000000)
					( Status sCSetFlattened )
					( Origin gBackEnd )
				)
				( attribute "RELATIVE_PROPAGATION_DELAY_SCOPE" "G"
					( Parent
						( matchGroupRef "@baseboard_fab2_lib.baseboard_fab2(sch_1):\MG_DQ_FAR_DIMM_NG_M_B_BYTE2\" )
					)
					( Status sCSetFlattened )
					( Origin gBackEnd )
				)
				( attribute "RELATIVE_PROPAGATION_DELAY" "-50.00 MIL,50.00 MIL"
					( Parent
						( matchGroupRef "@baseboard_fab2_lib.baseboard_fab2(sch_1):\MG_DQ_FAR_DIMM_NG_M_B_BYTE2\" )
					)
					( Units "uMatchProp" "ns" 1.000000)
					( Status sCSetFlattened )
					( Origin gBackEnd )
				)
			)
			( pinPair "@baseboard_fab2_lib.baseboard_fab2(sch_1):\PP5066\"
				( pinRef "@baseboard_fab2_lib.baseboard_fab2(sch_1):page24_i172:DDR1_DQ(23)" )
				( pinRef "@baseboard_fab2_lib.baseboard_fab2(sch_1):page46_i14:DQ(23)" )
				( attribute "RELATIVE_PROPAGATION_DELAY_SCOPE" "G"
					( Parent
						( matchGroupRef "@baseboard_fab2_lib.baseboard_fab2(sch_1):\MG_DQ-DQS_NEAR_DIMM_NG_M_B_BYTE2\" )
					)
					( Status sCSetFlattened )
					( Origin gBackEnd )
				)
				( attribute "RELATIVE_PROPAGATION_DELAY" "0.00 MIL,195.00 MIL"
					( Parent
						( matchGroupRef "@baseboard_fab2_lib.baseboard_fab2(sch_1):\MG_DQ-DQS_NEAR_DIMM_NG_M_B_BYTE2\" )
					)
					( Units "uMatchProp" "ns" 1.000000)
					( Status sCSetFlattened )
					( Origin gBackEnd )
				)
				( attribute "RELATIVE_PROPAGATION_DELAY_SCOPE" "G"
					( Parent
						( matchGroupRef "@baseboard_fab2_lib.baseboard_fab2(sch_1):\MG_DQ_NEAR_DIMM_NG_M_B_BYTE2\" )
					)
					( Status sCSetFlattened )
					( Origin gBackEnd )
				)
				( attribute "RELATIVE_PROPAGATION_DELAY" "-50.00 MIL,50.00 MIL"
					( Parent
						( matchGroupRef "@baseboard_fab2_lib.baseboard_fab2(sch_1):\MG_DQ_NEAR_DIMM_NG_M_B_BYTE2\" )
					)
					( Units "uMatchProp" "ns" 1.000000)
					( Status sCSetFlattened )
					( Origin gBackEnd )
				)
			)
			( pinPair "@baseboard_fab2_lib.baseboard_fab2(sch_1):\PP5019\"
				( pinRef "@baseboard_fab2_lib.baseboard_fab2(sch_1):page24_i172:DDR1_DQ(24)" )
				( pinRef "@baseboard_fab2_lib.baseboard_fab2(sch_1):page45_i111:DQ(25)" )
				( attribute "RELATIVE_PROPAGATION_DELAY_SCOPE" "G"
					( Parent
						( matchGroupRef "@baseboard_fab2_lib.baseboard_fab2(sch_1):\MG_DQ-DQS_FAR_DIMM_NG_M_B_BYTE3\" )
					)
					( Status sCSetFlattened )
					( Origin gBackEnd )
				)
				( attribute "RELATIVE_PROPAGATION_DELAY" "0.00 MIL,195.00 MIL"
					( Parent
						( matchGroupRef "@baseboard_fab2_lib.baseboard_fab2(sch_1):\MG_DQ-DQS_FAR_DIMM_NG_M_B_BYTE3\" )
					)
					( Units "uMatchProp" "ns" 1.000000)
					( Status sCSetFlattened )
					( Origin gBackEnd )
				)
				( attribute "RELATIVE_PROPAGATION_DELAY_SCOPE" "G"
					( Parent
						( matchGroupRef "@crescent_city_bb_fab1_lib.crescent_city_bb_fab1(sch_1):\MG_DQ_FAR_DIMM_NG_M_B_BYTE3\" )
					)
					( Origin gBackEnd )
				)
				( attribute "RELATIVE_PROPAGATION_DELAY" "-52.12 MIL,50.00 MIL"
					( Parent
						( matchGroupRef "@crescent_city_bb_fab1_lib.crescent_city_bb_fab1(sch_1):\MG_DQ_FAR_DIMM_NG_M_B_BYTE3\" )
					)
					( Units "uMatchProp" "ns" 1.000000)
					( Origin gBackEnd )
				)
			)
			( pinPair "@baseboard_fab2_lib.baseboard_fab2(sch_1):\PP5021\"
				( pinRef "@baseboard_fab2_lib.baseboard_fab2(sch_1):page24_i172:DDR1_DQ(24)" )
				( pinRef "@baseboard_fab2_lib.baseboard_fab2(sch_1):page46_i14:DQ(24)" )
				( attribute "RELATIVE_PROPAGATION_DELAY_SCOPE" "G"
					( Parent
						( matchGroupRef "@baseboard_fab2_lib.baseboard_fab2(sch_1):\MG_DQ-DQS_NEAR_DIMM_NG_M_B_BYTE3\" )
					)
					( Status sCSetFlattened )
					( Origin gBackEnd )
				)
				( attribute "RELATIVE_PROPAGATION_DELAY" "0.00 MIL,195.00 MIL"
					( Parent
						( matchGroupRef "@baseboard_fab2_lib.baseboard_fab2(sch_1):\MG_DQ-DQS_NEAR_DIMM_NG_M_B_BYTE3\" )
					)
					( Units "uMatchProp" "ns" 1.000000)
					( Status sCSetFlattened )
					( Origin gBackEnd )
				)
				( attribute "RELATIVE_PROPAGATION_DELAY_SCOPE" "G"
					( Parent
						( matchGroupRef "@crescent_city_bb_fab1_lib.crescent_city_bb_fab1(sch_1):\MG_DQ_NEAR_DIMM_NG_M_B_BYTE3\" )
					)
					( Origin gBackEnd )
				)
				( attribute "RELATIVE_PROPAGATION_DELAY" "-52.12 MIL,50.00 MIL"
					( Parent
						( matchGroupRef "@crescent_city_bb_fab1_lib.crescent_city_bb_fab1(sch_1):\MG_DQ_NEAR_DIMM_NG_M_B_BYTE3\" )
					)
					( Units "uMatchProp" "ns" 1.000000)
					( Origin gBackEnd )
				)
			)
			( pinPair "@baseboard_fab2_lib.baseboard_fab2(sch_1):\PP5022\"
				( pinRef "@baseboard_fab2_lib.baseboard_fab2(sch_1):page24_i172:DDR1_DQ(25)" )
				( pinRef "@baseboard_fab2_lib.baseboard_fab2(sch_1):page45_i111:DQ(24)" )
				( attribute "RELATIVE_PROPAGATION_DELAY_SCOPE" "G"
					( Parent
						( matchGroupRef "@baseboard_fab2_lib.baseboard_fab2(sch_1):\MG_DQ-DQS_FAR_DIMM_NG_M_B_BYTE3\" )
					)
					( Status sCSetFlattened )
					( Origin gBackEnd )
				)
				( attribute "RELATIVE_PROPAGATION_DELAY" "0.00 MIL,195.00 MIL"
					( Parent
						( matchGroupRef "@baseboard_fab2_lib.baseboard_fab2(sch_1):\MG_DQ-DQS_FAR_DIMM_NG_M_B_BYTE3\" )
					)
					( Units "uMatchProp" "ns" 1.000000)
					( Status sCSetFlattened )
					( Origin gBackEnd )
				)
				( attribute "RELATIVE_PROPAGATION_DELAY_SCOPE" "G"
					( Parent
						( matchGroupRef "@crescent_city_bb_fab1_lib.crescent_city_bb_fab1(sch_1):\MG_DQ_FAR_DIMM_NG_M_B_BYTE3\" )
					)
					( Origin gBackEnd )
				)
				( attribute "RELATIVE_PROPAGATION_DELAY" "-50.86 MIL,50.00 MIL"
					( Parent
						( matchGroupRef "@crescent_city_bb_fab1_lib.crescent_city_bb_fab1(sch_1):\MG_DQ_FAR_DIMM_NG_M_B_BYTE3\" )
					)
					( Units "uMatchProp" "ns" 1.000000)
					( Origin gBackEnd )
				)
			)
			( pinPair "@baseboard_fab2_lib.baseboard_fab2(sch_1):\PP5024\"
				( pinRef "@baseboard_fab2_lib.baseboard_fab2(sch_1):page24_i172:DDR1_DQ(25)" )
				( pinRef "@baseboard_fab2_lib.baseboard_fab2(sch_1):page46_i14:DQ(25)" )
				( attribute "RELATIVE_PROPAGATION_DELAY_SCOPE" "G"
					( Parent
						( matchGroupRef "@baseboard_fab2_lib.baseboard_fab2(sch_1):\MG_DQ-DQS_NEAR_DIMM_NG_M_B_BYTE3\" )
					)
					( Status sCSetFlattened )
					( Origin gBackEnd )
				)
				( attribute "RELATIVE_PROPAGATION_DELAY" "0.00 MIL,195.00 MIL"
					( Parent
						( matchGroupRef "@baseboard_fab2_lib.baseboard_fab2(sch_1):\MG_DQ-DQS_NEAR_DIMM_NG_M_B_BYTE3\" )
					)
					( Units "uMatchProp" "ns" 1.000000)
					( Status sCSetFlattened )
					( Origin gBackEnd )
				)
				( attribute "RELATIVE_PROPAGATION_DELAY_SCOPE" "G"
					( Parent
						( matchGroupRef "@crescent_city_bb_fab1_lib.crescent_city_bb_fab1(sch_1):\MG_DQ_NEAR_DIMM_NG_M_B_BYTE3\" )
					)
					( Origin gBackEnd )
				)
				( attribute "RELATIVE_PROPAGATION_DELAY" "-50.86 MIL,50.00 MIL"
					( Parent
						( matchGroupRef "@crescent_city_bb_fab1_lib.crescent_city_bb_fab1(sch_1):\MG_DQ_NEAR_DIMM_NG_M_B_BYTE3\" )
					)
					( Units "uMatchProp" "ns" 1.000000)
					( Origin gBackEnd )
				)
			)
			( pinPair "@baseboard_fab2_lib.baseboard_fab2(sch_1):\PP5025\"
				( pinRef "@baseboard_fab2_lib.baseboard_fab2(sch_1):page24_i172:DDR1_DQ(26)" )
				( pinRef "@baseboard_fab2_lib.baseboard_fab2(sch_1):page45_i111:DQ(27)" )
				( attribute "RELATIVE_PROPAGATION_DELAY_SCOPE" "G"
					( Parent
						( matchGroupRef "@baseboard_fab2_lib.baseboard_fab2(sch_1):\MG_DQ-DQS_FAR_DIMM_NG_M_B_BYTE3\" )
					)
					( Status sCSetFlattened )
					( Origin gBackEnd )
				)
				( attribute "RELATIVE_PROPAGATION_DELAY" "0.00 MIL,195.00 MIL"
					( Parent
						( matchGroupRef "@baseboard_fab2_lib.baseboard_fab2(sch_1):\MG_DQ-DQS_FAR_DIMM_NG_M_B_BYTE3\" )
					)
					( Units "uMatchProp" "ns" 1.000000)
					( Status sCSetFlattened )
					( Origin gBackEnd )
				)
				( attribute "RELATIVE_PROPAGATION_DELAY_SCOPE" "G"
					( Parent
						( matchGroupRef "@crescent_city_bb_fab1_lib.crescent_city_bb_fab1(sch_1):\MG_DQ_FAR_DIMM_NG_M_B_BYTE3\" )
					)
					( Origin gBackEnd )
				)
				( attribute "RELATIVE_PROPAGATION_DELAY" "-47.38 MIL,50.00 MIL"
					( Parent
						( matchGroupRef "@crescent_city_bb_fab1_lib.crescent_city_bb_fab1(sch_1):\MG_DQ_FAR_DIMM_NG_M_B_BYTE3\" )
					)
					( Units "uMatchProp" "ns" 1.000000)
					( Origin gBackEnd )
				)
			)
			( pinPair "@baseboard_fab2_lib.baseboard_fab2(sch_1):\PP5027\"
				( pinRef "@baseboard_fab2_lib.baseboard_fab2(sch_1):page24_i172:DDR1_DQ(26)" )
				( pinRef "@baseboard_fab2_lib.baseboard_fab2(sch_1):page46_i14:DQ(26)" )
				( attribute "RELATIVE_PROPAGATION_DELAY_SCOPE" "G"
					( Parent
						( matchGroupRef "@baseboard_fab2_lib.baseboard_fab2(sch_1):\MG_DQ-DQS_NEAR_DIMM_NG_M_B_BYTE3\" )
					)
					( Status sCSetFlattened )
					( Origin gBackEnd )
				)
				( attribute "RELATIVE_PROPAGATION_DELAY" "0.00 MIL,195.00 MIL"
					( Parent
						( matchGroupRef "@baseboard_fab2_lib.baseboard_fab2(sch_1):\MG_DQ-DQS_NEAR_DIMM_NG_M_B_BYTE3\" )
					)
					( Units "uMatchProp" "ns" 1.000000)
					( Status sCSetFlattened )
					( Origin gBackEnd )
				)
				( attribute "RELATIVE_PROPAGATION_DELAY_SCOPE" "G"
					( Parent
						( matchGroupRef "@crescent_city_bb_fab1_lib.crescent_city_bb_fab1(sch_1):\MG_DQ_NEAR_DIMM_NG_M_B_BYTE3\" )
					)
					( Origin gBackEnd )
				)
				( attribute "RELATIVE_PROPAGATION_DELAY" "-47.38 MIL,50.00 MIL"
					( Parent
						( matchGroupRef "@crescent_city_bb_fab1_lib.crescent_city_bb_fab1(sch_1):\MG_DQ_NEAR_DIMM_NG_M_B_BYTE3\" )
					)
					( Units "uMatchProp" "ns" 1.000000)
					( Origin gBackEnd )
				)
			)
			( pinPair "@baseboard_fab2_lib.baseboard_fab2(sch_1):\PP5028\"
				( pinRef "@baseboard_fab2_lib.baseboard_fab2(sch_1):page24_i172:DDR1_DQ(27)" )
				( pinRef "@baseboard_fab2_lib.baseboard_fab2(sch_1):page45_i111:DQ(26)" )
				( attribute "RELATIVE_PROPAGATION_DELAY_SCOPE" "G"
					( Parent
						( matchGroupRef "@baseboard_fab2_lib.baseboard_fab2(sch_1):\MG_DQ-DQS_FAR_DIMM_NG_M_B_BYTE3\" )
					)
					( Status sCSetFlattened )
					( Origin gBackEnd )
				)
				( attribute "RELATIVE_PROPAGATION_DELAY" "0.00 MIL,195.00 MIL"
					( Parent
						( matchGroupRef "@baseboard_fab2_lib.baseboard_fab2(sch_1):\MG_DQ-DQS_FAR_DIMM_NG_M_B_BYTE3\" )
					)
					( Units "uMatchProp" "ns" 1.000000)
					( Status sCSetFlattened )
					( Origin gBackEnd )
				)
				( attribute "RELATIVE_PROPAGATION_DELAY_SCOPE" "G"
					( Parent
						( matchGroupRef "@crescent_city_bb_fab1_lib.crescent_city_bb_fab1(sch_1):\MG_DQ_FAR_DIMM_NG_M_B_BYTE3\" )
					)
					( Origin gBackEnd )
				)
				( attribute "RELATIVE_PROPAGATION_DELAY" "-13.53 MIL,50.00 MIL"
					( Parent
						( matchGroupRef "@crescent_city_bb_fab1_lib.crescent_city_bb_fab1(sch_1):\MG_DQ_FAR_DIMM_NG_M_B_BYTE3\" )
					)
					( Units "uMatchProp" "ns" 1.000000)
					( Origin gBackEnd )
				)
			)
			( pinPair "@baseboard_fab2_lib.baseboard_fab2(sch_1):\PP5030\"
				( pinRef "@baseboard_fab2_lib.baseboard_fab2(sch_1):page24_i172:DDR1_DQ(27)" )
				( pinRef "@baseboard_fab2_lib.baseboard_fab2(sch_1):page46_i14:DQ(27)" )
				( attribute "RELATIVE_PROPAGATION_DELAY_SCOPE" "G"
					( Parent
						( matchGroupRef "@baseboard_fab2_lib.baseboard_fab2(sch_1):\MG_DQ-DQS_NEAR_DIMM_NG_M_B_BYTE3\" )
					)
					( Status sCSetFlattened )
					( Origin gBackEnd )
				)
				( attribute "RELATIVE_PROPAGATION_DELAY" "0.00 MIL,195.00 MIL"
					( Parent
						( matchGroupRef "@baseboard_fab2_lib.baseboard_fab2(sch_1):\MG_DQ-DQS_NEAR_DIMM_NG_M_B_BYTE3\" )
					)
					( Units "uMatchProp" "ns" 1.000000)
					( Status sCSetFlattened )
					( Origin gBackEnd )
				)
				( attribute "RELATIVE_PROPAGATION_DELAY_SCOPE" "G"
					( Parent
						( matchGroupRef "@crescent_city_bb_fab1_lib.crescent_city_bb_fab1(sch_1):\MG_DQ_NEAR_DIMM_NG_M_B_BYTE3\" )
					)
					( Origin gBackEnd )
				)
				( attribute "RELATIVE_PROPAGATION_DELAY" "-13.53 MIL,50.00 MIL"
					( Parent
						( matchGroupRef "@crescent_city_bb_fab1_lib.crescent_city_bb_fab1(sch_1):\MG_DQ_NEAR_DIMM_NG_M_B_BYTE3\" )
					)
					( Units "uMatchProp" "ns" 1.000000)
					( Origin gBackEnd )
				)
			)
			( pinPair "@baseboard_fab2_lib.baseboard_fab2(sch_1):\PP5031\"
				( pinRef "@baseboard_fab2_lib.baseboard_fab2(sch_1):page24_i172:DDR1_DQ(28)" )
				( pinRef "@baseboard_fab2_lib.baseboard_fab2(sch_1):page45_i111:DQ(29)" )
				( attribute "RELATIVE_PROPAGATION_DELAY_SCOPE" "G"
					( Parent
						( matchGroupRef "@baseboard_fab2_lib.baseboard_fab2(sch_1):\MG_DQ-DQS_FAR_DIMM_NG_M_B_BYTE3\" )
					)
					( Status sCSetFlattened )
					( Origin gBackEnd )
				)
				( attribute "RELATIVE_PROPAGATION_DELAY" "0.00 MIL,195.00 MIL"
					( Parent
						( matchGroupRef "@baseboard_fab2_lib.baseboard_fab2(sch_1):\MG_DQ-DQS_FAR_DIMM_NG_M_B_BYTE3\" )
					)
					( Units "uMatchProp" "ns" 1.000000)
					( Status sCSetFlattened )
					( Origin gBackEnd )
				)
				( attribute "RELATIVE_PROPAGATION_DELAY_SCOPE" "G"
					( Parent
						( matchGroupRef "@crescent_city_bb_fab1_lib.crescent_city_bb_fab1(sch_1):\MG_DQ_FAR_DIMM_NG_M_B_BYTE3\" )
					)
					( Origin gBackEnd )
				)
				( attribute "RELATIVE_PROPAGATION_DELAY" "-15.88 MIL,50.00 MIL"
					( Parent
						( matchGroupRef "@crescent_city_bb_fab1_lib.crescent_city_bb_fab1(sch_1):\MG_DQ_FAR_DIMM_NG_M_B_BYTE3\" )
					)
					( Units "uMatchProp" "ns" 1.000000)
					( Origin gBackEnd )
				)
			)
			( pinPair "@baseboard_fab2_lib.baseboard_fab2(sch_1):\PP5033\"
				( pinRef "@baseboard_fab2_lib.baseboard_fab2(sch_1):page24_i172:DDR1_DQ(28)" )
				( pinRef "@baseboard_fab2_lib.baseboard_fab2(sch_1):page46_i14:DQ(28)" )
				( attribute "RELATIVE_PROPAGATION_DELAY_SCOPE" "G"
					( Parent
						( matchGroupRef "@baseboard_fab2_lib.baseboard_fab2(sch_1):\MG_DQ-DQS_NEAR_DIMM_NG_M_B_BYTE3\" )
					)
					( Status sCSetFlattened )
					( Origin gBackEnd )
				)
				( attribute "RELATIVE_PROPAGATION_DELAY" "0.00 MIL,195.00 MIL"
					( Parent
						( matchGroupRef "@baseboard_fab2_lib.baseboard_fab2(sch_1):\MG_DQ-DQS_NEAR_DIMM_NG_M_B_BYTE3\" )
					)
					( Units "uMatchProp" "ns" 1.000000)
					( Status sCSetFlattened )
					( Origin gBackEnd )
				)
				( attribute "RELATIVE_PROPAGATION_DELAY_SCOPE" "G"
					( Parent
						( matchGroupRef "@crescent_city_bb_fab1_lib.crescent_city_bb_fab1(sch_1):\MG_DQ_NEAR_DIMM_NG_M_B_BYTE3\" )
					)
					( Origin gBackEnd )
				)
				( attribute "RELATIVE_PROPAGATION_DELAY" "-15.88 MIL,50.00 MIL"
					( Parent
						( matchGroupRef "@crescent_city_bb_fab1_lib.crescent_city_bb_fab1(sch_1):\MG_DQ_NEAR_DIMM_NG_M_B_BYTE3\" )
					)
					( Units "uMatchProp" "ns" 1.000000)
					( Origin gBackEnd )
				)
			)
			( pinPair "@baseboard_fab2_lib.baseboard_fab2(sch_1):\PP5034\"
				( pinRef "@baseboard_fab2_lib.baseboard_fab2(sch_1):page24_i172:DDR1_DQ(29)" )
				( pinRef "@baseboard_fab2_lib.baseboard_fab2(sch_1):page45_i111:DQ(28)" )
				( attribute "RELATIVE_PROPAGATION_DELAY_SCOPE" "G"
					( Parent
						( matchGroupRef "@baseboard_fab2_lib.baseboard_fab2(sch_1):\MG_DQ-DQS_FAR_DIMM_NG_M_B_BYTE3\" )
					)
					( Status sCSetFlattened )
					( Origin gBackEnd )
				)
				( attribute "RELATIVE_PROPAGATION_DELAY" "0.00 MIL,195.00 MIL"
					( Parent
						( matchGroupRef "@baseboard_fab2_lib.baseboard_fab2(sch_1):\MG_DQ-DQS_FAR_DIMM_NG_M_B_BYTE3\" )
					)
					( Units "uMatchProp" "ns" 1.000000)
					( Status sCSetFlattened )
					( Origin gBackEnd )
				)
				( attribute "RELATIVE_PROPAGATION_DELAY_SCOPE" "G"
					( Parent
						( matchGroupRef "@crescent_city_bb_fab1_lib.crescent_city_bb_fab1(sch_1):\MG_DQ_FAR_DIMM_NG_M_B_BYTE3\" )
					)
					( Origin gBackEnd )
				)
				( attribute "RELATIVE_PROPAGATION_DELAY" "TARGET,TARGET"
					( Parent
						( matchGroupRef "@crescent_city_bb_fab1_lib.crescent_city_bb_fab1(sch_1):\MG_DQ_FAR_DIMM_NG_M_B_BYTE3\" )
					)
					( Units "uMatchProp" "ns" 1.000000)
					( Origin gBackEnd )
				)
			)
			( pinPair "@baseboard_fab2_lib.baseboard_fab2(sch_1):\PP5036\"
				( pinRef "@baseboard_fab2_lib.baseboard_fab2(sch_1):page24_i172:DDR1_DQ(29)" )
				( pinRef "@baseboard_fab2_lib.baseboard_fab2(sch_1):page46_i14:DQ(29)" )
				( attribute "RELATIVE_PROPAGATION_DELAY_SCOPE" "G"
					( Parent
						( matchGroupRef "@baseboard_fab2_lib.baseboard_fab2(sch_1):\MG_DQ-DQS_NEAR_DIMM_NG_M_B_BYTE3\" )
					)
					( Status sCSetFlattened )
					( Origin gBackEnd )
				)
				( attribute "RELATIVE_PROPAGATION_DELAY" "0.00 MIL,195.00 MIL"
					( Parent
						( matchGroupRef "@baseboard_fab2_lib.baseboard_fab2(sch_1):\MG_DQ-DQS_NEAR_DIMM_NG_M_B_BYTE3\" )
					)
					( Units "uMatchProp" "ns" 1.000000)
					( Status sCSetFlattened )
					( Origin gBackEnd )
				)
				( attribute "RELATIVE_PROPAGATION_DELAY_SCOPE" "G"
					( Parent
						( matchGroupRef "@crescent_city_bb_fab1_lib.crescent_city_bb_fab1(sch_1):\MG_DQ_NEAR_DIMM_NG_M_B_BYTE3\" )
					)
					( Origin gBackEnd )
				)
				( attribute "RELATIVE_PROPAGATION_DELAY" "TARGET,TARGET"
					( Parent
						( matchGroupRef "@crescent_city_bb_fab1_lib.crescent_city_bb_fab1(sch_1):\MG_DQ_NEAR_DIMM_NG_M_B_BYTE3\" )
					)
					( Units "uMatchProp" "ns" 1.000000)
					( Origin gBackEnd )
				)
			)
			( pinPair "@baseboard_fab2_lib.baseboard_fab2(sch_1):\PP5037\"
				( pinRef "@baseboard_fab2_lib.baseboard_fab2(sch_1):page24_i172:DDR1_DQ(30)" )
				( pinRef "@baseboard_fab2_lib.baseboard_fab2(sch_1):page45_i111:DQ(31)" )
				( attribute "RELATIVE_PROPAGATION_DELAY_SCOPE" "G"
					( Parent
						( matchGroupRef "@baseboard_fab2_lib.baseboard_fab2(sch_1):\MG_DQ-DQS_FAR_DIMM_NG_M_B_BYTE3\" )
					)
					( Status sCSetFlattened )
					( Origin gBackEnd )
				)
				( attribute "RELATIVE_PROPAGATION_DELAY" "0.00 MIL,195.00 MIL"
					( Parent
						( matchGroupRef "@baseboard_fab2_lib.baseboard_fab2(sch_1):\MG_DQ-DQS_FAR_DIMM_NG_M_B_BYTE3\" )
					)
					( Units "uMatchProp" "ns" 1.000000)
					( Status sCSetFlattened )
					( Origin gBackEnd )
				)
				( attribute "RELATIVE_PROPAGATION_DELAY_SCOPE" "G"
					( Parent
						( matchGroupRef "@crescent_city_bb_fab1_lib.crescent_city_bb_fab1(sch_1):\MG_DQ_FAR_DIMM_NG_M_B_BYTE3\" )
					)
					( Origin gBackEnd )
				)
				( attribute "RELATIVE_PROPAGATION_DELAY" "-48.40 MIL,50.00 MIL"
					( Parent
						( matchGroupRef "@crescent_city_bb_fab1_lib.crescent_city_bb_fab1(sch_1):\MG_DQ_FAR_DIMM_NG_M_B_BYTE3\" )
					)
					( Units "uMatchProp" "ns" 1.000000)
					( Origin gBackEnd )
				)
			)
			( pinPair "@baseboard_fab2_lib.baseboard_fab2(sch_1):\PP5039\"
				( pinRef "@baseboard_fab2_lib.baseboard_fab2(sch_1):page24_i172:DDR1_DQ(30)" )
				( pinRef "@baseboard_fab2_lib.baseboard_fab2(sch_1):page46_i14:DQ(30)" )
				( attribute "RELATIVE_PROPAGATION_DELAY_SCOPE" "G"
					( Parent
						( matchGroupRef "@baseboard_fab2_lib.baseboard_fab2(sch_1):\MG_DQ-DQS_NEAR_DIMM_NG_M_B_BYTE3\" )
					)
					( Status sCSetFlattened )
					( Origin gBackEnd )
				)
				( attribute "RELATIVE_PROPAGATION_DELAY" "0.00 MIL,195.00 MIL"
					( Parent
						( matchGroupRef "@baseboard_fab2_lib.baseboard_fab2(sch_1):\MG_DQ-DQS_NEAR_DIMM_NG_M_B_BYTE3\" )
					)
					( Units "uMatchProp" "ns" 1.000000)
					( Status sCSetFlattened )
					( Origin gBackEnd )
				)
				( attribute "RELATIVE_PROPAGATION_DELAY_SCOPE" "G"
					( Parent
						( matchGroupRef "@crescent_city_bb_fab1_lib.crescent_city_bb_fab1(sch_1):\MG_DQ_NEAR_DIMM_NG_M_B_BYTE3\" )
					)
					( Origin gBackEnd )
				)
				( attribute "RELATIVE_PROPAGATION_DELAY" "-48.40 MIL,50.00 MIL"
					( Parent
						( matchGroupRef "@crescent_city_bb_fab1_lib.crescent_city_bb_fab1(sch_1):\MG_DQ_NEAR_DIMM_NG_M_B_BYTE3\" )
					)
					( Units "uMatchProp" "ns" 1.000000)
					( Origin gBackEnd )
				)
			)
			( pinPair "@baseboard_fab2_lib.baseboard_fab2(sch_1):\PP5040\"
				( pinRef "@baseboard_fab2_lib.baseboard_fab2(sch_1):page24_i172:DDR1_DQ(31)" )
				( pinRef "@baseboard_fab2_lib.baseboard_fab2(sch_1):page45_i111:DQ(30)" )
				( attribute "RELATIVE_PROPAGATION_DELAY_SCOPE" "G"
					( Parent
						( matchGroupRef "@baseboard_fab2_lib.baseboard_fab2(sch_1):\MG_DQ-DQS_FAR_DIMM_NG_M_B_BYTE3\" )
					)
					( Status sCSetFlattened )
					( Origin gBackEnd )
				)
				( attribute "RELATIVE_PROPAGATION_DELAY" "0.00 MIL,195.00 MIL"
					( Parent
						( matchGroupRef "@baseboard_fab2_lib.baseboard_fab2(sch_1):\MG_DQ-DQS_FAR_DIMM_NG_M_B_BYTE3\" )
					)
					( Units "uMatchProp" "ns" 1.000000)
					( Status sCSetFlattened )
					( Origin gBackEnd )
				)
				( attribute "RELATIVE_PROPAGATION_DELAY_SCOPE" "G"
					( Parent
						( matchGroupRef "@crescent_city_bb_fab1_lib.crescent_city_bb_fab1(sch_1):\MG_DQ_FAR_DIMM_NG_M_B_BYTE3\" )
					)
					( Origin gBackEnd )
				)
				( attribute "RELATIVE_PROPAGATION_DELAY" "-46.39 MIL,50.00 MIL"
					( Parent
						( matchGroupRef "@crescent_city_bb_fab1_lib.crescent_city_bb_fab1(sch_1):\MG_DQ_FAR_DIMM_NG_M_B_BYTE3\" )
					)
					( Units "uMatchProp" "ns" 1.000000)
					( Origin gBackEnd )
				)
			)
			( pinPair "@baseboard_fab2_lib.baseboard_fab2(sch_1):\PP5042\"
				( pinRef "@baseboard_fab2_lib.baseboard_fab2(sch_1):page24_i172:DDR1_DQ(31)" )
				( pinRef "@baseboard_fab2_lib.baseboard_fab2(sch_1):page46_i14:DQ(31)" )
				( attribute "RELATIVE_PROPAGATION_DELAY_SCOPE" "G"
					( Parent
						( matchGroupRef "@baseboard_fab2_lib.baseboard_fab2(sch_1):\MG_DQ-DQS_NEAR_DIMM_NG_M_B_BYTE3\" )
					)
					( Status sCSetFlattened )
					( Origin gBackEnd )
				)
				( attribute "RELATIVE_PROPAGATION_DELAY" "0.00 MIL,195.00 MIL"
					( Parent
						( matchGroupRef "@baseboard_fab2_lib.baseboard_fab2(sch_1):\MG_DQ-DQS_NEAR_DIMM_NG_M_B_BYTE3\" )
					)
					( Units "uMatchProp" "ns" 1.000000)
					( Status sCSetFlattened )
					( Origin gBackEnd )
				)
				( attribute "RELATIVE_PROPAGATION_DELAY_SCOPE" "G"
					( Parent
						( matchGroupRef "@crescent_city_bb_fab1_lib.crescent_city_bb_fab1(sch_1):\MG_DQ_NEAR_DIMM_NG_M_B_BYTE3\" )
					)
					( Origin gBackEnd )
				)
				( attribute "RELATIVE_PROPAGATION_DELAY" "-46.39 MIL,50.00 MIL"
					( Parent
						( matchGroupRef "@crescent_city_bb_fab1_lib.crescent_city_bb_fab1(sch_1):\MG_DQ_NEAR_DIMM_NG_M_B_BYTE3\" )
					)
					( Units "uMatchProp" "ns" 1.000000)
					( Origin gBackEnd )
				)
			)
			( pinPair "@baseboard_fab2_lib.baseboard_fab2(sch_1):\PP4995\"
				( pinRef "@baseboard_fab2_lib.baseboard_fab2(sch_1):page24_i172:DDR1_DQ(32)" )
				( pinRef "@baseboard_fab2_lib.baseboard_fab2(sch_1):page45_i111:DQ(33)" )
				( attribute "RELATIVE_PROPAGATION_DELAY_SCOPE" "G"
					( Parent
						( matchGroupRef "@baseboard_fab2_lib.baseboard_fab2(sch_1):\MG_DQ-DQS_FAR_DIMM_NG_M_B_BYTE4\" )
					)
					( Status sCSetFlattened )
					( Origin gBackEnd )
				)
				( attribute "RELATIVE_PROPAGATION_DELAY" "0.00 MIL,195.00 MIL"
					( Parent
						( matchGroupRef "@baseboard_fab2_lib.baseboard_fab2(sch_1):\MG_DQ-DQS_FAR_DIMM_NG_M_B_BYTE4\" )
					)
					( Units "uMatchProp" "ns" 1.000000)
					( Status sCSetFlattened )
					( Origin gBackEnd )
				)
				( attribute "RELATIVE_PROPAGATION_DELAY_SCOPE" "G"
					( Parent
						( matchGroupRef "@crescent_city_bb_fab1_lib.crescent_city_bb_fab1(sch_1):\MG_DQ_FAR_DIMM_NG_M_B_BYTE4\" )
					)
					( Status sCSetFlattened )
					( Origin gBackEnd )
				)
				( attribute "RELATIVE_PROPAGATION_DELAY" "-50.00 MIL,50.00 MIL"
					( Parent
						( matchGroupRef "@crescent_city_bb_fab1_lib.crescent_city_bb_fab1(sch_1):\MG_DQ_FAR_DIMM_NG_M_B_BYTE4\" )
					)
					( Units "uMatchProp" "ns" 1.000000)
					( Status sCSetFlattened )
					( Origin gBackEnd )
				)
			)
			( pinPair "@baseboard_fab2_lib.baseboard_fab2(sch_1):\PP4997\"
				( pinRef "@baseboard_fab2_lib.baseboard_fab2(sch_1):page24_i172:DDR1_DQ(32)" )
				( pinRef "@baseboard_fab2_lib.baseboard_fab2(sch_1):page46_i14:DQ(32)" )
				( attribute "RELATIVE_PROPAGATION_DELAY_SCOPE" "G"
					( Parent
						( matchGroupRef "@baseboard_fab2_lib.baseboard_fab2(sch_1):\MG_DQ-DQS_NEAR_DIMM_NG_M_B_BYTE4\" )
					)
					( Status sCSetFlattened )
					( Origin gBackEnd )
				)
				( attribute "RELATIVE_PROPAGATION_DELAY" "0.00 MIL,195.00 MIL"
					( Parent
						( matchGroupRef "@baseboard_fab2_lib.baseboard_fab2(sch_1):\MG_DQ-DQS_NEAR_DIMM_NG_M_B_BYTE4\" )
					)
					( Units "uMatchProp" "ns" 1.000000)
					( Status sCSetFlattened )
					( Origin gBackEnd )
				)
				( attribute "RELATIVE_PROPAGATION_DELAY_SCOPE" "G"
					( Parent
						( matchGroupRef "@crescent_city_bb_fab1_lib.crescent_city_bb_fab1(sch_1):\MG_DQ_NEAR_DIMM_NG_M_B_BYTE4\" )
					)
					( Status sCSetFlattened )
					( Origin gBackEnd )
				)
				( attribute "RELATIVE_PROPAGATION_DELAY" "-50.00 MIL,50.00 MIL"
					( Parent
						( matchGroupRef "@crescent_city_bb_fab1_lib.crescent_city_bb_fab1(sch_1):\MG_DQ_NEAR_DIMM_NG_M_B_BYTE4\" )
					)
					( Units "uMatchProp" "ns" 1.000000)
					( Status sCSetFlattened )
					( Origin gBackEnd )
				)
			)
			( pinPair "@baseboard_fab2_lib.baseboard_fab2(sch_1):\PP4998\"
				( pinRef "@baseboard_fab2_lib.baseboard_fab2(sch_1):page24_i172:DDR1_DQ(33)" )
				( pinRef "@baseboard_fab2_lib.baseboard_fab2(sch_1):page45_i111:DQ(32)" )
				( attribute "RELATIVE_PROPAGATION_DELAY_SCOPE" "G"
					( Parent
						( matchGroupRef "@baseboard_fab2_lib.baseboard_fab2(sch_1):\MG_DQ-DQS_FAR_DIMM_NG_M_B_BYTE4\" )
					)
					( Status sCSetFlattened )
					( Origin gBackEnd )
				)
				( attribute "RELATIVE_PROPAGATION_DELAY" "0.00 MIL,195.00 MIL"
					( Parent
						( matchGroupRef "@baseboard_fab2_lib.baseboard_fab2(sch_1):\MG_DQ-DQS_FAR_DIMM_NG_M_B_BYTE4\" )
					)
					( Units "uMatchProp" "ns" 1.000000)
					( Status sCSetFlattened )
					( Origin gBackEnd )
				)
				( attribute "RELATIVE_PROPAGATION_DELAY_SCOPE" "G"
					( Parent
						( matchGroupRef "@crescent_city_bb_fab1_lib.crescent_city_bb_fab1(sch_1):\MG_DQ_FAR_DIMM_NG_M_B_BYTE4\" )
					)
					( Status sCSetFlattened )
					( Origin gBackEnd )
				)
				( attribute "RELATIVE_PROPAGATION_DELAY" "-50.00 MIL,50.00 MIL"
					( Parent
						( matchGroupRef "@crescent_city_bb_fab1_lib.crescent_city_bb_fab1(sch_1):\MG_DQ_FAR_DIMM_NG_M_B_BYTE4\" )
					)
					( Units "uMatchProp" "ns" 1.000000)
					( Status sCSetFlattened )
					( Origin gBackEnd )
				)
			)
			( pinPair "@baseboard_fab2_lib.baseboard_fab2(sch_1):\PP5000\"
				( pinRef "@baseboard_fab2_lib.baseboard_fab2(sch_1):page24_i172:DDR1_DQ(33)" )
				( pinRef "@baseboard_fab2_lib.baseboard_fab2(sch_1):page46_i14:DQ(33)" )
				( attribute "RELATIVE_PROPAGATION_DELAY_SCOPE" "G"
					( Parent
						( matchGroupRef "@baseboard_fab2_lib.baseboard_fab2(sch_1):\MG_DQ-DQS_NEAR_DIMM_NG_M_B_BYTE4\" )
					)
					( Status sCSetFlattened )
					( Origin gBackEnd )
				)
				( attribute "RELATIVE_PROPAGATION_DELAY" "0.00 MIL,195.00 MIL"
					( Parent
						( matchGroupRef "@baseboard_fab2_lib.baseboard_fab2(sch_1):\MG_DQ-DQS_NEAR_DIMM_NG_M_B_BYTE4\" )
					)
					( Units "uMatchProp" "ns" 1.000000)
					( Status sCSetFlattened )
					( Origin gBackEnd )
				)
				( attribute "RELATIVE_PROPAGATION_DELAY_SCOPE" "G"
					( Parent
						( matchGroupRef "@crescent_city_bb_fab1_lib.crescent_city_bb_fab1(sch_1):\MG_DQ_NEAR_DIMM_NG_M_B_BYTE4\" )
					)
					( Status sCSetFlattened )
					( Origin gBackEnd )
				)
				( attribute "RELATIVE_PROPAGATION_DELAY" "-50.00 MIL,50.00 MIL"
					( Parent
						( matchGroupRef "@crescent_city_bb_fab1_lib.crescent_city_bb_fab1(sch_1):\MG_DQ_NEAR_DIMM_NG_M_B_BYTE4\" )
					)
					( Units "uMatchProp" "ns" 1.000000)
					( Status sCSetFlattened )
					( Origin gBackEnd )
				)
			)
			( pinPair "@baseboard_fab2_lib.baseboard_fab2(sch_1):\PP5001\"
				( pinRef "@baseboard_fab2_lib.baseboard_fab2(sch_1):page24_i172:DDR1_DQ(34)" )
				( pinRef "@baseboard_fab2_lib.baseboard_fab2(sch_1):page45_i111:DQ(35)" )
				( attribute "RELATIVE_PROPAGATION_DELAY_SCOPE" "G"
					( Parent
						( matchGroupRef "@baseboard_fab2_lib.baseboard_fab2(sch_1):\MG_DQ-DQS_FAR_DIMM_NG_M_B_BYTE4\" )
					)
					( Status sCSetFlattened )
					( Origin gBackEnd )
				)
				( attribute "RELATIVE_PROPAGATION_DELAY" "0.00 MIL,195.00 MIL"
					( Parent
						( matchGroupRef "@baseboard_fab2_lib.baseboard_fab2(sch_1):\MG_DQ-DQS_FAR_DIMM_NG_M_B_BYTE4\" )
					)
					( Units "uMatchProp" "ns" 1.000000)
					( Status sCSetFlattened )
					( Origin gBackEnd )
				)
				( attribute "RELATIVE_PROPAGATION_DELAY_SCOPE" "G"
					( Parent
						( matchGroupRef "@crescent_city_bb_fab1_lib.crescent_city_bb_fab1(sch_1):\MG_DQ_FAR_DIMM_NG_M_B_BYTE4\" )
					)
					( Status sCSetFlattened )
					( Origin gBackEnd )
				)
				( attribute "RELATIVE_PROPAGATION_DELAY" "-50.00 MIL,50.00 MIL"
					( Parent
						( matchGroupRef "@crescent_city_bb_fab1_lib.crescent_city_bb_fab1(sch_1):\MG_DQ_FAR_DIMM_NG_M_B_BYTE4\" )
					)
					( Units "uMatchProp" "ns" 1.000000)
					( Status sCSetFlattened )
					( Origin gBackEnd )
				)
			)
			( pinPair "@baseboard_fab2_lib.baseboard_fab2(sch_1):\PP5003\"
				( pinRef "@baseboard_fab2_lib.baseboard_fab2(sch_1):page24_i172:DDR1_DQ(34)" )
				( pinRef "@baseboard_fab2_lib.baseboard_fab2(sch_1):page46_i14:DQ(34)" )
				( attribute "RELATIVE_PROPAGATION_DELAY_SCOPE" "G"
					( Parent
						( matchGroupRef "@baseboard_fab2_lib.baseboard_fab2(sch_1):\MG_DQ-DQS_NEAR_DIMM_NG_M_B_BYTE4\" )
					)
					( Status sCSetFlattened )
					( Origin gBackEnd )
				)
				( attribute "RELATIVE_PROPAGATION_DELAY" "0.00 MIL,195.00 MIL"
					( Parent
						( matchGroupRef "@baseboard_fab2_lib.baseboard_fab2(sch_1):\MG_DQ-DQS_NEAR_DIMM_NG_M_B_BYTE4\" )
					)
					( Units "uMatchProp" "ns" 1.000000)
					( Status sCSetFlattened )
					( Origin gBackEnd )
				)
				( attribute "RELATIVE_PROPAGATION_DELAY_SCOPE" "G"
					( Parent
						( matchGroupRef "@crescent_city_bb_fab1_lib.crescent_city_bb_fab1(sch_1):\MG_DQ_NEAR_DIMM_NG_M_B_BYTE4\" )
					)
					( Status sCSetFlattened )
					( Origin gBackEnd )
				)
				( attribute "RELATIVE_PROPAGATION_DELAY" "-50.00 MIL,50.00 MIL"
					( Parent
						( matchGroupRef "@crescent_city_bb_fab1_lib.crescent_city_bb_fab1(sch_1):\MG_DQ_NEAR_DIMM_NG_M_B_BYTE4\" )
					)
					( Units "uMatchProp" "ns" 1.000000)
					( Status sCSetFlattened )
					( Origin gBackEnd )
				)
			)
			( pinPair "@baseboard_fab2_lib.baseboard_fab2(sch_1):\PP5004\"
				( pinRef "@baseboard_fab2_lib.baseboard_fab2(sch_1):page24_i172:DDR1_DQ(35)" )
				( pinRef "@baseboard_fab2_lib.baseboard_fab2(sch_1):page45_i111:DQ(34)" )
				( attribute "RELATIVE_PROPAGATION_DELAY_SCOPE" "G"
					( Parent
						( matchGroupRef "@baseboard_fab2_lib.baseboard_fab2(sch_1):\MG_DQ-DQS_FAR_DIMM_NG_M_B_BYTE4\" )
					)
					( Status sCSetFlattened )
					( Origin gBackEnd )
				)
				( attribute "RELATIVE_PROPAGATION_DELAY" "0.00 MIL,195.00 MIL"
					( Parent
						( matchGroupRef "@baseboard_fab2_lib.baseboard_fab2(sch_1):\MG_DQ-DQS_FAR_DIMM_NG_M_B_BYTE4\" )
					)
					( Units "uMatchProp" "ns" 1.000000)
					( Status sCSetFlattened )
					( Origin gBackEnd )
				)
				( attribute "RELATIVE_PROPAGATION_DELAY_SCOPE" "G"
					( Parent
						( matchGroupRef "@crescent_city_bb_fab1_lib.crescent_city_bb_fab1(sch_1):\MG_DQ_FAR_DIMM_NG_M_B_BYTE4\" )
					)
					( Status sCSetFlattened )
					( Origin gBackEnd )
				)
				( attribute "RELATIVE_PROPAGATION_DELAY" "-50.00 MIL,50.00 MIL"
					( Parent
						( matchGroupRef "@crescent_city_bb_fab1_lib.crescent_city_bb_fab1(sch_1):\MG_DQ_FAR_DIMM_NG_M_B_BYTE4\" )
					)
					( Units "uMatchProp" "ns" 1.000000)
					( Status sCSetFlattened )
					( Origin gBackEnd )
				)
			)
			( pinPair "@baseboard_fab2_lib.baseboard_fab2(sch_1):\PP5006\"
				( pinRef "@baseboard_fab2_lib.baseboard_fab2(sch_1):page24_i172:DDR1_DQ(35)" )
				( pinRef "@baseboard_fab2_lib.baseboard_fab2(sch_1):page46_i14:DQ(35)" )
				( attribute "RELATIVE_PROPAGATION_DELAY_SCOPE" "G"
					( Parent
						( matchGroupRef "@baseboard_fab2_lib.baseboard_fab2(sch_1):\MG_DQ-DQS_NEAR_DIMM_NG_M_B_BYTE4\" )
					)
					( Status sCSetFlattened )
					( Origin gBackEnd )
				)
				( attribute "RELATIVE_PROPAGATION_DELAY" "0.00 MIL,195.00 MIL"
					( Parent
						( matchGroupRef "@baseboard_fab2_lib.baseboard_fab2(sch_1):\MG_DQ-DQS_NEAR_DIMM_NG_M_B_BYTE4\" )
					)
					( Units "uMatchProp" "ns" 1.000000)
					( Status sCSetFlattened )
					( Origin gBackEnd )
				)
				( attribute "RELATIVE_PROPAGATION_DELAY_SCOPE" "G"
					( Parent
						( matchGroupRef "@crescent_city_bb_fab1_lib.crescent_city_bb_fab1(sch_1):\MG_DQ_NEAR_DIMM_NG_M_B_BYTE4\" )
					)
					( Status sCSetFlattened )
					( Origin gBackEnd )
				)
				( attribute "RELATIVE_PROPAGATION_DELAY" "-50.00 MIL,50.00 MIL"
					( Parent
						( matchGroupRef "@crescent_city_bb_fab1_lib.crescent_city_bb_fab1(sch_1):\MG_DQ_NEAR_DIMM_NG_M_B_BYTE4\" )
					)
					( Units "uMatchProp" "ns" 1.000000)
					( Status sCSetFlattened )
					( Origin gBackEnd )
				)
			)
			( pinPair "@baseboard_fab2_lib.baseboard_fab2(sch_1):\PP5007\"
				( pinRef "@baseboard_fab2_lib.baseboard_fab2(sch_1):page24_i172:DDR1_DQ(36)" )
				( pinRef "@baseboard_fab2_lib.baseboard_fab2(sch_1):page45_i111:DQ(37)" )
				( attribute "RELATIVE_PROPAGATION_DELAY_SCOPE" "G"
					( Parent
						( matchGroupRef "@baseboard_fab2_lib.baseboard_fab2(sch_1):\MG_DQ-DQS_FAR_DIMM_NG_M_B_BYTE4\" )
					)
					( Status sCSetFlattened )
					( Origin gBackEnd )
				)
				( attribute "RELATIVE_PROPAGATION_DELAY" "0.00 MIL,195.00 MIL"
					( Parent
						( matchGroupRef "@baseboard_fab2_lib.baseboard_fab2(sch_1):\MG_DQ-DQS_FAR_DIMM_NG_M_B_BYTE4\" )
					)
					( Units "uMatchProp" "ns" 1.000000)
					( Status sCSetFlattened )
					( Origin gBackEnd )
				)
				( attribute "RELATIVE_PROPAGATION_DELAY_SCOPE" "G"
					( Parent
						( matchGroupRef "@crescent_city_bb_fab1_lib.crescent_city_bb_fab1(sch_1):\MG_DQ_FAR_DIMM_NG_M_B_BYTE4\" )
					)
					( Status sCSetFlattened )
					( Origin gBackEnd )
				)
				( attribute "RELATIVE_PROPAGATION_DELAY" "-50.00 MIL,50.00 MIL"
					( Parent
						( matchGroupRef "@crescent_city_bb_fab1_lib.crescent_city_bb_fab1(sch_1):\MG_DQ_FAR_DIMM_NG_M_B_BYTE4\" )
					)
					( Units "uMatchProp" "ns" 1.000000)
					( Status sCSetFlattened )
					( Origin gBackEnd )
				)
			)
			( pinPair "@baseboard_fab2_lib.baseboard_fab2(sch_1):\PP5009\"
				( pinRef "@baseboard_fab2_lib.baseboard_fab2(sch_1):page24_i172:DDR1_DQ(36)" )
				( pinRef "@baseboard_fab2_lib.baseboard_fab2(sch_1):page46_i14:DQ(36)" )
				( attribute "RELATIVE_PROPAGATION_DELAY_SCOPE" "G"
					( Parent
						( matchGroupRef "@baseboard_fab2_lib.baseboard_fab2(sch_1):\MG_DQ-DQS_NEAR_DIMM_NG_M_B_BYTE4\" )
					)
					( Status sCSetFlattened )
					( Origin gBackEnd )
				)
				( attribute "RELATIVE_PROPAGATION_DELAY" "0.00 MIL,195.00 MIL"
					( Parent
						( matchGroupRef "@baseboard_fab2_lib.baseboard_fab2(sch_1):\MG_DQ-DQS_NEAR_DIMM_NG_M_B_BYTE4\" )
					)
					( Units "uMatchProp" "ns" 1.000000)
					( Status sCSetFlattened )
					( Origin gBackEnd )
				)
				( attribute "RELATIVE_PROPAGATION_DELAY_SCOPE" "G"
					( Parent
						( matchGroupRef "@crescent_city_bb_fab1_lib.crescent_city_bb_fab1(sch_1):\MG_DQ_NEAR_DIMM_NG_M_B_BYTE4\" )
					)
					( Status sCSetFlattened )
					( Origin gBackEnd )
				)
				( attribute "RELATIVE_PROPAGATION_DELAY" "-50.00 MIL,50.00 MIL"
					( Parent
						( matchGroupRef "@crescent_city_bb_fab1_lib.crescent_city_bb_fab1(sch_1):\MG_DQ_NEAR_DIMM_NG_M_B_BYTE4\" )
					)
					( Units "uMatchProp" "ns" 1.000000)
					( Status sCSetFlattened )
					( Origin gBackEnd )
				)
			)
			( pinPair "@baseboard_fab2_lib.baseboard_fab2(sch_1):\PP5010\"
				( pinRef "@baseboard_fab2_lib.baseboard_fab2(sch_1):page24_i172:DDR1_DQ(37)" )
				( pinRef "@baseboard_fab2_lib.baseboard_fab2(sch_1):page45_i111:DQ(36)" )
				( attribute "RELATIVE_PROPAGATION_DELAY_SCOPE" "G"
					( Parent
						( matchGroupRef "@baseboard_fab2_lib.baseboard_fab2(sch_1):\MG_DQ-DQS_FAR_DIMM_NG_M_B_BYTE4\" )
					)
					( Status sCSetFlattened )
					( Origin gBackEnd )
				)
				( attribute "RELATIVE_PROPAGATION_DELAY" "0.00 MIL,195.00 MIL"
					( Parent
						( matchGroupRef "@baseboard_fab2_lib.baseboard_fab2(sch_1):\MG_DQ-DQS_FAR_DIMM_NG_M_B_BYTE4\" )
					)
					( Units "uMatchProp" "ns" 1.000000)
					( Status sCSetFlattened )
					( Origin gBackEnd )
				)
				( attribute "RELATIVE_PROPAGATION_DELAY_SCOPE" "G"
					( Parent
						( matchGroupRef "@crescent_city_bb_fab1_lib.crescent_city_bb_fab1(sch_1):\MG_DQ_FAR_DIMM_NG_M_B_BYTE4\" )
					)
					( Origin gBackEnd )
				)
				( attribute "RELATIVE_PROPAGATION_DELAY" "TARGET,TARGET"
					( Parent
						( matchGroupRef "@crescent_city_bb_fab1_lib.crescent_city_bb_fab1(sch_1):\MG_DQ_FAR_DIMM_NG_M_B_BYTE4\" )
					)
					( Units "uMatchProp" "ns" 1.000000)
					( Origin gBackEnd )
				)
			)
			( pinPair "@baseboard_fab2_lib.baseboard_fab2(sch_1):\PP5012\"
				( pinRef "@baseboard_fab2_lib.baseboard_fab2(sch_1):page24_i172:DDR1_DQ(37)" )
				( pinRef "@baseboard_fab2_lib.baseboard_fab2(sch_1):page46_i14:DQ(37)" )
				( attribute "RELATIVE_PROPAGATION_DELAY_SCOPE" "G"
					( Parent
						( matchGroupRef "@baseboard_fab2_lib.baseboard_fab2(sch_1):\MG_DQ-DQS_NEAR_DIMM_NG_M_B_BYTE4\" )
					)
					( Status sCSetFlattened )
					( Origin gBackEnd )
				)
				( attribute "RELATIVE_PROPAGATION_DELAY" "0.00 MIL,195.00 MIL"
					( Parent
						( matchGroupRef "@baseboard_fab2_lib.baseboard_fab2(sch_1):\MG_DQ-DQS_NEAR_DIMM_NG_M_B_BYTE4\" )
					)
					( Units "uMatchProp" "ns" 1.000000)
					( Status sCSetFlattened )
					( Origin gBackEnd )
				)
				( attribute "RELATIVE_PROPAGATION_DELAY_SCOPE" "G"
					( Parent
						( matchGroupRef "@crescent_city_bb_fab1_lib.crescent_city_bb_fab1(sch_1):\MG_DQ_NEAR_DIMM_NG_M_B_BYTE4\" )
					)
					( Origin gBackEnd )
				)
				( attribute "RELATIVE_PROPAGATION_DELAY" "TARGET,TARGET"
					( Parent
						( matchGroupRef "@crescent_city_bb_fab1_lib.crescent_city_bb_fab1(sch_1):\MG_DQ_NEAR_DIMM_NG_M_B_BYTE4\" )
					)
					( Units "uMatchProp" "ns" 1.000000)
					( Origin gBackEnd )
				)
			)
			( pinPair "@baseboard_fab2_lib.baseboard_fab2(sch_1):\PP5013\"
				( pinRef "@baseboard_fab2_lib.baseboard_fab2(sch_1):page24_i172:DDR1_DQ(38)" )
				( pinRef "@baseboard_fab2_lib.baseboard_fab2(sch_1):page45_i111:DQ(39)" )
				( attribute "RELATIVE_PROPAGATION_DELAY_SCOPE" "G"
					( Parent
						( matchGroupRef "@baseboard_fab2_lib.baseboard_fab2(sch_1):\MG_DQ-DQS_FAR_DIMM_NG_M_B_BYTE4\" )
					)
					( Status sCSetFlattened )
					( Origin gBackEnd )
				)
				( attribute "RELATIVE_PROPAGATION_DELAY" "0.00 MIL,195.00 MIL"
					( Parent
						( matchGroupRef "@baseboard_fab2_lib.baseboard_fab2(sch_1):\MG_DQ-DQS_FAR_DIMM_NG_M_B_BYTE4\" )
					)
					( Units "uMatchProp" "ns" 1.000000)
					( Status sCSetFlattened )
					( Origin gBackEnd )
				)
				( attribute "RELATIVE_PROPAGATION_DELAY_SCOPE" "G"
					( Parent
						( matchGroupRef "@crescent_city_bb_fab1_lib.crescent_city_bb_fab1(sch_1):\MG_DQ_FAR_DIMM_NG_M_B_BYTE4\" )
					)
					( Status sCSetFlattened )
					( Origin gBackEnd )
				)
				( attribute "RELATIVE_PROPAGATION_DELAY" "-50.00 MIL,50.00 MIL"
					( Parent
						( matchGroupRef "@crescent_city_bb_fab1_lib.crescent_city_bb_fab1(sch_1):\MG_DQ_FAR_DIMM_NG_M_B_BYTE4\" )
					)
					( Units "uMatchProp" "ns" 1.000000)
					( Status sCSetFlattened )
					( Origin gBackEnd )
				)
			)
			( pinPair "@baseboard_fab2_lib.baseboard_fab2(sch_1):\PP5015\"
				( pinRef "@baseboard_fab2_lib.baseboard_fab2(sch_1):page24_i172:DDR1_DQ(38)" )
				( pinRef "@baseboard_fab2_lib.baseboard_fab2(sch_1):page46_i14:DQ(38)" )
				( attribute "RELATIVE_PROPAGATION_DELAY_SCOPE" "G"
					( Parent
						( matchGroupRef "@baseboard_fab2_lib.baseboard_fab2(sch_1):\MG_DQ-DQS_NEAR_DIMM_NG_M_B_BYTE4\" )
					)
					( Status sCSetFlattened )
					( Origin gBackEnd )
				)
				( attribute "RELATIVE_PROPAGATION_DELAY" "0.00 MIL,195.00 MIL"
					( Parent
						( matchGroupRef "@baseboard_fab2_lib.baseboard_fab2(sch_1):\MG_DQ-DQS_NEAR_DIMM_NG_M_B_BYTE4\" )
					)
					( Units "uMatchProp" "ns" 1.000000)
					( Status sCSetFlattened )
					( Origin gBackEnd )
				)
				( attribute "RELATIVE_PROPAGATION_DELAY_SCOPE" "G"
					( Parent
						( matchGroupRef "@crescent_city_bb_fab1_lib.crescent_city_bb_fab1(sch_1):\MG_DQ_NEAR_DIMM_NG_M_B_BYTE4\" )
					)
					( Status sCSetFlattened )
					( Origin gBackEnd )
				)
				( attribute "RELATIVE_PROPAGATION_DELAY" "-50.00 MIL,50.00 MIL"
					( Parent
						( matchGroupRef "@crescent_city_bb_fab1_lib.crescent_city_bb_fab1(sch_1):\MG_DQ_NEAR_DIMM_NG_M_B_BYTE4\" )
					)
					( Units "uMatchProp" "ns" 1.000000)
					( Status sCSetFlattened )
					( Origin gBackEnd )
				)
			)
			( pinPair "@baseboard_fab2_lib.baseboard_fab2(sch_1):\PP5016\"
				( pinRef "@baseboard_fab2_lib.baseboard_fab2(sch_1):page24_i172:DDR1_DQ(39)" )
				( pinRef "@baseboard_fab2_lib.baseboard_fab2(sch_1):page45_i111:DQ(38)" )
				( attribute "RELATIVE_PROPAGATION_DELAY_SCOPE" "G"
					( Parent
						( matchGroupRef "@baseboard_fab2_lib.baseboard_fab2(sch_1):\MG_DQ-DQS_FAR_DIMM_NG_M_B_BYTE4\" )
					)
					( Status sCSetFlattened )
					( Origin gBackEnd )
				)
				( attribute "RELATIVE_PROPAGATION_DELAY" "0.00 MIL,195.00 MIL"
					( Parent
						( matchGroupRef "@baseboard_fab2_lib.baseboard_fab2(sch_1):\MG_DQ-DQS_FAR_DIMM_NG_M_B_BYTE4\" )
					)
					( Units "uMatchProp" "ns" 1.000000)
					( Status sCSetFlattened )
					( Origin gBackEnd )
				)
				( attribute "RELATIVE_PROPAGATION_DELAY_SCOPE" "G"
					( Parent
						( matchGroupRef "@crescent_city_bb_fab1_lib.crescent_city_bb_fab1(sch_1):\MG_DQ_FAR_DIMM_NG_M_B_BYTE4\" )
					)
					( Status sCSetFlattened )
					( Origin gBackEnd )
				)
				( attribute "RELATIVE_PROPAGATION_DELAY" "-50.00 MIL,50.00 MIL"
					( Parent
						( matchGroupRef "@crescent_city_bb_fab1_lib.crescent_city_bb_fab1(sch_1):\MG_DQ_FAR_DIMM_NG_M_B_BYTE4\" )
					)
					( Units "uMatchProp" "ns" 1.000000)
					( Status sCSetFlattened )
					( Origin gBackEnd )
				)
			)
			( pinPair "@baseboard_fab2_lib.baseboard_fab2(sch_1):\PP5018\"
				( pinRef "@baseboard_fab2_lib.baseboard_fab2(sch_1):page24_i172:DDR1_DQ(39)" )
				( pinRef "@baseboard_fab2_lib.baseboard_fab2(sch_1):page46_i14:DQ(39)" )
				( attribute "RELATIVE_PROPAGATION_DELAY_SCOPE" "G"
					( Parent
						( matchGroupRef "@baseboard_fab2_lib.baseboard_fab2(sch_1):\MG_DQ-DQS_NEAR_DIMM_NG_M_B_BYTE4\" )
					)
					( Status sCSetFlattened )
					( Origin gBackEnd )
				)
				( attribute "RELATIVE_PROPAGATION_DELAY" "0.00 MIL,195.00 MIL"
					( Parent
						( matchGroupRef "@baseboard_fab2_lib.baseboard_fab2(sch_1):\MG_DQ-DQS_NEAR_DIMM_NG_M_B_BYTE4\" )
					)
					( Units "uMatchProp" "ns" 1.000000)
					( Status sCSetFlattened )
					( Origin gBackEnd )
				)
				( attribute "RELATIVE_PROPAGATION_DELAY_SCOPE" "G"
					( Parent
						( matchGroupRef "@crescent_city_bb_fab1_lib.crescent_city_bb_fab1(sch_1):\MG_DQ_NEAR_DIMM_NG_M_B_BYTE4\" )
					)
					( Status sCSetFlattened )
					( Origin gBackEnd )
				)
				( attribute "RELATIVE_PROPAGATION_DELAY" "-50.00 MIL,50.00 MIL"
					( Parent
						( matchGroupRef "@crescent_city_bb_fab1_lib.crescent_city_bb_fab1(sch_1):\MG_DQ_NEAR_DIMM_NG_M_B_BYTE4\" )
					)
					( Units "uMatchProp" "ns" 1.000000)
					( Status sCSetFlattened )
					( Origin gBackEnd )
				)
			)
			( pinPair "@baseboard_fab2_lib.baseboard_fab2(sch_1):\PP4971\"
				( pinRef "@baseboard_fab2_lib.baseboard_fab2(sch_1):page24_i172:DDR1_DQ(40)" )
				( pinRef "@baseboard_fab2_lib.baseboard_fab2(sch_1):page45_i111:DQ(41)" )
				( attribute "RELATIVE_PROPAGATION_DELAY_SCOPE" "G"
					( Parent
						( matchGroupRef "@baseboard_fab2_lib.baseboard_fab2(sch_1):\MG_DQ-DQS_FAR_DIMM_NG_M_B_BYTE5\" )
					)
					( Status sCSetFlattened )
					( Origin gBackEnd )
				)
				( attribute "RELATIVE_PROPAGATION_DELAY" "0.00 MIL,195.00 MIL"
					( Parent
						( matchGroupRef "@baseboard_fab2_lib.baseboard_fab2(sch_1):\MG_DQ-DQS_FAR_DIMM_NG_M_B_BYTE5\" )
					)
					( Units "uMatchProp" "ns" 1.000000)
					( Status sCSetFlattened )
					( Origin gBackEnd )
				)
				( attribute "RELATIVE_PROPAGATION_DELAY_SCOPE" "G"
					( Parent
						( matchGroupRef "@baseboard_fab2_lib.baseboard_fab2(sch_1):\MG_DQ_FAR_DIMM_NG_M_B_BYTE5\" )
					)
					( Status sCSetFlattened )
					( Origin gBackEnd )
				)
				( attribute "RELATIVE_PROPAGATION_DELAY" "-50.00 MIL,50.00 MIL"
					( Parent
						( matchGroupRef "@baseboard_fab2_lib.baseboard_fab2(sch_1):\MG_DQ_FAR_DIMM_NG_M_B_BYTE5\" )
					)
					( Units "uMatchProp" "ns" 1.000000)
					( Status sCSetFlattened )
					( Origin gBackEnd )
				)
			)
			( pinPair "@baseboard_fab2_lib.baseboard_fab2(sch_1):\PP4973\"
				( pinRef "@baseboard_fab2_lib.baseboard_fab2(sch_1):page24_i172:DDR1_DQ(40)" )
				( pinRef "@baseboard_fab2_lib.baseboard_fab2(sch_1):page46_i14:DQ(40)" )
				( attribute "RELATIVE_PROPAGATION_DELAY_SCOPE" "G"
					( Parent
						( matchGroupRef "@baseboard_fab2_lib.baseboard_fab2(sch_1):\MG_DQ-DQS_NEAR_DIMM_NG_M_B_BYTE5\" )
					)
					( Status sCSetFlattened )
					( Origin gBackEnd )
				)
				( attribute "RELATIVE_PROPAGATION_DELAY" "0.00 MIL,195.00 MIL"
					( Parent
						( matchGroupRef "@baseboard_fab2_lib.baseboard_fab2(sch_1):\MG_DQ-DQS_NEAR_DIMM_NG_M_B_BYTE5\" )
					)
					( Units "uMatchProp" "ns" 1.000000)
					( Status sCSetFlattened )
					( Origin gBackEnd )
				)
				( attribute "RELATIVE_PROPAGATION_DELAY_SCOPE" "G"
					( Parent
						( matchGroupRef "@baseboard_fab2_lib.baseboard_fab2(sch_1):\MG_DQ_NEAR_DIMM_NG_M_B_BYTE5\" )
					)
					( Status sCSetFlattened )
					( Origin gBackEnd )
				)
				( attribute "RELATIVE_PROPAGATION_DELAY" "-50.00 MIL,50.00 MIL"
					( Parent
						( matchGroupRef "@baseboard_fab2_lib.baseboard_fab2(sch_1):\MG_DQ_NEAR_DIMM_NG_M_B_BYTE5\" )
					)
					( Units "uMatchProp" "ns" 1.000000)
					( Status sCSetFlattened )
					( Origin gBackEnd )
				)
			)
			( pinPair "@baseboard_fab2_lib.baseboard_fab2(sch_1):\PP4974\"
				( pinRef "@baseboard_fab2_lib.baseboard_fab2(sch_1):page24_i172:DDR1_DQ(41)" )
				( pinRef "@baseboard_fab2_lib.baseboard_fab2(sch_1):page45_i111:DQ(40)" )
				( attribute "RELATIVE_PROPAGATION_DELAY_SCOPE" "G"
					( Parent
						( matchGroupRef "@baseboard_fab2_lib.baseboard_fab2(sch_1):\MG_DQ-DQS_FAR_DIMM_NG_M_B_BYTE5\" )
					)
					( Status sCSetFlattened )
					( Origin gBackEnd )
				)
				( attribute "RELATIVE_PROPAGATION_DELAY" "0.00 MIL,195.00 MIL"
					( Parent
						( matchGroupRef "@baseboard_fab2_lib.baseboard_fab2(sch_1):\MG_DQ-DQS_FAR_DIMM_NG_M_B_BYTE5\" )
					)
					( Units "uMatchProp" "ns" 1.000000)
					( Status sCSetFlattened )
					( Origin gBackEnd )
				)
				( attribute "RELATIVE_PROPAGATION_DELAY_SCOPE" "G"
					( Parent
						( matchGroupRef "@baseboard_fab2_lib.baseboard_fab2(sch_1):\MG_DQ_FAR_DIMM_NG_M_B_BYTE5\" )
					)
					( Status sCSetFlattened )
					( Origin gBackEnd )
				)
				( attribute "RELATIVE_PROPAGATION_DELAY" "-50.00 MIL,50.00 MIL"
					( Parent
						( matchGroupRef "@baseboard_fab2_lib.baseboard_fab2(sch_1):\MG_DQ_FAR_DIMM_NG_M_B_BYTE5\" )
					)
					( Units "uMatchProp" "ns" 1.000000)
					( Status sCSetFlattened )
					( Origin gBackEnd )
				)
			)
			( pinPair "@baseboard_fab2_lib.baseboard_fab2(sch_1):\PP4976\"
				( pinRef "@baseboard_fab2_lib.baseboard_fab2(sch_1):page24_i172:DDR1_DQ(41)" )
				( pinRef "@baseboard_fab2_lib.baseboard_fab2(sch_1):page46_i14:DQ(41)" )
				( attribute "RELATIVE_PROPAGATION_DELAY_SCOPE" "G"
					( Parent
						( matchGroupRef "@baseboard_fab2_lib.baseboard_fab2(sch_1):\MG_DQ-DQS_NEAR_DIMM_NG_M_B_BYTE5\" )
					)
					( Status sCSetFlattened )
					( Origin gBackEnd )
				)
				( attribute "RELATIVE_PROPAGATION_DELAY" "0.00 MIL,195.00 MIL"
					( Parent
						( matchGroupRef "@baseboard_fab2_lib.baseboard_fab2(sch_1):\MG_DQ-DQS_NEAR_DIMM_NG_M_B_BYTE5\" )
					)
					( Units "uMatchProp" "ns" 1.000000)
					( Status sCSetFlattened )
					( Origin gBackEnd )
				)
				( attribute "RELATIVE_PROPAGATION_DELAY_SCOPE" "G"
					( Parent
						( matchGroupRef "@baseboard_fab2_lib.baseboard_fab2(sch_1):\MG_DQ_NEAR_DIMM_NG_M_B_BYTE5\" )
					)
					( Status sCSetFlattened )
					( Origin gBackEnd )
				)
				( attribute "RELATIVE_PROPAGATION_DELAY" "-50.00 MIL,50.00 MIL"
					( Parent
						( matchGroupRef "@baseboard_fab2_lib.baseboard_fab2(sch_1):\MG_DQ_NEAR_DIMM_NG_M_B_BYTE5\" )
					)
					( Units "uMatchProp" "ns" 1.000000)
					( Status sCSetFlattened )
					( Origin gBackEnd )
				)
			)
			( pinPair "@baseboard_fab2_lib.baseboard_fab2(sch_1):\PP4977\"
				( pinRef "@baseboard_fab2_lib.baseboard_fab2(sch_1):page24_i172:DDR1_DQ(42)" )
				( pinRef "@baseboard_fab2_lib.baseboard_fab2(sch_1):page45_i111:DQ(43)" )
				( attribute "RELATIVE_PROPAGATION_DELAY_SCOPE" "G"
					( Parent
						( matchGroupRef "@baseboard_fab2_lib.baseboard_fab2(sch_1):\MG_DQ-DQS_FAR_DIMM_NG_M_B_BYTE5\" )
					)
					( Status sCSetFlattened )
					( Origin gBackEnd )
				)
				( attribute "RELATIVE_PROPAGATION_DELAY" "0.00 MIL,195.00 MIL"
					( Parent
						( matchGroupRef "@baseboard_fab2_lib.baseboard_fab2(sch_1):\MG_DQ-DQS_FAR_DIMM_NG_M_B_BYTE5\" )
					)
					( Units "uMatchProp" "ns" 1.000000)
					( Status sCSetFlattened )
					( Origin gBackEnd )
				)
				( attribute "RELATIVE_PROPAGATION_DELAY_SCOPE" "G"
					( Parent
						( matchGroupRef "@baseboard_fab2_lib.baseboard_fab2(sch_1):\MG_DQ_FAR_DIMM_NG_M_B_BYTE5\" )
					)
					( Status sCSetFlattened )
					( Origin gBackEnd )
				)
				( attribute "RELATIVE_PROPAGATION_DELAY" "-50.00 MIL,50.00 MIL"
					( Parent
						( matchGroupRef "@baseboard_fab2_lib.baseboard_fab2(sch_1):\MG_DQ_FAR_DIMM_NG_M_B_BYTE5\" )
					)
					( Units "uMatchProp" "ns" 1.000000)
					( Status sCSetFlattened )
					( Origin gBackEnd )
				)
			)
			( pinPair "@baseboard_fab2_lib.baseboard_fab2(sch_1):\PP4979\"
				( pinRef "@baseboard_fab2_lib.baseboard_fab2(sch_1):page24_i172:DDR1_DQ(42)" )
				( pinRef "@baseboard_fab2_lib.baseboard_fab2(sch_1):page46_i14:DQ(42)" )
				( attribute "RELATIVE_PROPAGATION_DELAY_SCOPE" "G"
					( Parent
						( matchGroupRef "@baseboard_fab2_lib.baseboard_fab2(sch_1):\MG_DQ-DQS_NEAR_DIMM_NG_M_B_BYTE5\" )
					)
					( Status sCSetFlattened )
					( Origin gBackEnd )
				)
				( attribute "RELATIVE_PROPAGATION_DELAY" "0.00 MIL,195.00 MIL"
					( Parent
						( matchGroupRef "@baseboard_fab2_lib.baseboard_fab2(sch_1):\MG_DQ-DQS_NEAR_DIMM_NG_M_B_BYTE5\" )
					)
					( Units "uMatchProp" "ns" 1.000000)
					( Status sCSetFlattened )
					( Origin gBackEnd )
				)
				( attribute "RELATIVE_PROPAGATION_DELAY_SCOPE" "G"
					( Parent
						( matchGroupRef "@baseboard_fab2_lib.baseboard_fab2(sch_1):\MG_DQ_NEAR_DIMM_NG_M_B_BYTE5\" )
					)
					( Status sCSetFlattened )
					( Origin gBackEnd )
				)
				( attribute "RELATIVE_PROPAGATION_DELAY" "-50.00 MIL,50.00 MIL"
					( Parent
						( matchGroupRef "@baseboard_fab2_lib.baseboard_fab2(sch_1):\MG_DQ_NEAR_DIMM_NG_M_B_BYTE5\" )
					)
					( Units "uMatchProp" "ns" 1.000000)
					( Status sCSetFlattened )
					( Origin gBackEnd )
				)
			)
			( pinPair "@baseboard_fab2_lib.baseboard_fab2(sch_1):\PP4980\"
				( pinRef "@baseboard_fab2_lib.baseboard_fab2(sch_1):page24_i172:DDR1_DQ(43)" )
				( pinRef "@baseboard_fab2_lib.baseboard_fab2(sch_1):page45_i111:DQ(42)" )
				( attribute "RELATIVE_PROPAGATION_DELAY_SCOPE" "G"
					( Parent
						( matchGroupRef "@baseboard_fab2_lib.baseboard_fab2(sch_1):\MG_DQ-DQS_FAR_DIMM_NG_M_B_BYTE5\" )
					)
					( Status sCSetFlattened )
					( Origin gBackEnd )
				)
				( attribute "RELATIVE_PROPAGATION_DELAY" "0.00 MIL,195.00 MIL"
					( Parent
						( matchGroupRef "@baseboard_fab2_lib.baseboard_fab2(sch_1):\MG_DQ-DQS_FAR_DIMM_NG_M_B_BYTE5\" )
					)
					( Units "uMatchProp" "ns" 1.000000)
					( Status sCSetFlattened )
					( Origin gBackEnd )
				)
				( attribute "RELATIVE_PROPAGATION_DELAY_SCOPE" "G"
					( Parent
						( matchGroupRef "@baseboard_fab2_lib.baseboard_fab2(sch_1):\MG_DQ_FAR_DIMM_NG_M_B_BYTE5\" )
					)
					( Status sCSetFlattened )
					( Origin gBackEnd )
				)
				( attribute "RELATIVE_PROPAGATION_DELAY" "-50.00 MIL,50.00 MIL"
					( Parent
						( matchGroupRef "@baseboard_fab2_lib.baseboard_fab2(sch_1):\MG_DQ_FAR_DIMM_NG_M_B_BYTE5\" )
					)
					( Units "uMatchProp" "ns" 1.000000)
					( Status sCSetFlattened )
					( Origin gBackEnd )
				)
			)
			( pinPair "@baseboard_fab2_lib.baseboard_fab2(sch_1):\PP4982\"
				( pinRef "@baseboard_fab2_lib.baseboard_fab2(sch_1):page24_i172:DDR1_DQ(43)" )
				( pinRef "@baseboard_fab2_lib.baseboard_fab2(sch_1):page46_i14:DQ(43)" )
				( attribute "RELATIVE_PROPAGATION_DELAY_SCOPE" "G"
					( Parent
						( matchGroupRef "@baseboard_fab2_lib.baseboard_fab2(sch_1):\MG_DQ-DQS_NEAR_DIMM_NG_M_B_BYTE5\" )
					)
					( Status sCSetFlattened )
					( Origin gBackEnd )
				)
				( attribute "RELATIVE_PROPAGATION_DELAY" "0.00 MIL,195.00 MIL"
					( Parent
						( matchGroupRef "@baseboard_fab2_lib.baseboard_fab2(sch_1):\MG_DQ-DQS_NEAR_DIMM_NG_M_B_BYTE5\" )
					)
					( Units "uMatchProp" "ns" 1.000000)
					( Status sCSetFlattened )
					( Origin gBackEnd )
				)
				( attribute "RELATIVE_PROPAGATION_DELAY_SCOPE" "G"
					( Parent
						( matchGroupRef "@baseboard_fab2_lib.baseboard_fab2(sch_1):\MG_DQ_NEAR_DIMM_NG_M_B_BYTE5\" )
					)
					( Status sCSetFlattened )
					( Origin gBackEnd )
				)
				( attribute "RELATIVE_PROPAGATION_DELAY" "-50.00 MIL,50.00 MIL"
					( Parent
						( matchGroupRef "@baseboard_fab2_lib.baseboard_fab2(sch_1):\MG_DQ_NEAR_DIMM_NG_M_B_BYTE5\" )
					)
					( Units "uMatchProp" "ns" 1.000000)
					( Status sCSetFlattened )
					( Origin gBackEnd )
				)
			)
			( pinPair "@baseboard_fab2_lib.baseboard_fab2(sch_1):\PP4983\"
				( pinRef "@baseboard_fab2_lib.baseboard_fab2(sch_1):page24_i172:DDR1_DQ(44)" )
				( pinRef "@baseboard_fab2_lib.baseboard_fab2(sch_1):page45_i111:DQ(45)" )
				( attribute "RELATIVE_PROPAGATION_DELAY_SCOPE" "G"
					( Parent
						( matchGroupRef "@baseboard_fab2_lib.baseboard_fab2(sch_1):\MG_DQ-DQS_FAR_DIMM_NG_M_B_BYTE5\" )
					)
					( Status sCSetFlattened )
					( Origin gBackEnd )
				)
				( attribute "RELATIVE_PROPAGATION_DELAY" "0.00 MIL,195.00 MIL"
					( Parent
						( matchGroupRef "@baseboard_fab2_lib.baseboard_fab2(sch_1):\MG_DQ-DQS_FAR_DIMM_NG_M_B_BYTE5\" )
					)
					( Units "uMatchProp" "ns" 1.000000)
					( Status sCSetFlattened )
					( Origin gBackEnd )
				)
				( attribute "RELATIVE_PROPAGATION_DELAY_SCOPE" "G"
					( Parent
						( matchGroupRef "@baseboard_fab2_lib.baseboard_fab2(sch_1):\MG_DQ_FAR_DIMM_NG_M_B_BYTE5\" )
					)
					( Status sCSetFlattened )
					( Origin gBackEnd )
				)
				( attribute "RELATIVE_PROPAGATION_DELAY" "-50.00 MIL,50.00 MIL"
					( Parent
						( matchGroupRef "@baseboard_fab2_lib.baseboard_fab2(sch_1):\MG_DQ_FAR_DIMM_NG_M_B_BYTE5\" )
					)
					( Units "uMatchProp" "ns" 1.000000)
					( Status sCSetFlattened )
					( Origin gBackEnd )
				)
			)
			( pinPair "@baseboard_fab2_lib.baseboard_fab2(sch_1):\PP4985\"
				( pinRef "@baseboard_fab2_lib.baseboard_fab2(sch_1):page24_i172:DDR1_DQ(44)" )
				( pinRef "@baseboard_fab2_lib.baseboard_fab2(sch_1):page46_i14:DQ(44)" )
				( attribute "RELATIVE_PROPAGATION_DELAY_SCOPE" "G"
					( Parent
						( matchGroupRef "@baseboard_fab2_lib.baseboard_fab2(sch_1):\MG_DQ-DQS_NEAR_DIMM_NG_M_B_BYTE5\" )
					)
					( Status sCSetFlattened )
					( Origin gBackEnd )
				)
				( attribute "RELATIVE_PROPAGATION_DELAY" "0.00 MIL,195.00 MIL"
					( Parent
						( matchGroupRef "@baseboard_fab2_lib.baseboard_fab2(sch_1):\MG_DQ-DQS_NEAR_DIMM_NG_M_B_BYTE5\" )
					)
					( Units "uMatchProp" "ns" 1.000000)
					( Status sCSetFlattened )
					( Origin gBackEnd )
				)
				( attribute "RELATIVE_PROPAGATION_DELAY_SCOPE" "G"
					( Parent
						( matchGroupRef "@baseboard_fab2_lib.baseboard_fab2(sch_1):\MG_DQ_NEAR_DIMM_NG_M_B_BYTE5\" )
					)
					( Status sCSetFlattened )
					( Origin gBackEnd )
				)
				( attribute "RELATIVE_PROPAGATION_DELAY" "-50.00 MIL,50.00 MIL"
					( Parent
						( matchGroupRef "@baseboard_fab2_lib.baseboard_fab2(sch_1):\MG_DQ_NEAR_DIMM_NG_M_B_BYTE5\" )
					)
					( Units "uMatchProp" "ns" 1.000000)
					( Status sCSetFlattened )
					( Origin gBackEnd )
				)
			)
			( pinPair "@baseboard_fab2_lib.baseboard_fab2(sch_1):\PP4986\"
				( pinRef "@baseboard_fab2_lib.baseboard_fab2(sch_1):page24_i172:DDR1_DQ(45)" )
				( pinRef "@baseboard_fab2_lib.baseboard_fab2(sch_1):page45_i111:DQ(44)" )
				( attribute "RELATIVE_PROPAGATION_DELAY_SCOPE" "G"
					( Parent
						( matchGroupRef "@baseboard_fab2_lib.baseboard_fab2(sch_1):\MG_DQ-DQS_FAR_DIMM_NG_M_B_BYTE5\" )
					)
					( Status sCSetFlattened )
					( Origin gBackEnd )
				)
				( attribute "RELATIVE_PROPAGATION_DELAY" "0.00 MIL,195.00 MIL"
					( Parent
						( matchGroupRef "@baseboard_fab2_lib.baseboard_fab2(sch_1):\MG_DQ-DQS_FAR_DIMM_NG_M_B_BYTE5\" )
					)
					( Units "uMatchProp" "ns" 1.000000)
					( Status sCSetFlattened )
					( Origin gBackEnd )
				)
				( attribute "RELATIVE_PROPAGATION_DELAY_SCOPE" "G"
					( Parent
						( matchGroupRef "@baseboard_fab2_lib.baseboard_fab2(sch_1):\MG_DQ_FAR_DIMM_NG_M_B_BYTE5\" )
					)
					( Status sCSetFlattened )
					( Origin gBackEnd )
				)
				( attribute "RELATIVE_PROPAGATION_DELAY" "-50.00 MIL,50.00 MIL"
					( Parent
						( matchGroupRef "@baseboard_fab2_lib.baseboard_fab2(sch_1):\MG_DQ_FAR_DIMM_NG_M_B_BYTE5\" )
					)
					( Units "uMatchProp" "ns" 1.000000)
					( Status sCSetFlattened )
					( Origin gBackEnd )
				)
			)
			( pinPair "@baseboard_fab2_lib.baseboard_fab2(sch_1):\PP4988\"
				( pinRef "@baseboard_fab2_lib.baseboard_fab2(sch_1):page24_i172:DDR1_DQ(45)" )
				( pinRef "@baseboard_fab2_lib.baseboard_fab2(sch_1):page46_i14:DQ(45)" )
				( attribute "RELATIVE_PROPAGATION_DELAY_SCOPE" "G"
					( Parent
						( matchGroupRef "@baseboard_fab2_lib.baseboard_fab2(sch_1):\MG_DQ-DQS_NEAR_DIMM_NG_M_B_BYTE5\" )
					)
					( Status sCSetFlattened )
					( Origin gBackEnd )
				)
				( attribute "RELATIVE_PROPAGATION_DELAY" "0.00 MIL,195.00 MIL"
					( Parent
						( matchGroupRef "@baseboard_fab2_lib.baseboard_fab2(sch_1):\MG_DQ-DQS_NEAR_DIMM_NG_M_B_BYTE5\" )
					)
					( Units "uMatchProp" "ns" 1.000000)
					( Status sCSetFlattened )
					( Origin gBackEnd )
				)
				( attribute "RELATIVE_PROPAGATION_DELAY_SCOPE" "G"
					( Parent
						( matchGroupRef "@baseboard_fab2_lib.baseboard_fab2(sch_1):\MG_DQ_NEAR_DIMM_NG_M_B_BYTE5\" )
					)
					( Status sCSetFlattened )
					( Origin gBackEnd )
				)
				( attribute "RELATIVE_PROPAGATION_DELAY" "-50.00 MIL,50.00 MIL"
					( Parent
						( matchGroupRef "@baseboard_fab2_lib.baseboard_fab2(sch_1):\MG_DQ_NEAR_DIMM_NG_M_B_BYTE5\" )
					)
					( Units "uMatchProp" "ns" 1.000000)
					( Status sCSetFlattened )
					( Origin gBackEnd )
				)
			)
			( pinPair "@baseboard_fab2_lib.baseboard_fab2(sch_1):\PP4989\"
				( pinRef "@baseboard_fab2_lib.baseboard_fab2(sch_1):page24_i172:DDR1_DQ(46)" )
				( pinRef "@baseboard_fab2_lib.baseboard_fab2(sch_1):page45_i111:DQ(47)" )
				( attribute "RELATIVE_PROPAGATION_DELAY_SCOPE" "G"
					( Parent
						( matchGroupRef "@baseboard_fab2_lib.baseboard_fab2(sch_1):\MG_DQ-DQS_FAR_DIMM_NG_M_B_BYTE5\" )
					)
					( Status sCSetFlattened )
					( Origin gBackEnd )
				)
				( attribute "RELATIVE_PROPAGATION_DELAY" "0.00 MIL,195.00 MIL"
					( Parent
						( matchGroupRef "@baseboard_fab2_lib.baseboard_fab2(sch_1):\MG_DQ-DQS_FAR_DIMM_NG_M_B_BYTE5\" )
					)
					( Units "uMatchProp" "ns" 1.000000)
					( Status sCSetFlattened )
					( Origin gBackEnd )
				)
				( attribute "RELATIVE_PROPAGATION_DELAY_SCOPE" "G"
					( Parent
						( matchGroupRef "@baseboard_fab2_lib.baseboard_fab2(sch_1):\MG_DQ_FAR_DIMM_NG_M_B_BYTE5\" )
					)
					( Status sCSetFlattened )
					( Origin gBackEnd )
				)
				( attribute "RELATIVE_PROPAGATION_DELAY" "-50.00 MIL,50.00 MIL"
					( Parent
						( matchGroupRef "@baseboard_fab2_lib.baseboard_fab2(sch_1):\MG_DQ_FAR_DIMM_NG_M_B_BYTE5\" )
					)
					( Units "uMatchProp" "ns" 1.000000)
					( Status sCSetFlattened )
					( Origin gBackEnd )
				)
			)
			( pinPair "@baseboard_fab2_lib.baseboard_fab2(sch_1):\PP4991\"
				( pinRef "@baseboard_fab2_lib.baseboard_fab2(sch_1):page24_i172:DDR1_DQ(46)" )
				( pinRef "@baseboard_fab2_lib.baseboard_fab2(sch_1):page46_i14:DQ(46)" )
				( attribute "RELATIVE_PROPAGATION_DELAY_SCOPE" "G"
					( Parent
						( matchGroupRef "@baseboard_fab2_lib.baseboard_fab2(sch_1):\MG_DQ-DQS_NEAR_DIMM_NG_M_B_BYTE5\" )
					)
					( Status sCSetFlattened )
					( Origin gBackEnd )
				)
				( attribute "RELATIVE_PROPAGATION_DELAY" "0.00 MIL,195.00 MIL"
					( Parent
						( matchGroupRef "@baseboard_fab2_lib.baseboard_fab2(sch_1):\MG_DQ-DQS_NEAR_DIMM_NG_M_B_BYTE5\" )
					)
					( Units "uMatchProp" "ns" 1.000000)
					( Status sCSetFlattened )
					( Origin gBackEnd )
				)
				( attribute "RELATIVE_PROPAGATION_DELAY_SCOPE" "G"
					( Parent
						( matchGroupRef "@baseboard_fab2_lib.baseboard_fab2(sch_1):\MG_DQ_NEAR_DIMM_NG_M_B_BYTE5\" )
					)
					( Status sCSetFlattened )
					( Origin gBackEnd )
				)
				( attribute "RELATIVE_PROPAGATION_DELAY" "-50.00 MIL,50.00 MIL"
					( Parent
						( matchGroupRef "@baseboard_fab2_lib.baseboard_fab2(sch_1):\MG_DQ_NEAR_DIMM_NG_M_B_BYTE5\" )
					)
					( Units "uMatchProp" "ns" 1.000000)
					( Status sCSetFlattened )
					( Origin gBackEnd )
				)
			)
			( pinPair "@baseboard_fab2_lib.baseboard_fab2(sch_1):\PP4992\"
				( pinRef "@baseboard_fab2_lib.baseboard_fab2(sch_1):page24_i172:DDR1_DQ(47)" )
				( pinRef "@baseboard_fab2_lib.baseboard_fab2(sch_1):page45_i111:DQ(46)" )
				( attribute "RELATIVE_PROPAGATION_DELAY_SCOPE" "G"
					( Parent
						( matchGroupRef "@baseboard_fab2_lib.baseboard_fab2(sch_1):\MG_DQ-DQS_FAR_DIMM_NG_M_B_BYTE5\" )
					)
					( Status sCSetFlattened )
					( Origin gBackEnd )
				)
				( attribute "RELATIVE_PROPAGATION_DELAY" "0.00 MIL,195.00 MIL"
					( Parent
						( matchGroupRef "@baseboard_fab2_lib.baseboard_fab2(sch_1):\MG_DQ-DQS_FAR_DIMM_NG_M_B_BYTE5\" )
					)
					( Units "uMatchProp" "ns" 1.000000)
					( Status sCSetFlattened )
					( Origin gBackEnd )
				)
				( attribute "RELATIVE_PROPAGATION_DELAY_SCOPE" "G"
					( Parent
						( matchGroupRef "@baseboard_fab2_lib.baseboard_fab2(sch_1):\MG_DQ_FAR_DIMM_NG_M_B_BYTE5\" )
					)
					( Status sCSetFlattened )
					( Origin gBackEnd )
				)
				( attribute "RELATIVE_PROPAGATION_DELAY" "-50.00 MIL,50.00 MIL"
					( Parent
						( matchGroupRef "@baseboard_fab2_lib.baseboard_fab2(sch_1):\MG_DQ_FAR_DIMM_NG_M_B_BYTE5\" )
					)
					( Units "uMatchProp" "ns" 1.000000)
					( Status sCSetFlattened )
					( Origin gBackEnd )
				)
			)
			( pinPair "@baseboard_fab2_lib.baseboard_fab2(sch_1):\PP4994\"
				( pinRef "@baseboard_fab2_lib.baseboard_fab2(sch_1):page24_i172:DDR1_DQ(47)" )
				( pinRef "@baseboard_fab2_lib.baseboard_fab2(sch_1):page46_i14:DQ(47)" )
				( attribute "RELATIVE_PROPAGATION_DELAY_SCOPE" "G"
					( Parent
						( matchGroupRef "@baseboard_fab2_lib.baseboard_fab2(sch_1):\MG_DQ-DQS_NEAR_DIMM_NG_M_B_BYTE5\" )
					)
					( Status sCSetFlattened )
					( Origin gBackEnd )
				)
				( attribute "RELATIVE_PROPAGATION_DELAY" "0.00 MIL,195.00 MIL"
					( Parent
						( matchGroupRef "@baseboard_fab2_lib.baseboard_fab2(sch_1):\MG_DQ-DQS_NEAR_DIMM_NG_M_B_BYTE5\" )
					)
					( Units "uMatchProp" "ns" 1.000000)
					( Status sCSetFlattened )
					( Origin gBackEnd )
				)
				( attribute "RELATIVE_PROPAGATION_DELAY_SCOPE" "G"
					( Parent
						( matchGroupRef "@baseboard_fab2_lib.baseboard_fab2(sch_1):\MG_DQ_NEAR_DIMM_NG_M_B_BYTE5\" )
					)
					( Status sCSetFlattened )
					( Origin gBackEnd )
				)
				( attribute "RELATIVE_PROPAGATION_DELAY" "-50.00 MIL,50.00 MIL"
					( Parent
						( matchGroupRef "@baseboard_fab2_lib.baseboard_fab2(sch_1):\MG_DQ_NEAR_DIMM_NG_M_B_BYTE5\" )
					)
					( Units "uMatchProp" "ns" 1.000000)
					( Status sCSetFlattened )
					( Origin gBackEnd )
				)
			)
			( pinPair "@baseboard_fab2_lib.baseboard_fab2(sch_1):\PP4947\"
				( pinRef "@baseboard_fab2_lib.baseboard_fab2(sch_1):page24_i172:DDR1_DQ(48)" )
				( pinRef "@baseboard_fab2_lib.baseboard_fab2(sch_1):page45_i111:DQ(49)" )
				( attribute "RELATIVE_PROPAGATION_DELAY_SCOPE" "G"
					( Parent
						( matchGroupRef "@baseboard_fab2_lib.baseboard_fab2(sch_1):\MG_DQ-DQS_FAR_DIMM_NG_M_B_BYTE6\" )
					)
					( Status sCSetFlattened )
					( Origin gBackEnd )
				)
				( attribute "RELATIVE_PROPAGATION_DELAY" "0.00 MIL,195.00 MIL"
					( Parent
						( matchGroupRef "@baseboard_fab2_lib.baseboard_fab2(sch_1):\MG_DQ-DQS_FAR_DIMM_NG_M_B_BYTE6\" )
					)
					( Units "uMatchProp" "ns" 1.000000)
					( Status sCSetFlattened )
					( Origin gBackEnd )
				)
				( attribute "RELATIVE_PROPAGATION_DELAY_SCOPE" "G"
					( Parent
						( matchGroupRef "@baseboard_fab2_lib.baseboard_fab2(sch_1):\MG_DQ_FAR_DIMM_NG_M_B_BYTE6\" )
					)
					( Status sCSetFlattened )
					( Origin gBackEnd )
				)
				( attribute "RELATIVE_PROPAGATION_DELAY" "-50.00 MIL,50.00 MIL"
					( Parent
						( matchGroupRef "@baseboard_fab2_lib.baseboard_fab2(sch_1):\MG_DQ_FAR_DIMM_NG_M_B_BYTE6\" )
					)
					( Units "uMatchProp" "ns" 1.000000)
					( Status sCSetFlattened )
					( Origin gBackEnd )
				)
			)
			( pinPair "@baseboard_fab2_lib.baseboard_fab2(sch_1):\PP4949\"
				( pinRef "@baseboard_fab2_lib.baseboard_fab2(sch_1):page24_i172:DDR1_DQ(48)" )
				( pinRef "@baseboard_fab2_lib.baseboard_fab2(sch_1):page46_i14:DQ(48)" )
				( attribute "RELATIVE_PROPAGATION_DELAY_SCOPE" "G"
					( Parent
						( matchGroupRef "@baseboard_fab2_lib.baseboard_fab2(sch_1):\MG_DQ-DQS_NEAR_DIMM_NG_M_B_BYTE6\" )
					)
					( Status sCSetFlattened )
					( Origin gBackEnd )
				)
				( attribute "RELATIVE_PROPAGATION_DELAY" "0.00 MIL,195.00 MIL"
					( Parent
						( matchGroupRef "@baseboard_fab2_lib.baseboard_fab2(sch_1):\MG_DQ-DQS_NEAR_DIMM_NG_M_B_BYTE6\" )
					)
					( Units "uMatchProp" "ns" 1.000000)
					( Status sCSetFlattened )
					( Origin gBackEnd )
				)
				( attribute "RELATIVE_PROPAGATION_DELAY_SCOPE" "G"
					( Parent
						( matchGroupRef "@baseboard_fab2_lib.baseboard_fab2(sch_1):\MG_DQ_NEAR_DIMM_NG_M_B_BYTE6\" )
					)
					( Status sCSetFlattened )
					( Origin gBackEnd )
				)
				( attribute "RELATIVE_PROPAGATION_DELAY" "-50.00 MIL,50.00 MIL"
					( Parent
						( matchGroupRef "@baseboard_fab2_lib.baseboard_fab2(sch_1):\MG_DQ_NEAR_DIMM_NG_M_B_BYTE6\" )
					)
					( Units "uMatchProp" "ns" 1.000000)
					( Status sCSetFlattened )
					( Origin gBackEnd )
				)
			)
			( pinPair "@baseboard_fab2_lib.baseboard_fab2(sch_1):\PP4950\"
				( pinRef "@baseboard_fab2_lib.baseboard_fab2(sch_1):page24_i172:DDR1_DQ(49)" )
				( pinRef "@baseboard_fab2_lib.baseboard_fab2(sch_1):page45_i111:DQ(48)" )
				( attribute "RELATIVE_PROPAGATION_DELAY_SCOPE" "G"
					( Parent
						( matchGroupRef "@baseboard_fab2_lib.baseboard_fab2(sch_1):\MG_DQ-DQS_FAR_DIMM_NG_M_B_BYTE6\" )
					)
					( Status sCSetFlattened )
					( Origin gBackEnd )
				)
				( attribute "RELATIVE_PROPAGATION_DELAY" "0.00 MIL,195.00 MIL"
					( Parent
						( matchGroupRef "@baseboard_fab2_lib.baseboard_fab2(sch_1):\MG_DQ-DQS_FAR_DIMM_NG_M_B_BYTE6\" )
					)
					( Units "uMatchProp" "ns" 1.000000)
					( Status sCSetFlattened )
					( Origin gBackEnd )
				)
				( attribute "RELATIVE_PROPAGATION_DELAY_SCOPE" "G"
					( Parent
						( matchGroupRef "@baseboard_fab2_lib.baseboard_fab2(sch_1):\MG_DQ_FAR_DIMM_NG_M_B_BYTE6\" )
					)
					( Status sCSetFlattened )
					( Origin gBackEnd )
				)
				( attribute "RELATIVE_PROPAGATION_DELAY" "-50.00 MIL,50.00 MIL"
					( Parent
						( matchGroupRef "@baseboard_fab2_lib.baseboard_fab2(sch_1):\MG_DQ_FAR_DIMM_NG_M_B_BYTE6\" )
					)
					( Units "uMatchProp" "ns" 1.000000)
					( Status sCSetFlattened )
					( Origin gBackEnd )
				)
			)
			( pinPair "@baseboard_fab2_lib.baseboard_fab2(sch_1):\PP4952\"
				( pinRef "@baseboard_fab2_lib.baseboard_fab2(sch_1):page24_i172:DDR1_DQ(49)" )
				( pinRef "@baseboard_fab2_lib.baseboard_fab2(sch_1):page46_i14:DQ(49)" )
				( attribute "RELATIVE_PROPAGATION_DELAY_SCOPE" "G"
					( Parent
						( matchGroupRef "@baseboard_fab2_lib.baseboard_fab2(sch_1):\MG_DQ-DQS_NEAR_DIMM_NG_M_B_BYTE6\" )
					)
					( Status sCSetFlattened )
					( Origin gBackEnd )
				)
				( attribute "RELATIVE_PROPAGATION_DELAY" "0.00 MIL,195.00 MIL"
					( Parent
						( matchGroupRef "@baseboard_fab2_lib.baseboard_fab2(sch_1):\MG_DQ-DQS_NEAR_DIMM_NG_M_B_BYTE6\" )
					)
					( Units "uMatchProp" "ns" 1.000000)
					( Status sCSetFlattened )
					( Origin gBackEnd )
				)
				( attribute "RELATIVE_PROPAGATION_DELAY_SCOPE" "G"
					( Parent
						( matchGroupRef "@baseboard_fab2_lib.baseboard_fab2(sch_1):\MG_DQ_NEAR_DIMM_NG_M_B_BYTE6\" )
					)
					( Status sCSetFlattened )
					( Origin gBackEnd )
				)
				( attribute "RELATIVE_PROPAGATION_DELAY" "-50.00 MIL,50.00 MIL"
					( Parent
						( matchGroupRef "@baseboard_fab2_lib.baseboard_fab2(sch_1):\MG_DQ_NEAR_DIMM_NG_M_B_BYTE6\" )
					)
					( Units "uMatchProp" "ns" 1.000000)
					( Status sCSetFlattened )
					( Origin gBackEnd )
				)
			)
			( pinPair "@baseboard_fab2_lib.baseboard_fab2(sch_1):\PP4953\"
				( pinRef "@baseboard_fab2_lib.baseboard_fab2(sch_1):page24_i172:DDR1_DQ(50)" )
				( pinRef "@baseboard_fab2_lib.baseboard_fab2(sch_1):page45_i111:DQ(51)" )
				( attribute "RELATIVE_PROPAGATION_DELAY_SCOPE" "G"
					( Parent
						( matchGroupRef "@baseboard_fab2_lib.baseboard_fab2(sch_1):\MG_DQ-DQS_FAR_DIMM_NG_M_B_BYTE6\" )
					)
					( Status sCSetFlattened )
					( Origin gBackEnd )
				)
				( attribute "RELATIVE_PROPAGATION_DELAY" "0.00 MIL,195.00 MIL"
					( Parent
						( matchGroupRef "@baseboard_fab2_lib.baseboard_fab2(sch_1):\MG_DQ-DQS_FAR_DIMM_NG_M_B_BYTE6\" )
					)
					( Units "uMatchProp" "ns" 1.000000)
					( Status sCSetFlattened )
					( Origin gBackEnd )
				)
				( attribute "RELATIVE_PROPAGATION_DELAY_SCOPE" "G"
					( Parent
						( matchGroupRef "@baseboard_fab2_lib.baseboard_fab2(sch_1):\MG_DQ_FAR_DIMM_NG_M_B_BYTE6\" )
					)
					( Status sCSetFlattened )
					( Origin gBackEnd )
				)
				( attribute "RELATIVE_PROPAGATION_DELAY" "-50.00 MIL,50.00 MIL"
					( Parent
						( matchGroupRef "@baseboard_fab2_lib.baseboard_fab2(sch_1):\MG_DQ_FAR_DIMM_NG_M_B_BYTE6\" )
					)
					( Units "uMatchProp" "ns" 1.000000)
					( Status sCSetFlattened )
					( Origin gBackEnd )
				)
			)
			( pinPair "@baseboard_fab2_lib.baseboard_fab2(sch_1):\PP4955\"
				( pinRef "@baseboard_fab2_lib.baseboard_fab2(sch_1):page24_i172:DDR1_DQ(50)" )
				( pinRef "@baseboard_fab2_lib.baseboard_fab2(sch_1):page46_i14:DQ(50)" )
				( attribute "RELATIVE_PROPAGATION_DELAY_SCOPE" "G"
					( Parent
						( matchGroupRef "@baseboard_fab2_lib.baseboard_fab2(sch_1):\MG_DQ-DQS_NEAR_DIMM_NG_M_B_BYTE6\" )
					)
					( Status sCSetFlattened )
					( Origin gBackEnd )
				)
				( attribute "RELATIVE_PROPAGATION_DELAY" "0.00 MIL,195.00 MIL"
					( Parent
						( matchGroupRef "@baseboard_fab2_lib.baseboard_fab2(sch_1):\MG_DQ-DQS_NEAR_DIMM_NG_M_B_BYTE6\" )
					)
					( Units "uMatchProp" "ns" 1.000000)
					( Status sCSetFlattened )
					( Origin gBackEnd )
				)
				( attribute "RELATIVE_PROPAGATION_DELAY_SCOPE" "G"
					( Parent
						( matchGroupRef "@baseboard_fab2_lib.baseboard_fab2(sch_1):\MG_DQ_NEAR_DIMM_NG_M_B_BYTE6\" )
					)
					( Status sCSetFlattened )
					( Origin gBackEnd )
				)
				( attribute "RELATIVE_PROPAGATION_DELAY" "-50.00 MIL,50.00 MIL"
					( Parent
						( matchGroupRef "@baseboard_fab2_lib.baseboard_fab2(sch_1):\MG_DQ_NEAR_DIMM_NG_M_B_BYTE6\" )
					)
					( Units "uMatchProp" "ns" 1.000000)
					( Status sCSetFlattened )
					( Origin gBackEnd )
				)
			)
			( pinPair "@baseboard_fab2_lib.baseboard_fab2(sch_1):\PP4956\"
				( pinRef "@baseboard_fab2_lib.baseboard_fab2(sch_1):page24_i172:DDR1_DQ(51)" )
				( pinRef "@baseboard_fab2_lib.baseboard_fab2(sch_1):page45_i111:DQ(50)" )
				( attribute "RELATIVE_PROPAGATION_DELAY_SCOPE" "G"
					( Parent
						( matchGroupRef "@baseboard_fab2_lib.baseboard_fab2(sch_1):\MG_DQ-DQS_FAR_DIMM_NG_M_B_BYTE6\" )
					)
					( Status sCSetFlattened )
					( Origin gBackEnd )
				)
				( attribute "RELATIVE_PROPAGATION_DELAY" "0.00 MIL,195.00 MIL"
					( Parent
						( matchGroupRef "@baseboard_fab2_lib.baseboard_fab2(sch_1):\MG_DQ-DQS_FAR_DIMM_NG_M_B_BYTE6\" )
					)
					( Units "uMatchProp" "ns" 1.000000)
					( Status sCSetFlattened )
					( Origin gBackEnd )
				)
				( attribute "RELATIVE_PROPAGATION_DELAY_SCOPE" "G"
					( Parent
						( matchGroupRef "@baseboard_fab2_lib.baseboard_fab2(sch_1):\MG_DQ_FAR_DIMM_NG_M_B_BYTE6\" )
					)
					( Status sCSetFlattened )
					( Origin gBackEnd )
				)
				( attribute "RELATIVE_PROPAGATION_DELAY" "-50.00 MIL,50.00 MIL"
					( Parent
						( matchGroupRef "@baseboard_fab2_lib.baseboard_fab2(sch_1):\MG_DQ_FAR_DIMM_NG_M_B_BYTE6\" )
					)
					( Units "uMatchProp" "ns" 1.000000)
					( Status sCSetFlattened )
					( Origin gBackEnd )
				)
			)
			( pinPair "@baseboard_fab2_lib.baseboard_fab2(sch_1):\PP4958\"
				( pinRef "@baseboard_fab2_lib.baseboard_fab2(sch_1):page24_i172:DDR1_DQ(51)" )
				( pinRef "@baseboard_fab2_lib.baseboard_fab2(sch_1):page46_i14:DQ(51)" )
				( attribute "RELATIVE_PROPAGATION_DELAY_SCOPE" "G"
					( Parent
						( matchGroupRef "@baseboard_fab2_lib.baseboard_fab2(sch_1):\MG_DQ-DQS_NEAR_DIMM_NG_M_B_BYTE6\" )
					)
					( Status sCSetFlattened )
					( Origin gBackEnd )
				)
				( attribute "RELATIVE_PROPAGATION_DELAY" "0.00 MIL,195.00 MIL"
					( Parent
						( matchGroupRef "@baseboard_fab2_lib.baseboard_fab2(sch_1):\MG_DQ-DQS_NEAR_DIMM_NG_M_B_BYTE6\" )
					)
					( Units "uMatchProp" "ns" 1.000000)
					( Status sCSetFlattened )
					( Origin gBackEnd )
				)
				( attribute "RELATIVE_PROPAGATION_DELAY_SCOPE" "G"
					( Parent
						( matchGroupRef "@baseboard_fab2_lib.baseboard_fab2(sch_1):\MG_DQ_NEAR_DIMM_NG_M_B_BYTE6\" )
					)
					( Status sCSetFlattened )
					( Origin gBackEnd )
				)
				( attribute "RELATIVE_PROPAGATION_DELAY" "-50.00 MIL,50.00 MIL"
					( Parent
						( matchGroupRef "@baseboard_fab2_lib.baseboard_fab2(sch_1):\MG_DQ_NEAR_DIMM_NG_M_B_BYTE6\" )
					)
					( Units "uMatchProp" "ns" 1.000000)
					( Status sCSetFlattened )
					( Origin gBackEnd )
				)
			)
			( pinPair "@baseboard_fab2_lib.baseboard_fab2(sch_1):\PP4959\"
				( pinRef "@baseboard_fab2_lib.baseboard_fab2(sch_1):page24_i172:DDR1_DQ(52)" )
				( pinRef "@baseboard_fab2_lib.baseboard_fab2(sch_1):page45_i111:DQ(53)" )
				( attribute "RELATIVE_PROPAGATION_DELAY_SCOPE" "G"
					( Parent
						( matchGroupRef "@baseboard_fab2_lib.baseboard_fab2(sch_1):\MG_DQ-DQS_FAR_DIMM_NG_M_B_BYTE6\" )
					)
					( Status sCSetFlattened )
					( Origin gBackEnd )
				)
				( attribute "RELATIVE_PROPAGATION_DELAY" "0.00 MIL,195.00 MIL"
					( Parent
						( matchGroupRef "@baseboard_fab2_lib.baseboard_fab2(sch_1):\MG_DQ-DQS_FAR_DIMM_NG_M_B_BYTE6\" )
					)
					( Units "uMatchProp" "ns" 1.000000)
					( Status sCSetFlattened )
					( Origin gBackEnd )
				)
				( attribute "RELATIVE_PROPAGATION_DELAY_SCOPE" "G"
					( Parent
						( matchGroupRef "@baseboard_fab2_lib.baseboard_fab2(sch_1):\MG_DQ_FAR_DIMM_NG_M_B_BYTE6\" )
					)
					( Status sCSetFlattened )
					( Origin gBackEnd )
				)
				( attribute "RELATIVE_PROPAGATION_DELAY" "-50.00 MIL,50.00 MIL"
					( Parent
						( matchGroupRef "@baseboard_fab2_lib.baseboard_fab2(sch_1):\MG_DQ_FAR_DIMM_NG_M_B_BYTE6\" )
					)
					( Units "uMatchProp" "ns" 1.000000)
					( Status sCSetFlattened )
					( Origin gBackEnd )
				)
			)
			( pinPair "@baseboard_fab2_lib.baseboard_fab2(sch_1):\PP4961\"
				( pinRef "@baseboard_fab2_lib.baseboard_fab2(sch_1):page24_i172:DDR1_DQ(52)" )
				( pinRef "@baseboard_fab2_lib.baseboard_fab2(sch_1):page46_i14:DQ(52)" )
				( attribute "RELATIVE_PROPAGATION_DELAY_SCOPE" "G"
					( Parent
						( matchGroupRef "@baseboard_fab2_lib.baseboard_fab2(sch_1):\MG_DQ-DQS_NEAR_DIMM_NG_M_B_BYTE6\" )
					)
					( Status sCSetFlattened )
					( Origin gBackEnd )
				)
				( attribute "RELATIVE_PROPAGATION_DELAY" "0.00 MIL,195.00 MIL"
					( Parent
						( matchGroupRef "@baseboard_fab2_lib.baseboard_fab2(sch_1):\MG_DQ-DQS_NEAR_DIMM_NG_M_B_BYTE6\" )
					)
					( Units "uMatchProp" "ns" 1.000000)
					( Status sCSetFlattened )
					( Origin gBackEnd )
				)
				( attribute "RELATIVE_PROPAGATION_DELAY_SCOPE" "G"
					( Parent
						( matchGroupRef "@baseboard_fab2_lib.baseboard_fab2(sch_1):\MG_DQ_NEAR_DIMM_NG_M_B_BYTE6\" )
					)
					( Status sCSetFlattened )
					( Origin gBackEnd )
				)
				( attribute "RELATIVE_PROPAGATION_DELAY" "-50.00 MIL,50.00 MIL"
					( Parent
						( matchGroupRef "@baseboard_fab2_lib.baseboard_fab2(sch_1):\MG_DQ_NEAR_DIMM_NG_M_B_BYTE6\" )
					)
					( Units "uMatchProp" "ns" 1.000000)
					( Status sCSetFlattened )
					( Origin gBackEnd )
				)
			)
			( pinPair "@baseboard_fab2_lib.baseboard_fab2(sch_1):\PP4962\"
				( pinRef "@baseboard_fab2_lib.baseboard_fab2(sch_1):page24_i172:DDR1_DQ(53)" )
				( pinRef "@baseboard_fab2_lib.baseboard_fab2(sch_1):page45_i111:DQ(52)" )
				( attribute "RELATIVE_PROPAGATION_DELAY_SCOPE" "G"
					( Parent
						( matchGroupRef "@baseboard_fab2_lib.baseboard_fab2(sch_1):\MG_DQ-DQS_FAR_DIMM_NG_M_B_BYTE6\" )
					)
					( Status sCSetFlattened )
					( Origin gBackEnd )
				)
				( attribute "RELATIVE_PROPAGATION_DELAY" "0.00 MIL,195.00 MIL"
					( Parent
						( matchGroupRef "@baseboard_fab2_lib.baseboard_fab2(sch_1):\MG_DQ-DQS_FAR_DIMM_NG_M_B_BYTE6\" )
					)
					( Units "uMatchProp" "ns" 1.000000)
					( Status sCSetFlattened )
					( Origin gBackEnd )
				)
				( attribute "RELATIVE_PROPAGATION_DELAY_SCOPE" "G"
					( Parent
						( matchGroupRef "@baseboard_fab2_lib.baseboard_fab2(sch_1):\MG_DQ_FAR_DIMM_NG_M_B_BYTE6\" )
					)
					( Status sCSetFlattened )
					( Origin gBackEnd )
				)
				( attribute "RELATIVE_PROPAGATION_DELAY" "-50.00 MIL,50.00 MIL"
					( Parent
						( matchGroupRef "@baseboard_fab2_lib.baseboard_fab2(sch_1):\MG_DQ_FAR_DIMM_NG_M_B_BYTE6\" )
					)
					( Units "uMatchProp" "ns" 1.000000)
					( Status sCSetFlattened )
					( Origin gBackEnd )
				)
			)
			( pinPair "@baseboard_fab2_lib.baseboard_fab2(sch_1):\PP4964\"
				( pinRef "@baseboard_fab2_lib.baseboard_fab2(sch_1):page24_i172:DDR1_DQ(53)" )
				( pinRef "@baseboard_fab2_lib.baseboard_fab2(sch_1):page46_i14:DQ(53)" )
				( attribute "RELATIVE_PROPAGATION_DELAY_SCOPE" "G"
					( Parent
						( matchGroupRef "@baseboard_fab2_lib.baseboard_fab2(sch_1):\MG_DQ-DQS_NEAR_DIMM_NG_M_B_BYTE6\" )
					)
					( Status sCSetFlattened )
					( Origin gBackEnd )
				)
				( attribute "RELATIVE_PROPAGATION_DELAY" "0.00 MIL,195.00 MIL"
					( Parent
						( matchGroupRef "@baseboard_fab2_lib.baseboard_fab2(sch_1):\MG_DQ-DQS_NEAR_DIMM_NG_M_B_BYTE6\" )
					)
					( Units "uMatchProp" "ns" 1.000000)
					( Status sCSetFlattened )
					( Origin gBackEnd )
				)
				( attribute "RELATIVE_PROPAGATION_DELAY_SCOPE" "G"
					( Parent
						( matchGroupRef "@baseboard_fab2_lib.baseboard_fab2(sch_1):\MG_DQ_NEAR_DIMM_NG_M_B_BYTE6\" )
					)
					( Status sCSetFlattened )
					( Origin gBackEnd )
				)
				( attribute "RELATIVE_PROPAGATION_DELAY" "-50.00 MIL,50.00 MIL"
					( Parent
						( matchGroupRef "@baseboard_fab2_lib.baseboard_fab2(sch_1):\MG_DQ_NEAR_DIMM_NG_M_B_BYTE6\" )
					)
					( Units "uMatchProp" "ns" 1.000000)
					( Status sCSetFlattened )
					( Origin gBackEnd )
				)
			)
			( pinPair "@baseboard_fab2_lib.baseboard_fab2(sch_1):\PP4965\"
				( pinRef "@baseboard_fab2_lib.baseboard_fab2(sch_1):page24_i172:DDR1_DQ(54)" )
				( pinRef "@baseboard_fab2_lib.baseboard_fab2(sch_1):page45_i111:DQ(55)" )
				( attribute "RELATIVE_PROPAGATION_DELAY_SCOPE" "G"
					( Parent
						( matchGroupRef "@baseboard_fab2_lib.baseboard_fab2(sch_1):\MG_DQ-DQS_FAR_DIMM_NG_M_B_BYTE6\" )
					)
					( Status sCSetFlattened )
					( Origin gBackEnd )
				)
				( attribute "RELATIVE_PROPAGATION_DELAY" "0.00 MIL,195.00 MIL"
					( Parent
						( matchGroupRef "@baseboard_fab2_lib.baseboard_fab2(sch_1):\MG_DQ-DQS_FAR_DIMM_NG_M_B_BYTE6\" )
					)
					( Units "uMatchProp" "ns" 1.000000)
					( Status sCSetFlattened )
					( Origin gBackEnd )
				)
				( attribute "RELATIVE_PROPAGATION_DELAY_SCOPE" "G"
					( Parent
						( matchGroupRef "@baseboard_fab2_lib.baseboard_fab2(sch_1):\MG_DQ_FAR_DIMM_NG_M_B_BYTE6\" )
					)
					( Status sCSetFlattened )
					( Origin gBackEnd )
				)
				( attribute "RELATIVE_PROPAGATION_DELAY" "-50.00 MIL,50.00 MIL"
					( Parent
						( matchGroupRef "@baseboard_fab2_lib.baseboard_fab2(sch_1):\MG_DQ_FAR_DIMM_NG_M_B_BYTE6\" )
					)
					( Units "uMatchProp" "ns" 1.000000)
					( Status sCSetFlattened )
					( Origin gBackEnd )
				)
			)
			( pinPair "@baseboard_fab2_lib.baseboard_fab2(sch_1):\PP4967\"
				( pinRef "@baseboard_fab2_lib.baseboard_fab2(sch_1):page24_i172:DDR1_DQ(54)" )
				( pinRef "@baseboard_fab2_lib.baseboard_fab2(sch_1):page46_i14:DQ(54)" )
				( attribute "RELATIVE_PROPAGATION_DELAY_SCOPE" "G"
					( Parent
						( matchGroupRef "@baseboard_fab2_lib.baseboard_fab2(sch_1):\MG_DQ-DQS_NEAR_DIMM_NG_M_B_BYTE6\" )
					)
					( Status sCSetFlattened )
					( Origin gBackEnd )
				)
				( attribute "RELATIVE_PROPAGATION_DELAY" "0.00 MIL,195.00 MIL"
					( Parent
						( matchGroupRef "@baseboard_fab2_lib.baseboard_fab2(sch_1):\MG_DQ-DQS_NEAR_DIMM_NG_M_B_BYTE6\" )
					)
					( Units "uMatchProp" "ns" 1.000000)
					( Status sCSetFlattened )
					( Origin gBackEnd )
				)
				( attribute "RELATIVE_PROPAGATION_DELAY_SCOPE" "G"
					( Parent
						( matchGroupRef "@baseboard_fab2_lib.baseboard_fab2(sch_1):\MG_DQ_NEAR_DIMM_NG_M_B_BYTE6\" )
					)
					( Status sCSetFlattened )
					( Origin gBackEnd )
				)
				( attribute "RELATIVE_PROPAGATION_DELAY" "-50.00 MIL,50.00 MIL"
					( Parent
						( matchGroupRef "@baseboard_fab2_lib.baseboard_fab2(sch_1):\MG_DQ_NEAR_DIMM_NG_M_B_BYTE6\" )
					)
					( Units "uMatchProp" "ns" 1.000000)
					( Status sCSetFlattened )
					( Origin gBackEnd )
				)
			)
			( pinPair "@baseboard_fab2_lib.baseboard_fab2(sch_1):\PP4968\"
				( pinRef "@baseboard_fab2_lib.baseboard_fab2(sch_1):page24_i172:DDR1_DQ(55)" )
				( pinRef "@baseboard_fab2_lib.baseboard_fab2(sch_1):page45_i111:DQ(54)" )
				( attribute "RELATIVE_PROPAGATION_DELAY_SCOPE" "G"
					( Parent
						( matchGroupRef "@baseboard_fab2_lib.baseboard_fab2(sch_1):\MG_DQ-DQS_FAR_DIMM_NG_M_B_BYTE6\" )
					)
					( Status sCSetFlattened )
					( Origin gBackEnd )
				)
				( attribute "RELATIVE_PROPAGATION_DELAY" "0.00 MIL,195.00 MIL"
					( Parent
						( matchGroupRef "@baseboard_fab2_lib.baseboard_fab2(sch_1):\MG_DQ-DQS_FAR_DIMM_NG_M_B_BYTE6\" )
					)
					( Units "uMatchProp" "ns" 1.000000)
					( Status sCSetFlattened )
					( Origin gBackEnd )
				)
				( attribute "RELATIVE_PROPAGATION_DELAY_SCOPE" "G"
					( Parent
						( matchGroupRef "@baseboard_fab2_lib.baseboard_fab2(sch_1):\MG_DQ_FAR_DIMM_NG_M_B_BYTE6\" )
					)
					( Status sCSetFlattened )
					( Origin gBackEnd )
				)
				( attribute "RELATIVE_PROPAGATION_DELAY" "-50.00 MIL,50.00 MIL"
					( Parent
						( matchGroupRef "@baseboard_fab2_lib.baseboard_fab2(sch_1):\MG_DQ_FAR_DIMM_NG_M_B_BYTE6\" )
					)
					( Units "uMatchProp" "ns" 1.000000)
					( Status sCSetFlattened )
					( Origin gBackEnd )
				)
			)
			( pinPair "@baseboard_fab2_lib.baseboard_fab2(sch_1):\PP4970\"
				( pinRef "@baseboard_fab2_lib.baseboard_fab2(sch_1):page24_i172:DDR1_DQ(55)" )
				( pinRef "@baseboard_fab2_lib.baseboard_fab2(sch_1):page46_i14:DQ(55)" )
				( attribute "RELATIVE_PROPAGATION_DELAY_SCOPE" "G"
					( Parent
						( matchGroupRef "@baseboard_fab2_lib.baseboard_fab2(sch_1):\MG_DQ-DQS_NEAR_DIMM_NG_M_B_BYTE6\" )
					)
					( Status sCSetFlattened )
					( Origin gBackEnd )
				)
				( attribute "RELATIVE_PROPAGATION_DELAY" "0.00 MIL,195.00 MIL"
					( Parent
						( matchGroupRef "@baseboard_fab2_lib.baseboard_fab2(sch_1):\MG_DQ-DQS_NEAR_DIMM_NG_M_B_BYTE6\" )
					)
					( Units "uMatchProp" "ns" 1.000000)
					( Status sCSetFlattened )
					( Origin gBackEnd )
				)
				( attribute "RELATIVE_PROPAGATION_DELAY_SCOPE" "G"
					( Parent
						( matchGroupRef "@baseboard_fab2_lib.baseboard_fab2(sch_1):\MG_DQ_NEAR_DIMM_NG_M_B_BYTE6\" )
					)
					( Status sCSetFlattened )
					( Origin gBackEnd )
				)
				( attribute "RELATIVE_PROPAGATION_DELAY" "-50.00 MIL,50.00 MIL"
					( Parent
						( matchGroupRef "@baseboard_fab2_lib.baseboard_fab2(sch_1):\MG_DQ_NEAR_DIMM_NG_M_B_BYTE6\" )
					)
					( Units "uMatchProp" "ns" 1.000000)
					( Status sCSetFlattened )
					( Origin gBackEnd )
				)
			)
			( pinPair "@baseboard_fab2_lib.baseboard_fab2(sch_1):\PP4923\"
				( pinRef "@baseboard_fab2_lib.baseboard_fab2(sch_1):page24_i172:DDR1_DQ(56)" )
				( pinRef "@baseboard_fab2_lib.baseboard_fab2(sch_1):page45_i111:DQ(57)" )
				( attribute "RELATIVE_PROPAGATION_DELAY_SCOPE" "G"
					( Parent
						( matchGroupRef "@baseboard_fab2_lib.baseboard_fab2(sch_1):\MG_DQ-DQS_FAR_DIMM_NG_M_B_BYTE7\" )
					)
					( Status sCSetFlattened )
					( Origin gBackEnd )
				)
				( attribute "RELATIVE_PROPAGATION_DELAY" "0.00 MIL,195.00 MIL"
					( Parent
						( matchGroupRef "@baseboard_fab2_lib.baseboard_fab2(sch_1):\MG_DQ-DQS_FAR_DIMM_NG_M_B_BYTE7\" )
					)
					( Units "uMatchProp" "ns" 1.000000)
					( Status sCSetFlattened )
					( Origin gBackEnd )
				)
				( attribute "RELATIVE_PROPAGATION_DELAY_SCOPE" "G"
					( Parent
						( matchGroupRef "@baseboard_fab2_lib.baseboard_fab2(sch_1):\MG_DQ_FAR_DIMM_NG_M_B_BYTE7\" )
					)
					( Status sCSetFlattened )
					( Origin gBackEnd )
				)
				( attribute "RELATIVE_PROPAGATION_DELAY" "-50.00 MIL,50.00 MIL"
					( Parent
						( matchGroupRef "@baseboard_fab2_lib.baseboard_fab2(sch_1):\MG_DQ_FAR_DIMM_NG_M_B_BYTE7\" )
					)
					( Units "uMatchProp" "ns" 1.000000)
					( Status sCSetFlattened )
					( Origin gBackEnd )
				)
			)
			( pinPair "@baseboard_fab2_lib.baseboard_fab2(sch_1):\PP4925\"
				( pinRef "@baseboard_fab2_lib.baseboard_fab2(sch_1):page24_i172:DDR1_DQ(56)" )
				( pinRef "@baseboard_fab2_lib.baseboard_fab2(sch_1):page46_i14:DQ(56)" )
				( attribute "RELATIVE_PROPAGATION_DELAY_SCOPE" "G"
					( Parent
						( matchGroupRef "@baseboard_fab2_lib.baseboard_fab2(sch_1):\MG_DQ-DQS_NEAR_DIMM_NG_M_B_BYTE7\" )
					)
					( Status sCSetFlattened )
					( Origin gBackEnd )
				)
				( attribute "RELATIVE_PROPAGATION_DELAY" "0.00 MIL,195.00 MIL"
					( Parent
						( matchGroupRef "@baseboard_fab2_lib.baseboard_fab2(sch_1):\MG_DQ-DQS_NEAR_DIMM_NG_M_B_BYTE7\" )
					)
					( Units "uMatchProp" "ns" 1.000000)
					( Status sCSetFlattened )
					( Origin gBackEnd )
				)
				( attribute "RELATIVE_PROPAGATION_DELAY_SCOPE" "G"
					( Parent
						( matchGroupRef "@baseboard_fab2_lib.baseboard_fab2(sch_1):\MG_DQ_NEAR_DIMM_NG_M_B_BYTE7\" )
					)
					( Status sCSetFlattened )
					( Origin gBackEnd )
				)
				( attribute "RELATIVE_PROPAGATION_DELAY" "-50.00 MIL,50.00 MIL"
					( Parent
						( matchGroupRef "@baseboard_fab2_lib.baseboard_fab2(sch_1):\MG_DQ_NEAR_DIMM_NG_M_B_BYTE7\" )
					)
					( Units "uMatchProp" "ns" 1.000000)
					( Status sCSetFlattened )
					( Origin gBackEnd )
				)
			)
			( pinPair "@baseboard_fab2_lib.baseboard_fab2(sch_1):\PP4926\"
				( pinRef "@baseboard_fab2_lib.baseboard_fab2(sch_1):page24_i172:DDR1_DQ(57)" )
				( pinRef "@baseboard_fab2_lib.baseboard_fab2(sch_1):page45_i111:DQ(56)" )
				( attribute "RELATIVE_PROPAGATION_DELAY_SCOPE" "G"
					( Parent
						( matchGroupRef "@baseboard_fab2_lib.baseboard_fab2(sch_1):\MG_DQ-DQS_FAR_DIMM_NG_M_B_BYTE7\" )
					)
					( Status sCSetFlattened )
					( Origin gBackEnd )
				)
				( attribute "RELATIVE_PROPAGATION_DELAY" "0.00 MIL,195.00 MIL"
					( Parent
						( matchGroupRef "@baseboard_fab2_lib.baseboard_fab2(sch_1):\MG_DQ-DQS_FAR_DIMM_NG_M_B_BYTE7\" )
					)
					( Units "uMatchProp" "ns" 1.000000)
					( Status sCSetFlattened )
					( Origin gBackEnd )
				)
				( attribute "RELATIVE_PROPAGATION_DELAY_SCOPE" "G"
					( Parent
						( matchGroupRef "@baseboard_fab2_lib.baseboard_fab2(sch_1):\MG_DQ_FAR_DIMM_NG_M_B_BYTE7\" )
					)
					( Status sCSetFlattened )
					( Origin gBackEnd )
				)
				( attribute "RELATIVE_PROPAGATION_DELAY" "-50.00 MIL,50.00 MIL"
					( Parent
						( matchGroupRef "@baseboard_fab2_lib.baseboard_fab2(sch_1):\MG_DQ_FAR_DIMM_NG_M_B_BYTE7\" )
					)
					( Units "uMatchProp" "ns" 1.000000)
					( Status sCSetFlattened )
					( Origin gBackEnd )
				)
			)
			( pinPair "@baseboard_fab2_lib.baseboard_fab2(sch_1):\PP4928\"
				( pinRef "@baseboard_fab2_lib.baseboard_fab2(sch_1):page24_i172:DDR1_DQ(57)" )
				( pinRef "@baseboard_fab2_lib.baseboard_fab2(sch_1):page46_i14:DQ(57)" )
				( attribute "RELATIVE_PROPAGATION_DELAY_SCOPE" "G"
					( Parent
						( matchGroupRef "@baseboard_fab2_lib.baseboard_fab2(sch_1):\MG_DQ-DQS_NEAR_DIMM_NG_M_B_BYTE7\" )
					)
					( Status sCSetFlattened )
					( Origin gBackEnd )
				)
				( attribute "RELATIVE_PROPAGATION_DELAY" "0.00 MIL,195.00 MIL"
					( Parent
						( matchGroupRef "@baseboard_fab2_lib.baseboard_fab2(sch_1):\MG_DQ-DQS_NEAR_DIMM_NG_M_B_BYTE7\" )
					)
					( Units "uMatchProp" "ns" 1.000000)
					( Status sCSetFlattened )
					( Origin gBackEnd )
				)
				( attribute "RELATIVE_PROPAGATION_DELAY_SCOPE" "G"
					( Parent
						( matchGroupRef "@baseboard_fab2_lib.baseboard_fab2(sch_1):\MG_DQ_NEAR_DIMM_NG_M_B_BYTE7\" )
					)
					( Status sCSetFlattened )
					( Origin gBackEnd )
				)
				( attribute "RELATIVE_PROPAGATION_DELAY" "-50.00 MIL,50.00 MIL"
					( Parent
						( matchGroupRef "@baseboard_fab2_lib.baseboard_fab2(sch_1):\MG_DQ_NEAR_DIMM_NG_M_B_BYTE7\" )
					)
					( Units "uMatchProp" "ns" 1.000000)
					( Status sCSetFlattened )
					( Origin gBackEnd )
				)
			)
			( pinPair "@baseboard_fab2_lib.baseboard_fab2(sch_1):\PP4929\"
				( pinRef "@baseboard_fab2_lib.baseboard_fab2(sch_1):page24_i172:DDR1_DQ(58)" )
				( pinRef "@baseboard_fab2_lib.baseboard_fab2(sch_1):page45_i111:DQ(59)" )
				( attribute "RELATIVE_PROPAGATION_DELAY_SCOPE" "G"
					( Parent
						( matchGroupRef "@baseboard_fab2_lib.baseboard_fab2(sch_1):\MG_DQ-DQS_FAR_DIMM_NG_M_B_BYTE7\" )
					)
					( Status sCSetFlattened )
					( Origin gBackEnd )
				)
				( attribute "RELATIVE_PROPAGATION_DELAY" "0.00 MIL,195.00 MIL"
					( Parent
						( matchGroupRef "@baseboard_fab2_lib.baseboard_fab2(sch_1):\MG_DQ-DQS_FAR_DIMM_NG_M_B_BYTE7\" )
					)
					( Units "uMatchProp" "ns" 1.000000)
					( Status sCSetFlattened )
					( Origin gBackEnd )
				)
				( attribute "RELATIVE_PROPAGATION_DELAY_SCOPE" "G"
					( Parent
						( matchGroupRef "@baseboard_fab2_lib.baseboard_fab2(sch_1):\MG_DQ_FAR_DIMM_NG_M_B_BYTE7\" )
					)
					( Status sCSetFlattened )
					( Origin gBackEnd )
				)
				( attribute "RELATIVE_PROPAGATION_DELAY" "-50.00 MIL,50.00 MIL"
					( Parent
						( matchGroupRef "@baseboard_fab2_lib.baseboard_fab2(sch_1):\MG_DQ_FAR_DIMM_NG_M_B_BYTE7\" )
					)
					( Units "uMatchProp" "ns" 1.000000)
					( Status sCSetFlattened )
					( Origin gBackEnd )
				)
			)
			( pinPair "@baseboard_fab2_lib.baseboard_fab2(sch_1):\PP4931\"
				( pinRef "@baseboard_fab2_lib.baseboard_fab2(sch_1):page24_i172:DDR1_DQ(58)" )
				( pinRef "@baseboard_fab2_lib.baseboard_fab2(sch_1):page46_i14:DQ(58)" )
				( attribute "RELATIVE_PROPAGATION_DELAY_SCOPE" "G"
					( Parent
						( matchGroupRef "@baseboard_fab2_lib.baseboard_fab2(sch_1):\MG_DQ-DQS_NEAR_DIMM_NG_M_B_BYTE7\" )
					)
					( Status sCSetFlattened )
					( Origin gBackEnd )
				)
				( attribute "RELATIVE_PROPAGATION_DELAY" "0.00 MIL,195.00 MIL"
					( Parent
						( matchGroupRef "@baseboard_fab2_lib.baseboard_fab2(sch_1):\MG_DQ-DQS_NEAR_DIMM_NG_M_B_BYTE7\" )
					)
					( Units "uMatchProp" "ns" 1.000000)
					( Status sCSetFlattened )
					( Origin gBackEnd )
				)
				( attribute "RELATIVE_PROPAGATION_DELAY_SCOPE" "G"
					( Parent
						( matchGroupRef "@baseboard_fab2_lib.baseboard_fab2(sch_1):\MG_DQ_NEAR_DIMM_NG_M_B_BYTE7\" )
					)
					( Status sCSetFlattened )
					( Origin gBackEnd )
				)
				( attribute "RELATIVE_PROPAGATION_DELAY" "-50.00 MIL,50.00 MIL"
					( Parent
						( matchGroupRef "@baseboard_fab2_lib.baseboard_fab2(sch_1):\MG_DQ_NEAR_DIMM_NG_M_B_BYTE7\" )
					)
					( Units "uMatchProp" "ns" 1.000000)
					( Status sCSetFlattened )
					( Origin gBackEnd )
				)
			)
			( pinPair "@baseboard_fab2_lib.baseboard_fab2(sch_1):\PP4932\"
				( pinRef "@baseboard_fab2_lib.baseboard_fab2(sch_1):page24_i172:DDR1_DQ(59)" )
				( pinRef "@baseboard_fab2_lib.baseboard_fab2(sch_1):page45_i111:DQ(58)" )
				( attribute "RELATIVE_PROPAGATION_DELAY_SCOPE" "G"
					( Parent
						( matchGroupRef "@baseboard_fab2_lib.baseboard_fab2(sch_1):\MG_DQ-DQS_FAR_DIMM_NG_M_B_BYTE7\" )
					)
					( Status sCSetFlattened )
					( Origin gBackEnd )
				)
				( attribute "RELATIVE_PROPAGATION_DELAY" "0.00 MIL,195.00 MIL"
					( Parent
						( matchGroupRef "@baseboard_fab2_lib.baseboard_fab2(sch_1):\MG_DQ-DQS_FAR_DIMM_NG_M_B_BYTE7\" )
					)
					( Units "uMatchProp" "ns" 1.000000)
					( Status sCSetFlattened )
					( Origin gBackEnd )
				)
				( attribute "RELATIVE_PROPAGATION_DELAY_SCOPE" "G"
					( Parent
						( matchGroupRef "@baseboard_fab2_lib.baseboard_fab2(sch_1):\MG_DQ_FAR_DIMM_NG_M_B_BYTE7\" )
					)
					( Status sCSetFlattened )
					( Origin gBackEnd )
				)
				( attribute "RELATIVE_PROPAGATION_DELAY" "-50.00 MIL,50.00 MIL"
					( Parent
						( matchGroupRef "@baseboard_fab2_lib.baseboard_fab2(sch_1):\MG_DQ_FAR_DIMM_NG_M_B_BYTE7\" )
					)
					( Units "uMatchProp" "ns" 1.000000)
					( Status sCSetFlattened )
					( Origin gBackEnd )
				)
			)
			( pinPair "@baseboard_fab2_lib.baseboard_fab2(sch_1):\PP4934\"
				( pinRef "@baseboard_fab2_lib.baseboard_fab2(sch_1):page24_i172:DDR1_DQ(59)" )
				( pinRef "@baseboard_fab2_lib.baseboard_fab2(sch_1):page46_i14:DQ(59)" )
				( attribute "RELATIVE_PROPAGATION_DELAY_SCOPE" "G"
					( Parent
						( matchGroupRef "@baseboard_fab2_lib.baseboard_fab2(sch_1):\MG_DQ-DQS_NEAR_DIMM_NG_M_B_BYTE7\" )
					)
					( Status sCSetFlattened )
					( Origin gBackEnd )
				)
				( attribute "RELATIVE_PROPAGATION_DELAY" "0.00 MIL,195.00 MIL"
					( Parent
						( matchGroupRef "@baseboard_fab2_lib.baseboard_fab2(sch_1):\MG_DQ-DQS_NEAR_DIMM_NG_M_B_BYTE7\" )
					)
					( Units "uMatchProp" "ns" 1.000000)
					( Status sCSetFlattened )
					( Origin gBackEnd )
				)
				( attribute "RELATIVE_PROPAGATION_DELAY_SCOPE" "G"
					( Parent
						( matchGroupRef "@baseboard_fab2_lib.baseboard_fab2(sch_1):\MG_DQ_NEAR_DIMM_NG_M_B_BYTE7\" )
					)
					( Status sCSetFlattened )
					( Origin gBackEnd )
				)
				( attribute "RELATIVE_PROPAGATION_DELAY" "-50.00 MIL,50.00 MIL"
					( Parent
						( matchGroupRef "@baseboard_fab2_lib.baseboard_fab2(sch_1):\MG_DQ_NEAR_DIMM_NG_M_B_BYTE7\" )
					)
					( Units "uMatchProp" "ns" 1.000000)
					( Status sCSetFlattened )
					( Origin gBackEnd )
				)
			)
			( pinPair "@baseboard_fab2_lib.baseboard_fab2(sch_1):\PP4935\"
				( pinRef "@baseboard_fab2_lib.baseboard_fab2(sch_1):page24_i172:DDR1_DQ(60)" )
				( pinRef "@baseboard_fab2_lib.baseboard_fab2(sch_1):page45_i111:DQ(61)" )
				( attribute "RELATIVE_PROPAGATION_DELAY_SCOPE" "G"
					( Parent
						( matchGroupRef "@baseboard_fab2_lib.baseboard_fab2(sch_1):\MG_DQ-DQS_FAR_DIMM_NG_M_B_BYTE7\" )
					)
					( Status sCSetFlattened )
					( Origin gBackEnd )
				)
				( attribute "RELATIVE_PROPAGATION_DELAY" "0.00 MIL,195.00 MIL"
					( Parent
						( matchGroupRef "@baseboard_fab2_lib.baseboard_fab2(sch_1):\MG_DQ-DQS_FAR_DIMM_NG_M_B_BYTE7\" )
					)
					( Units "uMatchProp" "ns" 1.000000)
					( Status sCSetFlattened )
					( Origin gBackEnd )
				)
				( attribute "RELATIVE_PROPAGATION_DELAY_SCOPE" "G"
					( Parent
						( matchGroupRef "@baseboard_fab2_lib.baseboard_fab2(sch_1):\MG_DQ_FAR_DIMM_NG_M_B_BYTE7\" )
					)
					( Status sCSetFlattened )
					( Origin gBackEnd )
				)
				( attribute "RELATIVE_PROPAGATION_DELAY" "-50.00 MIL,50.00 MIL"
					( Parent
						( matchGroupRef "@baseboard_fab2_lib.baseboard_fab2(sch_1):\MG_DQ_FAR_DIMM_NG_M_B_BYTE7\" )
					)
					( Units "uMatchProp" "ns" 1.000000)
					( Status sCSetFlattened )
					( Origin gBackEnd )
				)
			)
			( pinPair "@baseboard_fab2_lib.baseboard_fab2(sch_1):\PP4937\"
				( pinRef "@baseboard_fab2_lib.baseboard_fab2(sch_1):page24_i172:DDR1_DQ(60)" )
				( pinRef "@baseboard_fab2_lib.baseboard_fab2(sch_1):page46_i14:DQ(60)" )
				( attribute "RELATIVE_PROPAGATION_DELAY_SCOPE" "G"
					( Parent
						( matchGroupRef "@baseboard_fab2_lib.baseboard_fab2(sch_1):\MG_DQ-DQS_NEAR_DIMM_NG_M_B_BYTE7\" )
					)
					( Status sCSetFlattened )
					( Origin gBackEnd )
				)
				( attribute "RELATIVE_PROPAGATION_DELAY" "0.00 MIL,195.00 MIL"
					( Parent
						( matchGroupRef "@baseboard_fab2_lib.baseboard_fab2(sch_1):\MG_DQ-DQS_NEAR_DIMM_NG_M_B_BYTE7\" )
					)
					( Units "uMatchProp" "ns" 1.000000)
					( Status sCSetFlattened )
					( Origin gBackEnd )
				)
				( attribute "RELATIVE_PROPAGATION_DELAY_SCOPE" "G"
					( Parent
						( matchGroupRef "@baseboard_fab2_lib.baseboard_fab2(sch_1):\MG_DQ_NEAR_DIMM_NG_M_B_BYTE7\" )
					)
					( Status sCSetFlattened )
					( Origin gBackEnd )
				)
				( attribute "RELATIVE_PROPAGATION_DELAY" "-50.00 MIL,50.00 MIL"
					( Parent
						( matchGroupRef "@baseboard_fab2_lib.baseboard_fab2(sch_1):\MG_DQ_NEAR_DIMM_NG_M_B_BYTE7\" )
					)
					( Units "uMatchProp" "ns" 1.000000)
					( Status sCSetFlattened )
					( Origin gBackEnd )
				)
			)
			( pinPair "@baseboard_fab2_lib.baseboard_fab2(sch_1):\PP4938\"
				( pinRef "@baseboard_fab2_lib.baseboard_fab2(sch_1):page24_i172:DDR1_DQ(61)" )
				( pinRef "@baseboard_fab2_lib.baseboard_fab2(sch_1):page45_i111:DQ(60)" )
				( attribute "RELATIVE_PROPAGATION_DELAY_SCOPE" "G"
					( Parent
						( matchGroupRef "@baseboard_fab2_lib.baseboard_fab2(sch_1):\MG_DQ-DQS_FAR_DIMM_NG_M_B_BYTE7\" )
					)
					( Status sCSetFlattened )
					( Origin gBackEnd )
				)
				( attribute "RELATIVE_PROPAGATION_DELAY" "0.00 MIL,195.00 MIL"
					( Parent
						( matchGroupRef "@baseboard_fab2_lib.baseboard_fab2(sch_1):\MG_DQ-DQS_FAR_DIMM_NG_M_B_BYTE7\" )
					)
					( Units "uMatchProp" "ns" 1.000000)
					( Status sCSetFlattened )
					( Origin gBackEnd )
				)
				( attribute "RELATIVE_PROPAGATION_DELAY_SCOPE" "G"
					( Parent
						( matchGroupRef "@baseboard_fab2_lib.baseboard_fab2(sch_1):\MG_DQ_FAR_DIMM_NG_M_B_BYTE7\" )
					)
					( Status sCSetFlattened )
					( Origin gBackEnd )
				)
				( attribute "RELATIVE_PROPAGATION_DELAY" "-50.00 MIL,50.00 MIL"
					( Parent
						( matchGroupRef "@baseboard_fab2_lib.baseboard_fab2(sch_1):\MG_DQ_FAR_DIMM_NG_M_B_BYTE7\" )
					)
					( Units "uMatchProp" "ns" 1.000000)
					( Status sCSetFlattened )
					( Origin gBackEnd )
				)
			)
			( pinPair "@baseboard_fab2_lib.baseboard_fab2(sch_1):\PP4940\"
				( pinRef "@baseboard_fab2_lib.baseboard_fab2(sch_1):page24_i172:DDR1_DQ(61)" )
				( pinRef "@baseboard_fab2_lib.baseboard_fab2(sch_1):page46_i14:DQ(61)" )
				( attribute "RELATIVE_PROPAGATION_DELAY_SCOPE" "G"
					( Parent
						( matchGroupRef "@baseboard_fab2_lib.baseboard_fab2(sch_1):\MG_DQ-DQS_NEAR_DIMM_NG_M_B_BYTE7\" )
					)
					( Status sCSetFlattened )
					( Origin gBackEnd )
				)
				( attribute "RELATIVE_PROPAGATION_DELAY" "0.00 MIL,195.00 MIL"
					( Parent
						( matchGroupRef "@baseboard_fab2_lib.baseboard_fab2(sch_1):\MG_DQ-DQS_NEAR_DIMM_NG_M_B_BYTE7\" )
					)
					( Units "uMatchProp" "ns" 1.000000)
					( Status sCSetFlattened )
					( Origin gBackEnd )
				)
				( attribute "RELATIVE_PROPAGATION_DELAY_SCOPE" "G"
					( Parent
						( matchGroupRef "@baseboard_fab2_lib.baseboard_fab2(sch_1):\MG_DQ_NEAR_DIMM_NG_M_B_BYTE7\" )
					)
					( Status sCSetFlattened )
					( Origin gBackEnd )
				)
				( attribute "RELATIVE_PROPAGATION_DELAY" "-50.00 MIL,50.00 MIL"
					( Parent
						( matchGroupRef "@baseboard_fab2_lib.baseboard_fab2(sch_1):\MG_DQ_NEAR_DIMM_NG_M_B_BYTE7\" )
					)
					( Units "uMatchProp" "ns" 1.000000)
					( Status sCSetFlattened )
					( Origin gBackEnd )
				)
			)
			( pinPair "@baseboard_fab2_lib.baseboard_fab2(sch_1):\PP4941\"
				( pinRef "@baseboard_fab2_lib.baseboard_fab2(sch_1):page24_i172:DDR1_DQ(62)" )
				( pinRef "@baseboard_fab2_lib.baseboard_fab2(sch_1):page45_i111:DQ(63)" )
				( attribute "RELATIVE_PROPAGATION_DELAY_SCOPE" "G"
					( Parent
						( matchGroupRef "@baseboard_fab2_lib.baseboard_fab2(sch_1):\MG_DQ-DQS_FAR_DIMM_NG_M_B_BYTE7\" )
					)
					( Status sCSetFlattened )
					( Origin gBackEnd )
				)
				( attribute "RELATIVE_PROPAGATION_DELAY" "0.00 MIL,195.00 MIL"
					( Parent
						( matchGroupRef "@baseboard_fab2_lib.baseboard_fab2(sch_1):\MG_DQ-DQS_FAR_DIMM_NG_M_B_BYTE7\" )
					)
					( Units "uMatchProp" "ns" 1.000000)
					( Status sCSetFlattened )
					( Origin gBackEnd )
				)
				( attribute "RELATIVE_PROPAGATION_DELAY_SCOPE" "G"
					( Parent
						( matchGroupRef "@baseboard_fab2_lib.baseboard_fab2(sch_1):\MG_DQ_FAR_DIMM_NG_M_B_BYTE7\" )
					)
					( Status sCSetFlattened )
					( Origin gBackEnd )
				)
				( attribute "RELATIVE_PROPAGATION_DELAY" "-50.00 MIL,50.00 MIL"
					( Parent
						( matchGroupRef "@baseboard_fab2_lib.baseboard_fab2(sch_1):\MG_DQ_FAR_DIMM_NG_M_B_BYTE7\" )
					)
					( Units "uMatchProp" "ns" 1.000000)
					( Status sCSetFlattened )
					( Origin gBackEnd )
				)
			)
			( pinPair "@baseboard_fab2_lib.baseboard_fab2(sch_1):\PP4943\"
				( pinRef "@baseboard_fab2_lib.baseboard_fab2(sch_1):page24_i172:DDR1_DQ(62)" )
				( pinRef "@baseboard_fab2_lib.baseboard_fab2(sch_1):page46_i14:DQ(62)" )
				( attribute "RELATIVE_PROPAGATION_DELAY_SCOPE" "G"
					( Parent
						( matchGroupRef "@baseboard_fab2_lib.baseboard_fab2(sch_1):\MG_DQ-DQS_NEAR_DIMM_NG_M_B_BYTE7\" )
					)
					( Status sCSetFlattened )
					( Origin gBackEnd )
				)
				( attribute "RELATIVE_PROPAGATION_DELAY" "0.00 MIL,195.00 MIL"
					( Parent
						( matchGroupRef "@baseboard_fab2_lib.baseboard_fab2(sch_1):\MG_DQ-DQS_NEAR_DIMM_NG_M_B_BYTE7\" )
					)
					( Units "uMatchProp" "ns" 1.000000)
					( Status sCSetFlattened )
					( Origin gBackEnd )
				)
				( attribute "RELATIVE_PROPAGATION_DELAY_SCOPE" "G"
					( Parent
						( matchGroupRef "@baseboard_fab2_lib.baseboard_fab2(sch_1):\MG_DQ_NEAR_DIMM_NG_M_B_BYTE7\" )
					)
					( Status sCSetFlattened )
					( Origin gBackEnd )
				)
				( attribute "RELATIVE_PROPAGATION_DELAY" "-50.00 MIL,50.00 MIL"
					( Parent
						( matchGroupRef "@baseboard_fab2_lib.baseboard_fab2(sch_1):\MG_DQ_NEAR_DIMM_NG_M_B_BYTE7\" )
					)
					( Units "uMatchProp" "ns" 1.000000)
					( Status sCSetFlattened )
					( Origin gBackEnd )
				)
			)
			( pinPair "@baseboard_fab2_lib.baseboard_fab2(sch_1):\PP4944\"
				( pinRef "@baseboard_fab2_lib.baseboard_fab2(sch_1):page24_i172:DDR1_DQ(63)" )
				( pinRef "@baseboard_fab2_lib.baseboard_fab2(sch_1):page45_i111:DQ(62)" )
				( attribute "RELATIVE_PROPAGATION_DELAY_SCOPE" "G"
					( Parent
						( matchGroupRef "@baseboard_fab2_lib.baseboard_fab2(sch_1):\MG_DQ-DQS_FAR_DIMM_NG_M_B_BYTE7\" )
					)
					( Status sCSetFlattened )
					( Origin gBackEnd )
				)
				( attribute "RELATIVE_PROPAGATION_DELAY" "0.00 MIL,195.00 MIL"
					( Parent
						( matchGroupRef "@baseboard_fab2_lib.baseboard_fab2(sch_1):\MG_DQ-DQS_FAR_DIMM_NG_M_B_BYTE7\" )
					)
					( Units "uMatchProp" "ns" 1.000000)
					( Status sCSetFlattened )
					( Origin gBackEnd )
				)
				( attribute "RELATIVE_PROPAGATION_DELAY_SCOPE" "G"
					( Parent
						( matchGroupRef "@baseboard_fab2_lib.baseboard_fab2(sch_1):\MG_DQ_FAR_DIMM_NG_M_B_BYTE7\" )
					)
					( Status sCSetFlattened )
					( Origin gBackEnd )
				)
				( attribute "RELATIVE_PROPAGATION_DELAY" "-50.00 MIL,50.00 MIL"
					( Parent
						( matchGroupRef "@baseboard_fab2_lib.baseboard_fab2(sch_1):\MG_DQ_FAR_DIMM_NG_M_B_BYTE7\" )
					)
					( Units "uMatchProp" "ns" 1.000000)
					( Status sCSetFlattened )
					( Origin gBackEnd )
				)
			)
			( pinPair "@baseboard_fab2_lib.baseboard_fab2(sch_1):\PP4946\"
				( pinRef "@baseboard_fab2_lib.baseboard_fab2(sch_1):page24_i172:DDR1_DQ(63)" )
				( pinRef "@baseboard_fab2_lib.baseboard_fab2(sch_1):page46_i14:DQ(63)" )
				( attribute "RELATIVE_PROPAGATION_DELAY_SCOPE" "G"
					( Parent
						( matchGroupRef "@baseboard_fab2_lib.baseboard_fab2(sch_1):\MG_DQ-DQS_NEAR_DIMM_NG_M_B_BYTE7\" )
					)
					( Status sCSetFlattened )
					( Origin gBackEnd )
				)
				( attribute "RELATIVE_PROPAGATION_DELAY" "0.00 MIL,195.00 MIL"
					( Parent
						( matchGroupRef "@baseboard_fab2_lib.baseboard_fab2(sch_1):\MG_DQ-DQS_NEAR_DIMM_NG_M_B_BYTE7\" )
					)
					( Units "uMatchProp" "ns" 1.000000)
					( Status sCSetFlattened )
					( Origin gBackEnd )
				)
				( attribute "RELATIVE_PROPAGATION_DELAY_SCOPE" "G"
					( Parent
						( matchGroupRef "@baseboard_fab2_lib.baseboard_fab2(sch_1):\MG_DQ_NEAR_DIMM_NG_M_B_BYTE7\" )
					)
					( Status sCSetFlattened )
					( Origin gBackEnd )
				)
				( attribute "RELATIVE_PROPAGATION_DELAY" "-50.00 MIL,50.00 MIL"
					( Parent
						( matchGroupRef "@baseboard_fab2_lib.baseboard_fab2(sch_1):\MG_DQ_NEAR_DIMM_NG_M_B_BYTE7\" )
					)
					( Units "uMatchProp" "ns" 1.000000)
					( Status sCSetFlattened )
					( Origin gBackEnd )
				)
			)
			( pinPair "@baseboard_fab2_lib.baseboard_fab2(sch_1):\PP4875\"
				( pinRef "@baseboard_fab2_lib.baseboard_fab2(sch_1):page25_i172:DDR2_DQ(0)" )
				( pinRef "@baseboard_fab2_lib.baseboard_fab2(sch_1):page47_i111:DQ(1)" )
				( attribute "RELATIVE_PROPAGATION_DELAY_SCOPE" "G"
					( Parent
						( matchGroupRef "@baseboard_fab2_lib.baseboard_fab2(sch_1):\MG_DQ-DQS_FAR_DIMM_NG_M_C_BYTE0\" )
					)
					( Status sCSetFlattened )
					( Origin gBackEnd )
				)
				( attribute "RELATIVE_PROPAGATION_DELAY" "0.00 MIL,195.00 MIL"
					( Parent
						( matchGroupRef "@baseboard_fab2_lib.baseboard_fab2(sch_1):\MG_DQ-DQS_FAR_DIMM_NG_M_C_BYTE0\" )
					)
					( Units "uMatchProp" "ns" 1.000000)
					( Status sCSetFlattened )
					( Origin gBackEnd )
				)
				( attribute "RELATIVE_PROPAGATION_DELAY_SCOPE" "G"
					( Parent
						( matchGroupRef "@baseboard_fab2_lib.baseboard_fab2(sch_1):\MG_DQ_FAR_DIMM_NG_M_C_BYTE0\" )
					)
					( Status sCSetFlattened )
					( Origin gBackEnd )
				)
				( attribute "RELATIVE_PROPAGATION_DELAY" "-50.00 MIL,50.00 MIL"
					( Parent
						( matchGroupRef "@baseboard_fab2_lib.baseboard_fab2(sch_1):\MG_DQ_FAR_DIMM_NG_M_C_BYTE0\" )
					)
					( Units "uMatchProp" "ns" 1.000000)
					( Status sCSetFlattened )
					( Origin gBackEnd )
				)
			)
			( pinPair "@baseboard_fab2_lib.baseboard_fab2(sch_1):\PP4877\"
				( pinRef "@baseboard_fab2_lib.baseboard_fab2(sch_1):page25_i172:DDR2_DQ(0)" )
				( pinRef "@baseboard_fab2_lib.baseboard_fab2(sch_1):page48_i111:DQ(0)" )
				( attribute "RELATIVE_PROPAGATION_DELAY_SCOPE" "G"
					( Parent
						( matchGroupRef "@baseboard_fab2_lib.baseboard_fab2(sch_1):\MG_DQ-DQS_NEAR_DIMM_NG_M_C_BYTE0\" )
					)
					( Status sCSetFlattened )
					( Origin gBackEnd )
				)
				( attribute "RELATIVE_PROPAGATION_DELAY" "0.00 MIL,195.00 MIL"
					( Parent
						( matchGroupRef "@baseboard_fab2_lib.baseboard_fab2(sch_1):\MG_DQ-DQS_NEAR_DIMM_NG_M_C_BYTE0\" )
					)
					( Units "uMatchProp" "ns" 1.000000)
					( Status sCSetFlattened )
					( Origin gBackEnd )
				)
				( attribute "RELATIVE_PROPAGATION_DELAY_SCOPE" "G"
					( Parent
						( matchGroupRef "@baseboard_fab2_lib.baseboard_fab2(sch_1):\MG_DQ_NEAR_DIMM_NG_M_C_BYTE0\" )
					)
					( Status sCSetFlattened )
					( Origin gBackEnd )
				)
				( attribute "RELATIVE_PROPAGATION_DELAY" "-50.00 MIL,50.00 MIL"
					( Parent
						( matchGroupRef "@baseboard_fab2_lib.baseboard_fab2(sch_1):\MG_DQ_NEAR_DIMM_NG_M_C_BYTE0\" )
					)
					( Units "uMatchProp" "ns" 1.000000)
					( Status sCSetFlattened )
					( Origin gBackEnd )
				)
			)
			( pinPair "@baseboard_fab2_lib.baseboard_fab2(sch_1):\PP2110\"
				( pinRef "@baseboard_fab2_lib.baseboard_fab2(sch_1):page60_i172:DDR3_DQ(57)" )
				( pinRef "@baseboard_fab2_lib.baseboard_fab2(sch_1):page83_i111:DQ(56)" )
				( attribute "RELATIVE_PROPAGATION_DELAY_SCOPE" "G"
					( Parent
						( matchGroupRef "@baseboard_fab2_lib.baseboard_fab2(sch_1):\MG_DQ-DQS_FAR_DIMM_NG_M_K_BYTE7\" )
					)
					( Status sCSetFlattened )
					( Origin gBackEnd )
				)
				( attribute "RELATIVE_PROPAGATION_DELAY" "0.00 MIL,195.00 MIL"
					( Parent
						( matchGroupRef "@baseboard_fab2_lib.baseboard_fab2(sch_1):\MG_DQ-DQS_FAR_DIMM_NG_M_K_BYTE7\" )
					)
					( Units "uMatchProp" "ns" 1.000000)
					( Status sCSetFlattened )
					( Origin gBackEnd )
				)
				( attribute "RELATIVE_PROPAGATION_DELAY_SCOPE" "G"
					( Parent
						( matchGroupRef "@crescent_city_bb_fab1_lib.crescent_city_bb_fab1(sch_1):\MG_DQ_FAR_DIMM_NG_M_K_BYTE7\" )
					)
					( Status sCSetFlattened )
					( Origin gBackEnd )
				)
				( attribute "RELATIVE_PROPAGATION_DELAY" "-50.00 MIL,50.00 MIL"
					( Parent
						( matchGroupRef "@crescent_city_bb_fab1_lib.crescent_city_bb_fab1(sch_1):\MG_DQ_FAR_DIMM_NG_M_K_BYTE7\" )
					)
					( Units "uMatchProp" "ns" 1.000000)
					( Status sCSetFlattened )
					( Origin gBackEnd )
				)
			)
			( pinPair "@baseboard_fab2_lib.baseboard_fab2(sch_1):\PP2112\"
				( pinRef "@baseboard_fab2_lib.baseboard_fab2(sch_1):page60_i172:DDR3_DQ(57)" )
				( pinRef "@baseboard_fab2_lib.baseboard_fab2(sch_1):page84_i14:DQ(57)" )
				( attribute "RELATIVE_PROPAGATION_DELAY_SCOPE" "G"
					( Parent
						( matchGroupRef "@baseboard_fab2_lib.baseboard_fab2(sch_1):\MG_DQ-DQS_NEAR_DIMM_NG_M_K_BYTE7\" )
					)
					( Status sCSetFlattened )
					( Origin gBackEnd )
				)
				( attribute "RELATIVE_PROPAGATION_DELAY" "0.00 MIL,195.00 MIL"
					( Parent
						( matchGroupRef "@baseboard_fab2_lib.baseboard_fab2(sch_1):\MG_DQ-DQS_NEAR_DIMM_NG_M_K_BYTE7\" )
					)
					( Units "uMatchProp" "ns" 1.000000)
					( Status sCSetFlattened )
					( Origin gBackEnd )
				)
				( attribute "RELATIVE_PROPAGATION_DELAY_SCOPE" "G"
					( Parent
						( matchGroupRef "@crescent_city_bb_fab1_lib.crescent_city_bb_fab1(sch_1):\MG_DQ_NEAR_DIMM_NG_M_K_BYTE7\" )
					)
					( Origin gBackEnd )
				)
				( attribute "RELATIVE_PROPAGATION_DELAY" "TARGET,TARGET"
					( Parent
						( matchGroupRef "@crescent_city_bb_fab1_lib.crescent_city_bb_fab1(sch_1):\MG_DQ_NEAR_DIMM_NG_M_K_BYTE7\" )
					)
					( Units "uMatchProp" "ns" 1.000000)
					( Origin gBackEnd )
				)
			)
			( pinPair "@baseboard_fab2_lib.baseboard_fab2(sch_1):\PP2113\"
				( pinRef "@baseboard_fab2_lib.baseboard_fab2(sch_1):page60_i172:DDR3_DQ(58)" )
				( pinRef "@baseboard_fab2_lib.baseboard_fab2(sch_1):page83_i111:DQ(59)" )
				( attribute "RELATIVE_PROPAGATION_DELAY_SCOPE" "G"
					( Parent
						( matchGroupRef "@baseboard_fab2_lib.baseboard_fab2(sch_1):\MG_DQ-DQS_FAR_DIMM_NG_M_K_BYTE7\" )
					)
					( Status sCSetFlattened )
					( Origin gBackEnd )
				)
				( attribute "RELATIVE_PROPAGATION_DELAY" "0.00 MIL,195.00 MIL"
					( Parent
						( matchGroupRef "@baseboard_fab2_lib.baseboard_fab2(sch_1):\MG_DQ-DQS_FAR_DIMM_NG_M_K_BYTE7\" )
					)
					( Units "uMatchProp" "ns" 1.000000)
					( Status sCSetFlattened )
					( Origin gBackEnd )
				)
				( attribute "RELATIVE_PROPAGATION_DELAY_SCOPE" "G"
					( Parent
						( matchGroupRef "@crescent_city_bb_fab1_lib.crescent_city_bb_fab1(sch_1):\MG_DQ_FAR_DIMM_NG_M_K_BYTE7\" )
					)
					( Origin gBackEnd )
				)
				( attribute "RELATIVE_PROPAGATION_DELAY" "TARGET,TARGET"
					( Parent
						( matchGroupRef "@crescent_city_bb_fab1_lib.crescent_city_bb_fab1(sch_1):\MG_DQ_FAR_DIMM_NG_M_K_BYTE7\" )
					)
					( Units "uMatchProp" "ns" 1.000000)
					( Origin gBackEnd )
				)
			)
			( pinPair "@baseboard_fab2_lib.baseboard_fab2(sch_1):\PP2115\"
				( pinRef "@baseboard_fab2_lib.baseboard_fab2(sch_1):page60_i172:DDR3_DQ(58)" )
				( pinRef "@baseboard_fab2_lib.baseboard_fab2(sch_1):page84_i14:DQ(58)" )
				( attribute "RELATIVE_PROPAGATION_DELAY_SCOPE" "G"
					( Parent
						( matchGroupRef "@baseboard_fab2_lib.baseboard_fab2(sch_1):\MG_DQ-DQS_NEAR_DIMM_NG_M_K_BYTE7\" )
					)
					( Status sCSetFlattened )
					( Origin gBackEnd )
				)
				( attribute "RELATIVE_PROPAGATION_DELAY" "0.00 MIL,195.00 MIL"
					( Parent
						( matchGroupRef "@baseboard_fab2_lib.baseboard_fab2(sch_1):\MG_DQ-DQS_NEAR_DIMM_NG_M_K_BYTE7\" )
					)
					( Units "uMatchProp" "ns" 1.000000)
					( Status sCSetFlattened )
					( Origin gBackEnd )
				)
				( attribute "RELATIVE_PROPAGATION_DELAY_SCOPE" "G"
					( Parent
						( matchGroupRef "@crescent_city_bb_fab1_lib.crescent_city_bb_fab1(sch_1):\MG_DQ_NEAR_DIMM_NG_M_K_BYTE7\" )
					)
					( Status sCSetFlattened )
					( Origin gBackEnd )
				)
				( attribute "RELATIVE_PROPAGATION_DELAY" "-50.00 MIL,50.00 MIL"
					( Parent
						( matchGroupRef "@crescent_city_bb_fab1_lib.crescent_city_bb_fab1(sch_1):\MG_DQ_NEAR_DIMM_NG_M_K_BYTE7\" )
					)
					( Units "uMatchProp" "ns" 1.000000)
					( Status sCSetFlattened )
					( Origin gBackEnd )
				)
			)
			( pinPair "@baseboard_fab2_lib.baseboard_fab2(sch_1):\PP2116\"
				( pinRef "@baseboard_fab2_lib.baseboard_fab2(sch_1):page60_i172:DDR3_DQ(59)" )
				( pinRef "@baseboard_fab2_lib.baseboard_fab2(sch_1):page83_i111:DQ(58)" )
				( attribute "RELATIVE_PROPAGATION_DELAY_SCOPE" "G"
					( Parent
						( matchGroupRef "@baseboard_fab2_lib.baseboard_fab2(sch_1):\MG_DQ-DQS_FAR_DIMM_NG_M_K_BYTE7\" )
					)
					( Status sCSetFlattened )
					( Origin gBackEnd )
				)
				( attribute "RELATIVE_PROPAGATION_DELAY" "0.00 MIL,195.00 MIL"
					( Parent
						( matchGroupRef "@baseboard_fab2_lib.baseboard_fab2(sch_1):\MG_DQ-DQS_FAR_DIMM_NG_M_K_BYTE7\" )
					)
					( Units "uMatchProp" "ns" 1.000000)
					( Status sCSetFlattened )
					( Origin gBackEnd )
				)
				( attribute "RELATIVE_PROPAGATION_DELAY_SCOPE" "G"
					( Parent
						( matchGroupRef "@crescent_city_bb_fab1_lib.crescent_city_bb_fab1(sch_1):\MG_DQ_FAR_DIMM_NG_M_K_BYTE7\" )
					)
					( Status sCSetFlattened )
					( Origin gBackEnd )
				)
				( attribute "RELATIVE_PROPAGATION_DELAY" "-50.00 MIL,50.00 MIL"
					( Parent
						( matchGroupRef "@crescent_city_bb_fab1_lib.crescent_city_bb_fab1(sch_1):\MG_DQ_FAR_DIMM_NG_M_K_BYTE7\" )
					)
					( Units "uMatchProp" "ns" 1.000000)
					( Status sCSetFlattened )
					( Origin gBackEnd )
				)
			)
			( pinPair "@baseboard_fab2_lib.baseboard_fab2(sch_1):\PP2118\"
				( pinRef "@baseboard_fab2_lib.baseboard_fab2(sch_1):page60_i172:DDR3_DQ(59)" )
				( pinRef "@baseboard_fab2_lib.baseboard_fab2(sch_1):page84_i14:DQ(59)" )
				( attribute "RELATIVE_PROPAGATION_DELAY_SCOPE" "G"
					( Parent
						( matchGroupRef "@baseboard_fab2_lib.baseboard_fab2(sch_1):\MG_DQ-DQS_NEAR_DIMM_NG_M_K_BYTE7\" )
					)
					( Status sCSetFlattened )
					( Origin gBackEnd )
				)
				( attribute "RELATIVE_PROPAGATION_DELAY" "0.00 MIL,195.00 MIL"
					( Parent
						( matchGroupRef "@baseboard_fab2_lib.baseboard_fab2(sch_1):\MG_DQ-DQS_NEAR_DIMM_NG_M_K_BYTE7\" )
					)
					( Units "uMatchProp" "ns" 1.000000)
					( Status sCSetFlattened )
					( Origin gBackEnd )
				)
				( attribute "RELATIVE_PROPAGATION_DELAY_SCOPE" "G"
					( Parent
						( matchGroupRef "@crescent_city_bb_fab1_lib.crescent_city_bb_fab1(sch_1):\MG_DQ_NEAR_DIMM_NG_M_K_BYTE7\" )
					)
					( Status sCSetFlattened )
					( Origin gBackEnd )
				)
				( attribute "RELATIVE_PROPAGATION_DELAY" "-50.00 MIL,50.00 MIL"
					( Parent
						( matchGroupRef "@crescent_city_bb_fab1_lib.crescent_city_bb_fab1(sch_1):\MG_DQ_NEAR_DIMM_NG_M_K_BYTE7\" )
					)
					( Units "uMatchProp" "ns" 1.000000)
					( Status sCSetFlattened )
					( Origin gBackEnd )
				)
			)
			( pinPair "@baseboard_fab2_lib.baseboard_fab2(sch_1):\PP2119\"
				( pinRef "@baseboard_fab2_lib.baseboard_fab2(sch_1):page60_i172:DDR3_DQ(60)" )
				( pinRef "@baseboard_fab2_lib.baseboard_fab2(sch_1):page83_i111:DQ(61)" )
				( attribute "RELATIVE_PROPAGATION_DELAY_SCOPE" "G"
					( Parent
						( matchGroupRef "@baseboard_fab2_lib.baseboard_fab2(sch_1):\MG_DQ-DQS_FAR_DIMM_NG_M_K_BYTE7\" )
					)
					( Status sCSetFlattened )
					( Origin gBackEnd )
				)
				( attribute "RELATIVE_PROPAGATION_DELAY" "0.00 MIL,195.00 MIL"
					( Parent
						( matchGroupRef "@baseboard_fab2_lib.baseboard_fab2(sch_1):\MG_DQ-DQS_FAR_DIMM_NG_M_K_BYTE7\" )
					)
					( Units "uMatchProp" "ns" 1.000000)
					( Status sCSetFlattened )
					( Origin gBackEnd )
				)
				( attribute "RELATIVE_PROPAGATION_DELAY_SCOPE" "G"
					( Parent
						( matchGroupRef "@crescent_city_bb_fab1_lib.crescent_city_bb_fab1(sch_1):\MG_DQ_FAR_DIMM_NG_M_K_BYTE7\" )
					)
					( Status sCSetFlattened )
					( Origin gBackEnd )
				)
				( attribute "RELATIVE_PROPAGATION_DELAY" "-50.00 MIL,50.00 MIL"
					( Parent
						( matchGroupRef "@crescent_city_bb_fab1_lib.crescent_city_bb_fab1(sch_1):\MG_DQ_FAR_DIMM_NG_M_K_BYTE7\" )
					)
					( Units "uMatchProp" "ns" 1.000000)
					( Status sCSetFlattened )
					( Origin gBackEnd )
				)
			)
			( pinPair "@baseboard_fab2_lib.baseboard_fab2(sch_1):\PP2121\"
				( pinRef "@baseboard_fab2_lib.baseboard_fab2(sch_1):page60_i172:DDR3_DQ(60)" )
				( pinRef "@baseboard_fab2_lib.baseboard_fab2(sch_1):page84_i14:DQ(60)" )
				( attribute "RELATIVE_PROPAGATION_DELAY_SCOPE" "G"
					( Parent
						( matchGroupRef "@baseboard_fab2_lib.baseboard_fab2(sch_1):\MG_DQ-DQS_NEAR_DIMM_NG_M_K_BYTE7\" )
					)
					( Status sCSetFlattened )
					( Origin gBackEnd )
				)
				( attribute "RELATIVE_PROPAGATION_DELAY" "0.00 MIL,195.00 MIL"
					( Parent
						( matchGroupRef "@baseboard_fab2_lib.baseboard_fab2(sch_1):\MG_DQ-DQS_NEAR_DIMM_NG_M_K_BYTE7\" )
					)
					( Units "uMatchProp" "ns" 1.000000)
					( Status sCSetFlattened )
					( Origin gBackEnd )
				)
				( attribute "RELATIVE_PROPAGATION_DELAY_SCOPE" "G"
					( Parent
						( matchGroupRef "@crescent_city_bb_fab1_lib.crescent_city_bb_fab1(sch_1):\MG_DQ_NEAR_DIMM_NG_M_K_BYTE7\" )
					)
					( Status sCSetFlattened )
					( Origin gBackEnd )
				)
				( attribute "RELATIVE_PROPAGATION_DELAY" "-50.00 MIL,50.00 MIL"
					( Parent
						( matchGroupRef "@crescent_city_bb_fab1_lib.crescent_city_bb_fab1(sch_1):\MG_DQ_NEAR_DIMM_NG_M_K_BYTE7\" )
					)
					( Units "uMatchProp" "ns" 1.000000)
					( Status sCSetFlattened )
					( Origin gBackEnd )
				)
			)
			( pinPair "@baseboard_fab2_lib.baseboard_fab2(sch_1):\PP2122\"
				( pinRef "@baseboard_fab2_lib.baseboard_fab2(sch_1):page60_i172:DDR3_DQ(61)" )
				( pinRef "@baseboard_fab2_lib.baseboard_fab2(sch_1):page83_i111:DQ(60)" )
				( attribute "RELATIVE_PROPAGATION_DELAY_SCOPE" "G"
					( Parent
						( matchGroupRef "@baseboard_fab2_lib.baseboard_fab2(sch_1):\MG_DQ-DQS_FAR_DIMM_NG_M_K_BYTE7\" )
					)
					( Status sCSetFlattened )
					( Origin gBackEnd )
				)
				( attribute "RELATIVE_PROPAGATION_DELAY" "0.00 MIL,195.00 MIL"
					( Parent
						( matchGroupRef "@baseboard_fab2_lib.baseboard_fab2(sch_1):\MG_DQ-DQS_FAR_DIMM_NG_M_K_BYTE7\" )
					)
					( Units "uMatchProp" "ns" 1.000000)
					( Status sCSetFlattened )
					( Origin gBackEnd )
				)
				( attribute "RELATIVE_PROPAGATION_DELAY_SCOPE" "G"
					( Parent
						( matchGroupRef "@crescent_city_bb_fab1_lib.crescent_city_bb_fab1(sch_1):\MG_DQ_FAR_DIMM_NG_M_K_BYTE7\" )
					)
					( Status sCSetFlattened )
					( Origin gBackEnd )
				)
				( attribute "RELATIVE_PROPAGATION_DELAY" "-50.00 MIL,50.00 MIL"
					( Parent
						( matchGroupRef "@crescent_city_bb_fab1_lib.crescent_city_bb_fab1(sch_1):\MG_DQ_FAR_DIMM_NG_M_K_BYTE7\" )
					)
					( Units "uMatchProp" "ns" 1.000000)
					( Status sCSetFlattened )
					( Origin gBackEnd )
				)
			)
			( pinPair "@baseboard_fab2_lib.baseboard_fab2(sch_1):\PP2124\"
				( pinRef "@baseboard_fab2_lib.baseboard_fab2(sch_1):page60_i172:DDR3_DQ(61)" )
				( pinRef "@baseboard_fab2_lib.baseboard_fab2(sch_1):page84_i14:DQ(61)" )
				( attribute "RELATIVE_PROPAGATION_DELAY_SCOPE" "G"
					( Parent
						( matchGroupRef "@baseboard_fab2_lib.baseboard_fab2(sch_1):\MG_DQ-DQS_NEAR_DIMM_NG_M_K_BYTE7\" )
					)
					( Status sCSetFlattened )
					( Origin gBackEnd )
				)
				( attribute "RELATIVE_PROPAGATION_DELAY" "0.00 MIL,195.00 MIL"
					( Parent
						( matchGroupRef "@baseboard_fab2_lib.baseboard_fab2(sch_1):\MG_DQ-DQS_NEAR_DIMM_NG_M_K_BYTE7\" )
					)
					( Units "uMatchProp" "ns" 1.000000)
					( Status sCSetFlattened )
					( Origin gBackEnd )
				)
				( attribute "RELATIVE_PROPAGATION_DELAY_SCOPE" "G"
					( Parent
						( matchGroupRef "@crescent_city_bb_fab1_lib.crescent_city_bb_fab1(sch_1):\MG_DQ_NEAR_DIMM_NG_M_K_BYTE7\" )
					)
					( Status sCSetFlattened )
					( Origin gBackEnd )
				)
				( attribute "RELATIVE_PROPAGATION_DELAY" "-50.00 MIL,50.00 MIL"
					( Parent
						( matchGroupRef "@crescent_city_bb_fab1_lib.crescent_city_bb_fab1(sch_1):\MG_DQ_NEAR_DIMM_NG_M_K_BYTE7\" )
					)
					( Units "uMatchProp" "ns" 1.000000)
					( Status sCSetFlattened )
					( Origin gBackEnd )
				)
			)
			( pinPair "@baseboard_fab2_lib.baseboard_fab2(sch_1):\PP2125\"
				( pinRef "@baseboard_fab2_lib.baseboard_fab2(sch_1):page60_i172:DDR3_DQ(62)" )
				( pinRef "@baseboard_fab2_lib.baseboard_fab2(sch_1):page83_i111:DQ(63)" )
				( attribute "RELATIVE_PROPAGATION_DELAY_SCOPE" "G"
					( Parent
						( matchGroupRef "@baseboard_fab2_lib.baseboard_fab2(sch_1):\MG_DQ-DQS_FAR_DIMM_NG_M_K_BYTE7\" )
					)
					( Status sCSetFlattened )
					( Origin gBackEnd )
				)
				( attribute "RELATIVE_PROPAGATION_DELAY" "0.00 MIL,195.00 MIL"
					( Parent
						( matchGroupRef "@baseboard_fab2_lib.baseboard_fab2(sch_1):\MG_DQ-DQS_FAR_DIMM_NG_M_K_BYTE7\" )
					)
					( Units "uMatchProp" "ns" 1.000000)
					( Status sCSetFlattened )
					( Origin gBackEnd )
				)
				( attribute "RELATIVE_PROPAGATION_DELAY_SCOPE" "G"
					( Parent
						( matchGroupRef "@crescent_city_bb_fab1_lib.crescent_city_bb_fab1(sch_1):\MG_DQ_FAR_DIMM_NG_M_K_BYTE7\" )
					)
					( Status sCSetFlattened )
					( Origin gBackEnd )
				)
				( attribute "RELATIVE_PROPAGATION_DELAY" "-50.00 MIL,50.00 MIL"
					( Parent
						( matchGroupRef "@crescent_city_bb_fab1_lib.crescent_city_bb_fab1(sch_1):\MG_DQ_FAR_DIMM_NG_M_K_BYTE7\" )
					)
					( Units "uMatchProp" "ns" 1.000000)
					( Status sCSetFlattened )
					( Origin gBackEnd )
				)
			)
			( pinPair "@baseboard_fab2_lib.baseboard_fab2(sch_1):\PP2127\"
				( pinRef "@baseboard_fab2_lib.baseboard_fab2(sch_1):page60_i172:DDR3_DQ(62)" )
				( pinRef "@baseboard_fab2_lib.baseboard_fab2(sch_1):page84_i14:DQ(62)" )
				( attribute "RELATIVE_PROPAGATION_DELAY_SCOPE" "G"
					( Parent
						( matchGroupRef "@baseboard_fab2_lib.baseboard_fab2(sch_1):\MG_DQ-DQS_NEAR_DIMM_NG_M_K_BYTE7\" )
					)
					( Status sCSetFlattened )
					( Origin gBackEnd )
				)
				( attribute "RELATIVE_PROPAGATION_DELAY" "0.00 MIL,195.00 MIL"
					( Parent
						( matchGroupRef "@baseboard_fab2_lib.baseboard_fab2(sch_1):\MG_DQ-DQS_NEAR_DIMM_NG_M_K_BYTE7\" )
					)
					( Units "uMatchProp" "ns" 1.000000)
					( Status sCSetFlattened )
					( Origin gBackEnd )
				)
				( attribute "RELATIVE_PROPAGATION_DELAY_SCOPE" "G"
					( Parent
						( matchGroupRef "@crescent_city_bb_fab1_lib.crescent_city_bb_fab1(sch_1):\MG_DQ_NEAR_DIMM_NG_M_K_BYTE7\" )
					)
					( Status sCSetFlattened )
					( Origin gBackEnd )
				)
				( attribute "RELATIVE_PROPAGATION_DELAY" "-50.00 MIL,50.00 MIL"
					( Parent
						( matchGroupRef "@crescent_city_bb_fab1_lib.crescent_city_bb_fab1(sch_1):\MG_DQ_NEAR_DIMM_NG_M_K_BYTE7\" )
					)
					( Units "uMatchProp" "ns" 1.000000)
					( Status sCSetFlattened )
					( Origin gBackEnd )
				)
			)
			( pinPair "@baseboard_fab2_lib.baseboard_fab2(sch_1):\PP2128\"
				( pinRef "@baseboard_fab2_lib.baseboard_fab2(sch_1):page60_i172:DDR3_DQ(63)" )
				( pinRef "@baseboard_fab2_lib.baseboard_fab2(sch_1):page83_i111:DQ(62)" )
				( attribute "RELATIVE_PROPAGATION_DELAY_SCOPE" "G"
					( Parent
						( matchGroupRef "@baseboard_fab2_lib.baseboard_fab2(sch_1):\MG_DQ-DQS_FAR_DIMM_NG_M_K_BYTE7\" )
					)
					( Status sCSetFlattened )
					( Origin gBackEnd )
				)
				( attribute "RELATIVE_PROPAGATION_DELAY" "0.00 MIL,195.00 MIL"
					( Parent
						( matchGroupRef "@baseboard_fab2_lib.baseboard_fab2(sch_1):\MG_DQ-DQS_FAR_DIMM_NG_M_K_BYTE7\" )
					)
					( Units "uMatchProp" "ns" 1.000000)
					( Status sCSetFlattened )
					( Origin gBackEnd )
				)
				( attribute "RELATIVE_PROPAGATION_DELAY_SCOPE" "G"
					( Parent
						( matchGroupRef "@crescent_city_bb_fab1_lib.crescent_city_bb_fab1(sch_1):\MG_DQ_FAR_DIMM_NG_M_K_BYTE7\" )
					)
					( Status sCSetFlattened )
					( Origin gBackEnd )
				)
				( attribute "RELATIVE_PROPAGATION_DELAY" "-50.00 MIL,50.00 MIL"
					( Parent
						( matchGroupRef "@crescent_city_bb_fab1_lib.crescent_city_bb_fab1(sch_1):\MG_DQ_FAR_DIMM_NG_M_K_BYTE7\" )
					)
					( Units "uMatchProp" "ns" 1.000000)
					( Status sCSetFlattened )
					( Origin gBackEnd )
				)
			)
			( pinPair "@baseboard_fab2_lib.baseboard_fab2(sch_1):\PP2130\"
				( pinRef "@baseboard_fab2_lib.baseboard_fab2(sch_1):page60_i172:DDR3_DQ(63)" )
				( pinRef "@baseboard_fab2_lib.baseboard_fab2(sch_1):page84_i14:DQ(63)" )
				( attribute "RELATIVE_PROPAGATION_DELAY_SCOPE" "G"
					( Parent
						( matchGroupRef "@baseboard_fab2_lib.baseboard_fab2(sch_1):\MG_DQ-DQS_NEAR_DIMM_NG_M_K_BYTE7\" )
					)
					( Status sCSetFlattened )
					( Origin gBackEnd )
				)
				( attribute "RELATIVE_PROPAGATION_DELAY" "0.00 MIL,195.00 MIL"
					( Parent
						( matchGroupRef "@baseboard_fab2_lib.baseboard_fab2(sch_1):\MG_DQ-DQS_NEAR_DIMM_NG_M_K_BYTE7\" )
					)
					( Units "uMatchProp" "ns" 1.000000)
					( Status sCSetFlattened )
					( Origin gBackEnd )
				)
				( attribute "RELATIVE_PROPAGATION_DELAY_SCOPE" "G"
					( Parent
						( matchGroupRef "@crescent_city_bb_fab1_lib.crescent_city_bb_fab1(sch_1):\MG_DQ_NEAR_DIMM_NG_M_K_BYTE7\" )
					)
					( Status sCSetFlattened )
					( Origin gBackEnd )
				)
				( attribute "RELATIVE_PROPAGATION_DELAY" "-50.00 MIL,50.00 MIL"
					( Parent
						( matchGroupRef "@crescent_city_bb_fab1_lib.crescent_city_bb_fab1(sch_1):\MG_DQ_NEAR_DIMM_NG_M_K_BYTE7\" )
					)
					( Units "uMatchProp" "ns" 1.000000)
					( Status sCSetFlattened )
					( Origin gBackEnd )
				)
			)
			( pinPair "@baseboard_fab2_lib.baseboard_fab2(sch_1):\PP2059\"
				( pinRef "@baseboard_fab2_lib.baseboard_fab2(sch_1):page61_i172:DDR4_DQ(0)" )
				( pinRef "@baseboard_fab2_lib.baseboard_fab2(sch_1):page85_i111:DQ(1)" )
				( attribute "RELATIVE_PROPAGATION_DELAY_SCOPE" "G"
					( Parent
						( matchGroupRef "@baseboard_fab2_lib.baseboard_fab2(sch_1):\MG_DQ-DQS_FAR_DIMM_NG_M_L_BYTE0\" )
					)
					( Status sCSetFlattened )
					( Origin gBackEnd )
				)
				( attribute "RELATIVE_PROPAGATION_DELAY" "0.00 MIL,195.00 MIL"
					( Parent
						( matchGroupRef "@baseboard_fab2_lib.baseboard_fab2(sch_1):\MG_DQ-DQS_FAR_DIMM_NG_M_L_BYTE0\" )
					)
					( Units "uMatchProp" "ns" 1.000000)
					( Status sCSetFlattened )
					( Origin gBackEnd )
				)
				( attribute "RELATIVE_PROPAGATION_DELAY_SCOPE" "G"
					( Parent
						( matchGroupRef "@baseboard_fab2_lib.baseboard_fab2(sch_1):\MG_DQ_FAR_DIMM_NG_M_L_BYTE0\" )
					)
					( Status sCSetFlattened )
					( Origin gBackEnd )
				)
				( attribute "RELATIVE_PROPAGATION_DELAY" "-50.00 MIL,50.00 MIL"
					( Parent
						( matchGroupRef "@baseboard_fab2_lib.baseboard_fab2(sch_1):\MG_DQ_FAR_DIMM_NG_M_L_BYTE0\" )
					)
					( Units "uMatchProp" "ns" 1.000000)
					( Status sCSetFlattened )
					( Origin gBackEnd )
				)
			)
			( pinPair "@baseboard_fab2_lib.baseboard_fab2(sch_1):\PP2060\"
				( pinRef "@baseboard_fab2_lib.baseboard_fab2(sch_1):page61_i172:DDR4_DQ(0)" )
				( pinRef "@baseboard_fab2_lib.baseboard_fab2(sch_1):page86_i12:DQ(0)" )
				( attribute "RELATIVE_PROPAGATION_DELAY_SCOPE" "G"
					( Parent
						( matchGroupRef "@baseboard_fab2_lib.baseboard_fab2(sch_1):\MG_DQ-DQS_NEAR_DIMM_NG_M_L_BYTE0\" )
					)
					( Status sCSetFlattened )
					( Origin gBackEnd )
				)
				( attribute "RELATIVE_PROPAGATION_DELAY" "0.00 MIL,195.00 MIL"
					( Parent
						( matchGroupRef "@baseboard_fab2_lib.baseboard_fab2(sch_1):\MG_DQ-DQS_NEAR_DIMM_NG_M_L_BYTE0\" )
					)
					( Units "uMatchProp" "ns" 1.000000)
					( Status sCSetFlattened )
					( Origin gBackEnd )
				)
				( attribute "RELATIVE_PROPAGATION_DELAY_SCOPE" "G"
					( Parent
						( matchGroupRef "@baseboard_fab2_lib.baseboard_fab2(sch_1):\MG_DQ_NEAR_DIMM_NG_M_L_BYTE0\" )
					)
					( Status sCSetFlattened )
					( Origin gBackEnd )
				)
				( attribute "RELATIVE_PROPAGATION_DELAY" "-50.00 MIL,50.00 MIL"
					( Parent
						( matchGroupRef "@baseboard_fab2_lib.baseboard_fab2(sch_1):\MG_DQ_NEAR_DIMM_NG_M_L_BYTE0\" )
					)
					( Units "uMatchProp" "ns" 1.000000)
					( Status sCSetFlattened )
					( Origin gBackEnd )
				)
			)
			( pinPair "@baseboard_fab2_lib.baseboard_fab2(sch_1):\PP2062\"
				( pinRef "@baseboard_fab2_lib.baseboard_fab2(sch_1):page61_i172:DDR4_DQ(1)" )
				( pinRef "@baseboard_fab2_lib.baseboard_fab2(sch_1):page85_i111:DQ(0)" )
				( attribute "RELATIVE_PROPAGATION_DELAY_SCOPE" "G"
					( Parent
						( matchGroupRef "@baseboard_fab2_lib.baseboard_fab2(sch_1):\MG_DQ-DQS_FAR_DIMM_NG_M_L_BYTE0\" )
					)
					( Status sCSetFlattened )
					( Origin gBackEnd )
				)
				( attribute "RELATIVE_PROPAGATION_DELAY" "0.00 MIL,195.00 MIL"
					( Parent
						( matchGroupRef "@baseboard_fab2_lib.baseboard_fab2(sch_1):\MG_DQ-DQS_FAR_DIMM_NG_M_L_BYTE0\" )
					)
					( Units "uMatchProp" "ns" 1.000000)
					( Status sCSetFlattened )
					( Origin gBackEnd )
				)
				( attribute "RELATIVE_PROPAGATION_DELAY_SCOPE" "G"
					( Parent
						( matchGroupRef "@baseboard_fab2_lib.baseboard_fab2(sch_1):\MG_DQ_FAR_DIMM_NG_M_L_BYTE0\" )
					)
					( Status sCSetFlattened )
					( Origin gBackEnd )
				)
				( attribute "RELATIVE_PROPAGATION_DELAY" "-50.00 MIL,50.00 MIL"
					( Parent
						( matchGroupRef "@baseboard_fab2_lib.baseboard_fab2(sch_1):\MG_DQ_FAR_DIMM_NG_M_L_BYTE0\" )
					)
					( Units "uMatchProp" "ns" 1.000000)
					( Status sCSetFlattened )
					( Origin gBackEnd )
				)
			)
			( pinPair "@baseboard_fab2_lib.baseboard_fab2(sch_1):\PP2063\"
				( pinRef "@baseboard_fab2_lib.baseboard_fab2(sch_1):page61_i172:DDR4_DQ(1)" )
				( pinRef "@baseboard_fab2_lib.baseboard_fab2(sch_1):page86_i12:DQ(1)" )
				( attribute "RELATIVE_PROPAGATION_DELAY_SCOPE" "G"
					( Parent
						( matchGroupRef "@baseboard_fab2_lib.baseboard_fab2(sch_1):\MG_DQ-DQS_NEAR_DIMM_NG_M_L_BYTE0\" )
					)
					( Status sCSetFlattened )
					( Origin gBackEnd )
				)
				( attribute "RELATIVE_PROPAGATION_DELAY" "0.00 MIL,195.00 MIL"
					( Parent
						( matchGroupRef "@baseboard_fab2_lib.baseboard_fab2(sch_1):\MG_DQ-DQS_NEAR_DIMM_NG_M_L_BYTE0\" )
					)
					( Units "uMatchProp" "ns" 1.000000)
					( Status sCSetFlattened )
					( Origin gBackEnd )
				)
				( attribute "RELATIVE_PROPAGATION_DELAY_SCOPE" "G"
					( Parent
						( matchGroupRef "@baseboard_fab2_lib.baseboard_fab2(sch_1):\MG_DQ_NEAR_DIMM_NG_M_L_BYTE0\" )
					)
					( Status sCSetFlattened )
					( Origin gBackEnd )
				)
				( attribute "RELATIVE_PROPAGATION_DELAY" "-50.00 MIL,50.00 MIL"
					( Parent
						( matchGroupRef "@baseboard_fab2_lib.baseboard_fab2(sch_1):\MG_DQ_NEAR_DIMM_NG_M_L_BYTE0\" )
					)
					( Units "uMatchProp" "ns" 1.000000)
					( Status sCSetFlattened )
					( Origin gBackEnd )
				)
			)
			( pinPair "@baseboard_fab2_lib.baseboard_fab2(sch_1):\PP2065\"
				( pinRef "@baseboard_fab2_lib.baseboard_fab2(sch_1):page61_i172:DDR4_DQ(2)" )
				( pinRef "@baseboard_fab2_lib.baseboard_fab2(sch_1):page85_i111:DQ(3)" )
				( attribute "RELATIVE_PROPAGATION_DELAY_SCOPE" "G"
					( Parent
						( matchGroupRef "@baseboard_fab2_lib.baseboard_fab2(sch_1):\MG_DQ-DQS_FAR_DIMM_NG_M_L_BYTE0\" )
					)
					( Status sCSetFlattened )
					( Origin gBackEnd )
				)
				( attribute "RELATIVE_PROPAGATION_DELAY" "0.00 MIL,195.00 MIL"
					( Parent
						( matchGroupRef "@baseboard_fab2_lib.baseboard_fab2(sch_1):\MG_DQ-DQS_FAR_DIMM_NG_M_L_BYTE0\" )
					)
					( Units "uMatchProp" "ns" 1.000000)
					( Status sCSetFlattened )
					( Origin gBackEnd )
				)
				( attribute "RELATIVE_PROPAGATION_DELAY_SCOPE" "G"
					( Parent
						( matchGroupRef "@baseboard_fab2_lib.baseboard_fab2(sch_1):\MG_DQ_FAR_DIMM_NG_M_L_BYTE0\" )
					)
					( Status sCSetFlattened )
					( Origin gBackEnd )
				)
				( attribute "RELATIVE_PROPAGATION_DELAY" "-50.00 MIL,50.00 MIL"
					( Parent
						( matchGroupRef "@baseboard_fab2_lib.baseboard_fab2(sch_1):\MG_DQ_FAR_DIMM_NG_M_L_BYTE0\" )
					)
					( Units "uMatchProp" "ns" 1.000000)
					( Status sCSetFlattened )
					( Origin gBackEnd )
				)
			)
			( pinPair "@baseboard_fab2_lib.baseboard_fab2(sch_1):\PP2066\"
				( pinRef "@baseboard_fab2_lib.baseboard_fab2(sch_1):page61_i172:DDR4_DQ(2)" )
				( pinRef "@baseboard_fab2_lib.baseboard_fab2(sch_1):page86_i12:DQ(2)" )
				( attribute "RELATIVE_PROPAGATION_DELAY_SCOPE" "G"
					( Parent
						( matchGroupRef "@baseboard_fab2_lib.baseboard_fab2(sch_1):\MG_DQ-DQS_NEAR_DIMM_NG_M_L_BYTE0\" )
					)
					( Status sCSetFlattened )
					( Origin gBackEnd )
				)
				( attribute "RELATIVE_PROPAGATION_DELAY" "0.00 MIL,195.00 MIL"
					( Parent
						( matchGroupRef "@baseboard_fab2_lib.baseboard_fab2(sch_1):\MG_DQ-DQS_NEAR_DIMM_NG_M_L_BYTE0\" )
					)
					( Units "uMatchProp" "ns" 1.000000)
					( Status sCSetFlattened )
					( Origin gBackEnd )
				)
				( attribute "RELATIVE_PROPAGATION_DELAY_SCOPE" "G"
					( Parent
						( matchGroupRef "@baseboard_fab2_lib.baseboard_fab2(sch_1):\MG_DQ_NEAR_DIMM_NG_M_L_BYTE0\" )
					)
					( Status sCSetFlattened )
					( Origin gBackEnd )
				)
				( attribute "RELATIVE_PROPAGATION_DELAY" "-50.00 MIL,50.00 MIL"
					( Parent
						( matchGroupRef "@baseboard_fab2_lib.baseboard_fab2(sch_1):\MG_DQ_NEAR_DIMM_NG_M_L_BYTE0\" )
					)
					( Units "uMatchProp" "ns" 1.000000)
					( Status sCSetFlattened )
					( Origin gBackEnd )
				)
			)
			( pinPair "@baseboard_fab2_lib.baseboard_fab2(sch_1):\PP2068\"
				( pinRef "@baseboard_fab2_lib.baseboard_fab2(sch_1):page61_i172:DDR4_DQ(3)" )
				( pinRef "@baseboard_fab2_lib.baseboard_fab2(sch_1):page85_i111:DQ(2)" )
				( attribute "RELATIVE_PROPAGATION_DELAY_SCOPE" "G"
					( Parent
						( matchGroupRef "@baseboard_fab2_lib.baseboard_fab2(sch_1):\MG_DQ-DQS_FAR_DIMM_NG_M_L_BYTE0\" )
					)
					( Status sCSetFlattened )
					( Origin gBackEnd )
				)
				( attribute "RELATIVE_PROPAGATION_DELAY" "0.00 MIL,195.00 MIL"
					( Parent
						( matchGroupRef "@baseboard_fab2_lib.baseboard_fab2(sch_1):\MG_DQ-DQS_FAR_DIMM_NG_M_L_BYTE0\" )
					)
					( Units "uMatchProp" "ns" 1.000000)
					( Status sCSetFlattened )
					( Origin gBackEnd )
				)
				( attribute "RELATIVE_PROPAGATION_DELAY_SCOPE" "G"
					( Parent
						( matchGroupRef "@baseboard_fab2_lib.baseboard_fab2(sch_1):\MG_DQ_FAR_DIMM_NG_M_L_BYTE0\" )
					)
					( Status sCSetFlattened )
					( Origin gBackEnd )
				)
				( attribute "RELATIVE_PROPAGATION_DELAY" "-50.00 MIL,50.00 MIL"
					( Parent
						( matchGroupRef "@baseboard_fab2_lib.baseboard_fab2(sch_1):\MG_DQ_FAR_DIMM_NG_M_L_BYTE0\" )
					)
					( Units "uMatchProp" "ns" 1.000000)
					( Status sCSetFlattened )
					( Origin gBackEnd )
				)
			)
			( pinPair "@baseboard_fab2_lib.baseboard_fab2(sch_1):\PP2069\"
				( pinRef "@baseboard_fab2_lib.baseboard_fab2(sch_1):page61_i172:DDR4_DQ(3)" )
				( pinRef "@baseboard_fab2_lib.baseboard_fab2(sch_1):page86_i12:DQ(3)" )
				( attribute "RELATIVE_PROPAGATION_DELAY_SCOPE" "G"
					( Parent
						( matchGroupRef "@baseboard_fab2_lib.baseboard_fab2(sch_1):\MG_DQ-DQS_NEAR_DIMM_NG_M_L_BYTE0\" )
					)
					( Status sCSetFlattened )
					( Origin gBackEnd )
				)
				( attribute "RELATIVE_PROPAGATION_DELAY" "0.00 MIL,195.00 MIL"
					( Parent
						( matchGroupRef "@baseboard_fab2_lib.baseboard_fab2(sch_1):\MG_DQ-DQS_NEAR_DIMM_NG_M_L_BYTE0\" )
					)
					( Units "uMatchProp" "ns" 1.000000)
					( Status sCSetFlattened )
					( Origin gBackEnd )
				)
				( attribute "RELATIVE_PROPAGATION_DELAY_SCOPE" "G"
					( Parent
						( matchGroupRef "@baseboard_fab2_lib.baseboard_fab2(sch_1):\MG_DQ_NEAR_DIMM_NG_M_L_BYTE0\" )
					)
					( Status sCSetFlattened )
					( Origin gBackEnd )
				)
				( attribute "RELATIVE_PROPAGATION_DELAY" "-50.00 MIL,50.00 MIL"
					( Parent
						( matchGroupRef "@baseboard_fab2_lib.baseboard_fab2(sch_1):\MG_DQ_NEAR_DIMM_NG_M_L_BYTE0\" )
					)
					( Units "uMatchProp" "ns" 1.000000)
					( Status sCSetFlattened )
					( Origin gBackEnd )
				)
			)
			( pinPair "@baseboard_fab2_lib.baseboard_fab2(sch_1):\PP2071\"
				( pinRef "@baseboard_fab2_lib.baseboard_fab2(sch_1):page61_i172:DDR4_DQ(4)" )
				( pinRef "@baseboard_fab2_lib.baseboard_fab2(sch_1):page85_i111:DQ(5)" )
				( attribute "RELATIVE_PROPAGATION_DELAY_SCOPE" "G"
					( Parent
						( matchGroupRef "@baseboard_fab2_lib.baseboard_fab2(sch_1):\MG_DQ-DQS_FAR_DIMM_NG_M_L_BYTE0\" )
					)
					( Status sCSetFlattened )
					( Origin gBackEnd )
				)
				( attribute "RELATIVE_PROPAGATION_DELAY" "0.00 MIL,195.00 MIL"
					( Parent
						( matchGroupRef "@baseboard_fab2_lib.baseboard_fab2(sch_1):\MG_DQ-DQS_FAR_DIMM_NG_M_L_BYTE0\" )
					)
					( Units "uMatchProp" "ns" 1.000000)
					( Status sCSetFlattened )
					( Origin gBackEnd )
				)
				( attribute "RELATIVE_PROPAGATION_DELAY_SCOPE" "G"
					( Parent
						( matchGroupRef "@baseboard_fab2_lib.baseboard_fab2(sch_1):\MG_DQ_FAR_DIMM_NG_M_L_BYTE0\" )
					)
					( Status sCSetFlattened )
					( Origin gBackEnd )
				)
				( attribute "RELATIVE_PROPAGATION_DELAY" "-50.00 MIL,50.00 MIL"
					( Parent
						( matchGroupRef "@baseboard_fab2_lib.baseboard_fab2(sch_1):\MG_DQ_FAR_DIMM_NG_M_L_BYTE0\" )
					)
					( Units "uMatchProp" "ns" 1.000000)
					( Status sCSetFlattened )
					( Origin gBackEnd )
				)
			)
			( pinPair "@baseboard_fab2_lib.baseboard_fab2(sch_1):\PP2072\"
				( pinRef "@baseboard_fab2_lib.baseboard_fab2(sch_1):page61_i172:DDR4_DQ(4)" )
				( pinRef "@baseboard_fab2_lib.baseboard_fab2(sch_1):page86_i12:DQ(4)" )
				( attribute "RELATIVE_PROPAGATION_DELAY_SCOPE" "G"
					( Parent
						( matchGroupRef "@baseboard_fab2_lib.baseboard_fab2(sch_1):\MG_DQ-DQS_NEAR_DIMM_NG_M_L_BYTE0\" )
					)
					( Status sCSetFlattened )
					( Origin gBackEnd )
				)
				( attribute "RELATIVE_PROPAGATION_DELAY" "0.00 MIL,195.00 MIL"
					( Parent
						( matchGroupRef "@baseboard_fab2_lib.baseboard_fab2(sch_1):\MG_DQ-DQS_NEAR_DIMM_NG_M_L_BYTE0\" )
					)
					( Units "uMatchProp" "ns" 1.000000)
					( Status sCSetFlattened )
					( Origin gBackEnd )
				)
				( attribute "RELATIVE_PROPAGATION_DELAY_SCOPE" "G"
					( Parent
						( matchGroupRef "@baseboard_fab2_lib.baseboard_fab2(sch_1):\MG_DQ_NEAR_DIMM_NG_M_L_BYTE0\" )
					)
					( Status sCSetFlattened )
					( Origin gBackEnd )
				)
				( attribute "RELATIVE_PROPAGATION_DELAY" "-50.00 MIL,50.00 MIL"
					( Parent
						( matchGroupRef "@baseboard_fab2_lib.baseboard_fab2(sch_1):\MG_DQ_NEAR_DIMM_NG_M_L_BYTE0\" )
					)
					( Units "uMatchProp" "ns" 1.000000)
					( Status sCSetFlattened )
					( Origin gBackEnd )
				)
			)
			( pinPair "@baseboard_fab2_lib.baseboard_fab2(sch_1):\PP2074\"
				( pinRef "@baseboard_fab2_lib.baseboard_fab2(sch_1):page61_i172:DDR4_DQ(5)" )
				( pinRef "@baseboard_fab2_lib.baseboard_fab2(sch_1):page85_i111:DQ(4)" )
				( attribute "RELATIVE_PROPAGATION_DELAY_SCOPE" "G"
					( Parent
						( matchGroupRef "@baseboard_fab2_lib.baseboard_fab2(sch_1):\MG_DQ-DQS_FAR_DIMM_NG_M_L_BYTE0\" )
					)
					( Status sCSetFlattened )
					( Origin gBackEnd )
				)
				( attribute "RELATIVE_PROPAGATION_DELAY" "0.00 MIL,195.00 MIL"
					( Parent
						( matchGroupRef "@baseboard_fab2_lib.baseboard_fab2(sch_1):\MG_DQ-DQS_FAR_DIMM_NG_M_L_BYTE0\" )
					)
					( Units "uMatchProp" "ns" 1.000000)
					( Status sCSetFlattened )
					( Origin gBackEnd )
				)
				( attribute "RELATIVE_PROPAGATION_DELAY_SCOPE" "G"
					( Parent
						( matchGroupRef "@baseboard_fab2_lib.baseboard_fab2(sch_1):\MG_DQ_FAR_DIMM_NG_M_L_BYTE0\" )
					)
					( Status sCSetFlattened )
					( Origin gBackEnd )
				)
				( attribute "RELATIVE_PROPAGATION_DELAY" "-50.00 MIL,50.00 MIL"
					( Parent
						( matchGroupRef "@baseboard_fab2_lib.baseboard_fab2(sch_1):\MG_DQ_FAR_DIMM_NG_M_L_BYTE0\" )
					)
					( Units "uMatchProp" "ns" 1.000000)
					( Status sCSetFlattened )
					( Origin gBackEnd )
				)
			)
			( pinPair "@baseboard_fab2_lib.baseboard_fab2(sch_1):\PP2075\"
				( pinRef "@baseboard_fab2_lib.baseboard_fab2(sch_1):page61_i172:DDR4_DQ(5)" )
				( pinRef "@baseboard_fab2_lib.baseboard_fab2(sch_1):page86_i12:DQ(5)" )
				( attribute "RELATIVE_PROPAGATION_DELAY_SCOPE" "G"
					( Parent
						( matchGroupRef "@baseboard_fab2_lib.baseboard_fab2(sch_1):\MG_DQ-DQS_NEAR_DIMM_NG_M_L_BYTE0\" )
					)
					( Status sCSetFlattened )
					( Origin gBackEnd )
				)
				( attribute "RELATIVE_PROPAGATION_DELAY" "0.00 MIL,195.00 MIL"
					( Parent
						( matchGroupRef "@baseboard_fab2_lib.baseboard_fab2(sch_1):\MG_DQ-DQS_NEAR_DIMM_NG_M_L_BYTE0\" )
					)
					( Units "uMatchProp" "ns" 1.000000)
					( Status sCSetFlattened )
					( Origin gBackEnd )
				)
				( attribute "RELATIVE_PROPAGATION_DELAY_SCOPE" "G"
					( Parent
						( matchGroupRef "@baseboard_fab2_lib.baseboard_fab2(sch_1):\MG_DQ_NEAR_DIMM_NG_M_L_BYTE0\" )
					)
					( Status sCSetFlattened )
					( Origin gBackEnd )
				)
				( attribute "RELATIVE_PROPAGATION_DELAY" "-50.00 MIL,50.00 MIL"
					( Parent
						( matchGroupRef "@baseboard_fab2_lib.baseboard_fab2(sch_1):\MG_DQ_NEAR_DIMM_NG_M_L_BYTE0\" )
					)
					( Units "uMatchProp" "ns" 1.000000)
					( Status sCSetFlattened )
					( Origin gBackEnd )
				)
			)
			( pinPair "@baseboard_fab2_lib.baseboard_fab2(sch_1):\PP2077\"
				( pinRef "@baseboard_fab2_lib.baseboard_fab2(sch_1):page61_i172:DDR4_DQ(6)" )
				( pinRef "@baseboard_fab2_lib.baseboard_fab2(sch_1):page85_i111:DQ(7)" )
				( attribute "RELATIVE_PROPAGATION_DELAY_SCOPE" "G"
					( Parent
						( matchGroupRef "@baseboard_fab2_lib.baseboard_fab2(sch_1):\MG_DQ-DQS_FAR_DIMM_NG_M_L_BYTE0\" )
					)
					( Status sCSetFlattened )
					( Origin gBackEnd )
				)
				( attribute "RELATIVE_PROPAGATION_DELAY" "0.00 MIL,195.00 MIL"
					( Parent
						( matchGroupRef "@baseboard_fab2_lib.baseboard_fab2(sch_1):\MG_DQ-DQS_FAR_DIMM_NG_M_L_BYTE0\" )
					)
					( Units "uMatchProp" "ns" 1.000000)
					( Status sCSetFlattened )
					( Origin gBackEnd )
				)
				( attribute "RELATIVE_PROPAGATION_DELAY_SCOPE" "G"
					( Parent
						( matchGroupRef "@baseboard_fab2_lib.baseboard_fab2(sch_1):\MG_DQ_FAR_DIMM_NG_M_L_BYTE0\" )
					)
					( Status sCSetFlattened )
					( Origin gBackEnd )
				)
				( attribute "RELATIVE_PROPAGATION_DELAY" "-50.00 MIL,50.00 MIL"
					( Parent
						( matchGroupRef "@baseboard_fab2_lib.baseboard_fab2(sch_1):\MG_DQ_FAR_DIMM_NG_M_L_BYTE0\" )
					)
					( Units "uMatchProp" "ns" 1.000000)
					( Status sCSetFlattened )
					( Origin gBackEnd )
				)
			)
			( pinPair "@baseboard_fab2_lib.baseboard_fab2(sch_1):\PP2078\"
				( pinRef "@baseboard_fab2_lib.baseboard_fab2(sch_1):page61_i172:DDR4_DQ(6)" )
				( pinRef "@baseboard_fab2_lib.baseboard_fab2(sch_1):page86_i12:DQ(6)" )
				( attribute "RELATIVE_PROPAGATION_DELAY_SCOPE" "G"
					( Parent
						( matchGroupRef "@baseboard_fab2_lib.baseboard_fab2(sch_1):\MG_DQ-DQS_NEAR_DIMM_NG_M_L_BYTE0\" )
					)
					( Status sCSetFlattened )
					( Origin gBackEnd )
				)
				( attribute "RELATIVE_PROPAGATION_DELAY" "0.00 MIL,195.00 MIL"
					( Parent
						( matchGroupRef "@baseboard_fab2_lib.baseboard_fab2(sch_1):\MG_DQ-DQS_NEAR_DIMM_NG_M_L_BYTE0\" )
					)
					( Units "uMatchProp" "ns" 1.000000)
					( Status sCSetFlattened )
					( Origin gBackEnd )
				)
				( attribute "RELATIVE_PROPAGATION_DELAY_SCOPE" "G"
					( Parent
						( matchGroupRef "@baseboard_fab2_lib.baseboard_fab2(sch_1):\MG_DQ_NEAR_DIMM_NG_M_L_BYTE0\" )
					)
					( Status sCSetFlattened )
					( Origin gBackEnd )
				)
				( attribute "RELATIVE_PROPAGATION_DELAY" "-50.00 MIL,50.00 MIL"
					( Parent
						( matchGroupRef "@baseboard_fab2_lib.baseboard_fab2(sch_1):\MG_DQ_NEAR_DIMM_NG_M_L_BYTE0\" )
					)
					( Units "uMatchProp" "ns" 1.000000)
					( Status sCSetFlattened )
					( Origin gBackEnd )
				)
			)
			( pinPair "@baseboard_fab2_lib.baseboard_fab2(sch_1):\PP2080\"
				( pinRef "@baseboard_fab2_lib.baseboard_fab2(sch_1):page61_i172:DDR4_DQ(7)" )
				( pinRef "@baseboard_fab2_lib.baseboard_fab2(sch_1):page85_i111:DQ(6)" )
				( attribute "RELATIVE_PROPAGATION_DELAY_SCOPE" "G"
					( Parent
						( matchGroupRef "@baseboard_fab2_lib.baseboard_fab2(sch_1):\MG_DQ-DQS_FAR_DIMM_NG_M_L_BYTE0\" )
					)
					( Status sCSetFlattened )
					( Origin gBackEnd )
				)
				( attribute "RELATIVE_PROPAGATION_DELAY" "0.00 MIL,195.00 MIL"
					( Parent
						( matchGroupRef "@baseboard_fab2_lib.baseboard_fab2(sch_1):\MG_DQ-DQS_FAR_DIMM_NG_M_L_BYTE0\" )
					)
					( Units "uMatchProp" "ns" 1.000000)
					( Status sCSetFlattened )
					( Origin gBackEnd )
				)
				( attribute "RELATIVE_PROPAGATION_DELAY_SCOPE" "G"
					( Parent
						( matchGroupRef "@baseboard_fab2_lib.baseboard_fab2(sch_1):\MG_DQ_FAR_DIMM_NG_M_L_BYTE0\" )
					)
					( Status sCSetFlattened )
					( Origin gBackEnd )
				)
				( attribute "RELATIVE_PROPAGATION_DELAY" "-50.00 MIL,50.00 MIL"
					( Parent
						( matchGroupRef "@baseboard_fab2_lib.baseboard_fab2(sch_1):\MG_DQ_FAR_DIMM_NG_M_L_BYTE0\" )
					)
					( Units "uMatchProp" "ns" 1.000000)
					( Status sCSetFlattened )
					( Origin gBackEnd )
				)
			)
			( pinPair "@baseboard_fab2_lib.baseboard_fab2(sch_1):\PP2081\"
				( pinRef "@baseboard_fab2_lib.baseboard_fab2(sch_1):page61_i172:DDR4_DQ(7)" )
				( pinRef "@baseboard_fab2_lib.baseboard_fab2(sch_1):page86_i12:DQ(7)" )
				( attribute "RELATIVE_PROPAGATION_DELAY_SCOPE" "G"
					( Parent
						( matchGroupRef "@baseboard_fab2_lib.baseboard_fab2(sch_1):\MG_DQ-DQS_NEAR_DIMM_NG_M_L_BYTE0\" )
					)
					( Status sCSetFlattened )
					( Origin gBackEnd )
				)
				( attribute "RELATIVE_PROPAGATION_DELAY" "0.00 MIL,195.00 MIL"
					( Parent
						( matchGroupRef "@baseboard_fab2_lib.baseboard_fab2(sch_1):\MG_DQ-DQS_NEAR_DIMM_NG_M_L_BYTE0\" )
					)
					( Units "uMatchProp" "ns" 1.000000)
					( Status sCSetFlattened )
					( Origin gBackEnd )
				)
				( attribute "RELATIVE_PROPAGATION_DELAY_SCOPE" "G"
					( Parent
						( matchGroupRef "@baseboard_fab2_lib.baseboard_fab2(sch_1):\MG_DQ_NEAR_DIMM_NG_M_L_BYTE0\" )
					)
					( Status sCSetFlattened )
					( Origin gBackEnd )
				)
				( attribute "RELATIVE_PROPAGATION_DELAY" "-50.00 MIL,50.00 MIL"
					( Parent
						( matchGroupRef "@baseboard_fab2_lib.baseboard_fab2(sch_1):\MG_DQ_NEAR_DIMM_NG_M_L_BYTE0\" )
					)
					( Units "uMatchProp" "ns" 1.000000)
					( Status sCSetFlattened )
					( Origin gBackEnd )
				)
			)
			( pinPair "@baseboard_fab2_lib.baseboard_fab2(sch_1):\PP2035\"
				( pinRef "@baseboard_fab2_lib.baseboard_fab2(sch_1):page61_i172:DDR4_DQ(8)" )
				( pinRef "@baseboard_fab2_lib.baseboard_fab2(sch_1):page85_i111:DQ(9)" )
				( attribute "RELATIVE_PROPAGATION_DELAY_SCOPE" "G"
					( Parent
						( matchGroupRef "@baseboard_fab2_lib.baseboard_fab2(sch_1):\MG_DQ-DQS_FAR_DIMM_NG_M_L_BYTE1\" )
					)
					( Status sCSetFlattened )
					( Origin gBackEnd )
				)
				( attribute "RELATIVE_PROPAGATION_DELAY" "0.00 MIL,195.00 MIL"
					( Parent
						( matchGroupRef "@baseboard_fab2_lib.baseboard_fab2(sch_1):\MG_DQ-DQS_FAR_DIMM_NG_M_L_BYTE1\" )
					)
					( Units "uMatchProp" "ns" 1.000000)
					( Status sCSetFlattened )
					( Origin gBackEnd )
				)
				( attribute "RELATIVE_PROPAGATION_DELAY_SCOPE" "G"
					( Parent
						( matchGroupRef "@baseboard_fab2_lib.baseboard_fab2(sch_1):\MG_DQ_FAR_DIMM_NG_M_L_BYTE1\" )
					)
					( Status sCSetFlattened )
					( Origin gBackEnd )
				)
				( attribute "RELATIVE_PROPAGATION_DELAY" "-50.00 MIL,50.00 MIL"
					( Parent
						( matchGroupRef "@baseboard_fab2_lib.baseboard_fab2(sch_1):\MG_DQ_FAR_DIMM_NG_M_L_BYTE1\" )
					)
					( Units "uMatchProp" "ns" 1.000000)
					( Status sCSetFlattened )
					( Origin gBackEnd )
				)
			)
			( pinPair "@baseboard_fab2_lib.baseboard_fab2(sch_1):\PP2036\"
				( pinRef "@baseboard_fab2_lib.baseboard_fab2(sch_1):page61_i172:DDR4_DQ(8)" )
				( pinRef "@baseboard_fab2_lib.baseboard_fab2(sch_1):page86_i12:DQ(8)" )
				( attribute "RELATIVE_PROPAGATION_DELAY_SCOPE" "G"
					( Parent
						( matchGroupRef "@baseboard_fab2_lib.baseboard_fab2(sch_1):\MG_DQ-DQS_NEAR_DIMM_NG_M_L_BYTE1\" )
					)
					( Status sCSetFlattened )
					( Origin gBackEnd )
				)
				( attribute "RELATIVE_PROPAGATION_DELAY" "0.00 MIL,195.00 MIL"
					( Parent
						( matchGroupRef "@baseboard_fab2_lib.baseboard_fab2(sch_1):\MG_DQ-DQS_NEAR_DIMM_NG_M_L_BYTE1\" )
					)
					( Units "uMatchProp" "ns" 1.000000)
					( Status sCSetFlattened )
					( Origin gBackEnd )
				)
				( attribute "RELATIVE_PROPAGATION_DELAY_SCOPE" "G"
					( Parent
						( matchGroupRef "@baseboard_fab2_lib.baseboard_fab2(sch_1):\MG_DQ_NEAR_DIMM_NG_M_L_BYTE1\" )
					)
					( Status sCSetFlattened )
					( Origin gBackEnd )
				)
				( attribute "RELATIVE_PROPAGATION_DELAY" "-50.00 MIL,50.00 MIL"
					( Parent
						( matchGroupRef "@baseboard_fab2_lib.baseboard_fab2(sch_1):\MG_DQ_NEAR_DIMM_NG_M_L_BYTE1\" )
					)
					( Units "uMatchProp" "ns" 1.000000)
					( Status sCSetFlattened )
					( Origin gBackEnd )
				)
			)
			( pinPair "@baseboard_fab2_lib.baseboard_fab2(sch_1):\PP2038\"
				( pinRef "@baseboard_fab2_lib.baseboard_fab2(sch_1):page61_i172:DDR4_DQ(9)" )
				( pinRef "@baseboard_fab2_lib.baseboard_fab2(sch_1):page85_i111:DQ(8)" )
				( attribute "RELATIVE_PROPAGATION_DELAY_SCOPE" "G"
					( Parent
						( matchGroupRef "@baseboard_fab2_lib.baseboard_fab2(sch_1):\MG_DQ-DQS_FAR_DIMM_NG_M_L_BYTE1\" )
					)
					( Status sCSetFlattened )
					( Origin gBackEnd )
				)
				( attribute "RELATIVE_PROPAGATION_DELAY" "0.00 MIL,195.00 MIL"
					( Parent
						( matchGroupRef "@baseboard_fab2_lib.baseboard_fab2(sch_1):\MG_DQ-DQS_FAR_DIMM_NG_M_L_BYTE1\" )
					)
					( Units "uMatchProp" "ns" 1.000000)
					( Status sCSetFlattened )
					( Origin gBackEnd )
				)
				( attribute "RELATIVE_PROPAGATION_DELAY_SCOPE" "G"
					( Parent
						( matchGroupRef "@baseboard_fab2_lib.baseboard_fab2(sch_1):\MG_DQ_FAR_DIMM_NG_M_L_BYTE1\" )
					)
					( Status sCSetFlattened )
					( Origin gBackEnd )
				)
				( attribute "RELATIVE_PROPAGATION_DELAY" "-50.00 MIL,50.00 MIL"
					( Parent
						( matchGroupRef "@baseboard_fab2_lib.baseboard_fab2(sch_1):\MG_DQ_FAR_DIMM_NG_M_L_BYTE1\" )
					)
					( Units "uMatchProp" "ns" 1.000000)
					( Status sCSetFlattened )
					( Origin gBackEnd )
				)
			)
			( pinPair "@baseboard_fab2_lib.baseboard_fab2(sch_1):\PP2039\"
				( pinRef "@baseboard_fab2_lib.baseboard_fab2(sch_1):page61_i172:DDR4_DQ(9)" )
				( pinRef "@baseboard_fab2_lib.baseboard_fab2(sch_1):page86_i12:DQ(9)" )
				( attribute "RELATIVE_PROPAGATION_DELAY_SCOPE" "G"
					( Parent
						( matchGroupRef "@baseboard_fab2_lib.baseboard_fab2(sch_1):\MG_DQ-DQS_NEAR_DIMM_NG_M_L_BYTE1\" )
					)
					( Status sCSetFlattened )
					( Origin gBackEnd )
				)
				( attribute "RELATIVE_PROPAGATION_DELAY" "0.00 MIL,195.00 MIL"
					( Parent
						( matchGroupRef "@baseboard_fab2_lib.baseboard_fab2(sch_1):\MG_DQ-DQS_NEAR_DIMM_NG_M_L_BYTE1\" )
					)
					( Units "uMatchProp" "ns" 1.000000)
					( Status sCSetFlattened )
					( Origin gBackEnd )
				)
				( attribute "RELATIVE_PROPAGATION_DELAY_SCOPE" "G"
					( Parent
						( matchGroupRef "@baseboard_fab2_lib.baseboard_fab2(sch_1):\MG_DQ_NEAR_DIMM_NG_M_L_BYTE1\" )
					)
					( Status sCSetFlattened )
					( Origin gBackEnd )
				)
				( attribute "RELATIVE_PROPAGATION_DELAY" "-50.00 MIL,50.00 MIL"
					( Parent
						( matchGroupRef "@baseboard_fab2_lib.baseboard_fab2(sch_1):\MG_DQ_NEAR_DIMM_NG_M_L_BYTE1\" )
					)
					( Units "uMatchProp" "ns" 1.000000)
					( Status sCSetFlattened )
					( Origin gBackEnd )
				)
			)
			( pinPair "@baseboard_fab2_lib.baseboard_fab2(sch_1):\PP2041\"
				( pinRef "@baseboard_fab2_lib.baseboard_fab2(sch_1):page61_i172:DDR4_DQ(10)" )
				( pinRef "@baseboard_fab2_lib.baseboard_fab2(sch_1):page85_i111:DQ(11)" )
				( attribute "RELATIVE_PROPAGATION_DELAY_SCOPE" "G"
					( Parent
						( matchGroupRef "@baseboard_fab2_lib.baseboard_fab2(sch_1):\MG_DQ-DQS_FAR_DIMM_NG_M_L_BYTE1\" )
					)
					( Status sCSetFlattened )
					( Origin gBackEnd )
				)
				( attribute "RELATIVE_PROPAGATION_DELAY" "0.00 MIL,195.00 MIL"
					( Parent
						( matchGroupRef "@baseboard_fab2_lib.baseboard_fab2(sch_1):\MG_DQ-DQS_FAR_DIMM_NG_M_L_BYTE1\" )
					)
					( Units "uMatchProp" "ns" 1.000000)
					( Status sCSetFlattened )
					( Origin gBackEnd )
				)
				( attribute "RELATIVE_PROPAGATION_DELAY_SCOPE" "G"
					( Parent
						( matchGroupRef "@baseboard_fab2_lib.baseboard_fab2(sch_1):\MG_DQ_FAR_DIMM_NG_M_L_BYTE1\" )
					)
					( Status sCSetFlattened )
					( Origin gBackEnd )
				)
				( attribute "RELATIVE_PROPAGATION_DELAY" "-50.00 MIL,50.00 MIL"
					( Parent
						( matchGroupRef "@baseboard_fab2_lib.baseboard_fab2(sch_1):\MG_DQ_FAR_DIMM_NG_M_L_BYTE1\" )
					)
					( Units "uMatchProp" "ns" 1.000000)
					( Status sCSetFlattened )
					( Origin gBackEnd )
				)
			)
			( pinPair "@baseboard_fab2_lib.baseboard_fab2(sch_1):\PP2042\"
				( pinRef "@baseboard_fab2_lib.baseboard_fab2(sch_1):page61_i172:DDR4_DQ(10)" )
				( pinRef "@baseboard_fab2_lib.baseboard_fab2(sch_1):page86_i12:DQ(10)" )
				( attribute "RELATIVE_PROPAGATION_DELAY_SCOPE" "G"
					( Parent
						( matchGroupRef "@baseboard_fab2_lib.baseboard_fab2(sch_1):\MG_DQ-DQS_NEAR_DIMM_NG_M_L_BYTE1\" )
					)
					( Status sCSetFlattened )
					( Origin gBackEnd )
				)
				( attribute "RELATIVE_PROPAGATION_DELAY" "0.00 MIL,195.00 MIL"
					( Parent
						( matchGroupRef "@baseboard_fab2_lib.baseboard_fab2(sch_1):\MG_DQ-DQS_NEAR_DIMM_NG_M_L_BYTE1\" )
					)
					( Units "uMatchProp" "ns" 1.000000)
					( Status sCSetFlattened )
					( Origin gBackEnd )
				)
				( attribute "RELATIVE_PROPAGATION_DELAY_SCOPE" "G"
					( Parent
						( matchGroupRef "@baseboard_fab2_lib.baseboard_fab2(sch_1):\MG_DQ_NEAR_DIMM_NG_M_L_BYTE1\" )
					)
					( Status sCSetFlattened )
					( Origin gBackEnd )
				)
				( attribute "RELATIVE_PROPAGATION_DELAY" "-50.00 MIL,50.00 MIL"
					( Parent
						( matchGroupRef "@baseboard_fab2_lib.baseboard_fab2(sch_1):\MG_DQ_NEAR_DIMM_NG_M_L_BYTE1\" )
					)
					( Units "uMatchProp" "ns" 1.000000)
					( Status sCSetFlattened )
					( Origin gBackEnd )
				)
			)
			( pinPair "@baseboard_fab2_lib.baseboard_fab2(sch_1):\PP2044\"
				( pinRef "@baseboard_fab2_lib.baseboard_fab2(sch_1):page61_i172:DDR4_DQ(11)" )
				( pinRef "@baseboard_fab2_lib.baseboard_fab2(sch_1):page85_i111:DQ(10)" )
				( attribute "RELATIVE_PROPAGATION_DELAY_SCOPE" "G"
					( Parent
						( matchGroupRef "@baseboard_fab2_lib.baseboard_fab2(sch_1):\MG_DQ-DQS_FAR_DIMM_NG_M_L_BYTE1\" )
					)
					( Status sCSetFlattened )
					( Origin gBackEnd )
				)
				( attribute "RELATIVE_PROPAGATION_DELAY" "0.00 MIL,195.00 MIL"
					( Parent
						( matchGroupRef "@baseboard_fab2_lib.baseboard_fab2(sch_1):\MG_DQ-DQS_FAR_DIMM_NG_M_L_BYTE1\" )
					)
					( Units "uMatchProp" "ns" 1.000000)
					( Status sCSetFlattened )
					( Origin gBackEnd )
				)
				( attribute "RELATIVE_PROPAGATION_DELAY_SCOPE" "G"
					( Parent
						( matchGroupRef "@baseboard_fab2_lib.baseboard_fab2(sch_1):\MG_DQ_FAR_DIMM_NG_M_L_BYTE1\" )
					)
					( Status sCSetFlattened )
					( Origin gBackEnd )
				)
				( attribute "RELATIVE_PROPAGATION_DELAY" "-50.00 MIL,50.00 MIL"
					( Parent
						( matchGroupRef "@baseboard_fab2_lib.baseboard_fab2(sch_1):\MG_DQ_FAR_DIMM_NG_M_L_BYTE1\" )
					)
					( Units "uMatchProp" "ns" 1.000000)
					( Status sCSetFlattened )
					( Origin gBackEnd )
				)
			)
			( pinPair "@baseboard_fab2_lib.baseboard_fab2(sch_1):\PP2045\"
				( pinRef "@baseboard_fab2_lib.baseboard_fab2(sch_1):page61_i172:DDR4_DQ(11)" )
				( pinRef "@baseboard_fab2_lib.baseboard_fab2(sch_1):page86_i12:DQ(11)" )
				( attribute "RELATIVE_PROPAGATION_DELAY_SCOPE" "G"
					( Parent
						( matchGroupRef "@baseboard_fab2_lib.baseboard_fab2(sch_1):\MG_DQ-DQS_NEAR_DIMM_NG_M_L_BYTE1\" )
					)
					( Status sCSetFlattened )
					( Origin gBackEnd )
				)
				( attribute "RELATIVE_PROPAGATION_DELAY" "0.00 MIL,195.00 MIL"
					( Parent
						( matchGroupRef "@baseboard_fab2_lib.baseboard_fab2(sch_1):\MG_DQ-DQS_NEAR_DIMM_NG_M_L_BYTE1\" )
					)
					( Units "uMatchProp" "ns" 1.000000)
					( Status sCSetFlattened )
					( Origin gBackEnd )
				)
				( attribute "RELATIVE_PROPAGATION_DELAY_SCOPE" "G"
					( Parent
						( matchGroupRef "@baseboard_fab2_lib.baseboard_fab2(sch_1):\MG_DQ_NEAR_DIMM_NG_M_L_BYTE1\" )
					)
					( Status sCSetFlattened )
					( Origin gBackEnd )
				)
				( attribute "RELATIVE_PROPAGATION_DELAY" "-50.00 MIL,50.00 MIL"
					( Parent
						( matchGroupRef "@baseboard_fab2_lib.baseboard_fab2(sch_1):\MG_DQ_NEAR_DIMM_NG_M_L_BYTE1\" )
					)
					( Units "uMatchProp" "ns" 1.000000)
					( Status sCSetFlattened )
					( Origin gBackEnd )
				)
			)
			( pinPair "@baseboard_fab2_lib.baseboard_fab2(sch_1):\PP2047\"
				( pinRef "@baseboard_fab2_lib.baseboard_fab2(sch_1):page61_i172:DDR4_DQ(12)" )
				( pinRef "@baseboard_fab2_lib.baseboard_fab2(sch_1):page85_i111:DQ(13)" )
				( attribute "RELATIVE_PROPAGATION_DELAY_SCOPE" "G"
					( Parent
						( matchGroupRef "@baseboard_fab2_lib.baseboard_fab2(sch_1):\MG_DQ-DQS_FAR_DIMM_NG_M_L_BYTE1\" )
					)
					( Status sCSetFlattened )
					( Origin gBackEnd )
				)
				( attribute "RELATIVE_PROPAGATION_DELAY" "0.00 MIL,195.00 MIL"
					( Parent
						( matchGroupRef "@baseboard_fab2_lib.baseboard_fab2(sch_1):\MG_DQ-DQS_FAR_DIMM_NG_M_L_BYTE1\" )
					)
					( Units "uMatchProp" "ns" 1.000000)
					( Status sCSetFlattened )
					( Origin gBackEnd )
				)
				( attribute "RELATIVE_PROPAGATION_DELAY_SCOPE" "G"
					( Parent
						( matchGroupRef "@baseboard_fab2_lib.baseboard_fab2(sch_1):\MG_DQ_FAR_DIMM_NG_M_L_BYTE1\" )
					)
					( Status sCSetFlattened )
					( Origin gBackEnd )
				)
				( attribute "RELATIVE_PROPAGATION_DELAY" "-50.00 MIL,50.00 MIL"
					( Parent
						( matchGroupRef "@baseboard_fab2_lib.baseboard_fab2(sch_1):\MG_DQ_FAR_DIMM_NG_M_L_BYTE1\" )
					)
					( Units "uMatchProp" "ns" 1.000000)
					( Status sCSetFlattened )
					( Origin gBackEnd )
				)
			)
			( pinPair "@baseboard_fab2_lib.baseboard_fab2(sch_1):\PP2048\"
				( pinRef "@baseboard_fab2_lib.baseboard_fab2(sch_1):page61_i172:DDR4_DQ(12)" )
				( pinRef "@baseboard_fab2_lib.baseboard_fab2(sch_1):page86_i12:DQ(12)" )
				( attribute "RELATIVE_PROPAGATION_DELAY_SCOPE" "G"
					( Parent
						( matchGroupRef "@baseboard_fab2_lib.baseboard_fab2(sch_1):\MG_DQ-DQS_NEAR_DIMM_NG_M_L_BYTE1\" )
					)
					( Status sCSetFlattened )
					( Origin gBackEnd )
				)
				( attribute "RELATIVE_PROPAGATION_DELAY" "0.00 MIL,195.00 MIL"
					( Parent
						( matchGroupRef "@baseboard_fab2_lib.baseboard_fab2(sch_1):\MG_DQ-DQS_NEAR_DIMM_NG_M_L_BYTE1\" )
					)
					( Units "uMatchProp" "ns" 1.000000)
					( Status sCSetFlattened )
					( Origin gBackEnd )
				)
				( attribute "RELATIVE_PROPAGATION_DELAY_SCOPE" "G"
					( Parent
						( matchGroupRef "@baseboard_fab2_lib.baseboard_fab2(sch_1):\MG_DQ_NEAR_DIMM_NG_M_L_BYTE1\" )
					)
					( Status sCSetFlattened )
					( Origin gBackEnd )
				)
				( attribute "RELATIVE_PROPAGATION_DELAY" "-50.00 MIL,50.00 MIL"
					( Parent
						( matchGroupRef "@baseboard_fab2_lib.baseboard_fab2(sch_1):\MG_DQ_NEAR_DIMM_NG_M_L_BYTE1\" )
					)
					( Units "uMatchProp" "ns" 1.000000)
					( Status sCSetFlattened )
					( Origin gBackEnd )
				)
			)
			( pinPair "@baseboard_fab2_lib.baseboard_fab2(sch_1):\PP2050\"
				( pinRef "@baseboard_fab2_lib.baseboard_fab2(sch_1):page61_i172:DDR4_DQ(13)" )
				( pinRef "@baseboard_fab2_lib.baseboard_fab2(sch_1):page85_i111:DQ(12)" )
				( attribute "RELATIVE_PROPAGATION_DELAY_SCOPE" "G"
					( Parent
						( matchGroupRef "@baseboard_fab2_lib.baseboard_fab2(sch_1):\MG_DQ-DQS_FAR_DIMM_NG_M_L_BYTE1\" )
					)
					( Status sCSetFlattened )
					( Origin gBackEnd )
				)
				( attribute "RELATIVE_PROPAGATION_DELAY" "0.00 MIL,195.00 MIL"
					( Parent
						( matchGroupRef "@baseboard_fab2_lib.baseboard_fab2(sch_1):\MG_DQ-DQS_FAR_DIMM_NG_M_L_BYTE1\" )
					)
					( Units "uMatchProp" "ns" 1.000000)
					( Status sCSetFlattened )
					( Origin gBackEnd )
				)
				( attribute "RELATIVE_PROPAGATION_DELAY_SCOPE" "G"
					( Parent
						( matchGroupRef "@baseboard_fab2_lib.baseboard_fab2(sch_1):\MG_DQ_FAR_DIMM_NG_M_L_BYTE1\" )
					)
					( Status sCSetFlattened )
					( Origin gBackEnd )
				)
				( attribute "RELATIVE_PROPAGATION_DELAY" "-50.00 MIL,50.00 MIL"
					( Parent
						( matchGroupRef "@baseboard_fab2_lib.baseboard_fab2(sch_1):\MG_DQ_FAR_DIMM_NG_M_L_BYTE1\" )
					)
					( Units "uMatchProp" "ns" 1.000000)
					( Status sCSetFlattened )
					( Origin gBackEnd )
				)
			)
			( pinPair "@baseboard_fab2_lib.baseboard_fab2(sch_1):\PP2051\"
				( pinRef "@baseboard_fab2_lib.baseboard_fab2(sch_1):page61_i172:DDR4_DQ(13)" )
				( pinRef "@baseboard_fab2_lib.baseboard_fab2(sch_1):page86_i12:DQ(13)" )
				( attribute "RELATIVE_PROPAGATION_DELAY_SCOPE" "G"
					( Parent
						( matchGroupRef "@baseboard_fab2_lib.baseboard_fab2(sch_1):\MG_DQ-DQS_NEAR_DIMM_NG_M_L_BYTE1\" )
					)
					( Status sCSetFlattened )
					( Origin gBackEnd )
				)
				( attribute "RELATIVE_PROPAGATION_DELAY" "0.00 MIL,195.00 MIL"
					( Parent
						( matchGroupRef "@baseboard_fab2_lib.baseboard_fab2(sch_1):\MG_DQ-DQS_NEAR_DIMM_NG_M_L_BYTE1\" )
					)
					( Units "uMatchProp" "ns" 1.000000)
					( Status sCSetFlattened )
					( Origin gBackEnd )
				)
				( attribute "RELATIVE_PROPAGATION_DELAY_SCOPE" "G"
					( Parent
						( matchGroupRef "@baseboard_fab2_lib.baseboard_fab2(sch_1):\MG_DQ_NEAR_DIMM_NG_M_L_BYTE1\" )
					)
					( Status sCSetFlattened )
					( Origin gBackEnd )
				)
				( attribute "RELATIVE_PROPAGATION_DELAY" "-50.00 MIL,50.00 MIL"
					( Parent
						( matchGroupRef "@baseboard_fab2_lib.baseboard_fab2(sch_1):\MG_DQ_NEAR_DIMM_NG_M_L_BYTE1\" )
					)
					( Units "uMatchProp" "ns" 1.000000)
					( Status sCSetFlattened )
					( Origin gBackEnd )
				)
			)
			( pinPair "@baseboard_fab2_lib.baseboard_fab2(sch_1):\PP2053\"
				( pinRef "@baseboard_fab2_lib.baseboard_fab2(sch_1):page61_i172:DDR4_DQ(14)" )
				( pinRef "@baseboard_fab2_lib.baseboard_fab2(sch_1):page85_i111:DQ(15)" )
				( attribute "RELATIVE_PROPAGATION_DELAY_SCOPE" "G"
					( Parent
						( matchGroupRef "@baseboard_fab2_lib.baseboard_fab2(sch_1):\MG_DQ-DQS_FAR_DIMM_NG_M_L_BYTE1\" )
					)
					( Status sCSetFlattened )
					( Origin gBackEnd )
				)
				( attribute "RELATIVE_PROPAGATION_DELAY" "0.00 MIL,195.00 MIL"
					( Parent
						( matchGroupRef "@baseboard_fab2_lib.baseboard_fab2(sch_1):\MG_DQ-DQS_FAR_DIMM_NG_M_L_BYTE1\" )
					)
					( Units "uMatchProp" "ns" 1.000000)
					( Status sCSetFlattened )
					( Origin gBackEnd )
				)
				( attribute "RELATIVE_PROPAGATION_DELAY_SCOPE" "G"
					( Parent
						( matchGroupRef "@baseboard_fab2_lib.baseboard_fab2(sch_1):\MG_DQ_FAR_DIMM_NG_M_L_BYTE1\" )
					)
					( Status sCSetFlattened )
					( Origin gBackEnd )
				)
				( attribute "RELATIVE_PROPAGATION_DELAY" "-50.00 MIL,50.00 MIL"
					( Parent
						( matchGroupRef "@baseboard_fab2_lib.baseboard_fab2(sch_1):\MG_DQ_FAR_DIMM_NG_M_L_BYTE1\" )
					)
					( Units "uMatchProp" "ns" 1.000000)
					( Status sCSetFlattened )
					( Origin gBackEnd )
				)
			)
			( pinPair "@baseboard_fab2_lib.baseboard_fab2(sch_1):\PP2054\"
				( pinRef "@baseboard_fab2_lib.baseboard_fab2(sch_1):page61_i172:DDR4_DQ(14)" )
				( pinRef "@baseboard_fab2_lib.baseboard_fab2(sch_1):page86_i12:DQ(14)" )
				( attribute "RELATIVE_PROPAGATION_DELAY_SCOPE" "G"
					( Parent
						( matchGroupRef "@baseboard_fab2_lib.baseboard_fab2(sch_1):\MG_DQ-DQS_NEAR_DIMM_NG_M_L_BYTE1\" )
					)
					( Status sCSetFlattened )
					( Origin gBackEnd )
				)
				( attribute "RELATIVE_PROPAGATION_DELAY" "0.00 MIL,195.00 MIL"
					( Parent
						( matchGroupRef "@baseboard_fab2_lib.baseboard_fab2(sch_1):\MG_DQ-DQS_NEAR_DIMM_NG_M_L_BYTE1\" )
					)
					( Units "uMatchProp" "ns" 1.000000)
					( Status sCSetFlattened )
					( Origin gBackEnd )
				)
				( attribute "RELATIVE_PROPAGATION_DELAY_SCOPE" "G"
					( Parent
						( matchGroupRef "@baseboard_fab2_lib.baseboard_fab2(sch_1):\MG_DQ_NEAR_DIMM_NG_M_L_BYTE1\" )
					)
					( Status sCSetFlattened )
					( Origin gBackEnd )
				)
				( attribute "RELATIVE_PROPAGATION_DELAY" "-50.00 MIL,50.00 MIL"
					( Parent
						( matchGroupRef "@baseboard_fab2_lib.baseboard_fab2(sch_1):\MG_DQ_NEAR_DIMM_NG_M_L_BYTE1\" )
					)
					( Units "uMatchProp" "ns" 1.000000)
					( Status sCSetFlattened )
					( Origin gBackEnd )
				)
			)
			( pinPair "@baseboard_fab2_lib.baseboard_fab2(sch_1):\PP2056\"
				( pinRef "@baseboard_fab2_lib.baseboard_fab2(sch_1):page61_i172:DDR4_DQ(15)" )
				( pinRef "@baseboard_fab2_lib.baseboard_fab2(sch_1):page85_i111:DQ(14)" )
				( attribute "RELATIVE_PROPAGATION_DELAY_SCOPE" "G"
					( Parent
						( matchGroupRef "@baseboard_fab2_lib.baseboard_fab2(sch_1):\MG_DQ-DQS_FAR_DIMM_NG_M_L_BYTE1\" )
					)
					( Status sCSetFlattened )
					( Origin gBackEnd )
				)
				( attribute "RELATIVE_PROPAGATION_DELAY" "0.00 MIL,195.00 MIL"
					( Parent
						( matchGroupRef "@baseboard_fab2_lib.baseboard_fab2(sch_1):\MG_DQ-DQS_FAR_DIMM_NG_M_L_BYTE1\" )
					)
					( Units "uMatchProp" "ns" 1.000000)
					( Status sCSetFlattened )
					( Origin gBackEnd )
				)
				( attribute "RELATIVE_PROPAGATION_DELAY_SCOPE" "G"
					( Parent
						( matchGroupRef "@baseboard_fab2_lib.baseboard_fab2(sch_1):\MG_DQ_FAR_DIMM_NG_M_L_BYTE1\" )
					)
					( Status sCSetFlattened )
					( Origin gBackEnd )
				)
				( attribute "RELATIVE_PROPAGATION_DELAY" "-50.00 MIL,50.00 MIL"
					( Parent
						( matchGroupRef "@baseboard_fab2_lib.baseboard_fab2(sch_1):\MG_DQ_FAR_DIMM_NG_M_L_BYTE1\" )
					)
					( Units "uMatchProp" "ns" 1.000000)
					( Status sCSetFlattened )
					( Origin gBackEnd )
				)
			)
			( pinPair "@baseboard_fab2_lib.baseboard_fab2(sch_1):\PP2057\"
				( pinRef "@baseboard_fab2_lib.baseboard_fab2(sch_1):page61_i172:DDR4_DQ(15)" )
				( pinRef "@baseboard_fab2_lib.baseboard_fab2(sch_1):page86_i12:DQ(15)" )
				( attribute "RELATIVE_PROPAGATION_DELAY_SCOPE" "G"
					( Parent
						( matchGroupRef "@baseboard_fab2_lib.baseboard_fab2(sch_1):\MG_DQ-DQS_NEAR_DIMM_NG_M_L_BYTE1\" )
					)
					( Status sCSetFlattened )
					( Origin gBackEnd )
				)
				( attribute "RELATIVE_PROPAGATION_DELAY" "0.00 MIL,195.00 MIL"
					( Parent
						( matchGroupRef "@baseboard_fab2_lib.baseboard_fab2(sch_1):\MG_DQ-DQS_NEAR_DIMM_NG_M_L_BYTE1\" )
					)
					( Units "uMatchProp" "ns" 1.000000)
					( Status sCSetFlattened )
					( Origin gBackEnd )
				)
				( attribute "RELATIVE_PROPAGATION_DELAY_SCOPE" "G"
					( Parent
						( matchGroupRef "@baseboard_fab2_lib.baseboard_fab2(sch_1):\MG_DQ_NEAR_DIMM_NG_M_L_BYTE1\" )
					)
					( Status sCSetFlattened )
					( Origin gBackEnd )
				)
				( attribute "RELATIVE_PROPAGATION_DELAY" "-50.00 MIL,50.00 MIL"
					( Parent
						( matchGroupRef "@baseboard_fab2_lib.baseboard_fab2(sch_1):\MG_DQ_NEAR_DIMM_NG_M_L_BYTE1\" )
					)
					( Units "uMatchProp" "ns" 1.000000)
					( Status sCSetFlattened )
					( Origin gBackEnd )
				)
			)
			( pinPair "@baseboard_fab2_lib.baseboard_fab2(sch_1):\PP2011\"
				( pinRef "@baseboard_fab2_lib.baseboard_fab2(sch_1):page61_i172:DDR4_DQ(16)" )
				( pinRef "@baseboard_fab2_lib.baseboard_fab2(sch_1):page85_i111:DQ(17)" )
				( attribute "RELATIVE_PROPAGATION_DELAY_SCOPE" "G"
					( Parent
						( matchGroupRef "@baseboard_fab2_lib.baseboard_fab2(sch_1):\MG_DQ-DQS_FAR_DIMM_NG_M_L_BYTE2\" )
					)
					( Status sCSetFlattened )
					( Origin gBackEnd )
				)
				( attribute "RELATIVE_PROPAGATION_DELAY" "0.00 MIL,195.00 MIL"
					( Parent
						( matchGroupRef "@baseboard_fab2_lib.baseboard_fab2(sch_1):\MG_DQ-DQS_FAR_DIMM_NG_M_L_BYTE2\" )
					)
					( Units "uMatchProp" "ns" 1.000000)
					( Status sCSetFlattened )
					( Origin gBackEnd )
				)
				( attribute "RELATIVE_PROPAGATION_DELAY_SCOPE" "G"
					( Parent
						( matchGroupRef "@crescent_city_bb_fab1_lib.crescent_city_bb_fab1(sch_1):\MG_DQ_FAR_DIMM_NG_M_L_BYTE2\" )
					)
					( Status sCSetFlattened )
					( Origin gBackEnd )
				)
				( attribute "RELATIVE_PROPAGATION_DELAY" "-50.00 MIL,50.00 MIL"
					( Parent
						( matchGroupRef "@crescent_city_bb_fab1_lib.crescent_city_bb_fab1(sch_1):\MG_DQ_FAR_DIMM_NG_M_L_BYTE2\" )
					)
					( Units "uMatchProp" "ns" 1.000000)
					( Status sCSetFlattened )
					( Origin gBackEnd )
				)
			)
			( pinPair "@baseboard_fab2_lib.baseboard_fab2(sch_1):\PP2012\"
				( pinRef "@baseboard_fab2_lib.baseboard_fab2(sch_1):page61_i172:DDR4_DQ(16)" )
				( pinRef "@baseboard_fab2_lib.baseboard_fab2(sch_1):page86_i12:DQ(16)" )
				( attribute "RELATIVE_PROPAGATION_DELAY_SCOPE" "G"
					( Parent
						( matchGroupRef "@baseboard_fab2_lib.baseboard_fab2(sch_1):\MG_DQ-DQS_NEAR_DIMM_NG_M_L_BYTE2\" )
					)
					( Status sCSetFlattened )
					( Origin gBackEnd )
				)
				( attribute "RELATIVE_PROPAGATION_DELAY" "0.00 MIL,195.00 MIL"
					( Parent
						( matchGroupRef "@baseboard_fab2_lib.baseboard_fab2(sch_1):\MG_DQ-DQS_NEAR_DIMM_NG_M_L_BYTE2\" )
					)
					( Units "uMatchProp" "ns" 1.000000)
					( Status sCSetFlattened )
					( Origin gBackEnd )
				)
				( attribute "RELATIVE_PROPAGATION_DELAY_SCOPE" "G"
					( Parent
						( matchGroupRef "@crescent_city_bb_fab1_lib.crescent_city_bb_fab1(sch_1):\MG_DQ_NEAR_DIMM_NG_M_L_BYTE2\" )
					)
					( Status sCSetFlattened )
					( Origin gBackEnd )
				)
				( attribute "RELATIVE_PROPAGATION_DELAY" "-50.00 MIL,50.00 MIL"
					( Parent
						( matchGroupRef "@crescent_city_bb_fab1_lib.crescent_city_bb_fab1(sch_1):\MG_DQ_NEAR_DIMM_NG_M_L_BYTE2\" )
					)
					( Units "uMatchProp" "ns" 1.000000)
					( Status sCSetFlattened )
					( Origin gBackEnd )
				)
			)
			( pinPair "@baseboard_fab2_lib.baseboard_fab2(sch_1):\PP2014\"
				( pinRef "@baseboard_fab2_lib.baseboard_fab2(sch_1):page61_i172:DDR4_DQ(17)" )
				( pinRef "@baseboard_fab2_lib.baseboard_fab2(sch_1):page85_i111:DQ(16)" )
				( attribute "RELATIVE_PROPAGATION_DELAY_SCOPE" "G"
					( Parent
						( matchGroupRef "@baseboard_fab2_lib.baseboard_fab2(sch_1):\MG_DQ-DQS_FAR_DIMM_NG_M_L_BYTE2\" )
					)
					( Status sCSetFlattened )
					( Origin gBackEnd )
				)
				( attribute "RELATIVE_PROPAGATION_DELAY" "0.00 MIL,195.00 MIL"
					( Parent
						( matchGroupRef "@baseboard_fab2_lib.baseboard_fab2(sch_1):\MG_DQ-DQS_FAR_DIMM_NG_M_L_BYTE2\" )
					)
					( Units "uMatchProp" "ns" 1.000000)
					( Status sCSetFlattened )
					( Origin gBackEnd )
				)
				( attribute "RELATIVE_PROPAGATION_DELAY_SCOPE" "G"
					( Parent
						( matchGroupRef "@crescent_city_bb_fab1_lib.crescent_city_bb_fab1(sch_1):\MG_DQ_FAR_DIMM_NG_M_L_BYTE2\" )
					)
					( Status sCSetFlattened )
					( Origin gBackEnd )
				)
				( attribute "RELATIVE_PROPAGATION_DELAY" "-50.00 MIL,50.00 MIL"
					( Parent
						( matchGroupRef "@crescent_city_bb_fab1_lib.crescent_city_bb_fab1(sch_1):\MG_DQ_FAR_DIMM_NG_M_L_BYTE2\" )
					)
					( Units "uMatchProp" "ns" 1.000000)
					( Status sCSetFlattened )
					( Origin gBackEnd )
				)
			)
			( pinPair "@baseboard_fab2_lib.baseboard_fab2(sch_1):\PP2015\"
				( pinRef "@baseboard_fab2_lib.baseboard_fab2(sch_1):page61_i172:DDR4_DQ(17)" )
				( pinRef "@baseboard_fab2_lib.baseboard_fab2(sch_1):page86_i12:DQ(17)" )
				( attribute "RELATIVE_PROPAGATION_DELAY_SCOPE" "G"
					( Parent
						( matchGroupRef "@baseboard_fab2_lib.baseboard_fab2(sch_1):\MG_DQ-DQS_NEAR_DIMM_NG_M_L_BYTE2\" )
					)
					( Status sCSetFlattened )
					( Origin gBackEnd )
				)
				( attribute "RELATIVE_PROPAGATION_DELAY" "0.00 MIL,195.00 MIL"
					( Parent
						( matchGroupRef "@baseboard_fab2_lib.baseboard_fab2(sch_1):\MG_DQ-DQS_NEAR_DIMM_NG_M_L_BYTE2\" )
					)
					( Units "uMatchProp" "ns" 1.000000)
					( Status sCSetFlattened )
					( Origin gBackEnd )
				)
				( attribute "RELATIVE_PROPAGATION_DELAY_SCOPE" "G"
					( Parent
						( matchGroupRef "@crescent_city_bb_fab1_lib.crescent_city_bb_fab1(sch_1):\MG_DQ_NEAR_DIMM_NG_M_L_BYTE2\" )
					)
					( Status sCSetFlattened )
					( Origin gBackEnd )
				)
				( attribute "RELATIVE_PROPAGATION_DELAY" "-50.00 MIL,50.00 MIL"
					( Parent
						( matchGroupRef "@crescent_city_bb_fab1_lib.crescent_city_bb_fab1(sch_1):\MG_DQ_NEAR_DIMM_NG_M_L_BYTE2\" )
					)
					( Units "uMatchProp" "ns" 1.000000)
					( Status sCSetFlattened )
					( Origin gBackEnd )
				)
			)
			( pinPair "@baseboard_fab2_lib.baseboard_fab2(sch_1):\PP2017\"
				( pinRef "@baseboard_fab2_lib.baseboard_fab2(sch_1):page61_i172:DDR4_DQ(18)" )
				( pinRef "@baseboard_fab2_lib.baseboard_fab2(sch_1):page85_i111:DQ(19)" )
				( attribute "RELATIVE_PROPAGATION_DELAY_SCOPE" "G"
					( Parent
						( matchGroupRef "@baseboard_fab2_lib.baseboard_fab2(sch_1):\MG_DQ-DQS_FAR_DIMM_NG_M_L_BYTE2\" )
					)
					( Status sCSetFlattened )
					( Origin gBackEnd )
				)
				( attribute "RELATIVE_PROPAGATION_DELAY" "0.00 MIL,195.00 MIL"
					( Parent
						( matchGroupRef "@baseboard_fab2_lib.baseboard_fab2(sch_1):\MG_DQ-DQS_FAR_DIMM_NG_M_L_BYTE2\" )
					)
					( Units "uMatchProp" "ns" 1.000000)
					( Status sCSetFlattened )
					( Origin gBackEnd )
				)
				( attribute "RELATIVE_PROPAGATION_DELAY_SCOPE" "G"
					( Parent
						( matchGroupRef "@crescent_city_bb_fab1_lib.crescent_city_bb_fab1(sch_1):\MG_DQ_FAR_DIMM_NG_M_L_BYTE2\" )
					)
					( Status sCSetFlattened )
					( Origin gBackEnd )
				)
				( attribute "RELATIVE_PROPAGATION_DELAY" "-50.00 MIL,50.00 MIL"
					( Parent
						( matchGroupRef "@crescent_city_bb_fab1_lib.crescent_city_bb_fab1(sch_1):\MG_DQ_FAR_DIMM_NG_M_L_BYTE2\" )
					)
					( Units "uMatchProp" "ns" 1.000000)
					( Status sCSetFlattened )
					( Origin gBackEnd )
				)
			)
			( pinPair "@baseboard_fab2_lib.baseboard_fab2(sch_1):\PP2018\"
				( pinRef "@baseboard_fab2_lib.baseboard_fab2(sch_1):page61_i172:DDR4_DQ(18)" )
				( pinRef "@baseboard_fab2_lib.baseboard_fab2(sch_1):page86_i12:DQ(18)" )
				( attribute "RELATIVE_PROPAGATION_DELAY_SCOPE" "G"
					( Parent
						( matchGroupRef "@baseboard_fab2_lib.baseboard_fab2(sch_1):\MG_DQ-DQS_NEAR_DIMM_NG_M_L_BYTE2\" )
					)
					( Status sCSetFlattened )
					( Origin gBackEnd )
				)
				( attribute "RELATIVE_PROPAGATION_DELAY" "0.00 MIL,195.00 MIL"
					( Parent
						( matchGroupRef "@baseboard_fab2_lib.baseboard_fab2(sch_1):\MG_DQ-DQS_NEAR_DIMM_NG_M_L_BYTE2\" )
					)
					( Units "uMatchProp" "ns" 1.000000)
					( Status sCSetFlattened )
					( Origin gBackEnd )
				)
				( attribute "RELATIVE_PROPAGATION_DELAY_SCOPE" "G"
					( Parent
						( matchGroupRef "@crescent_city_bb_fab1_lib.crescent_city_bb_fab1(sch_1):\MG_DQ_NEAR_DIMM_NG_M_L_BYTE2\" )
					)
					( Status sCSetFlattened )
					( Origin gBackEnd )
				)
				( attribute "RELATIVE_PROPAGATION_DELAY" "-50.00 MIL,50.00 MIL"
					( Parent
						( matchGroupRef "@crescent_city_bb_fab1_lib.crescent_city_bb_fab1(sch_1):\MG_DQ_NEAR_DIMM_NG_M_L_BYTE2\" )
					)
					( Units "uMatchProp" "ns" 1.000000)
					( Status sCSetFlattened )
					( Origin gBackEnd )
				)
			)
			( pinPair "@baseboard_fab2_lib.baseboard_fab2(sch_1):\PP2020\"
				( pinRef "@baseboard_fab2_lib.baseboard_fab2(sch_1):page61_i172:DDR4_DQ(19)" )
				( pinRef "@baseboard_fab2_lib.baseboard_fab2(sch_1):page85_i111:DQ(18)" )
				( attribute "RELATIVE_PROPAGATION_DELAY_SCOPE" "G"
					( Parent
						( matchGroupRef "@baseboard_fab2_lib.baseboard_fab2(sch_1):\MG_DQ-DQS_FAR_DIMM_NG_M_L_BYTE2\" )
					)
					( Status sCSetFlattened )
					( Origin gBackEnd )
				)
				( attribute "RELATIVE_PROPAGATION_DELAY" "0.00 MIL,195.00 MIL"
					( Parent
						( matchGroupRef "@baseboard_fab2_lib.baseboard_fab2(sch_1):\MG_DQ-DQS_FAR_DIMM_NG_M_L_BYTE2\" )
					)
					( Units "uMatchProp" "ns" 1.000000)
					( Status sCSetFlattened )
					( Origin gBackEnd )
				)
				( attribute "RELATIVE_PROPAGATION_DELAY_SCOPE" "G"
					( Parent
						( matchGroupRef "@crescent_city_bb_fab1_lib.crescent_city_bb_fab1(sch_1):\MG_DQ_FAR_DIMM_NG_M_L_BYTE2\" )
					)
					( Status sCSetFlattened )
					( Origin gBackEnd )
				)
				( attribute "RELATIVE_PROPAGATION_DELAY" "-50.00 MIL,50.00 MIL"
					( Parent
						( matchGroupRef "@crescent_city_bb_fab1_lib.crescent_city_bb_fab1(sch_1):\MG_DQ_FAR_DIMM_NG_M_L_BYTE2\" )
					)
					( Units "uMatchProp" "ns" 1.000000)
					( Status sCSetFlattened )
					( Origin gBackEnd )
				)
			)
			( pinPair "@baseboard_fab2_lib.baseboard_fab2(sch_1):\PP2021\"
				( pinRef "@baseboard_fab2_lib.baseboard_fab2(sch_1):page61_i172:DDR4_DQ(19)" )
				( pinRef "@baseboard_fab2_lib.baseboard_fab2(sch_1):page86_i12:DQ(19)" )
				( attribute "RELATIVE_PROPAGATION_DELAY_SCOPE" "G"
					( Parent
						( matchGroupRef "@baseboard_fab2_lib.baseboard_fab2(sch_1):\MG_DQ-DQS_NEAR_DIMM_NG_M_L_BYTE2\" )
					)
					( Status sCSetFlattened )
					( Origin gBackEnd )
				)
				( attribute "RELATIVE_PROPAGATION_DELAY" "0.00 MIL,195.00 MIL"
					( Parent
						( matchGroupRef "@baseboard_fab2_lib.baseboard_fab2(sch_1):\MG_DQ-DQS_NEAR_DIMM_NG_M_L_BYTE2\" )
					)
					( Units "uMatchProp" "ns" 1.000000)
					( Status sCSetFlattened )
					( Origin gBackEnd )
				)
				( attribute "RELATIVE_PROPAGATION_DELAY_SCOPE" "G"
					( Parent
						( matchGroupRef "@crescent_city_bb_fab1_lib.crescent_city_bb_fab1(sch_1):\MG_DQ_NEAR_DIMM_NG_M_L_BYTE2\" )
					)
					( Origin gBackEnd )
				)
				( attribute "RELATIVE_PROPAGATION_DELAY" "TARGET,TARGET"
					( Parent
						( matchGroupRef "@crescent_city_bb_fab1_lib.crescent_city_bb_fab1(sch_1):\MG_DQ_NEAR_DIMM_NG_M_L_BYTE2\" )
					)
					( Units "uMatchProp" "ns" 1.000000)
					( Origin gBackEnd )
				)
			)
			( pinPair "@baseboard_fab2_lib.baseboard_fab2(sch_1):\PP2023\"
				( pinRef "@baseboard_fab2_lib.baseboard_fab2(sch_1):page61_i172:DDR4_DQ(20)" )
				( pinRef "@baseboard_fab2_lib.baseboard_fab2(sch_1):page85_i111:DQ(21)" )
				( attribute "RELATIVE_PROPAGATION_DELAY_SCOPE" "G"
					( Parent
						( matchGroupRef "@baseboard_fab2_lib.baseboard_fab2(sch_1):\MG_DQ-DQS_FAR_DIMM_NG_M_L_BYTE2\" )
					)
					( Status sCSetFlattened )
					( Origin gBackEnd )
				)
				( attribute "RELATIVE_PROPAGATION_DELAY" "0.00 MIL,195.00 MIL"
					( Parent
						( matchGroupRef "@baseboard_fab2_lib.baseboard_fab2(sch_1):\MG_DQ-DQS_FAR_DIMM_NG_M_L_BYTE2\" )
					)
					( Units "uMatchProp" "ns" 1.000000)
					( Status sCSetFlattened )
					( Origin gBackEnd )
				)
				( attribute "RELATIVE_PROPAGATION_DELAY_SCOPE" "G"
					( Parent
						( matchGroupRef "@crescent_city_bb_fab1_lib.crescent_city_bb_fab1(sch_1):\MG_DQ_FAR_DIMM_NG_M_L_BYTE2\" )
					)
					( Status sCSetFlattened )
					( Origin gBackEnd )
				)
				( attribute "RELATIVE_PROPAGATION_DELAY" "-50.00 MIL,50.00 MIL"
					( Parent
						( matchGroupRef "@crescent_city_bb_fab1_lib.crescent_city_bb_fab1(sch_1):\MG_DQ_FAR_DIMM_NG_M_L_BYTE2\" )
					)
					( Units "uMatchProp" "ns" 1.000000)
					( Status sCSetFlattened )
					( Origin gBackEnd )
				)
			)
			( pinPair "@baseboard_fab2_lib.baseboard_fab2(sch_1):\PP2024\"
				( pinRef "@baseboard_fab2_lib.baseboard_fab2(sch_1):page61_i172:DDR4_DQ(20)" )
				( pinRef "@baseboard_fab2_lib.baseboard_fab2(sch_1):page86_i12:DQ(20)" )
				( attribute "RELATIVE_PROPAGATION_DELAY_SCOPE" "G"
					( Parent
						( matchGroupRef "@baseboard_fab2_lib.baseboard_fab2(sch_1):\MG_DQ-DQS_NEAR_DIMM_NG_M_L_BYTE2\" )
					)
					( Status sCSetFlattened )
					( Origin gBackEnd )
				)
				( attribute "RELATIVE_PROPAGATION_DELAY" "0.00 MIL,195.00 MIL"
					( Parent
						( matchGroupRef "@baseboard_fab2_lib.baseboard_fab2(sch_1):\MG_DQ-DQS_NEAR_DIMM_NG_M_L_BYTE2\" )
					)
					( Units "uMatchProp" "ns" 1.000000)
					( Status sCSetFlattened )
					( Origin gBackEnd )
				)
				( attribute "RELATIVE_PROPAGATION_DELAY_SCOPE" "G"
					( Parent
						( matchGroupRef "@crescent_city_bb_fab1_lib.crescent_city_bb_fab1(sch_1):\MG_DQ_NEAR_DIMM_NG_M_L_BYTE2\" )
					)
					( Status sCSetFlattened )
					( Origin gBackEnd )
				)
				( attribute "RELATIVE_PROPAGATION_DELAY" "-50.00 MIL,50.00 MIL"
					( Parent
						( matchGroupRef "@crescent_city_bb_fab1_lib.crescent_city_bb_fab1(sch_1):\MG_DQ_NEAR_DIMM_NG_M_L_BYTE2\" )
					)
					( Units "uMatchProp" "ns" 1.000000)
					( Status sCSetFlattened )
					( Origin gBackEnd )
				)
			)
			( pinPair "@baseboard_fab2_lib.baseboard_fab2(sch_1):\PP2026\"
				( pinRef "@baseboard_fab2_lib.baseboard_fab2(sch_1):page61_i172:DDR4_DQ(21)" )
				( pinRef "@baseboard_fab2_lib.baseboard_fab2(sch_1):page85_i111:DQ(20)" )
				( attribute "RELATIVE_PROPAGATION_DELAY_SCOPE" "G"
					( Parent
						( matchGroupRef "@baseboard_fab2_lib.baseboard_fab2(sch_1):\MG_DQ-DQS_FAR_DIMM_NG_M_L_BYTE2\" )
					)
					( Status sCSetFlattened )
					( Origin gBackEnd )
				)
				( attribute "RELATIVE_PROPAGATION_DELAY" "0.00 MIL,195.00 MIL"
					( Parent
						( matchGroupRef "@baseboard_fab2_lib.baseboard_fab2(sch_1):\MG_DQ-DQS_FAR_DIMM_NG_M_L_BYTE2\" )
					)
					( Units "uMatchProp" "ns" 1.000000)
					( Status sCSetFlattened )
					( Origin gBackEnd )
				)
				( attribute "RELATIVE_PROPAGATION_DELAY_SCOPE" "G"
					( Parent
						( matchGroupRef "@crescent_city_bb_fab1_lib.crescent_city_bb_fab1(sch_1):\MG_DQ_FAR_DIMM_NG_M_L_BYTE2\" )
					)
					( Status sCSetFlattened )
					( Origin gBackEnd )
				)
				( attribute "RELATIVE_PROPAGATION_DELAY" "-50.00 MIL,50.00 MIL"
					( Parent
						( matchGroupRef "@crescent_city_bb_fab1_lib.crescent_city_bb_fab1(sch_1):\MG_DQ_FAR_DIMM_NG_M_L_BYTE2\" )
					)
					( Units "uMatchProp" "ns" 1.000000)
					( Status sCSetFlattened )
					( Origin gBackEnd )
				)
			)
			( pinPair "@baseboard_fab2_lib.baseboard_fab2(sch_1):\PP2027\"
				( pinRef "@baseboard_fab2_lib.baseboard_fab2(sch_1):page61_i172:DDR4_DQ(21)" )
				( pinRef "@baseboard_fab2_lib.baseboard_fab2(sch_1):page86_i12:DQ(21)" )
				( attribute "RELATIVE_PROPAGATION_DELAY_SCOPE" "G"
					( Parent
						( matchGroupRef "@baseboard_fab2_lib.baseboard_fab2(sch_1):\MG_DQ-DQS_NEAR_DIMM_NG_M_L_BYTE2\" )
					)
					( Status sCSetFlattened )
					( Origin gBackEnd )
				)
				( attribute "RELATIVE_PROPAGATION_DELAY" "0.00 MIL,195.00 MIL"
					( Parent
						( matchGroupRef "@baseboard_fab2_lib.baseboard_fab2(sch_1):\MG_DQ-DQS_NEAR_DIMM_NG_M_L_BYTE2\" )
					)
					( Units "uMatchProp" "ns" 1.000000)
					( Status sCSetFlattened )
					( Origin gBackEnd )
				)
				( attribute "RELATIVE_PROPAGATION_DELAY_SCOPE" "G"
					( Parent
						( matchGroupRef "@crescent_city_bb_fab1_lib.crescent_city_bb_fab1(sch_1):\MG_DQ_NEAR_DIMM_NG_M_L_BYTE2\" )
					)
					( Status sCSetFlattened )
					( Origin gBackEnd )
				)
				( attribute "RELATIVE_PROPAGATION_DELAY" "-50.00 MIL,50.00 MIL"
					( Parent
						( matchGroupRef "@crescent_city_bb_fab1_lib.crescent_city_bb_fab1(sch_1):\MG_DQ_NEAR_DIMM_NG_M_L_BYTE2\" )
					)
					( Units "uMatchProp" "ns" 1.000000)
					( Status sCSetFlattened )
					( Origin gBackEnd )
				)
			)
			( pinPair "@baseboard_fab2_lib.baseboard_fab2(sch_1):\PP2029\"
				( pinRef "@baseboard_fab2_lib.baseboard_fab2(sch_1):page61_i172:DDR4_DQ(22)" )
				( pinRef "@baseboard_fab2_lib.baseboard_fab2(sch_1):page85_i111:DQ(23)" )
				( attribute "RELATIVE_PROPAGATION_DELAY_SCOPE" "G"
					( Parent
						( matchGroupRef "@baseboard_fab2_lib.baseboard_fab2(sch_1):\MG_DQ-DQS_FAR_DIMM_NG_M_L_BYTE2\" )
					)
					( Status sCSetFlattened )
					( Origin gBackEnd )
				)
				( attribute "RELATIVE_PROPAGATION_DELAY" "0.00 MIL,195.00 MIL"
					( Parent
						( matchGroupRef "@baseboard_fab2_lib.baseboard_fab2(sch_1):\MG_DQ-DQS_FAR_DIMM_NG_M_L_BYTE2\" )
					)
					( Units "uMatchProp" "ns" 1.000000)
					( Status sCSetFlattened )
					( Origin gBackEnd )
				)
				( attribute "RELATIVE_PROPAGATION_DELAY_SCOPE" "G"
					( Parent
						( matchGroupRef "@crescent_city_bb_fab1_lib.crescent_city_bb_fab1(sch_1):\MG_DQ_FAR_DIMM_NG_M_L_BYTE2\" )
					)
					( Origin gBackEnd )
				)
				( attribute "RELATIVE_PROPAGATION_DELAY" "TARGET,TARGET"
					( Parent
						( matchGroupRef "@crescent_city_bb_fab1_lib.crescent_city_bb_fab1(sch_1):\MG_DQ_FAR_DIMM_NG_M_L_BYTE2\" )
					)
					( Units "uMatchProp" "ns" 1.000000)
					( Origin gBackEnd )
				)
			)
			( pinPair "@baseboard_fab2_lib.baseboard_fab2(sch_1):\PP2030\"
				( pinRef "@baseboard_fab2_lib.baseboard_fab2(sch_1):page61_i172:DDR4_DQ(22)" )
				( pinRef "@baseboard_fab2_lib.baseboard_fab2(sch_1):page86_i12:DQ(22)" )
				( attribute "RELATIVE_PROPAGATION_DELAY_SCOPE" "G"
					( Parent
						( matchGroupRef "@baseboard_fab2_lib.baseboard_fab2(sch_1):\MG_DQ-DQS_NEAR_DIMM_NG_M_L_BYTE2\" )
					)
					( Status sCSetFlattened )
					( Origin gBackEnd )
				)
				( attribute "RELATIVE_PROPAGATION_DELAY" "0.00 MIL,195.00 MIL"
					( Parent
						( matchGroupRef "@baseboard_fab2_lib.baseboard_fab2(sch_1):\MG_DQ-DQS_NEAR_DIMM_NG_M_L_BYTE2\" )
					)
					( Units "uMatchProp" "ns" 1.000000)
					( Status sCSetFlattened )
					( Origin gBackEnd )
				)
				( attribute "RELATIVE_PROPAGATION_DELAY_SCOPE" "G"
					( Parent
						( matchGroupRef "@crescent_city_bb_fab1_lib.crescent_city_bb_fab1(sch_1):\MG_DQ_NEAR_DIMM_NG_M_L_BYTE2\" )
					)
					( Status sCSetFlattened )
					( Origin gBackEnd )
				)
				( attribute "RELATIVE_PROPAGATION_DELAY" "-50.00 MIL,50.00 MIL"
					( Parent
						( matchGroupRef "@crescent_city_bb_fab1_lib.crescent_city_bb_fab1(sch_1):\MG_DQ_NEAR_DIMM_NG_M_L_BYTE2\" )
					)
					( Units "uMatchProp" "ns" 1.000000)
					( Status sCSetFlattened )
					( Origin gBackEnd )
				)
			)
			( pinPair "@baseboard_fab2_lib.baseboard_fab2(sch_1):\PP2032\"
				( pinRef "@baseboard_fab2_lib.baseboard_fab2(sch_1):page61_i172:DDR4_DQ(23)" )
				( pinRef "@baseboard_fab2_lib.baseboard_fab2(sch_1):page85_i111:DQ(22)" )
				( attribute "RELATIVE_PROPAGATION_DELAY_SCOPE" "G"
					( Parent
						( matchGroupRef "@baseboard_fab2_lib.baseboard_fab2(sch_1):\MG_DQ-DQS_FAR_DIMM_NG_M_L_BYTE2\" )
					)
					( Status sCSetFlattened )
					( Origin gBackEnd )
				)
				( attribute "RELATIVE_PROPAGATION_DELAY" "0.00 MIL,195.00 MIL"
					( Parent
						( matchGroupRef "@baseboard_fab2_lib.baseboard_fab2(sch_1):\MG_DQ-DQS_FAR_DIMM_NG_M_L_BYTE2\" )
					)
					( Units "uMatchProp" "ns" 1.000000)
					( Status sCSetFlattened )
					( Origin gBackEnd )
				)
				( attribute "RELATIVE_PROPAGATION_DELAY_SCOPE" "G"
					( Parent
						( matchGroupRef "@crescent_city_bb_fab1_lib.crescent_city_bb_fab1(sch_1):\MG_DQ_FAR_DIMM_NG_M_L_BYTE2\" )
					)
					( Status sCSetFlattened )
					( Origin gBackEnd )
				)
				( attribute "RELATIVE_PROPAGATION_DELAY" "-50.00 MIL,50.00 MIL"
					( Parent
						( matchGroupRef "@crescent_city_bb_fab1_lib.crescent_city_bb_fab1(sch_1):\MG_DQ_FAR_DIMM_NG_M_L_BYTE2\" )
					)
					( Units "uMatchProp" "ns" 1.000000)
					( Status sCSetFlattened )
					( Origin gBackEnd )
				)
			)
			( pinPair "@baseboard_fab2_lib.baseboard_fab2(sch_1):\PP2033\"
				( pinRef "@baseboard_fab2_lib.baseboard_fab2(sch_1):page61_i172:DDR4_DQ(23)" )
				( pinRef "@baseboard_fab2_lib.baseboard_fab2(sch_1):page86_i12:DQ(23)" )
				( attribute "RELATIVE_PROPAGATION_DELAY_SCOPE" "G"
					( Parent
						( matchGroupRef "@baseboard_fab2_lib.baseboard_fab2(sch_1):\MG_DQ-DQS_NEAR_DIMM_NG_M_L_BYTE2\" )
					)
					( Status sCSetFlattened )
					( Origin gBackEnd )
				)
				( attribute "RELATIVE_PROPAGATION_DELAY" "0.00 MIL,195.00 MIL"
					( Parent
						( matchGroupRef "@baseboard_fab2_lib.baseboard_fab2(sch_1):\MG_DQ-DQS_NEAR_DIMM_NG_M_L_BYTE2\" )
					)
					( Units "uMatchProp" "ns" 1.000000)
					( Status sCSetFlattened )
					( Origin gBackEnd )
				)
				( attribute "RELATIVE_PROPAGATION_DELAY_SCOPE" "G"
					( Parent
						( matchGroupRef "@crescent_city_bb_fab1_lib.crescent_city_bb_fab1(sch_1):\MG_DQ_NEAR_DIMM_NG_M_L_BYTE2\" )
					)
					( Status sCSetFlattened )
					( Origin gBackEnd )
				)
				( attribute "RELATIVE_PROPAGATION_DELAY" "-50.00 MIL,50.00 MIL"
					( Parent
						( matchGroupRef "@crescent_city_bb_fab1_lib.crescent_city_bb_fab1(sch_1):\MG_DQ_NEAR_DIMM_NG_M_L_BYTE2\" )
					)
					( Units "uMatchProp" "ns" 1.000000)
					( Status sCSetFlattened )
					( Origin gBackEnd )
				)
			)
			( pinPair "@baseboard_fab2_lib.baseboard_fab2(sch_1):\PP1987\"
				( pinRef "@baseboard_fab2_lib.baseboard_fab2(sch_1):page61_i172:DDR4_DQ(24)" )
				( pinRef "@baseboard_fab2_lib.baseboard_fab2(sch_1):page85_i111:DQ(25)" )
				( attribute "RELATIVE_PROPAGATION_DELAY_SCOPE" "G"
					( Parent
						( matchGroupRef "@baseboard_fab2_lib.baseboard_fab2(sch_1):\MG_DQ-DQS_FAR_DIMM_NG_M_L_BYTE3\" )
					)
					( Status sCSetFlattened )
					( Origin gBackEnd )
				)
				( attribute "RELATIVE_PROPAGATION_DELAY" "0.00 MIL,195.00 MIL"
					( Parent
						( matchGroupRef "@baseboard_fab2_lib.baseboard_fab2(sch_1):\MG_DQ-DQS_FAR_DIMM_NG_M_L_BYTE3\" )
					)
					( Units "uMatchProp" "ns" 1.000000)
					( Status sCSetFlattened )
					( Origin gBackEnd )
				)
				( attribute "RELATIVE_PROPAGATION_DELAY_SCOPE" "G"
					( Parent
						( matchGroupRef "@crescent_city_bb_fab1_lib.crescent_city_bb_fab1(sch_1):\MG_DQ_FAR_DIMM_NG_M_L_BYTE3\" )
					)
					( Origin gBackEnd )
				)
				( attribute "RELATIVE_PROPAGATION_DELAY" "-64.27 MIL,50.00 MIL"
					( Parent
						( matchGroupRef "@crescent_city_bb_fab1_lib.crescent_city_bb_fab1(sch_1):\MG_DQ_FAR_DIMM_NG_M_L_BYTE3\" )
					)
					( Units "uMatchProp" "ns" 1.000000)
					( Origin gBackEnd )
				)
			)
			( pinPair "@baseboard_fab2_lib.baseboard_fab2(sch_1):\PP1988\"
				( pinRef "@baseboard_fab2_lib.baseboard_fab2(sch_1):page61_i172:DDR4_DQ(24)" )
				( pinRef "@baseboard_fab2_lib.baseboard_fab2(sch_1):page86_i12:DQ(24)" )
				( attribute "RELATIVE_PROPAGATION_DELAY_SCOPE" "G"
					( Parent
						( matchGroupRef "@baseboard_fab2_lib.baseboard_fab2(sch_1):\MG_DQ-DQS_NEAR_DIMM_NG_M_L_BYTE3\" )
					)
					( Status sCSetFlattened )
					( Origin gBackEnd )
				)
				( attribute "RELATIVE_PROPAGATION_DELAY" "0.00 MIL,195.00 MIL"
					( Parent
						( matchGroupRef "@baseboard_fab2_lib.baseboard_fab2(sch_1):\MG_DQ-DQS_NEAR_DIMM_NG_M_L_BYTE3\" )
					)
					( Units "uMatchProp" "ns" 1.000000)
					( Status sCSetFlattened )
					( Origin gBackEnd )
				)
				( attribute "RELATIVE_PROPAGATION_DELAY_SCOPE" "G"
					( Parent
						( matchGroupRef "@crescent_city_bb_fab1_lib.crescent_city_bb_fab1(sch_1):\MG_DQ_NEAR_DIMM_NG_M_L_BYTE3\" )
					)
					( Origin gBackEnd )
				)
				( attribute "RELATIVE_PROPAGATION_DELAY" "-64.27 MIL,50.00 MIL"
					( Parent
						( matchGroupRef "@crescent_city_bb_fab1_lib.crescent_city_bb_fab1(sch_1):\MG_DQ_NEAR_DIMM_NG_M_L_BYTE3\" )
					)
					( Units "uMatchProp" "ns" 1.000000)
					( Origin gBackEnd )
				)
			)
			( pinPair "@baseboard_fab2_lib.baseboard_fab2(sch_1):\PP1990\"
				( pinRef "@baseboard_fab2_lib.baseboard_fab2(sch_1):page61_i172:DDR4_DQ(25)" )
				( pinRef "@baseboard_fab2_lib.baseboard_fab2(sch_1):page85_i111:DQ(24)" )
				( attribute "RELATIVE_PROPAGATION_DELAY_SCOPE" "G"
					( Parent
						( matchGroupRef "@baseboard_fab2_lib.baseboard_fab2(sch_1):\MG_DQ-DQS_FAR_DIMM_NG_M_L_BYTE3\" )
					)
					( Status sCSetFlattened )
					( Origin gBackEnd )
				)
				( attribute "RELATIVE_PROPAGATION_DELAY" "0.00 MIL,195.00 MIL"
					( Parent
						( matchGroupRef "@baseboard_fab2_lib.baseboard_fab2(sch_1):\MG_DQ-DQS_FAR_DIMM_NG_M_L_BYTE3\" )
					)
					( Units "uMatchProp" "ns" 1.000000)
					( Status sCSetFlattened )
					( Origin gBackEnd )
				)
				( attribute "RELATIVE_PROPAGATION_DELAY_SCOPE" "G"
					( Parent
						( matchGroupRef "@crescent_city_bb_fab1_lib.crescent_city_bb_fab1(sch_1):\MG_DQ_FAR_DIMM_NG_M_L_BYTE3\" )
					)
					( Origin gBackEnd )
				)
				( attribute "RELATIVE_PROPAGATION_DELAY" "-67.43 MIL,50.00 MIL"
					( Parent
						( matchGroupRef "@crescent_city_bb_fab1_lib.crescent_city_bb_fab1(sch_1):\MG_DQ_FAR_DIMM_NG_M_L_BYTE3\" )
					)
					( Units "uMatchProp" "ns" 1.000000)
					( Origin gBackEnd )
				)
			)
			( pinPair "@baseboard_fab2_lib.baseboard_fab2(sch_1):\PP1991\"
				( pinRef "@baseboard_fab2_lib.baseboard_fab2(sch_1):page61_i172:DDR4_DQ(25)" )
				( pinRef "@baseboard_fab2_lib.baseboard_fab2(sch_1):page86_i12:DQ(25)" )
				( attribute "RELATIVE_PROPAGATION_DELAY_SCOPE" "G"
					( Parent
						( matchGroupRef "@baseboard_fab2_lib.baseboard_fab2(sch_1):\MG_DQ-DQS_NEAR_DIMM_NG_M_L_BYTE3\" )
					)
					( Status sCSetFlattened )
					( Origin gBackEnd )
				)
				( attribute "RELATIVE_PROPAGATION_DELAY" "0.00 MIL,195.00 MIL"
					( Parent
						( matchGroupRef "@baseboard_fab2_lib.baseboard_fab2(sch_1):\MG_DQ-DQS_NEAR_DIMM_NG_M_L_BYTE3\" )
					)
					( Units "uMatchProp" "ns" 1.000000)
					( Status sCSetFlattened )
					( Origin gBackEnd )
				)
				( attribute "RELATIVE_PROPAGATION_DELAY_SCOPE" "G"
					( Parent
						( matchGroupRef "@crescent_city_bb_fab1_lib.crescent_city_bb_fab1(sch_1):\MG_DQ_NEAR_DIMM_NG_M_L_BYTE3\" )
					)
					( Origin gBackEnd )
				)
				( attribute "RELATIVE_PROPAGATION_DELAY" "-67.43 MIL,50.00 MIL"
					( Parent
						( matchGroupRef "@crescent_city_bb_fab1_lib.crescent_city_bb_fab1(sch_1):\MG_DQ_NEAR_DIMM_NG_M_L_BYTE3\" )
					)
					( Units "uMatchProp" "ns" 1.000000)
					( Origin gBackEnd )
				)
			)
			( pinPair "@baseboard_fab2_lib.baseboard_fab2(sch_1):\PP1993\"
				( pinRef "@baseboard_fab2_lib.baseboard_fab2(sch_1):page61_i172:DDR4_DQ(26)" )
				( pinRef "@baseboard_fab2_lib.baseboard_fab2(sch_1):page85_i111:DQ(27)" )
				( attribute "RELATIVE_PROPAGATION_DELAY_SCOPE" "G"
					( Parent
						( matchGroupRef "@baseboard_fab2_lib.baseboard_fab2(sch_1):\MG_DQ-DQS_FAR_DIMM_NG_M_L_BYTE3\" )
					)
					( Status sCSetFlattened )
					( Origin gBackEnd )
				)
				( attribute "RELATIVE_PROPAGATION_DELAY" "0.00 MIL,195.00 MIL"
					( Parent
						( matchGroupRef "@baseboard_fab2_lib.baseboard_fab2(sch_1):\MG_DQ-DQS_FAR_DIMM_NG_M_L_BYTE3\" )
					)
					( Units "uMatchProp" "ns" 1.000000)
					( Status sCSetFlattened )
					( Origin gBackEnd )
				)
				( attribute "RELATIVE_PROPAGATION_DELAY_SCOPE" "G"
					( Parent
						( matchGroupRef "@crescent_city_bb_fab1_lib.crescent_city_bb_fab1(sch_1):\MG_DQ_FAR_DIMM_NG_M_L_BYTE3\" )
					)
					( Origin gBackEnd )
				)
				( attribute "RELATIVE_PROPAGATION_DELAY" "-75.65 MIL,50.00 MIL"
					( Parent
						( matchGroupRef "@crescent_city_bb_fab1_lib.crescent_city_bb_fab1(sch_1):\MG_DQ_FAR_DIMM_NG_M_L_BYTE3\" )
					)
					( Units "uMatchProp" "ns" 1.000000)
					( Origin gBackEnd )
				)
			)
			( pinPair "@baseboard_fab2_lib.baseboard_fab2(sch_1):\PP1994\"
				( pinRef "@baseboard_fab2_lib.baseboard_fab2(sch_1):page61_i172:DDR4_DQ(26)" )
				( pinRef "@baseboard_fab2_lib.baseboard_fab2(sch_1):page86_i12:DQ(26)" )
				( attribute "RELATIVE_PROPAGATION_DELAY_SCOPE" "G"
					( Parent
						( matchGroupRef "@baseboard_fab2_lib.baseboard_fab2(sch_1):\MG_DQ-DQS_NEAR_DIMM_NG_M_L_BYTE3\" )
					)
					( Status sCSetFlattened )
					( Origin gBackEnd )
				)
				( attribute "RELATIVE_PROPAGATION_DELAY" "0.00 MIL,195.00 MIL"
					( Parent
						( matchGroupRef "@baseboard_fab2_lib.baseboard_fab2(sch_1):\MG_DQ-DQS_NEAR_DIMM_NG_M_L_BYTE3\" )
					)
					( Units "uMatchProp" "ns" 1.000000)
					( Status sCSetFlattened )
					( Origin gBackEnd )
				)
				( attribute "RELATIVE_PROPAGATION_DELAY_SCOPE" "G"
					( Parent
						( matchGroupRef "@crescent_city_bb_fab1_lib.crescent_city_bb_fab1(sch_1):\MG_DQ_NEAR_DIMM_NG_M_L_BYTE3\" )
					)
					( Origin gBackEnd )
				)
				( attribute "RELATIVE_PROPAGATION_DELAY" "-75.65 MIL,50.00 MIL"
					( Parent
						( matchGroupRef "@crescent_city_bb_fab1_lib.crescent_city_bb_fab1(sch_1):\MG_DQ_NEAR_DIMM_NG_M_L_BYTE3\" )
					)
					( Units "uMatchProp" "ns" 1.000000)
					( Origin gBackEnd )
				)
			)
			( pinPair "@baseboard_fab2_lib.baseboard_fab2(sch_1):\PP1996\"
				( pinRef "@baseboard_fab2_lib.baseboard_fab2(sch_1):page61_i172:DDR4_DQ(27)" )
				( pinRef "@baseboard_fab2_lib.baseboard_fab2(sch_1):page85_i111:DQ(26)" )
				( attribute "RELATIVE_PROPAGATION_DELAY_SCOPE" "G"
					( Parent
						( matchGroupRef "@baseboard_fab2_lib.baseboard_fab2(sch_1):\MG_DQ-DQS_FAR_DIMM_NG_M_L_BYTE3\" )
					)
					( Status sCSetFlattened )
					( Origin gBackEnd )
				)
				( attribute "RELATIVE_PROPAGATION_DELAY" "0.00 MIL,195.00 MIL"
					( Parent
						( matchGroupRef "@baseboard_fab2_lib.baseboard_fab2(sch_1):\MG_DQ-DQS_FAR_DIMM_NG_M_L_BYTE3\" )
					)
					( Units "uMatchProp" "ns" 1.000000)
					( Status sCSetFlattened )
					( Origin gBackEnd )
				)
				( attribute "RELATIVE_PROPAGATION_DELAY_SCOPE" "G"
					( Parent
						( matchGroupRef "@crescent_city_bb_fab1_lib.crescent_city_bb_fab1(sch_1):\MG_DQ_FAR_DIMM_NG_M_L_BYTE3\" )
					)
					( Origin gBackEnd )
				)
				( attribute "RELATIVE_PROPAGATION_DELAY" "-57.85 MIL,50.00 MIL"
					( Parent
						( matchGroupRef "@crescent_city_bb_fab1_lib.crescent_city_bb_fab1(sch_1):\MG_DQ_FAR_DIMM_NG_M_L_BYTE3\" )
					)
					( Units "uMatchProp" "ns" 1.000000)
					( Origin gBackEnd )
				)
			)
			( pinPair "@baseboard_fab2_lib.baseboard_fab2(sch_1):\PP1997\"
				( pinRef "@baseboard_fab2_lib.baseboard_fab2(sch_1):page61_i172:DDR4_DQ(27)" )
				( pinRef "@baseboard_fab2_lib.baseboard_fab2(sch_1):page86_i12:DQ(27)" )
				( attribute "RELATIVE_PROPAGATION_DELAY_SCOPE" "G"
					( Parent
						( matchGroupRef "@baseboard_fab2_lib.baseboard_fab2(sch_1):\MG_DQ-DQS_NEAR_DIMM_NG_M_L_BYTE3\" )
					)
					( Status sCSetFlattened )
					( Origin gBackEnd )
				)
				( attribute "RELATIVE_PROPAGATION_DELAY" "0.00 MIL,195.00 MIL"
					( Parent
						( matchGroupRef "@baseboard_fab2_lib.baseboard_fab2(sch_1):\MG_DQ-DQS_NEAR_DIMM_NG_M_L_BYTE3\" )
					)
					( Units "uMatchProp" "ns" 1.000000)
					( Status sCSetFlattened )
					( Origin gBackEnd )
				)
				( attribute "RELATIVE_PROPAGATION_DELAY_SCOPE" "G"
					( Parent
						( matchGroupRef "@crescent_city_bb_fab1_lib.crescent_city_bb_fab1(sch_1):\MG_DQ_NEAR_DIMM_NG_M_L_BYTE3\" )
					)
					( Origin gBackEnd )
				)
				( attribute "RELATIVE_PROPAGATION_DELAY" "-57.85 MIL,50.00 MIL"
					( Parent
						( matchGroupRef "@crescent_city_bb_fab1_lib.crescent_city_bb_fab1(sch_1):\MG_DQ_NEAR_DIMM_NG_M_L_BYTE3\" )
					)
					( Units "uMatchProp" "ns" 1.000000)
					( Origin gBackEnd )
				)
			)
			( pinPair "@baseboard_fab2_lib.baseboard_fab2(sch_1):\PP1999\"
				( pinRef "@baseboard_fab2_lib.baseboard_fab2(sch_1):page61_i172:DDR4_DQ(28)" )
				( pinRef "@baseboard_fab2_lib.baseboard_fab2(sch_1):page85_i111:DQ(29)" )
				( attribute "RELATIVE_PROPAGATION_DELAY_SCOPE" "G"
					( Parent
						( matchGroupRef "@baseboard_fab2_lib.baseboard_fab2(sch_1):\MG_DQ-DQS_FAR_DIMM_NG_M_L_BYTE3\" )
					)
					( Status sCSetFlattened )
					( Origin gBackEnd )
				)
				( attribute "RELATIVE_PROPAGATION_DELAY" "0.00 MIL,195.00 MIL"
					( Parent
						( matchGroupRef "@baseboard_fab2_lib.baseboard_fab2(sch_1):\MG_DQ-DQS_FAR_DIMM_NG_M_L_BYTE3\" )
					)
					( Units "uMatchProp" "ns" 1.000000)
					( Status sCSetFlattened )
					( Origin gBackEnd )
				)
				( attribute "RELATIVE_PROPAGATION_DELAY_SCOPE" "G"
					( Parent
						( matchGroupRef "@crescent_city_bb_fab1_lib.crescent_city_bb_fab1(sch_1):\MG_DQ_FAR_DIMM_NG_M_L_BYTE3\" )
					)
					( Status sCSetFlattened )
					( Origin gBackEnd )
				)
				( attribute "RELATIVE_PROPAGATION_DELAY" "-50.00 MIL,50.00 MIL"
					( Parent
						( matchGroupRef "@crescent_city_bb_fab1_lib.crescent_city_bb_fab1(sch_1):\MG_DQ_FAR_DIMM_NG_M_L_BYTE3\" )
					)
					( Units "uMatchProp" "ns" 1.000000)
					( Status sCSetFlattened )
					( Origin gBackEnd )
				)
			)
			( pinPair "@baseboard_fab2_lib.baseboard_fab2(sch_1):\PP2000\"
				( pinRef "@baseboard_fab2_lib.baseboard_fab2(sch_1):page61_i172:DDR4_DQ(28)" )
				( pinRef "@baseboard_fab2_lib.baseboard_fab2(sch_1):page86_i12:DQ(28)" )
				( attribute "RELATIVE_PROPAGATION_DELAY_SCOPE" "G"
					( Parent
						( matchGroupRef "@baseboard_fab2_lib.baseboard_fab2(sch_1):\MG_DQ-DQS_NEAR_DIMM_NG_M_L_BYTE3\" )
					)
					( Status sCSetFlattened )
					( Origin gBackEnd )
				)
				( attribute "RELATIVE_PROPAGATION_DELAY" "0.00 MIL,195.00 MIL"
					( Parent
						( matchGroupRef "@baseboard_fab2_lib.baseboard_fab2(sch_1):\MG_DQ-DQS_NEAR_DIMM_NG_M_L_BYTE3\" )
					)
					( Units "uMatchProp" "ns" 1.000000)
					( Status sCSetFlattened )
					( Origin gBackEnd )
				)
				( attribute "RELATIVE_PROPAGATION_DELAY_SCOPE" "G"
					( Parent
						( matchGroupRef "@crescent_city_bb_fab1_lib.crescent_city_bb_fab1(sch_1):\MG_DQ_NEAR_DIMM_NG_M_L_BYTE3\" )
					)
					( Status sCSetFlattened )
					( Origin gBackEnd )
				)
				( attribute "RELATIVE_PROPAGATION_DELAY" "-50.00 MIL,50.00 MIL"
					( Parent
						( matchGroupRef "@crescent_city_bb_fab1_lib.crescent_city_bb_fab1(sch_1):\MG_DQ_NEAR_DIMM_NG_M_L_BYTE3\" )
					)
					( Units "uMatchProp" "ns" 1.000000)
					( Status sCSetFlattened )
					( Origin gBackEnd )
				)
			)
			( pinPair "@baseboard_fab2_lib.baseboard_fab2(sch_1):\PP2002\"
				( pinRef "@baseboard_fab2_lib.baseboard_fab2(sch_1):page61_i172:DDR4_DQ(29)" )
				( pinRef "@baseboard_fab2_lib.baseboard_fab2(sch_1):page85_i111:DQ(28)" )
				( attribute "RELATIVE_PROPAGATION_DELAY_SCOPE" "G"
					( Parent
						( matchGroupRef "@baseboard_fab2_lib.baseboard_fab2(sch_1):\MG_DQ-DQS_FAR_DIMM_NG_M_L_BYTE3\" )
					)
					( Status sCSetFlattened )
					( Origin gBackEnd )
				)
				( attribute "RELATIVE_PROPAGATION_DELAY" "0.00 MIL,195.00 MIL"
					( Parent
						( matchGroupRef "@baseboard_fab2_lib.baseboard_fab2(sch_1):\MG_DQ-DQS_FAR_DIMM_NG_M_L_BYTE3\" )
					)
					( Units "uMatchProp" "ns" 1.000000)
					( Status sCSetFlattened )
					( Origin gBackEnd )
				)
				( attribute "RELATIVE_PROPAGATION_DELAY_SCOPE" "G"
					( Parent
						( matchGroupRef "@crescent_city_bb_fab1_lib.crescent_city_bb_fab1(sch_1):\MG_DQ_FAR_DIMM_NG_M_L_BYTE3\" )
					)
					( Origin gBackEnd )
				)
				( attribute "RELATIVE_PROPAGATION_DELAY" "-61.41 MIL,50.00 MIL"
					( Parent
						( matchGroupRef "@crescent_city_bb_fab1_lib.crescent_city_bb_fab1(sch_1):\MG_DQ_FAR_DIMM_NG_M_L_BYTE3\" )
					)
					( Units "uMatchProp" "ns" 1.000000)
					( Origin gBackEnd )
				)
			)
			( pinPair "@baseboard_fab2_lib.baseboard_fab2(sch_1):\PP2003\"
				( pinRef "@baseboard_fab2_lib.baseboard_fab2(sch_1):page61_i172:DDR4_DQ(29)" )
				( pinRef "@baseboard_fab2_lib.baseboard_fab2(sch_1):page86_i12:DQ(29)" )
				( attribute "RELATIVE_PROPAGATION_DELAY_SCOPE" "G"
					( Parent
						( matchGroupRef "@baseboard_fab2_lib.baseboard_fab2(sch_1):\MG_DQ-DQS_NEAR_DIMM_NG_M_L_BYTE3\" )
					)
					( Status sCSetFlattened )
					( Origin gBackEnd )
				)
				( attribute "RELATIVE_PROPAGATION_DELAY" "0.00 MIL,195.00 MIL"
					( Parent
						( matchGroupRef "@baseboard_fab2_lib.baseboard_fab2(sch_1):\MG_DQ-DQS_NEAR_DIMM_NG_M_L_BYTE3\" )
					)
					( Units "uMatchProp" "ns" 1.000000)
					( Status sCSetFlattened )
					( Origin gBackEnd )
				)
				( attribute "RELATIVE_PROPAGATION_DELAY_SCOPE" "G"
					( Parent
						( matchGroupRef "@crescent_city_bb_fab1_lib.crescent_city_bb_fab1(sch_1):\MG_DQ_NEAR_DIMM_NG_M_L_BYTE3\" )
					)
					( Origin gBackEnd )
				)
				( attribute "RELATIVE_PROPAGATION_DELAY" "-61.41 MIL,50.00 MIL"
					( Parent
						( matchGroupRef "@crescent_city_bb_fab1_lib.crescent_city_bb_fab1(sch_1):\MG_DQ_NEAR_DIMM_NG_M_L_BYTE3\" )
					)
					( Units "uMatchProp" "ns" 1.000000)
					( Origin gBackEnd )
				)
			)
			( pinPair "@baseboard_fab2_lib.baseboard_fab2(sch_1):\PP2005\"
				( pinRef "@baseboard_fab2_lib.baseboard_fab2(sch_1):page61_i172:DDR4_DQ(30)" )
				( pinRef "@baseboard_fab2_lib.baseboard_fab2(sch_1):page85_i111:DQ(31)" )
				( attribute "RELATIVE_PROPAGATION_DELAY_SCOPE" "G"
					( Parent
						( matchGroupRef "@baseboard_fab2_lib.baseboard_fab2(sch_1):\MG_DQ-DQS_FAR_DIMM_NG_M_L_BYTE3\" )
					)
					( Status sCSetFlattened )
					( Origin gBackEnd )
				)
				( attribute "RELATIVE_PROPAGATION_DELAY" "0.00 MIL,195.00 MIL"
					( Parent
						( matchGroupRef "@baseboard_fab2_lib.baseboard_fab2(sch_1):\MG_DQ-DQS_FAR_DIMM_NG_M_L_BYTE3\" )
					)
					( Units "uMatchProp" "ns" 1.000000)
					( Status sCSetFlattened )
					( Origin gBackEnd )
				)
				( attribute "RELATIVE_PROPAGATION_DELAY_SCOPE" "G"
					( Parent
						( matchGroupRef "@crescent_city_bb_fab1_lib.crescent_city_bb_fab1(sch_1):\MG_DQ_FAR_DIMM_NG_M_L_BYTE3\" )
					)
					( Origin gBackEnd )
				)
				( attribute "RELATIVE_PROPAGATION_DELAY" "-70.54 MIL,50.00 MIL"
					( Parent
						( matchGroupRef "@crescent_city_bb_fab1_lib.crescent_city_bb_fab1(sch_1):\MG_DQ_FAR_DIMM_NG_M_L_BYTE3\" )
					)
					( Units "uMatchProp" "ns" 1.000000)
					( Origin gBackEnd )
				)
			)
			( pinPair "@baseboard_fab2_lib.baseboard_fab2(sch_1):\PP2006\"
				( pinRef "@baseboard_fab2_lib.baseboard_fab2(sch_1):page61_i172:DDR4_DQ(30)" )
				( pinRef "@baseboard_fab2_lib.baseboard_fab2(sch_1):page86_i12:DQ(30)" )
				( attribute "RELATIVE_PROPAGATION_DELAY_SCOPE" "G"
					( Parent
						( matchGroupRef "@baseboard_fab2_lib.baseboard_fab2(sch_1):\MG_DQ-DQS_NEAR_DIMM_NG_M_L_BYTE3\" )
					)
					( Status sCSetFlattened )
					( Origin gBackEnd )
				)
				( attribute "RELATIVE_PROPAGATION_DELAY" "0.00 MIL,195.00 MIL"
					( Parent
						( matchGroupRef "@baseboard_fab2_lib.baseboard_fab2(sch_1):\MG_DQ-DQS_NEAR_DIMM_NG_M_L_BYTE3\" )
					)
					( Units "uMatchProp" "ns" 1.000000)
					( Status sCSetFlattened )
					( Origin gBackEnd )
				)
				( attribute "RELATIVE_PROPAGATION_DELAY_SCOPE" "G"
					( Parent
						( matchGroupRef "@crescent_city_bb_fab1_lib.crescent_city_bb_fab1(sch_1):\MG_DQ_NEAR_DIMM_NG_M_L_BYTE3\" )
					)
					( Origin gBackEnd )
				)
				( attribute "RELATIVE_PROPAGATION_DELAY" "-70.54 MIL,50.00 MIL"
					( Parent
						( matchGroupRef "@crescent_city_bb_fab1_lib.crescent_city_bb_fab1(sch_1):\MG_DQ_NEAR_DIMM_NG_M_L_BYTE3\" )
					)
					( Units "uMatchProp" "ns" 1.000000)
					( Origin gBackEnd )
				)
			)
			( pinPair "@baseboard_fab2_lib.baseboard_fab2(sch_1):\PP2008\"
				( pinRef "@baseboard_fab2_lib.baseboard_fab2(sch_1):page61_i172:DDR4_DQ(31)" )
				( pinRef "@baseboard_fab2_lib.baseboard_fab2(sch_1):page85_i111:DQ(30)" )
				( attribute "RELATIVE_PROPAGATION_DELAY_SCOPE" "G"
					( Parent
						( matchGroupRef "@baseboard_fab2_lib.baseboard_fab2(sch_1):\MG_DQ-DQS_FAR_DIMM_NG_M_L_BYTE3\" )
					)
					( Status sCSetFlattened )
					( Origin gBackEnd )
				)
				( attribute "RELATIVE_PROPAGATION_DELAY" "0.00 MIL,195.00 MIL"
					( Parent
						( matchGroupRef "@baseboard_fab2_lib.baseboard_fab2(sch_1):\MG_DQ-DQS_FAR_DIMM_NG_M_L_BYTE3\" )
					)
					( Units "uMatchProp" "ns" 1.000000)
					( Status sCSetFlattened )
					( Origin gBackEnd )
				)
				( attribute "RELATIVE_PROPAGATION_DELAY_SCOPE" "G"
					( Parent
						( matchGroupRef "@crescent_city_bb_fab1_lib.crescent_city_bb_fab1(sch_1):\MG_DQ_FAR_DIMM_NG_M_L_BYTE3\" )
					)
					( Origin gBackEnd )
				)
				( attribute "RELATIVE_PROPAGATION_DELAY" "-72.73 MIL,50.00 MIL"
					( Parent
						( matchGroupRef "@crescent_city_bb_fab1_lib.crescent_city_bb_fab1(sch_1):\MG_DQ_FAR_DIMM_NG_M_L_BYTE3\" )
					)
					( Units "uMatchProp" "ns" 1.000000)
					( Origin gBackEnd )
				)
			)
			( pinPair "@baseboard_fab2_lib.baseboard_fab2(sch_1):\PP2009\"
				( pinRef "@baseboard_fab2_lib.baseboard_fab2(sch_1):page61_i172:DDR4_DQ(31)" )
				( pinRef "@baseboard_fab2_lib.baseboard_fab2(sch_1):page86_i12:DQ(31)" )
				( attribute "RELATIVE_PROPAGATION_DELAY_SCOPE" "G"
					( Parent
						( matchGroupRef "@baseboard_fab2_lib.baseboard_fab2(sch_1):\MG_DQ-DQS_NEAR_DIMM_NG_M_L_BYTE3\" )
					)
					( Status sCSetFlattened )
					( Origin gBackEnd )
				)
				( attribute "RELATIVE_PROPAGATION_DELAY" "0.00 MIL,195.00 MIL"
					( Parent
						( matchGroupRef "@baseboard_fab2_lib.baseboard_fab2(sch_1):\MG_DQ-DQS_NEAR_DIMM_NG_M_L_BYTE3\" )
					)
					( Units "uMatchProp" "ns" 1.000000)
					( Status sCSetFlattened )
					( Origin gBackEnd )
				)
				( attribute "RELATIVE_PROPAGATION_DELAY_SCOPE" "G"
					( Parent
						( matchGroupRef "@crescent_city_bb_fab1_lib.crescent_city_bb_fab1(sch_1):\MG_DQ_NEAR_DIMM_NG_M_L_BYTE3\" )
					)
					( Origin gBackEnd )
				)
				( attribute "RELATIVE_PROPAGATION_DELAY" "-72.73 MIL,50.00 MIL"
					( Parent
						( matchGroupRef "@crescent_city_bb_fab1_lib.crescent_city_bb_fab1(sch_1):\MG_DQ_NEAR_DIMM_NG_M_L_BYTE3\" )
					)
					( Units "uMatchProp" "ns" 1.000000)
					( Origin gBackEnd )
				)
			)
			( pinPair "@baseboard_fab2_lib.baseboard_fab2(sch_1):\PP1963\"
				( pinRef "@baseboard_fab2_lib.baseboard_fab2(sch_1):page61_i172:DDR4_DQ(32)" )
				( pinRef "@baseboard_fab2_lib.baseboard_fab2(sch_1):page85_i111:DQ(33)" )
				( attribute "RELATIVE_PROPAGATION_DELAY_SCOPE" "G"
					( Parent
						( matchGroupRef "@baseboard_fab2_lib.baseboard_fab2(sch_1):\MG_DQ-DQS_FAR_DIMM_NG_M_L_BYTE4\" )
					)
					( Status sCSetFlattened )
					( Origin gBackEnd )
				)
				( attribute "RELATIVE_PROPAGATION_DELAY" "0.00 MIL,195.00 MIL"
					( Parent
						( matchGroupRef "@baseboard_fab2_lib.baseboard_fab2(sch_1):\MG_DQ-DQS_FAR_DIMM_NG_M_L_BYTE4\" )
					)
					( Units "uMatchProp" "ns" 1.000000)
					( Status sCSetFlattened )
					( Origin gBackEnd )
				)
				( attribute "RELATIVE_PROPAGATION_DELAY_SCOPE" "G"
					( Parent
						( matchGroupRef "@crescent_city_bb_fab1_lib.crescent_city_bb_fab1(sch_1):\MG_DQ_FAR_DIMM_NG_M_L_BYTE4\" )
					)
					( Status sCSetFlattened )
					( Origin gBackEnd )
				)
				( attribute "RELATIVE_PROPAGATION_DELAY" "-50.00 MIL,50.00 MIL"
					( Parent
						( matchGroupRef "@crescent_city_bb_fab1_lib.crescent_city_bb_fab1(sch_1):\MG_DQ_FAR_DIMM_NG_M_L_BYTE4\" )
					)
					( Units "uMatchProp" "ns" 1.000000)
					( Status sCSetFlattened )
					( Origin gBackEnd )
				)
			)
			( pinPair "@baseboard_fab2_lib.baseboard_fab2(sch_1):\PP1965\"
				( pinRef "@baseboard_fab2_lib.baseboard_fab2(sch_1):page61_i172:DDR4_DQ(32)" )
				( pinRef "@baseboard_fab2_lib.baseboard_fab2(sch_1):page86_i12:DQ(32)" )
				( attribute "RELATIVE_PROPAGATION_DELAY_SCOPE" "G"
					( Parent
						( matchGroupRef "@baseboard_fab2_lib.baseboard_fab2(sch_1):\MG_DQ-DQS_NEAR_DIMM_NG_M_L_BYTE4\" )
					)
					( Status sCSetFlattened )
					( Origin gBackEnd )
				)
				( attribute "RELATIVE_PROPAGATION_DELAY" "0.00 MIL,195.00 MIL"
					( Parent
						( matchGroupRef "@baseboard_fab2_lib.baseboard_fab2(sch_1):\MG_DQ-DQS_NEAR_DIMM_NG_M_L_BYTE4\" )
					)
					( Units "uMatchProp" "ns" 1.000000)
					( Status sCSetFlattened )
					( Origin gBackEnd )
				)
				( attribute "RELATIVE_PROPAGATION_DELAY_SCOPE" "G"
					( Parent
						( matchGroupRef "@crescent_city_bb_fab1_lib.crescent_city_bb_fab1(sch_1):\MG_DQ_NEAR_DIMM_NG_M_L_BYTE4\" )
					)
					( Status sCSetFlattened )
					( Origin gBackEnd )
				)
				( attribute "RELATIVE_PROPAGATION_DELAY" "-50.00 MIL,50.00 MIL"
					( Parent
						( matchGroupRef "@crescent_city_bb_fab1_lib.crescent_city_bb_fab1(sch_1):\MG_DQ_NEAR_DIMM_NG_M_L_BYTE4\" )
					)
					( Units "uMatchProp" "ns" 1.000000)
					( Status sCSetFlattened )
					( Origin gBackEnd )
				)
			)
			( pinPair "@baseboard_fab2_lib.baseboard_fab2(sch_1):\PP1966\"
				( pinRef "@baseboard_fab2_lib.baseboard_fab2(sch_1):page61_i172:DDR4_DQ(33)" )
				( pinRef "@baseboard_fab2_lib.baseboard_fab2(sch_1):page85_i111:DQ(32)" )
				( attribute "RELATIVE_PROPAGATION_DELAY_SCOPE" "G"
					( Parent
						( matchGroupRef "@baseboard_fab2_lib.baseboard_fab2(sch_1):\MG_DQ-DQS_FAR_DIMM_NG_M_L_BYTE4\" )
					)
					( Status sCSetFlattened )
					( Origin gBackEnd )
				)
				( attribute "RELATIVE_PROPAGATION_DELAY" "0.00 MIL,195.00 MIL"
					( Parent
						( matchGroupRef "@baseboard_fab2_lib.baseboard_fab2(sch_1):\MG_DQ-DQS_FAR_DIMM_NG_M_L_BYTE4\" )
					)
					( Units "uMatchProp" "ns" 1.000000)
					( Status sCSetFlattened )
					( Origin gBackEnd )
				)
				( attribute "RELATIVE_PROPAGATION_DELAY_SCOPE" "G"
					( Parent
						( matchGroupRef "@crescent_city_bb_fab1_lib.crescent_city_bb_fab1(sch_1):\MG_DQ_FAR_DIMM_NG_M_L_BYTE4\" )
					)
					( Status sCSetFlattened )
					( Origin gBackEnd )
				)
				( attribute "RELATIVE_PROPAGATION_DELAY" "-50.00 MIL,50.00 MIL"
					( Parent
						( matchGroupRef "@crescent_city_bb_fab1_lib.crescent_city_bb_fab1(sch_1):\MG_DQ_FAR_DIMM_NG_M_L_BYTE4\" )
					)
					( Units "uMatchProp" "ns" 1.000000)
					( Status sCSetFlattened )
					( Origin gBackEnd )
				)
			)
			( pinPair "@baseboard_fab2_lib.baseboard_fab2(sch_1):\PP1968\"
				( pinRef "@baseboard_fab2_lib.baseboard_fab2(sch_1):page61_i172:DDR4_DQ(33)" )
				( pinRef "@baseboard_fab2_lib.baseboard_fab2(sch_1):page86_i12:DQ(33)" )
				( attribute "RELATIVE_PROPAGATION_DELAY_SCOPE" "G"
					( Parent
						( matchGroupRef "@baseboard_fab2_lib.baseboard_fab2(sch_1):\MG_DQ-DQS_NEAR_DIMM_NG_M_L_BYTE4\" )
					)
					( Status sCSetFlattened )
					( Origin gBackEnd )
				)
				( attribute "RELATIVE_PROPAGATION_DELAY" "0.00 MIL,195.00 MIL"
					( Parent
						( matchGroupRef "@baseboard_fab2_lib.baseboard_fab2(sch_1):\MG_DQ-DQS_NEAR_DIMM_NG_M_L_BYTE4\" )
					)
					( Units "uMatchProp" "ns" 1.000000)
					( Status sCSetFlattened )
					( Origin gBackEnd )
				)
				( attribute "RELATIVE_PROPAGATION_DELAY_SCOPE" "G"
					( Parent
						( matchGroupRef "@crescent_city_bb_fab1_lib.crescent_city_bb_fab1(sch_1):\MG_DQ_NEAR_DIMM_NG_M_L_BYTE4\" )
					)
					( Status sCSetFlattened )
					( Origin gBackEnd )
				)
				( attribute "RELATIVE_PROPAGATION_DELAY" "-50.00 MIL,50.00 MIL"
					( Parent
						( matchGroupRef "@crescent_city_bb_fab1_lib.crescent_city_bb_fab1(sch_1):\MG_DQ_NEAR_DIMM_NG_M_L_BYTE4\" )
					)
					( Units "uMatchProp" "ns" 1.000000)
					( Status sCSetFlattened )
					( Origin gBackEnd )
				)
			)
			( pinPair "@baseboard_fab2_lib.baseboard_fab2(sch_1):\PP1969\"
				( pinRef "@baseboard_fab2_lib.baseboard_fab2(sch_1):page61_i172:DDR4_DQ(34)" )
				( pinRef "@baseboard_fab2_lib.baseboard_fab2(sch_1):page85_i111:DQ(35)" )
				( attribute "RELATIVE_PROPAGATION_DELAY_SCOPE" "G"
					( Parent
						( matchGroupRef "@baseboard_fab2_lib.baseboard_fab2(sch_1):\MG_DQ-DQS_FAR_DIMM_NG_M_L_BYTE4\" )
					)
					( Status sCSetFlattened )
					( Origin gBackEnd )
				)
				( attribute "RELATIVE_PROPAGATION_DELAY" "0.00 MIL,195.00 MIL"
					( Parent
						( matchGroupRef "@baseboard_fab2_lib.baseboard_fab2(sch_1):\MG_DQ-DQS_FAR_DIMM_NG_M_L_BYTE4\" )
					)
					( Units "uMatchProp" "ns" 1.000000)
					( Status sCSetFlattened )
					( Origin gBackEnd )
				)
				( attribute "RELATIVE_PROPAGATION_DELAY_SCOPE" "G"
					( Parent
						( matchGroupRef "@crescent_city_bb_fab1_lib.crescent_city_bb_fab1(sch_1):\MG_DQ_FAR_DIMM_NG_M_L_BYTE4\" )
					)
					( Status sCSetFlattened )
					( Origin gBackEnd )
				)
				( attribute "RELATIVE_PROPAGATION_DELAY" "-50.00 MIL,50.00 MIL"
					( Parent
						( matchGroupRef "@crescent_city_bb_fab1_lib.crescent_city_bb_fab1(sch_1):\MG_DQ_FAR_DIMM_NG_M_L_BYTE4\" )
					)
					( Units "uMatchProp" "ns" 1.000000)
					( Status sCSetFlattened )
					( Origin gBackEnd )
				)
			)
			( pinPair "@baseboard_fab2_lib.baseboard_fab2(sch_1):\PP1971\"
				( pinRef "@baseboard_fab2_lib.baseboard_fab2(sch_1):page61_i172:DDR4_DQ(34)" )
				( pinRef "@baseboard_fab2_lib.baseboard_fab2(sch_1):page86_i12:DQ(34)" )
				( attribute "RELATIVE_PROPAGATION_DELAY_SCOPE" "G"
					( Parent
						( matchGroupRef "@baseboard_fab2_lib.baseboard_fab2(sch_1):\MG_DQ-DQS_NEAR_DIMM_NG_M_L_BYTE4\" )
					)
					( Status sCSetFlattened )
					( Origin gBackEnd )
				)
				( attribute "RELATIVE_PROPAGATION_DELAY" "0.00 MIL,195.00 MIL"
					( Parent
						( matchGroupRef "@baseboard_fab2_lib.baseboard_fab2(sch_1):\MG_DQ-DQS_NEAR_DIMM_NG_M_L_BYTE4\" )
					)
					( Units "uMatchProp" "ns" 1.000000)
					( Status sCSetFlattened )
					( Origin gBackEnd )
				)
				( attribute "RELATIVE_PROPAGATION_DELAY_SCOPE" "G"
					( Parent
						( matchGroupRef "@crescent_city_bb_fab1_lib.crescent_city_bb_fab1(sch_1):\MG_DQ_NEAR_DIMM_NG_M_L_BYTE4\" )
					)
					( Status sCSetFlattened )
					( Origin gBackEnd )
				)
				( attribute "RELATIVE_PROPAGATION_DELAY" "-50.00 MIL,50.00 MIL"
					( Parent
						( matchGroupRef "@crescent_city_bb_fab1_lib.crescent_city_bb_fab1(sch_1):\MG_DQ_NEAR_DIMM_NG_M_L_BYTE4\" )
					)
					( Units "uMatchProp" "ns" 1.000000)
					( Status sCSetFlattened )
					( Origin gBackEnd )
				)
			)
			( pinPair "@baseboard_fab2_lib.baseboard_fab2(sch_1):\PP1972\"
				( pinRef "@baseboard_fab2_lib.baseboard_fab2(sch_1):page61_i172:DDR4_DQ(35)" )
				( pinRef "@baseboard_fab2_lib.baseboard_fab2(sch_1):page85_i111:DQ(34)" )
				( attribute "RELATIVE_PROPAGATION_DELAY_SCOPE" "G"
					( Parent
						( matchGroupRef "@baseboard_fab2_lib.baseboard_fab2(sch_1):\MG_DQ-DQS_FAR_DIMM_NG_M_L_BYTE4\" )
					)
					( Status sCSetFlattened )
					( Origin gBackEnd )
				)
				( attribute "RELATIVE_PROPAGATION_DELAY" "0.00 MIL,195.00 MIL"
					( Parent
						( matchGroupRef "@baseboard_fab2_lib.baseboard_fab2(sch_1):\MG_DQ-DQS_FAR_DIMM_NG_M_L_BYTE4\" )
					)
					( Units "uMatchProp" "ns" 1.000000)
					( Status sCSetFlattened )
					( Origin gBackEnd )
				)
				( attribute "RELATIVE_PROPAGATION_DELAY_SCOPE" "G"
					( Parent
						( matchGroupRef "@crescent_city_bb_fab1_lib.crescent_city_bb_fab1(sch_1):\MG_DQ_FAR_DIMM_NG_M_L_BYTE4\" )
					)
					( Status sCSetFlattened )
					( Origin gBackEnd )
				)
				( attribute "RELATIVE_PROPAGATION_DELAY" "-50.00 MIL,50.00 MIL"
					( Parent
						( matchGroupRef "@crescent_city_bb_fab1_lib.crescent_city_bb_fab1(sch_1):\MG_DQ_FAR_DIMM_NG_M_L_BYTE4\" )
					)
					( Units "uMatchProp" "ns" 1.000000)
					( Status sCSetFlattened )
					( Origin gBackEnd )
				)
			)
			( pinPair "@baseboard_fab2_lib.baseboard_fab2(sch_1):\PP1974\"
				( pinRef "@baseboard_fab2_lib.baseboard_fab2(sch_1):page61_i172:DDR4_DQ(35)" )
				( pinRef "@baseboard_fab2_lib.baseboard_fab2(sch_1):page86_i12:DQ(35)" )
				( attribute "RELATIVE_PROPAGATION_DELAY_SCOPE" "G"
					( Parent
						( matchGroupRef "@baseboard_fab2_lib.baseboard_fab2(sch_1):\MG_DQ-DQS_NEAR_DIMM_NG_M_L_BYTE4\" )
					)
					( Status sCSetFlattened )
					( Origin gBackEnd )
				)
				( attribute "RELATIVE_PROPAGATION_DELAY" "0.00 MIL,195.00 MIL"
					( Parent
						( matchGroupRef "@baseboard_fab2_lib.baseboard_fab2(sch_1):\MG_DQ-DQS_NEAR_DIMM_NG_M_L_BYTE4\" )
					)
					( Units "uMatchProp" "ns" 1.000000)
					( Status sCSetFlattened )
					( Origin gBackEnd )
				)
				( attribute "RELATIVE_PROPAGATION_DELAY_SCOPE" "G"
					( Parent
						( matchGroupRef "@crescent_city_bb_fab1_lib.crescent_city_bb_fab1(sch_1):\MG_DQ_NEAR_DIMM_NG_M_L_BYTE4\" )
					)
					( Origin gBackEnd )
				)
				( attribute "RELATIVE_PROPAGATION_DELAY" "TARGET,TARGET"
					( Parent
						( matchGroupRef "@crescent_city_bb_fab1_lib.crescent_city_bb_fab1(sch_1):\MG_DQ_NEAR_DIMM_NG_M_L_BYTE4\" )
					)
					( Units "uMatchProp" "ns" 1.000000)
					( Origin gBackEnd )
				)
			)
			( pinPair "@baseboard_fab2_lib.baseboard_fab2(sch_1):\PP1975\"
				( pinRef "@baseboard_fab2_lib.baseboard_fab2(sch_1):page61_i172:DDR4_DQ(36)" )
				( pinRef "@baseboard_fab2_lib.baseboard_fab2(sch_1):page85_i111:DQ(37)" )
				( attribute "RELATIVE_PROPAGATION_DELAY_SCOPE" "G"
					( Parent
						( matchGroupRef "@baseboard_fab2_lib.baseboard_fab2(sch_1):\MG_DQ-DQS_FAR_DIMM_NG_M_L_BYTE4\" )
					)
					( Status sCSetFlattened )
					( Origin gBackEnd )
				)
				( attribute "RELATIVE_PROPAGATION_DELAY" "0.00 MIL,195.00 MIL"
					( Parent
						( matchGroupRef "@baseboard_fab2_lib.baseboard_fab2(sch_1):\MG_DQ-DQS_FAR_DIMM_NG_M_L_BYTE4\" )
					)
					( Units "uMatchProp" "ns" 1.000000)
					( Status sCSetFlattened )
					( Origin gBackEnd )
				)
				( attribute "RELATIVE_PROPAGATION_DELAY_SCOPE" "G"
					( Parent
						( matchGroupRef "@crescent_city_bb_fab1_lib.crescent_city_bb_fab1(sch_1):\MG_DQ_FAR_DIMM_NG_M_L_BYTE4\" )
					)
					( Status sCSetFlattened )
					( Origin gBackEnd )
				)
				( attribute "RELATIVE_PROPAGATION_DELAY" "-50.00 MIL,50.00 MIL"
					( Parent
						( matchGroupRef "@crescent_city_bb_fab1_lib.crescent_city_bb_fab1(sch_1):\MG_DQ_FAR_DIMM_NG_M_L_BYTE4\" )
					)
					( Units "uMatchProp" "ns" 1.000000)
					( Status sCSetFlattened )
					( Origin gBackEnd )
				)
			)
			( pinPair "@baseboard_fab2_lib.baseboard_fab2(sch_1):\PP1977\"
				( pinRef "@baseboard_fab2_lib.baseboard_fab2(sch_1):page61_i172:DDR4_DQ(36)" )
				( pinRef "@baseboard_fab2_lib.baseboard_fab2(sch_1):page86_i12:DQ(36)" )
				( attribute "RELATIVE_PROPAGATION_DELAY_SCOPE" "G"
					( Parent
						( matchGroupRef "@baseboard_fab2_lib.baseboard_fab2(sch_1):\MG_DQ-DQS_NEAR_DIMM_NG_M_L_BYTE4\" )
					)
					( Status sCSetFlattened )
					( Origin gBackEnd )
				)
				( attribute "RELATIVE_PROPAGATION_DELAY" "0.00 MIL,195.00 MIL"
					( Parent
						( matchGroupRef "@baseboard_fab2_lib.baseboard_fab2(sch_1):\MG_DQ-DQS_NEAR_DIMM_NG_M_L_BYTE4\" )
					)
					( Units "uMatchProp" "ns" 1.000000)
					( Status sCSetFlattened )
					( Origin gBackEnd )
				)
				( attribute "RELATIVE_PROPAGATION_DELAY_SCOPE" "G"
					( Parent
						( matchGroupRef "@crescent_city_bb_fab1_lib.crescent_city_bb_fab1(sch_1):\MG_DQ_NEAR_DIMM_NG_M_L_BYTE4\" )
					)
					( Status sCSetFlattened )
					( Origin gBackEnd )
				)
				( attribute "RELATIVE_PROPAGATION_DELAY" "-50.00 MIL,50.00 MIL"
					( Parent
						( matchGroupRef "@crescent_city_bb_fab1_lib.crescent_city_bb_fab1(sch_1):\MG_DQ_NEAR_DIMM_NG_M_L_BYTE4\" )
					)
					( Units "uMatchProp" "ns" 1.000000)
					( Status sCSetFlattened )
					( Origin gBackEnd )
				)
			)
			( pinPair "@baseboard_fab2_lib.baseboard_fab2(sch_1):\PP1978\"
				( pinRef "@baseboard_fab2_lib.baseboard_fab2(sch_1):page61_i172:DDR4_DQ(37)" )
				( pinRef "@baseboard_fab2_lib.baseboard_fab2(sch_1):page85_i111:DQ(36)" )
				( attribute "RELATIVE_PROPAGATION_DELAY_SCOPE" "G"
					( Parent
						( matchGroupRef "@baseboard_fab2_lib.baseboard_fab2(sch_1):\MG_DQ-DQS_FAR_DIMM_NG_M_L_BYTE4\" )
					)
					( Status sCSetFlattened )
					( Origin gBackEnd )
				)
				( attribute "RELATIVE_PROPAGATION_DELAY" "0.00 MIL,195.00 MIL"
					( Parent
						( matchGroupRef "@baseboard_fab2_lib.baseboard_fab2(sch_1):\MG_DQ-DQS_FAR_DIMM_NG_M_L_BYTE4\" )
					)
					( Units "uMatchProp" "ns" 1.000000)
					( Status sCSetFlattened )
					( Origin gBackEnd )
				)
				( attribute "RELATIVE_PROPAGATION_DELAY_SCOPE" "G"
					( Parent
						( matchGroupRef "@crescent_city_bb_fab1_lib.crescent_city_bb_fab1(sch_1):\MG_DQ_FAR_DIMM_NG_M_L_BYTE4\" )
					)
					( Status sCSetFlattened )
					( Origin gBackEnd )
				)
				( attribute "RELATIVE_PROPAGATION_DELAY" "-50.00 MIL,50.00 MIL"
					( Parent
						( matchGroupRef "@crescent_city_bb_fab1_lib.crescent_city_bb_fab1(sch_1):\MG_DQ_FAR_DIMM_NG_M_L_BYTE4\" )
					)
					( Units "uMatchProp" "ns" 1.000000)
					( Status sCSetFlattened )
					( Origin gBackEnd )
				)
			)
			( pinPair "@baseboard_fab2_lib.baseboard_fab2(sch_1):\PP1980\"
				( pinRef "@baseboard_fab2_lib.baseboard_fab2(sch_1):page61_i172:DDR4_DQ(37)" )
				( pinRef "@baseboard_fab2_lib.baseboard_fab2(sch_1):page86_i12:DQ(37)" )
				( attribute "RELATIVE_PROPAGATION_DELAY_SCOPE" "G"
					( Parent
						( matchGroupRef "@baseboard_fab2_lib.baseboard_fab2(sch_1):\MG_DQ-DQS_NEAR_DIMM_NG_M_L_BYTE4\" )
					)
					( Status sCSetFlattened )
					( Origin gBackEnd )
				)
				( attribute "RELATIVE_PROPAGATION_DELAY" "0.00 MIL,195.00 MIL"
					( Parent
						( matchGroupRef "@baseboard_fab2_lib.baseboard_fab2(sch_1):\MG_DQ-DQS_NEAR_DIMM_NG_M_L_BYTE4\" )
					)
					( Units "uMatchProp" "ns" 1.000000)
					( Status sCSetFlattened )
					( Origin gBackEnd )
				)
				( attribute "RELATIVE_PROPAGATION_DELAY_SCOPE" "G"
					( Parent
						( matchGroupRef "@crescent_city_bb_fab1_lib.crescent_city_bb_fab1(sch_1):\MG_DQ_NEAR_DIMM_NG_M_L_BYTE4\" )
					)
					( Status sCSetFlattened )
					( Origin gBackEnd )
				)
				( attribute "RELATIVE_PROPAGATION_DELAY" "-50.00 MIL,50.00 MIL"
					( Parent
						( matchGroupRef "@crescent_city_bb_fab1_lib.crescent_city_bb_fab1(sch_1):\MG_DQ_NEAR_DIMM_NG_M_L_BYTE4\" )
					)
					( Units "uMatchProp" "ns" 1.000000)
					( Status sCSetFlattened )
					( Origin gBackEnd )
				)
			)
			( pinPair "@baseboard_fab2_lib.baseboard_fab2(sch_1):\PP1981\"
				( pinRef "@baseboard_fab2_lib.baseboard_fab2(sch_1):page61_i172:DDR4_DQ(38)" )
				( pinRef "@baseboard_fab2_lib.baseboard_fab2(sch_1):page85_i111:DQ(39)" )
				( attribute "RELATIVE_PROPAGATION_DELAY_SCOPE" "G"
					( Parent
						( matchGroupRef "@baseboard_fab2_lib.baseboard_fab2(sch_1):\MG_DQ-DQS_FAR_DIMM_NG_M_L_BYTE4\" )
					)
					( Status sCSetFlattened )
					( Origin gBackEnd )
				)
				( attribute "RELATIVE_PROPAGATION_DELAY" "0.00 MIL,195.00 MIL"
					( Parent
						( matchGroupRef "@baseboard_fab2_lib.baseboard_fab2(sch_1):\MG_DQ-DQS_FAR_DIMM_NG_M_L_BYTE4\" )
					)
					( Units "uMatchProp" "ns" 1.000000)
					( Status sCSetFlattened )
					( Origin gBackEnd )
				)
				( attribute "RELATIVE_PROPAGATION_DELAY_SCOPE" "G"
					( Parent
						( matchGroupRef "@crescent_city_bb_fab1_lib.crescent_city_bb_fab1(sch_1):\MG_DQ_FAR_DIMM_NG_M_L_BYTE4\" )
					)
					( Origin gBackEnd )
				)
				( attribute "RELATIVE_PROPAGATION_DELAY" "TARGET,TARGET"
					( Parent
						( matchGroupRef "@crescent_city_bb_fab1_lib.crescent_city_bb_fab1(sch_1):\MG_DQ_FAR_DIMM_NG_M_L_BYTE4\" )
					)
					( Units "uMatchProp" "ns" 1.000000)
					( Origin gBackEnd )
				)
			)
			( pinPair "@baseboard_fab2_lib.baseboard_fab2(sch_1):\PP1983\"
				( pinRef "@baseboard_fab2_lib.baseboard_fab2(sch_1):page61_i172:DDR4_DQ(38)" )
				( pinRef "@baseboard_fab2_lib.baseboard_fab2(sch_1):page86_i12:DQ(38)" )
				( attribute "RELATIVE_PROPAGATION_DELAY_SCOPE" "G"
					( Parent
						( matchGroupRef "@baseboard_fab2_lib.baseboard_fab2(sch_1):\MG_DQ-DQS_NEAR_DIMM_NG_M_L_BYTE4\" )
					)
					( Status sCSetFlattened )
					( Origin gBackEnd )
				)
				( attribute "RELATIVE_PROPAGATION_DELAY" "0.00 MIL,195.00 MIL"
					( Parent
						( matchGroupRef "@baseboard_fab2_lib.baseboard_fab2(sch_1):\MG_DQ-DQS_NEAR_DIMM_NG_M_L_BYTE4\" )
					)
					( Units "uMatchProp" "ns" 1.000000)
					( Status sCSetFlattened )
					( Origin gBackEnd )
				)
				( attribute "RELATIVE_PROPAGATION_DELAY_SCOPE" "G"
					( Parent
						( matchGroupRef "@crescent_city_bb_fab1_lib.crescent_city_bb_fab1(sch_1):\MG_DQ_NEAR_DIMM_NG_M_L_BYTE4\" )
					)
					( Status sCSetFlattened )
					( Origin gBackEnd )
				)
				( attribute "RELATIVE_PROPAGATION_DELAY" "-50.00 MIL,50.00 MIL"
					( Parent
						( matchGroupRef "@crescent_city_bb_fab1_lib.crescent_city_bb_fab1(sch_1):\MG_DQ_NEAR_DIMM_NG_M_L_BYTE4\" )
					)
					( Units "uMatchProp" "ns" 1.000000)
					( Status sCSetFlattened )
					( Origin gBackEnd )
				)
			)
			( pinPair "@baseboard_fab2_lib.baseboard_fab2(sch_1):\PP1984\"
				( pinRef "@baseboard_fab2_lib.baseboard_fab2(sch_1):page61_i172:DDR4_DQ(39)" )
				( pinRef "@baseboard_fab2_lib.baseboard_fab2(sch_1):page85_i111:DQ(38)" )
				( attribute "RELATIVE_PROPAGATION_DELAY_SCOPE" "G"
					( Parent
						( matchGroupRef "@baseboard_fab2_lib.baseboard_fab2(sch_1):\MG_DQ-DQS_FAR_DIMM_NG_M_L_BYTE4\" )
					)
					( Status sCSetFlattened )
					( Origin gBackEnd )
				)
				( attribute "RELATIVE_PROPAGATION_DELAY" "0.00 MIL,195.00 MIL"
					( Parent
						( matchGroupRef "@baseboard_fab2_lib.baseboard_fab2(sch_1):\MG_DQ-DQS_FAR_DIMM_NG_M_L_BYTE4\" )
					)
					( Units "uMatchProp" "ns" 1.000000)
					( Status sCSetFlattened )
					( Origin gBackEnd )
				)
				( attribute "RELATIVE_PROPAGATION_DELAY_SCOPE" "G"
					( Parent
						( matchGroupRef "@crescent_city_bb_fab1_lib.crescent_city_bb_fab1(sch_1):\MG_DQ_FAR_DIMM_NG_M_L_BYTE4\" )
					)
					( Status sCSetFlattened )
					( Origin gBackEnd )
				)
				( attribute "RELATIVE_PROPAGATION_DELAY" "-50.00 MIL,50.00 MIL"
					( Parent
						( matchGroupRef "@crescent_city_bb_fab1_lib.crescent_city_bb_fab1(sch_1):\MG_DQ_FAR_DIMM_NG_M_L_BYTE4\" )
					)
					( Units "uMatchProp" "ns" 1.000000)
					( Status sCSetFlattened )
					( Origin gBackEnd )
				)
			)
			( pinPair "@baseboard_fab2_lib.baseboard_fab2(sch_1):\PP1986\"
				( pinRef "@baseboard_fab2_lib.baseboard_fab2(sch_1):page61_i172:DDR4_DQ(39)" )
				( pinRef "@baseboard_fab2_lib.baseboard_fab2(sch_1):page86_i12:DQ(39)" )
				( attribute "RELATIVE_PROPAGATION_DELAY_SCOPE" "G"
					( Parent
						( matchGroupRef "@baseboard_fab2_lib.baseboard_fab2(sch_1):\MG_DQ-DQS_NEAR_DIMM_NG_M_L_BYTE4\" )
					)
					( Status sCSetFlattened )
					( Origin gBackEnd )
				)
				( attribute "RELATIVE_PROPAGATION_DELAY" "0.00 MIL,195.00 MIL"
					( Parent
						( matchGroupRef "@baseboard_fab2_lib.baseboard_fab2(sch_1):\MG_DQ-DQS_NEAR_DIMM_NG_M_L_BYTE4\" )
					)
					( Units "uMatchProp" "ns" 1.000000)
					( Status sCSetFlattened )
					( Origin gBackEnd )
				)
				( attribute "RELATIVE_PROPAGATION_DELAY_SCOPE" "G"
					( Parent
						( matchGroupRef "@crescent_city_bb_fab1_lib.crescent_city_bb_fab1(sch_1):\MG_DQ_NEAR_DIMM_NG_M_L_BYTE4\" )
					)
					( Status sCSetFlattened )
					( Origin gBackEnd )
				)
				( attribute "RELATIVE_PROPAGATION_DELAY" "-50.00 MIL,50.00 MIL"
					( Parent
						( matchGroupRef "@crescent_city_bb_fab1_lib.crescent_city_bb_fab1(sch_1):\MG_DQ_NEAR_DIMM_NG_M_L_BYTE4\" )
					)
					( Units "uMatchProp" "ns" 1.000000)
					( Status sCSetFlattened )
					( Origin gBackEnd )
				)
			)
			( pinPair "@baseboard_fab2_lib.baseboard_fab2(sch_1):\PP1939\"
				( pinRef "@baseboard_fab2_lib.baseboard_fab2(sch_1):page61_i172:DDR4_DQ(40)" )
				( pinRef "@baseboard_fab2_lib.baseboard_fab2(sch_1):page85_i111:DQ(41)" )
				( attribute "RELATIVE_PROPAGATION_DELAY_SCOPE" "G"
					( Parent
						( matchGroupRef "@baseboard_fab2_lib.baseboard_fab2(sch_1):\MG_DQ-DQS_FAR_DIMM_NG_M_L_BYTE5\" )
					)
					( Status sCSetFlattened )
					( Origin gBackEnd )
				)
				( attribute "RELATIVE_PROPAGATION_DELAY" "0.00 MIL,195.00 MIL"
					( Parent
						( matchGroupRef "@baseboard_fab2_lib.baseboard_fab2(sch_1):\MG_DQ-DQS_FAR_DIMM_NG_M_L_BYTE5\" )
					)
					( Units "uMatchProp" "ns" 1.000000)
					( Status sCSetFlattened )
					( Origin gBackEnd )
				)
				( attribute "RELATIVE_PROPAGATION_DELAY_SCOPE" "G"
					( Parent
						( matchGroupRef "@baseboard_fab2_lib.baseboard_fab2(sch_1):\MG_DQ_FAR_DIMM_NG_M_L_BYTE5\" )
					)
					( Status sCSetFlattened )
					( Origin gBackEnd )
				)
				( attribute "RELATIVE_PROPAGATION_DELAY" "-50.00 MIL,50.00 MIL"
					( Parent
						( matchGroupRef "@baseboard_fab2_lib.baseboard_fab2(sch_1):\MG_DQ_FAR_DIMM_NG_M_L_BYTE5\" )
					)
					( Units "uMatchProp" "ns" 1.000000)
					( Status sCSetFlattened )
					( Origin gBackEnd )
				)
			)
			( pinPair "@baseboard_fab2_lib.baseboard_fab2(sch_1):\PP1941\"
				( pinRef "@baseboard_fab2_lib.baseboard_fab2(sch_1):page61_i172:DDR4_DQ(40)" )
				( pinRef "@baseboard_fab2_lib.baseboard_fab2(sch_1):page86_i12:DQ(40)" )
				( attribute "RELATIVE_PROPAGATION_DELAY_SCOPE" "G"
					( Parent
						( matchGroupRef "@baseboard_fab2_lib.baseboard_fab2(sch_1):\MG_DQ-DQS_NEAR_DIMM_NG_M_L_BYTE5\" )
					)
					( Status sCSetFlattened )
					( Origin gBackEnd )
				)
				( attribute "RELATIVE_PROPAGATION_DELAY" "0.00 MIL,195.00 MIL"
					( Parent
						( matchGroupRef "@baseboard_fab2_lib.baseboard_fab2(sch_1):\MG_DQ-DQS_NEAR_DIMM_NG_M_L_BYTE5\" )
					)
					( Units "uMatchProp" "ns" 1.000000)
					( Status sCSetFlattened )
					( Origin gBackEnd )
				)
				( attribute "RELATIVE_PROPAGATION_DELAY_SCOPE" "G"
					( Parent
						( matchGroupRef "@baseboard_fab2_lib.baseboard_fab2(sch_1):\MG_DQ_NEAR_DIMM_NG_M_L_BYTE5\" )
					)
					( Status sCSetFlattened )
					( Origin gBackEnd )
				)
				( attribute "RELATIVE_PROPAGATION_DELAY" "-50.00 MIL,50.00 MIL"
					( Parent
						( matchGroupRef "@baseboard_fab2_lib.baseboard_fab2(sch_1):\MG_DQ_NEAR_DIMM_NG_M_L_BYTE5\" )
					)
					( Units "uMatchProp" "ns" 1.000000)
					( Status sCSetFlattened )
					( Origin gBackEnd )
				)
			)
			( pinPair "@baseboard_fab2_lib.baseboard_fab2(sch_1):\PP1942\"
				( pinRef "@baseboard_fab2_lib.baseboard_fab2(sch_1):page61_i172:DDR4_DQ(41)" )
				( pinRef "@baseboard_fab2_lib.baseboard_fab2(sch_1):page85_i111:DQ(40)" )
				( attribute "RELATIVE_PROPAGATION_DELAY_SCOPE" "G"
					( Parent
						( matchGroupRef "@baseboard_fab2_lib.baseboard_fab2(sch_1):\MG_DQ-DQS_FAR_DIMM_NG_M_L_BYTE5\" )
					)
					( Status sCSetFlattened )
					( Origin gBackEnd )
				)
				( attribute "RELATIVE_PROPAGATION_DELAY" "0.00 MIL,195.00 MIL"
					( Parent
						( matchGroupRef "@baseboard_fab2_lib.baseboard_fab2(sch_1):\MG_DQ-DQS_FAR_DIMM_NG_M_L_BYTE5\" )
					)
					( Units "uMatchProp" "ns" 1.000000)
					( Status sCSetFlattened )
					( Origin gBackEnd )
				)
				( attribute "RELATIVE_PROPAGATION_DELAY_SCOPE" "G"
					( Parent
						( matchGroupRef "@baseboard_fab2_lib.baseboard_fab2(sch_1):\MG_DQ_FAR_DIMM_NG_M_L_BYTE5\" )
					)
					( Status sCSetFlattened )
					( Origin gBackEnd )
				)
				( attribute "RELATIVE_PROPAGATION_DELAY" "-50.00 MIL,50.00 MIL"
					( Parent
						( matchGroupRef "@baseboard_fab2_lib.baseboard_fab2(sch_1):\MG_DQ_FAR_DIMM_NG_M_L_BYTE5\" )
					)
					( Units "uMatchProp" "ns" 1.000000)
					( Status sCSetFlattened )
					( Origin gBackEnd )
				)
			)
			( pinPair "@baseboard_fab2_lib.baseboard_fab2(sch_1):\PP1944\"
				( pinRef "@baseboard_fab2_lib.baseboard_fab2(sch_1):page61_i172:DDR4_DQ(41)" )
				( pinRef "@baseboard_fab2_lib.baseboard_fab2(sch_1):page86_i12:DQ(41)" )
				( attribute "RELATIVE_PROPAGATION_DELAY_SCOPE" "G"
					( Parent
						( matchGroupRef "@baseboard_fab2_lib.baseboard_fab2(sch_1):\MG_DQ-DQS_NEAR_DIMM_NG_M_L_BYTE5\" )
					)
					( Status sCSetFlattened )
					( Origin gBackEnd )
				)
				( attribute "RELATIVE_PROPAGATION_DELAY" "0.00 MIL,195.00 MIL"
					( Parent
						( matchGroupRef "@baseboard_fab2_lib.baseboard_fab2(sch_1):\MG_DQ-DQS_NEAR_DIMM_NG_M_L_BYTE5\" )
					)
					( Units "uMatchProp" "ns" 1.000000)
					( Status sCSetFlattened )
					( Origin gBackEnd )
				)
				( attribute "RELATIVE_PROPAGATION_DELAY_SCOPE" "G"
					( Parent
						( matchGroupRef "@baseboard_fab2_lib.baseboard_fab2(sch_1):\MG_DQ_NEAR_DIMM_NG_M_L_BYTE5\" )
					)
					( Status sCSetFlattened )
					( Origin gBackEnd )
				)
				( attribute "RELATIVE_PROPAGATION_DELAY" "-50.00 MIL,50.00 MIL"
					( Parent
						( matchGroupRef "@baseboard_fab2_lib.baseboard_fab2(sch_1):\MG_DQ_NEAR_DIMM_NG_M_L_BYTE5\" )
					)
					( Units "uMatchProp" "ns" 1.000000)
					( Status sCSetFlattened )
					( Origin gBackEnd )
				)
			)
			( pinPair "@baseboard_fab2_lib.baseboard_fab2(sch_1):\PP1945\"
				( pinRef "@baseboard_fab2_lib.baseboard_fab2(sch_1):page61_i172:DDR4_DQ(42)" )
				( pinRef "@baseboard_fab2_lib.baseboard_fab2(sch_1):page85_i111:DQ(43)" )
				( attribute "RELATIVE_PROPAGATION_DELAY_SCOPE" "G"
					( Parent
						( matchGroupRef "@baseboard_fab2_lib.baseboard_fab2(sch_1):\MG_DQ-DQS_FAR_DIMM_NG_M_L_BYTE5\" )
					)
					( Status sCSetFlattened )
					( Origin gBackEnd )
				)
				( attribute "RELATIVE_PROPAGATION_DELAY" "0.00 MIL,195.00 MIL"
					( Parent
						( matchGroupRef "@baseboard_fab2_lib.baseboard_fab2(sch_1):\MG_DQ-DQS_FAR_DIMM_NG_M_L_BYTE5\" )
					)
					( Units "uMatchProp" "ns" 1.000000)
					( Status sCSetFlattened )
					( Origin gBackEnd )
				)
				( attribute "RELATIVE_PROPAGATION_DELAY_SCOPE" "G"
					( Parent
						( matchGroupRef "@baseboard_fab2_lib.baseboard_fab2(sch_1):\MG_DQ_FAR_DIMM_NG_M_L_BYTE5\" )
					)
					( Status sCSetFlattened )
					( Origin gBackEnd )
				)
				( attribute "RELATIVE_PROPAGATION_DELAY" "-50.00 MIL,50.00 MIL"
					( Parent
						( matchGroupRef "@baseboard_fab2_lib.baseboard_fab2(sch_1):\MG_DQ_FAR_DIMM_NG_M_L_BYTE5\" )
					)
					( Units "uMatchProp" "ns" 1.000000)
					( Status sCSetFlattened )
					( Origin gBackEnd )
				)
			)
			( pinPair "@baseboard_fab2_lib.baseboard_fab2(sch_1):\PP1947\"
				( pinRef "@baseboard_fab2_lib.baseboard_fab2(sch_1):page61_i172:DDR4_DQ(42)" )
				( pinRef "@baseboard_fab2_lib.baseboard_fab2(sch_1):page86_i12:DQ(42)" )
				( attribute "RELATIVE_PROPAGATION_DELAY_SCOPE" "G"
					( Parent
						( matchGroupRef "@baseboard_fab2_lib.baseboard_fab2(sch_1):\MG_DQ-DQS_NEAR_DIMM_NG_M_L_BYTE5\" )
					)
					( Status sCSetFlattened )
					( Origin gBackEnd )
				)
				( attribute "RELATIVE_PROPAGATION_DELAY" "0.00 MIL,195.00 MIL"
					( Parent
						( matchGroupRef "@baseboard_fab2_lib.baseboard_fab2(sch_1):\MG_DQ-DQS_NEAR_DIMM_NG_M_L_BYTE5\" )
					)
					( Units "uMatchProp" "ns" 1.000000)
					( Status sCSetFlattened )
					( Origin gBackEnd )
				)
				( attribute "RELATIVE_PROPAGATION_DELAY_SCOPE" "G"
					( Parent
						( matchGroupRef "@baseboard_fab2_lib.baseboard_fab2(sch_1):\MG_DQ_NEAR_DIMM_NG_M_L_BYTE5\" )
					)
					( Status sCSetFlattened )
					( Origin gBackEnd )
				)
				( attribute "RELATIVE_PROPAGATION_DELAY" "-50.00 MIL,50.00 MIL"
					( Parent
						( matchGroupRef "@baseboard_fab2_lib.baseboard_fab2(sch_1):\MG_DQ_NEAR_DIMM_NG_M_L_BYTE5\" )
					)
					( Units "uMatchProp" "ns" 1.000000)
					( Status sCSetFlattened )
					( Origin gBackEnd )
				)
			)
			( pinPair "@baseboard_fab2_lib.baseboard_fab2(sch_1):\PP1948\"
				( pinRef "@baseboard_fab2_lib.baseboard_fab2(sch_1):page61_i172:DDR4_DQ(43)" )
				( pinRef "@baseboard_fab2_lib.baseboard_fab2(sch_1):page85_i111:DQ(42)" )
				( attribute "RELATIVE_PROPAGATION_DELAY_SCOPE" "G"
					( Parent
						( matchGroupRef "@baseboard_fab2_lib.baseboard_fab2(sch_1):\MG_DQ-DQS_FAR_DIMM_NG_M_L_BYTE5\" )
					)
					( Status sCSetFlattened )
					( Origin gBackEnd )
				)
				( attribute "RELATIVE_PROPAGATION_DELAY" "0.00 MIL,195.00 MIL"
					( Parent
						( matchGroupRef "@baseboard_fab2_lib.baseboard_fab2(sch_1):\MG_DQ-DQS_FAR_DIMM_NG_M_L_BYTE5\" )
					)
					( Units "uMatchProp" "ns" 1.000000)
					( Status sCSetFlattened )
					( Origin gBackEnd )
				)
				( attribute "RELATIVE_PROPAGATION_DELAY_SCOPE" "G"
					( Parent
						( matchGroupRef "@baseboard_fab2_lib.baseboard_fab2(sch_1):\MG_DQ_FAR_DIMM_NG_M_L_BYTE5\" )
					)
					( Status sCSetFlattened )
					( Origin gBackEnd )
				)
				( attribute "RELATIVE_PROPAGATION_DELAY" "-50.00 MIL,50.00 MIL"
					( Parent
						( matchGroupRef "@baseboard_fab2_lib.baseboard_fab2(sch_1):\MG_DQ_FAR_DIMM_NG_M_L_BYTE5\" )
					)
					( Units "uMatchProp" "ns" 1.000000)
					( Status sCSetFlattened )
					( Origin gBackEnd )
				)
			)
			( pinPair "@baseboard_fab2_lib.baseboard_fab2(sch_1):\PP1950\"
				( pinRef "@baseboard_fab2_lib.baseboard_fab2(sch_1):page61_i172:DDR4_DQ(43)" )
				( pinRef "@baseboard_fab2_lib.baseboard_fab2(sch_1):page86_i12:DQ(43)" )
				( attribute "RELATIVE_PROPAGATION_DELAY_SCOPE" "G"
					( Parent
						( matchGroupRef "@baseboard_fab2_lib.baseboard_fab2(sch_1):\MG_DQ-DQS_NEAR_DIMM_NG_M_L_BYTE5\" )
					)
					( Status sCSetFlattened )
					( Origin gBackEnd )
				)
				( attribute "RELATIVE_PROPAGATION_DELAY" "0.00 MIL,195.00 MIL"
					( Parent
						( matchGroupRef "@baseboard_fab2_lib.baseboard_fab2(sch_1):\MG_DQ-DQS_NEAR_DIMM_NG_M_L_BYTE5\" )
					)
					( Units "uMatchProp" "ns" 1.000000)
					( Status sCSetFlattened )
					( Origin gBackEnd )
				)
				( attribute "RELATIVE_PROPAGATION_DELAY_SCOPE" "G"
					( Parent
						( matchGroupRef "@baseboard_fab2_lib.baseboard_fab2(sch_1):\MG_DQ_NEAR_DIMM_NG_M_L_BYTE5\" )
					)
					( Status sCSetFlattened )
					( Origin gBackEnd )
				)
				( attribute "RELATIVE_PROPAGATION_DELAY" "-50.00 MIL,50.00 MIL"
					( Parent
						( matchGroupRef "@baseboard_fab2_lib.baseboard_fab2(sch_1):\MG_DQ_NEAR_DIMM_NG_M_L_BYTE5\" )
					)
					( Units "uMatchProp" "ns" 1.000000)
					( Status sCSetFlattened )
					( Origin gBackEnd )
				)
			)
			( pinPair "@baseboard_fab2_lib.baseboard_fab2(sch_1):\PP1951\"
				( pinRef "@baseboard_fab2_lib.baseboard_fab2(sch_1):page61_i172:DDR4_DQ(44)" )
				( pinRef "@baseboard_fab2_lib.baseboard_fab2(sch_1):page85_i111:DQ(45)" )
				( attribute "RELATIVE_PROPAGATION_DELAY_SCOPE" "G"
					( Parent
						( matchGroupRef "@baseboard_fab2_lib.baseboard_fab2(sch_1):\MG_DQ-DQS_FAR_DIMM_NG_M_L_BYTE5\" )
					)
					( Status sCSetFlattened )
					( Origin gBackEnd )
				)
				( attribute "RELATIVE_PROPAGATION_DELAY" "0.00 MIL,195.00 MIL"
					( Parent
						( matchGroupRef "@baseboard_fab2_lib.baseboard_fab2(sch_1):\MG_DQ-DQS_FAR_DIMM_NG_M_L_BYTE5\" )
					)
					( Units "uMatchProp" "ns" 1.000000)
					( Status sCSetFlattened )
					( Origin gBackEnd )
				)
				( attribute "RELATIVE_PROPAGATION_DELAY_SCOPE" "G"
					( Parent
						( matchGroupRef "@baseboard_fab2_lib.baseboard_fab2(sch_1):\MG_DQ_FAR_DIMM_NG_M_L_BYTE5\" )
					)
					( Status sCSetFlattened )
					( Origin gBackEnd )
				)
				( attribute "RELATIVE_PROPAGATION_DELAY" "-50.00 MIL,50.00 MIL"
					( Parent
						( matchGroupRef "@baseboard_fab2_lib.baseboard_fab2(sch_1):\MG_DQ_FAR_DIMM_NG_M_L_BYTE5\" )
					)
					( Units "uMatchProp" "ns" 1.000000)
					( Status sCSetFlattened )
					( Origin gBackEnd )
				)
			)
			( pinPair "@baseboard_fab2_lib.baseboard_fab2(sch_1):\PP1953\"
				( pinRef "@baseboard_fab2_lib.baseboard_fab2(sch_1):page61_i172:DDR4_DQ(44)" )
				( pinRef "@baseboard_fab2_lib.baseboard_fab2(sch_1):page86_i12:DQ(44)" )
				( attribute "RELATIVE_PROPAGATION_DELAY_SCOPE" "G"
					( Parent
						( matchGroupRef "@baseboard_fab2_lib.baseboard_fab2(sch_1):\MG_DQ-DQS_NEAR_DIMM_NG_M_L_BYTE5\" )
					)
					( Status sCSetFlattened )
					( Origin gBackEnd )
				)
				( attribute "RELATIVE_PROPAGATION_DELAY" "0.00 MIL,195.00 MIL"
					( Parent
						( matchGroupRef "@baseboard_fab2_lib.baseboard_fab2(sch_1):\MG_DQ-DQS_NEAR_DIMM_NG_M_L_BYTE5\" )
					)
					( Units "uMatchProp" "ns" 1.000000)
					( Status sCSetFlattened )
					( Origin gBackEnd )
				)
				( attribute "RELATIVE_PROPAGATION_DELAY_SCOPE" "G"
					( Parent
						( matchGroupRef "@baseboard_fab2_lib.baseboard_fab2(sch_1):\MG_DQ_NEAR_DIMM_NG_M_L_BYTE5\" )
					)
					( Status sCSetFlattened )
					( Origin gBackEnd )
				)
				( attribute "RELATIVE_PROPAGATION_DELAY" "-50.00 MIL,50.00 MIL"
					( Parent
						( matchGroupRef "@baseboard_fab2_lib.baseboard_fab2(sch_1):\MG_DQ_NEAR_DIMM_NG_M_L_BYTE5\" )
					)
					( Units "uMatchProp" "ns" 1.000000)
					( Status sCSetFlattened )
					( Origin gBackEnd )
				)
			)
			( pinPair "@baseboard_fab2_lib.baseboard_fab2(sch_1):\PP1954\"
				( pinRef "@baseboard_fab2_lib.baseboard_fab2(sch_1):page61_i172:DDR4_DQ(45)" )
				( pinRef "@baseboard_fab2_lib.baseboard_fab2(sch_1):page85_i111:DQ(44)" )
				( attribute "RELATIVE_PROPAGATION_DELAY_SCOPE" "G"
					( Parent
						( matchGroupRef "@baseboard_fab2_lib.baseboard_fab2(sch_1):\MG_DQ-DQS_FAR_DIMM_NG_M_L_BYTE5\" )
					)
					( Status sCSetFlattened )
					( Origin gBackEnd )
				)
				( attribute "RELATIVE_PROPAGATION_DELAY" "0.00 MIL,195.00 MIL"
					( Parent
						( matchGroupRef "@baseboard_fab2_lib.baseboard_fab2(sch_1):\MG_DQ-DQS_FAR_DIMM_NG_M_L_BYTE5\" )
					)
					( Units "uMatchProp" "ns" 1.000000)
					( Status sCSetFlattened )
					( Origin gBackEnd )
				)
				( attribute "RELATIVE_PROPAGATION_DELAY_SCOPE" "G"
					( Parent
						( matchGroupRef "@baseboard_fab2_lib.baseboard_fab2(sch_1):\MG_DQ_FAR_DIMM_NG_M_L_BYTE5\" )
					)
					( Status sCSetFlattened )
					( Origin gBackEnd )
				)
				( attribute "RELATIVE_PROPAGATION_DELAY" "-50.00 MIL,50.00 MIL"
					( Parent
						( matchGroupRef "@baseboard_fab2_lib.baseboard_fab2(sch_1):\MG_DQ_FAR_DIMM_NG_M_L_BYTE5\" )
					)
					( Units "uMatchProp" "ns" 1.000000)
					( Status sCSetFlattened )
					( Origin gBackEnd )
				)
			)
			( pinPair "@baseboard_fab2_lib.baseboard_fab2(sch_1):\PP1956\"
				( pinRef "@baseboard_fab2_lib.baseboard_fab2(sch_1):page61_i172:DDR4_DQ(45)" )
				( pinRef "@baseboard_fab2_lib.baseboard_fab2(sch_1):page86_i12:DQ(45)" )
				( attribute "RELATIVE_PROPAGATION_DELAY_SCOPE" "G"
					( Parent
						( matchGroupRef "@baseboard_fab2_lib.baseboard_fab2(sch_1):\MG_DQ-DQS_NEAR_DIMM_NG_M_L_BYTE5\" )
					)
					( Status sCSetFlattened )
					( Origin gBackEnd )
				)
				( attribute "RELATIVE_PROPAGATION_DELAY" "0.00 MIL,195.00 MIL"
					( Parent
						( matchGroupRef "@baseboard_fab2_lib.baseboard_fab2(sch_1):\MG_DQ-DQS_NEAR_DIMM_NG_M_L_BYTE5\" )
					)
					( Units "uMatchProp" "ns" 1.000000)
					( Status sCSetFlattened )
					( Origin gBackEnd )
				)
				( attribute "RELATIVE_PROPAGATION_DELAY_SCOPE" "G"
					( Parent
						( matchGroupRef "@baseboard_fab2_lib.baseboard_fab2(sch_1):\MG_DQ_NEAR_DIMM_NG_M_L_BYTE5\" )
					)
					( Status sCSetFlattened )
					( Origin gBackEnd )
				)
				( attribute "RELATIVE_PROPAGATION_DELAY" "-50.00 MIL,50.00 MIL"
					( Parent
						( matchGroupRef "@baseboard_fab2_lib.baseboard_fab2(sch_1):\MG_DQ_NEAR_DIMM_NG_M_L_BYTE5\" )
					)
					( Units "uMatchProp" "ns" 1.000000)
					( Status sCSetFlattened )
					( Origin gBackEnd )
				)
			)
			( pinPair "@baseboard_fab2_lib.baseboard_fab2(sch_1):\PP1957\"
				( pinRef "@baseboard_fab2_lib.baseboard_fab2(sch_1):page61_i172:DDR4_DQ(46)" )
				( pinRef "@baseboard_fab2_lib.baseboard_fab2(sch_1):page85_i111:DQ(47)" )
				( attribute "RELATIVE_PROPAGATION_DELAY_SCOPE" "G"
					( Parent
						( matchGroupRef "@baseboard_fab2_lib.baseboard_fab2(sch_1):\MG_DQ-DQS_FAR_DIMM_NG_M_L_BYTE5\" )
					)
					( Status sCSetFlattened )
					( Origin gBackEnd )
				)
				( attribute "RELATIVE_PROPAGATION_DELAY" "0.00 MIL,195.00 MIL"
					( Parent
						( matchGroupRef "@baseboard_fab2_lib.baseboard_fab2(sch_1):\MG_DQ-DQS_FAR_DIMM_NG_M_L_BYTE5\" )
					)
					( Units "uMatchProp" "ns" 1.000000)
					( Status sCSetFlattened )
					( Origin gBackEnd )
				)
				( attribute "RELATIVE_PROPAGATION_DELAY_SCOPE" "G"
					( Parent
						( matchGroupRef "@baseboard_fab2_lib.baseboard_fab2(sch_1):\MG_DQ_FAR_DIMM_NG_M_L_BYTE5\" )
					)
					( Status sCSetFlattened )
					( Origin gBackEnd )
				)
				( attribute "RELATIVE_PROPAGATION_DELAY" "-50.00 MIL,50.00 MIL"
					( Parent
						( matchGroupRef "@baseboard_fab2_lib.baseboard_fab2(sch_1):\MG_DQ_FAR_DIMM_NG_M_L_BYTE5\" )
					)
					( Units "uMatchProp" "ns" 1.000000)
					( Status sCSetFlattened )
					( Origin gBackEnd )
				)
			)
			( pinPair "@baseboard_fab2_lib.baseboard_fab2(sch_1):\PP1959\"
				( pinRef "@baseboard_fab2_lib.baseboard_fab2(sch_1):page61_i172:DDR4_DQ(46)" )
				( pinRef "@baseboard_fab2_lib.baseboard_fab2(sch_1):page86_i12:DQ(46)" )
				( attribute "RELATIVE_PROPAGATION_DELAY_SCOPE" "G"
					( Parent
						( matchGroupRef "@baseboard_fab2_lib.baseboard_fab2(sch_1):\MG_DQ-DQS_NEAR_DIMM_NG_M_L_BYTE5\" )
					)
					( Status sCSetFlattened )
					( Origin gBackEnd )
				)
				( attribute "RELATIVE_PROPAGATION_DELAY" "0.00 MIL,195.00 MIL"
					( Parent
						( matchGroupRef "@baseboard_fab2_lib.baseboard_fab2(sch_1):\MG_DQ-DQS_NEAR_DIMM_NG_M_L_BYTE5\" )
					)
					( Units "uMatchProp" "ns" 1.000000)
					( Status sCSetFlattened )
					( Origin gBackEnd )
				)
				( attribute "RELATIVE_PROPAGATION_DELAY_SCOPE" "G"
					( Parent
						( matchGroupRef "@baseboard_fab2_lib.baseboard_fab2(sch_1):\MG_DQ_NEAR_DIMM_NG_M_L_BYTE5\" )
					)
					( Status sCSetFlattened )
					( Origin gBackEnd )
				)
				( attribute "RELATIVE_PROPAGATION_DELAY" "-50.00 MIL,50.00 MIL"
					( Parent
						( matchGroupRef "@baseboard_fab2_lib.baseboard_fab2(sch_1):\MG_DQ_NEAR_DIMM_NG_M_L_BYTE5\" )
					)
					( Units "uMatchProp" "ns" 1.000000)
					( Status sCSetFlattened )
					( Origin gBackEnd )
				)
			)
			( pinPair "@baseboard_fab2_lib.baseboard_fab2(sch_1):\PP1960\"
				( pinRef "@baseboard_fab2_lib.baseboard_fab2(sch_1):page61_i172:DDR4_DQ(47)" )
				( pinRef "@baseboard_fab2_lib.baseboard_fab2(sch_1):page85_i111:DQ(46)" )
				( attribute "RELATIVE_PROPAGATION_DELAY_SCOPE" "G"
					( Parent
						( matchGroupRef "@baseboard_fab2_lib.baseboard_fab2(sch_1):\MG_DQ-DQS_FAR_DIMM_NG_M_L_BYTE5\" )
					)
					( Status sCSetFlattened )
					( Origin gBackEnd )
				)
				( attribute "RELATIVE_PROPAGATION_DELAY" "0.00 MIL,195.00 MIL"
					( Parent
						( matchGroupRef "@baseboard_fab2_lib.baseboard_fab2(sch_1):\MG_DQ-DQS_FAR_DIMM_NG_M_L_BYTE5\" )
					)
					( Units "uMatchProp" "ns" 1.000000)
					( Status sCSetFlattened )
					( Origin gBackEnd )
				)
				( attribute "RELATIVE_PROPAGATION_DELAY_SCOPE" "G"
					( Parent
						( matchGroupRef "@baseboard_fab2_lib.baseboard_fab2(sch_1):\MG_DQ_FAR_DIMM_NG_M_L_BYTE5\" )
					)
					( Status sCSetFlattened )
					( Origin gBackEnd )
				)
				( attribute "RELATIVE_PROPAGATION_DELAY" "-50.00 MIL,50.00 MIL"
					( Parent
						( matchGroupRef "@baseboard_fab2_lib.baseboard_fab2(sch_1):\MG_DQ_FAR_DIMM_NG_M_L_BYTE5\" )
					)
					( Units "uMatchProp" "ns" 1.000000)
					( Status sCSetFlattened )
					( Origin gBackEnd )
				)
			)
			( pinPair "@baseboard_fab2_lib.baseboard_fab2(sch_1):\PP1962\"
				( pinRef "@baseboard_fab2_lib.baseboard_fab2(sch_1):page61_i172:DDR4_DQ(47)" )
				( pinRef "@baseboard_fab2_lib.baseboard_fab2(sch_1):page86_i12:DQ(47)" )
				( attribute "RELATIVE_PROPAGATION_DELAY_SCOPE" "G"
					( Parent
						( matchGroupRef "@baseboard_fab2_lib.baseboard_fab2(sch_1):\MG_DQ-DQS_NEAR_DIMM_NG_M_L_BYTE5\" )
					)
					( Status sCSetFlattened )
					( Origin gBackEnd )
				)
				( attribute "RELATIVE_PROPAGATION_DELAY" "0.00 MIL,195.00 MIL"
					( Parent
						( matchGroupRef "@baseboard_fab2_lib.baseboard_fab2(sch_1):\MG_DQ-DQS_NEAR_DIMM_NG_M_L_BYTE5\" )
					)
					( Units "uMatchProp" "ns" 1.000000)
					( Status sCSetFlattened )
					( Origin gBackEnd )
				)
				( attribute "RELATIVE_PROPAGATION_DELAY_SCOPE" "G"
					( Parent
						( matchGroupRef "@baseboard_fab2_lib.baseboard_fab2(sch_1):\MG_DQ_NEAR_DIMM_NG_M_L_BYTE5\" )
					)
					( Status sCSetFlattened )
					( Origin gBackEnd )
				)
				( attribute "RELATIVE_PROPAGATION_DELAY" "-50.00 MIL,50.00 MIL"
					( Parent
						( matchGroupRef "@baseboard_fab2_lib.baseboard_fab2(sch_1):\MG_DQ_NEAR_DIMM_NG_M_L_BYTE5\" )
					)
					( Units "uMatchProp" "ns" 1.000000)
					( Status sCSetFlattened )
					( Origin gBackEnd )
				)
			)
			( pinPair "@baseboard_fab2_lib.baseboard_fab2(sch_1):\PP1915\"
				( pinRef "@baseboard_fab2_lib.baseboard_fab2(sch_1):page61_i172:DDR4_DQ(48)" )
				( pinRef "@baseboard_fab2_lib.baseboard_fab2(sch_1):page85_i111:DQ(49)" )
				( attribute "RELATIVE_PROPAGATION_DELAY_SCOPE" "G"
					( Parent
						( matchGroupRef "@baseboard_fab2_lib.baseboard_fab2(sch_1):\MG_DQ-DQS_FAR_DIMM_NG_M_L_BYTE6\" )
					)
					( Status sCSetFlattened )
					( Origin gBackEnd )
				)
				( attribute "RELATIVE_PROPAGATION_DELAY" "0.00 MIL,195.00 MIL"
					( Parent
						( matchGroupRef "@baseboard_fab2_lib.baseboard_fab2(sch_1):\MG_DQ-DQS_FAR_DIMM_NG_M_L_BYTE6\" )
					)
					( Units "uMatchProp" "ns" 1.000000)
					( Status sCSetFlattened )
					( Origin gBackEnd )
				)
				( attribute "RELATIVE_PROPAGATION_DELAY_SCOPE" "G"
					( Parent
						( matchGroupRef "@baseboard_fab2_lib.baseboard_fab2(sch_1):\MG_DQ_FAR_DIMM_NG_M_L_BYTE6\" )
					)
					( Status sCSetFlattened )
					( Origin gBackEnd )
				)
				( attribute "RELATIVE_PROPAGATION_DELAY" "-50.00 MIL,50.00 MIL"
					( Parent
						( matchGroupRef "@baseboard_fab2_lib.baseboard_fab2(sch_1):\MG_DQ_FAR_DIMM_NG_M_L_BYTE6\" )
					)
					( Units "uMatchProp" "ns" 1.000000)
					( Status sCSetFlattened )
					( Origin gBackEnd )
				)
			)
			( pinPair "@baseboard_fab2_lib.baseboard_fab2(sch_1):\PP1917\"
				( pinRef "@baseboard_fab2_lib.baseboard_fab2(sch_1):page61_i172:DDR4_DQ(48)" )
				( pinRef "@baseboard_fab2_lib.baseboard_fab2(sch_1):page86_i12:DQ(48)" )
				( attribute "RELATIVE_PROPAGATION_DELAY_SCOPE" "G"
					( Parent
						( matchGroupRef "@baseboard_fab2_lib.baseboard_fab2(sch_1):\MG_DQ-DQS_NEAR_DIMM_NG_M_L_BYTE6\" )
					)
					( Status sCSetFlattened )
					( Origin gBackEnd )
				)
				( attribute "RELATIVE_PROPAGATION_DELAY" "0.00 MIL,195.00 MIL"
					( Parent
						( matchGroupRef "@baseboard_fab2_lib.baseboard_fab2(sch_1):\MG_DQ-DQS_NEAR_DIMM_NG_M_L_BYTE6\" )
					)
					( Units "uMatchProp" "ns" 1.000000)
					( Status sCSetFlattened )
					( Origin gBackEnd )
				)
				( attribute "RELATIVE_PROPAGATION_DELAY_SCOPE" "G"
					( Parent
						( matchGroupRef "@baseboard_fab2_lib.baseboard_fab2(sch_1):\MG_DQ_NEAR_DIMM_NG_M_L_BYTE6\" )
					)
					( Status sCSetFlattened )
					( Origin gBackEnd )
				)
				( attribute "RELATIVE_PROPAGATION_DELAY" "-50.00 MIL,50.00 MIL"
					( Parent
						( matchGroupRef "@baseboard_fab2_lib.baseboard_fab2(sch_1):\MG_DQ_NEAR_DIMM_NG_M_L_BYTE6\" )
					)
					( Units "uMatchProp" "ns" 1.000000)
					( Status sCSetFlattened )
					( Origin gBackEnd )
				)
			)
			( pinPair "@baseboard_fab2_lib.baseboard_fab2(sch_1):\PP1918\"
				( pinRef "@baseboard_fab2_lib.baseboard_fab2(sch_1):page61_i172:DDR4_DQ(49)" )
				( pinRef "@baseboard_fab2_lib.baseboard_fab2(sch_1):page85_i111:DQ(48)" )
				( attribute "RELATIVE_PROPAGATION_DELAY_SCOPE" "G"
					( Parent
						( matchGroupRef "@baseboard_fab2_lib.baseboard_fab2(sch_1):\MG_DQ-DQS_FAR_DIMM_NG_M_L_BYTE6\" )
					)
					( Status sCSetFlattened )
					( Origin gBackEnd )
				)
				( attribute "RELATIVE_PROPAGATION_DELAY" "0.00 MIL,195.00 MIL"
					( Parent
						( matchGroupRef "@baseboard_fab2_lib.baseboard_fab2(sch_1):\MG_DQ-DQS_FAR_DIMM_NG_M_L_BYTE6\" )
					)
					( Units "uMatchProp" "ns" 1.000000)
					( Status sCSetFlattened )
					( Origin gBackEnd )
				)
				( attribute "RELATIVE_PROPAGATION_DELAY_SCOPE" "G"
					( Parent
						( matchGroupRef "@baseboard_fab2_lib.baseboard_fab2(sch_1):\MG_DQ_FAR_DIMM_NG_M_L_BYTE6\" )
					)
					( Status sCSetFlattened )
					( Origin gBackEnd )
				)
				( attribute "RELATIVE_PROPAGATION_DELAY" "-50.00 MIL,50.00 MIL"
					( Parent
						( matchGroupRef "@baseboard_fab2_lib.baseboard_fab2(sch_1):\MG_DQ_FAR_DIMM_NG_M_L_BYTE6\" )
					)
					( Units "uMatchProp" "ns" 1.000000)
					( Status sCSetFlattened )
					( Origin gBackEnd )
				)
			)
			( pinPair "@baseboard_fab2_lib.baseboard_fab2(sch_1):\PP1920\"
				( pinRef "@baseboard_fab2_lib.baseboard_fab2(sch_1):page61_i172:DDR4_DQ(49)" )
				( pinRef "@baseboard_fab2_lib.baseboard_fab2(sch_1):page86_i12:DQ(49)" )
				( attribute "RELATIVE_PROPAGATION_DELAY_SCOPE" "G"
					( Parent
						( matchGroupRef "@baseboard_fab2_lib.baseboard_fab2(sch_1):\MG_DQ-DQS_NEAR_DIMM_NG_M_L_BYTE6\" )
					)
					( Status sCSetFlattened )
					( Origin gBackEnd )
				)
				( attribute "RELATIVE_PROPAGATION_DELAY" "0.00 MIL,195.00 MIL"
					( Parent
						( matchGroupRef "@baseboard_fab2_lib.baseboard_fab2(sch_1):\MG_DQ-DQS_NEAR_DIMM_NG_M_L_BYTE6\" )
					)
					( Units "uMatchProp" "ns" 1.000000)
					( Status sCSetFlattened )
					( Origin gBackEnd )
				)
				( attribute "RELATIVE_PROPAGATION_DELAY_SCOPE" "G"
					( Parent
						( matchGroupRef "@baseboard_fab2_lib.baseboard_fab2(sch_1):\MG_DQ_NEAR_DIMM_NG_M_L_BYTE6\" )
					)
					( Status sCSetFlattened )
					( Origin gBackEnd )
				)
				( attribute "RELATIVE_PROPAGATION_DELAY" "-50.00 MIL,50.00 MIL"
					( Parent
						( matchGroupRef "@baseboard_fab2_lib.baseboard_fab2(sch_1):\MG_DQ_NEAR_DIMM_NG_M_L_BYTE6\" )
					)
					( Units "uMatchProp" "ns" 1.000000)
					( Status sCSetFlattened )
					( Origin gBackEnd )
				)
			)
			( pinPair "@baseboard_fab2_lib.baseboard_fab2(sch_1):\PP1921\"
				( pinRef "@baseboard_fab2_lib.baseboard_fab2(sch_1):page61_i172:DDR4_DQ(50)" )
				( pinRef "@baseboard_fab2_lib.baseboard_fab2(sch_1):page85_i111:DQ(51)" )
				( attribute "RELATIVE_PROPAGATION_DELAY_SCOPE" "G"
					( Parent
						( matchGroupRef "@baseboard_fab2_lib.baseboard_fab2(sch_1):\MG_DQ-DQS_FAR_DIMM_NG_M_L_BYTE6\" )
					)
					( Status sCSetFlattened )
					( Origin gBackEnd )
				)
				( attribute "RELATIVE_PROPAGATION_DELAY" "0.00 MIL,195.00 MIL"
					( Parent
						( matchGroupRef "@baseboard_fab2_lib.baseboard_fab2(sch_1):\MG_DQ-DQS_FAR_DIMM_NG_M_L_BYTE6\" )
					)
					( Units "uMatchProp" "ns" 1.000000)
					( Status sCSetFlattened )
					( Origin gBackEnd )
				)
				( attribute "RELATIVE_PROPAGATION_DELAY_SCOPE" "G"
					( Parent
						( matchGroupRef "@baseboard_fab2_lib.baseboard_fab2(sch_1):\MG_DQ_FAR_DIMM_NG_M_L_BYTE6\" )
					)
					( Status sCSetFlattened )
					( Origin gBackEnd )
				)
				( attribute "RELATIVE_PROPAGATION_DELAY" "-50.00 MIL,50.00 MIL"
					( Parent
						( matchGroupRef "@baseboard_fab2_lib.baseboard_fab2(sch_1):\MG_DQ_FAR_DIMM_NG_M_L_BYTE6\" )
					)
					( Units "uMatchProp" "ns" 1.000000)
					( Status sCSetFlattened )
					( Origin gBackEnd )
				)
			)
			( pinPair "@baseboard_fab2_lib.baseboard_fab2(sch_1):\PP1923\"
				( pinRef "@baseboard_fab2_lib.baseboard_fab2(sch_1):page61_i172:DDR4_DQ(50)" )
				( pinRef "@baseboard_fab2_lib.baseboard_fab2(sch_1):page86_i12:DQ(50)" )
				( attribute "RELATIVE_PROPAGATION_DELAY_SCOPE" "G"
					( Parent
						( matchGroupRef "@baseboard_fab2_lib.baseboard_fab2(sch_1):\MG_DQ-DQS_NEAR_DIMM_NG_M_L_BYTE6\" )
					)
					( Status sCSetFlattened )
					( Origin gBackEnd )
				)
				( attribute "RELATIVE_PROPAGATION_DELAY" "0.00 MIL,195.00 MIL"
					( Parent
						( matchGroupRef "@baseboard_fab2_lib.baseboard_fab2(sch_1):\MG_DQ-DQS_NEAR_DIMM_NG_M_L_BYTE6\" )
					)
					( Units "uMatchProp" "ns" 1.000000)
					( Status sCSetFlattened )
					( Origin gBackEnd )
				)
				( attribute "RELATIVE_PROPAGATION_DELAY_SCOPE" "G"
					( Parent
						( matchGroupRef "@baseboard_fab2_lib.baseboard_fab2(sch_1):\MG_DQ_NEAR_DIMM_NG_M_L_BYTE6\" )
					)
					( Status sCSetFlattened )
					( Origin gBackEnd )
				)
				( attribute "RELATIVE_PROPAGATION_DELAY" "-50.00 MIL,50.00 MIL"
					( Parent
						( matchGroupRef "@baseboard_fab2_lib.baseboard_fab2(sch_1):\MG_DQ_NEAR_DIMM_NG_M_L_BYTE6\" )
					)
					( Units "uMatchProp" "ns" 1.000000)
					( Status sCSetFlattened )
					( Origin gBackEnd )
				)
			)
			( pinPair "@baseboard_fab2_lib.baseboard_fab2(sch_1):\PP1924\"
				( pinRef "@baseboard_fab2_lib.baseboard_fab2(sch_1):page61_i172:DDR4_DQ(51)" )
				( pinRef "@baseboard_fab2_lib.baseboard_fab2(sch_1):page85_i111:DQ(50)" )
				( attribute "RELATIVE_PROPAGATION_DELAY_SCOPE" "G"
					( Parent
						( matchGroupRef "@baseboard_fab2_lib.baseboard_fab2(sch_1):\MG_DQ-DQS_FAR_DIMM_NG_M_L_BYTE6\" )
					)
					( Status sCSetFlattened )
					( Origin gBackEnd )
				)
				( attribute "RELATIVE_PROPAGATION_DELAY" "0.00 MIL,195.00 MIL"
					( Parent
						( matchGroupRef "@baseboard_fab2_lib.baseboard_fab2(sch_1):\MG_DQ-DQS_FAR_DIMM_NG_M_L_BYTE6\" )
					)
					( Units "uMatchProp" "ns" 1.000000)
					( Status sCSetFlattened )
					( Origin gBackEnd )
				)
				( attribute "RELATIVE_PROPAGATION_DELAY_SCOPE" "G"
					( Parent
						( matchGroupRef "@baseboard_fab2_lib.baseboard_fab2(sch_1):\MG_DQ_FAR_DIMM_NG_M_L_BYTE6\" )
					)
					( Status sCSetFlattened )
					( Origin gBackEnd )
				)
				( attribute "RELATIVE_PROPAGATION_DELAY" "-50.00 MIL,50.00 MIL"
					( Parent
						( matchGroupRef "@baseboard_fab2_lib.baseboard_fab2(sch_1):\MG_DQ_FAR_DIMM_NG_M_L_BYTE6\" )
					)
					( Units "uMatchProp" "ns" 1.000000)
					( Status sCSetFlattened )
					( Origin gBackEnd )
				)
			)
			( pinPair "@baseboard_fab2_lib.baseboard_fab2(sch_1):\PP1926\"
				( pinRef "@baseboard_fab2_lib.baseboard_fab2(sch_1):page61_i172:DDR4_DQ(51)" )
				( pinRef "@baseboard_fab2_lib.baseboard_fab2(sch_1):page86_i12:DQ(51)" )
				( attribute "RELATIVE_PROPAGATION_DELAY_SCOPE" "G"
					( Parent
						( matchGroupRef "@baseboard_fab2_lib.baseboard_fab2(sch_1):\MG_DQ-DQS_NEAR_DIMM_NG_M_L_BYTE6\" )
					)
					( Status sCSetFlattened )
					( Origin gBackEnd )
				)
				( attribute "RELATIVE_PROPAGATION_DELAY" "0.00 MIL,195.00 MIL"
					( Parent
						( matchGroupRef "@baseboard_fab2_lib.baseboard_fab2(sch_1):\MG_DQ-DQS_NEAR_DIMM_NG_M_L_BYTE6\" )
					)
					( Units "uMatchProp" "ns" 1.000000)
					( Status sCSetFlattened )
					( Origin gBackEnd )
				)
				( attribute "RELATIVE_PROPAGATION_DELAY_SCOPE" "G"
					( Parent
						( matchGroupRef "@baseboard_fab2_lib.baseboard_fab2(sch_1):\MG_DQ_NEAR_DIMM_NG_M_L_BYTE6\" )
					)
					( Status sCSetFlattened )
					( Origin gBackEnd )
				)
				( attribute "RELATIVE_PROPAGATION_DELAY" "-50.00 MIL,50.00 MIL"
					( Parent
						( matchGroupRef "@baseboard_fab2_lib.baseboard_fab2(sch_1):\MG_DQ_NEAR_DIMM_NG_M_L_BYTE6\" )
					)
					( Units "uMatchProp" "ns" 1.000000)
					( Status sCSetFlattened )
					( Origin gBackEnd )
				)
			)
			( pinPair "@baseboard_fab2_lib.baseboard_fab2(sch_1):\PP1927\"
				( pinRef "@baseboard_fab2_lib.baseboard_fab2(sch_1):page61_i172:DDR4_DQ(52)" )
				( pinRef "@baseboard_fab2_lib.baseboard_fab2(sch_1):page85_i111:DQ(53)" )
				( attribute "RELATIVE_PROPAGATION_DELAY_SCOPE" "G"
					( Parent
						( matchGroupRef "@baseboard_fab2_lib.baseboard_fab2(sch_1):\MG_DQ-DQS_FAR_DIMM_NG_M_L_BYTE6\" )
					)
					( Status sCSetFlattened )
					( Origin gBackEnd )
				)
				( attribute "RELATIVE_PROPAGATION_DELAY" "0.00 MIL,195.00 MIL"
					( Parent
						( matchGroupRef "@baseboard_fab2_lib.baseboard_fab2(sch_1):\MG_DQ-DQS_FAR_DIMM_NG_M_L_BYTE6\" )
					)
					( Units "uMatchProp" "ns" 1.000000)
					( Status sCSetFlattened )
					( Origin gBackEnd )
				)
				( attribute "RELATIVE_PROPAGATION_DELAY_SCOPE" "G"
					( Parent
						( matchGroupRef "@baseboard_fab2_lib.baseboard_fab2(sch_1):\MG_DQ_FAR_DIMM_NG_M_L_BYTE6\" )
					)
					( Status sCSetFlattened )
					( Origin gBackEnd )
				)
				( attribute "RELATIVE_PROPAGATION_DELAY" "-50.00 MIL,50.00 MIL"
					( Parent
						( matchGroupRef "@baseboard_fab2_lib.baseboard_fab2(sch_1):\MG_DQ_FAR_DIMM_NG_M_L_BYTE6\" )
					)
					( Units "uMatchProp" "ns" 1.000000)
					( Status sCSetFlattened )
					( Origin gBackEnd )
				)
			)
			( pinPair "@baseboard_fab2_lib.baseboard_fab2(sch_1):\PP1929\"
				( pinRef "@baseboard_fab2_lib.baseboard_fab2(sch_1):page61_i172:DDR4_DQ(52)" )
				( pinRef "@baseboard_fab2_lib.baseboard_fab2(sch_1):page86_i12:DQ(52)" )
				( attribute "RELATIVE_PROPAGATION_DELAY_SCOPE" "G"
					( Parent
						( matchGroupRef "@baseboard_fab2_lib.baseboard_fab2(sch_1):\MG_DQ-DQS_NEAR_DIMM_NG_M_L_BYTE6\" )
					)
					( Status sCSetFlattened )
					( Origin gBackEnd )
				)
				( attribute "RELATIVE_PROPAGATION_DELAY" "0.00 MIL,195.00 MIL"
					( Parent
						( matchGroupRef "@baseboard_fab2_lib.baseboard_fab2(sch_1):\MG_DQ-DQS_NEAR_DIMM_NG_M_L_BYTE6\" )
					)
					( Units "uMatchProp" "ns" 1.000000)
					( Status sCSetFlattened )
					( Origin gBackEnd )
				)
				( attribute "RELATIVE_PROPAGATION_DELAY_SCOPE" "G"
					( Parent
						( matchGroupRef "@baseboard_fab2_lib.baseboard_fab2(sch_1):\MG_DQ_NEAR_DIMM_NG_M_L_BYTE6\" )
					)
					( Status sCSetFlattened )
					( Origin gBackEnd )
				)
				( attribute "RELATIVE_PROPAGATION_DELAY" "-50.00 MIL,50.00 MIL"
					( Parent
						( matchGroupRef "@baseboard_fab2_lib.baseboard_fab2(sch_1):\MG_DQ_NEAR_DIMM_NG_M_L_BYTE6\" )
					)
					( Units "uMatchProp" "ns" 1.000000)
					( Status sCSetFlattened )
					( Origin gBackEnd )
				)
			)
			( pinPair "@baseboard_fab2_lib.baseboard_fab2(sch_1):\PP1930\"
				( pinRef "@baseboard_fab2_lib.baseboard_fab2(sch_1):page61_i172:DDR4_DQ(53)" )
				( pinRef "@baseboard_fab2_lib.baseboard_fab2(sch_1):page85_i111:DQ(52)" )
				( attribute "RELATIVE_PROPAGATION_DELAY_SCOPE" "G"
					( Parent
						( matchGroupRef "@baseboard_fab2_lib.baseboard_fab2(sch_1):\MG_DQ-DQS_FAR_DIMM_NG_M_L_BYTE6\" )
					)
					( Status sCSetFlattened )
					( Origin gBackEnd )
				)
				( attribute "RELATIVE_PROPAGATION_DELAY" "0.00 MIL,195.00 MIL"
					( Parent
						( matchGroupRef "@baseboard_fab2_lib.baseboard_fab2(sch_1):\MG_DQ-DQS_FAR_DIMM_NG_M_L_BYTE6\" )
					)
					( Units "uMatchProp" "ns" 1.000000)
					( Status sCSetFlattened )
					( Origin gBackEnd )
				)
				( attribute "RELATIVE_PROPAGATION_DELAY_SCOPE" "G"
					( Parent
						( matchGroupRef "@baseboard_fab2_lib.baseboard_fab2(sch_1):\MG_DQ_FAR_DIMM_NG_M_L_BYTE6\" )
					)
					( Status sCSetFlattened )
					( Origin gBackEnd )
				)
				( attribute "RELATIVE_PROPAGATION_DELAY" "-50.00 MIL,50.00 MIL"
					( Parent
						( matchGroupRef "@baseboard_fab2_lib.baseboard_fab2(sch_1):\MG_DQ_FAR_DIMM_NG_M_L_BYTE6\" )
					)
					( Units "uMatchProp" "ns" 1.000000)
					( Status sCSetFlattened )
					( Origin gBackEnd )
				)
			)
			( pinPair "@baseboard_fab2_lib.baseboard_fab2(sch_1):\PP1932\"
				( pinRef "@baseboard_fab2_lib.baseboard_fab2(sch_1):page61_i172:DDR4_DQ(53)" )
				( pinRef "@baseboard_fab2_lib.baseboard_fab2(sch_1):page86_i12:DQ(53)" )
				( attribute "RELATIVE_PROPAGATION_DELAY_SCOPE" "G"
					( Parent
						( matchGroupRef "@baseboard_fab2_lib.baseboard_fab2(sch_1):\MG_DQ-DQS_NEAR_DIMM_NG_M_L_BYTE6\" )
					)
					( Status sCSetFlattened )
					( Origin gBackEnd )
				)
				( attribute "RELATIVE_PROPAGATION_DELAY" "0.00 MIL,195.00 MIL"
					( Parent
						( matchGroupRef "@baseboard_fab2_lib.baseboard_fab2(sch_1):\MG_DQ-DQS_NEAR_DIMM_NG_M_L_BYTE6\" )
					)
					( Units "uMatchProp" "ns" 1.000000)
					( Status sCSetFlattened )
					( Origin gBackEnd )
				)
				( attribute "RELATIVE_PROPAGATION_DELAY_SCOPE" "G"
					( Parent
						( matchGroupRef "@baseboard_fab2_lib.baseboard_fab2(sch_1):\MG_DQ_NEAR_DIMM_NG_M_L_BYTE6\" )
					)
					( Status sCSetFlattened )
					( Origin gBackEnd )
				)
				( attribute "RELATIVE_PROPAGATION_DELAY" "-50.00 MIL,50.00 MIL"
					( Parent
						( matchGroupRef "@baseboard_fab2_lib.baseboard_fab2(sch_1):\MG_DQ_NEAR_DIMM_NG_M_L_BYTE6\" )
					)
					( Units "uMatchProp" "ns" 1.000000)
					( Status sCSetFlattened )
					( Origin gBackEnd )
				)
			)
			( pinPair "@baseboard_fab2_lib.baseboard_fab2(sch_1):\PP1933\"
				( pinRef "@baseboard_fab2_lib.baseboard_fab2(sch_1):page61_i172:DDR4_DQ(54)" )
				( pinRef "@baseboard_fab2_lib.baseboard_fab2(sch_1):page85_i111:DQ(55)" )
				( attribute "RELATIVE_PROPAGATION_DELAY_SCOPE" "G"
					( Parent
						( matchGroupRef "@baseboard_fab2_lib.baseboard_fab2(sch_1):\MG_DQ-DQS_FAR_DIMM_NG_M_L_BYTE6\" )
					)
					( Status sCSetFlattened )
					( Origin gBackEnd )
				)
				( attribute "RELATIVE_PROPAGATION_DELAY" "0.00 MIL,195.00 MIL"
					( Parent
						( matchGroupRef "@baseboard_fab2_lib.baseboard_fab2(sch_1):\MG_DQ-DQS_FAR_DIMM_NG_M_L_BYTE6\" )
					)
					( Units "uMatchProp" "ns" 1.000000)
					( Status sCSetFlattened )
					( Origin gBackEnd )
				)
				( attribute "RELATIVE_PROPAGATION_DELAY_SCOPE" "G"
					( Parent
						( matchGroupRef "@baseboard_fab2_lib.baseboard_fab2(sch_1):\MG_DQ_FAR_DIMM_NG_M_L_BYTE6\" )
					)
					( Status sCSetFlattened )
					( Origin gBackEnd )
				)
				( attribute "RELATIVE_PROPAGATION_DELAY" "-50.00 MIL,50.00 MIL"
					( Parent
						( matchGroupRef "@baseboard_fab2_lib.baseboard_fab2(sch_1):\MG_DQ_FAR_DIMM_NG_M_L_BYTE6\" )
					)
					( Units "uMatchProp" "ns" 1.000000)
					( Status sCSetFlattened )
					( Origin gBackEnd )
				)
			)
			( pinPair "@baseboard_fab2_lib.baseboard_fab2(sch_1):\PP1935\"
				( pinRef "@baseboard_fab2_lib.baseboard_fab2(sch_1):page61_i172:DDR4_DQ(54)" )
				( pinRef "@baseboard_fab2_lib.baseboard_fab2(sch_1):page86_i12:DQ(54)" )
				( attribute "RELATIVE_PROPAGATION_DELAY_SCOPE" "G"
					( Parent
						( matchGroupRef "@baseboard_fab2_lib.baseboard_fab2(sch_1):\MG_DQ-DQS_NEAR_DIMM_NG_M_L_BYTE6\" )
					)
					( Status sCSetFlattened )
					( Origin gBackEnd )
				)
				( attribute "RELATIVE_PROPAGATION_DELAY" "0.00 MIL,195.00 MIL"
					( Parent
						( matchGroupRef "@baseboard_fab2_lib.baseboard_fab2(sch_1):\MG_DQ-DQS_NEAR_DIMM_NG_M_L_BYTE6\" )
					)
					( Units "uMatchProp" "ns" 1.000000)
					( Status sCSetFlattened )
					( Origin gBackEnd )
				)
				( attribute "RELATIVE_PROPAGATION_DELAY_SCOPE" "G"
					( Parent
						( matchGroupRef "@baseboard_fab2_lib.baseboard_fab2(sch_1):\MG_DQ_NEAR_DIMM_NG_M_L_BYTE6\" )
					)
					( Status sCSetFlattened )
					( Origin gBackEnd )
				)
				( attribute "RELATIVE_PROPAGATION_DELAY" "-50.00 MIL,50.00 MIL"
					( Parent
						( matchGroupRef "@baseboard_fab2_lib.baseboard_fab2(sch_1):\MG_DQ_NEAR_DIMM_NG_M_L_BYTE6\" )
					)
					( Units "uMatchProp" "ns" 1.000000)
					( Status sCSetFlattened )
					( Origin gBackEnd )
				)
			)
			( pinPair "@baseboard_fab2_lib.baseboard_fab2(sch_1):\PP1936\"
				( pinRef "@baseboard_fab2_lib.baseboard_fab2(sch_1):page61_i172:DDR4_DQ(55)" )
				( pinRef "@baseboard_fab2_lib.baseboard_fab2(sch_1):page85_i111:DQ(54)" )
				( attribute "RELATIVE_PROPAGATION_DELAY_SCOPE" "G"
					( Parent
						( matchGroupRef "@baseboard_fab2_lib.baseboard_fab2(sch_1):\MG_DQ-DQS_FAR_DIMM_NG_M_L_BYTE6\" )
					)
					( Status sCSetFlattened )
					( Origin gBackEnd )
				)
				( attribute "RELATIVE_PROPAGATION_DELAY" "0.00 MIL,195.00 MIL"
					( Parent
						( matchGroupRef "@baseboard_fab2_lib.baseboard_fab2(sch_1):\MG_DQ-DQS_FAR_DIMM_NG_M_L_BYTE6\" )
					)
					( Units "uMatchProp" "ns" 1.000000)
					( Status sCSetFlattened )
					( Origin gBackEnd )
				)
				( attribute "RELATIVE_PROPAGATION_DELAY_SCOPE" "G"
					( Parent
						( matchGroupRef "@baseboard_fab2_lib.baseboard_fab2(sch_1):\MG_DQ_FAR_DIMM_NG_M_L_BYTE6\" )
					)
					( Status sCSetFlattened )
					( Origin gBackEnd )
				)
				( attribute "RELATIVE_PROPAGATION_DELAY" "-50.00 MIL,50.00 MIL"
					( Parent
						( matchGroupRef "@baseboard_fab2_lib.baseboard_fab2(sch_1):\MG_DQ_FAR_DIMM_NG_M_L_BYTE6\" )
					)
					( Units "uMatchProp" "ns" 1.000000)
					( Status sCSetFlattened )
					( Origin gBackEnd )
				)
			)
			( pinPair "@baseboard_fab2_lib.baseboard_fab2(sch_1):\PP1938\"
				( pinRef "@baseboard_fab2_lib.baseboard_fab2(sch_1):page61_i172:DDR4_DQ(55)" )
				( pinRef "@baseboard_fab2_lib.baseboard_fab2(sch_1):page86_i12:DQ(55)" )
				( attribute "RELATIVE_PROPAGATION_DELAY_SCOPE" "G"
					( Parent
						( matchGroupRef "@baseboard_fab2_lib.baseboard_fab2(sch_1):\MG_DQ-DQS_NEAR_DIMM_NG_M_L_BYTE6\" )
					)
					( Status sCSetFlattened )
					( Origin gBackEnd )
				)
				( attribute "RELATIVE_PROPAGATION_DELAY" "0.00 MIL,195.00 MIL"
					( Parent
						( matchGroupRef "@baseboard_fab2_lib.baseboard_fab2(sch_1):\MG_DQ-DQS_NEAR_DIMM_NG_M_L_BYTE6\" )
					)
					( Units "uMatchProp" "ns" 1.000000)
					( Status sCSetFlattened )
					( Origin gBackEnd )
				)
				( attribute "RELATIVE_PROPAGATION_DELAY_SCOPE" "G"
					( Parent
						( matchGroupRef "@baseboard_fab2_lib.baseboard_fab2(sch_1):\MG_DQ_NEAR_DIMM_NG_M_L_BYTE6\" )
					)
					( Status sCSetFlattened )
					( Origin gBackEnd )
				)
				( attribute "RELATIVE_PROPAGATION_DELAY" "-50.00 MIL,50.00 MIL"
					( Parent
						( matchGroupRef "@baseboard_fab2_lib.baseboard_fab2(sch_1):\MG_DQ_NEAR_DIMM_NG_M_L_BYTE6\" )
					)
					( Units "uMatchProp" "ns" 1.000000)
					( Status sCSetFlattened )
					( Origin gBackEnd )
				)
			)
			( pinPair "@baseboard_fab2_lib.baseboard_fab2(sch_1):\PP1891\"
				( pinRef "@baseboard_fab2_lib.baseboard_fab2(sch_1):page61_i172:DDR4_DQ(56)" )
				( pinRef "@baseboard_fab2_lib.baseboard_fab2(sch_1):page85_i111:DQ(57)" )
				( attribute "RELATIVE_PROPAGATION_DELAY_SCOPE" "G"
					( Parent
						( matchGroupRef "@baseboard_fab2_lib.baseboard_fab2(sch_1):\MG_DQ-DQS_FAR_DIMM_NG_M_L_BYTE7\" )
					)
					( Status sCSetFlattened )
					( Origin gBackEnd )
				)
				( attribute "RELATIVE_PROPAGATION_DELAY" "0.00 MIL,195.00 MIL"
					( Parent
						( matchGroupRef "@baseboard_fab2_lib.baseboard_fab2(sch_1):\MG_DQ-DQS_FAR_DIMM_NG_M_L_BYTE7\" )
					)
					( Units "uMatchProp" "ns" 1.000000)
					( Status sCSetFlattened )
					( Origin gBackEnd )
				)
				( attribute "RELATIVE_PROPAGATION_DELAY_SCOPE" "G"
					( Parent
						( matchGroupRef "@baseboard_fab2_lib.baseboard_fab2(sch_1):\MG_DQ_FAR_DIMM_NG_M_L_BYTE7\" )
					)
					( Status sCSetFlattened )
					( Origin gBackEnd )
				)
				( attribute "RELATIVE_PROPAGATION_DELAY" "-50.00 MIL,50.00 MIL"
					( Parent
						( matchGroupRef "@baseboard_fab2_lib.baseboard_fab2(sch_1):\MG_DQ_FAR_DIMM_NG_M_L_BYTE7\" )
					)
					( Units "uMatchProp" "ns" 1.000000)
					( Status sCSetFlattened )
					( Origin gBackEnd )
				)
			)
			( pinPair "@baseboard_fab2_lib.baseboard_fab2(sch_1):\PP1893\"
				( pinRef "@baseboard_fab2_lib.baseboard_fab2(sch_1):page61_i172:DDR4_DQ(56)" )
				( pinRef "@baseboard_fab2_lib.baseboard_fab2(sch_1):page86_i12:DQ(56)" )
				( attribute "RELATIVE_PROPAGATION_DELAY_SCOPE" "G"
					( Parent
						( matchGroupRef "@baseboard_fab2_lib.baseboard_fab2(sch_1):\MG_DQ-DQS_NEAR_DIMM_NG_M_L_BYTE7\" )
					)
					( Status sCSetFlattened )
					( Origin gBackEnd )
				)
				( attribute "RELATIVE_PROPAGATION_DELAY" "0.00 MIL,195.00 MIL"
					( Parent
						( matchGroupRef "@baseboard_fab2_lib.baseboard_fab2(sch_1):\MG_DQ-DQS_NEAR_DIMM_NG_M_L_BYTE7\" )
					)
					( Units "uMatchProp" "ns" 1.000000)
					( Status sCSetFlattened )
					( Origin gBackEnd )
				)
				( attribute "RELATIVE_PROPAGATION_DELAY_SCOPE" "G"
					( Parent
						( matchGroupRef "@baseboard_fab2_lib.baseboard_fab2(sch_1):\MG_DQ_NEAR_DIMM_NG_M_L_BYTE7\" )
					)
					( Status sCSetFlattened )
					( Origin gBackEnd )
				)
				( attribute "RELATIVE_PROPAGATION_DELAY" "-50.00 MIL,50.00 MIL"
					( Parent
						( matchGroupRef "@baseboard_fab2_lib.baseboard_fab2(sch_1):\MG_DQ_NEAR_DIMM_NG_M_L_BYTE7\" )
					)
					( Units "uMatchProp" "ns" 1.000000)
					( Status sCSetFlattened )
					( Origin gBackEnd )
				)
			)
			( pinPair "@baseboard_fab2_lib.baseboard_fab2(sch_1):\PP1894\"
				( pinRef "@baseboard_fab2_lib.baseboard_fab2(sch_1):page61_i172:DDR4_DQ(57)" )
				( pinRef "@baseboard_fab2_lib.baseboard_fab2(sch_1):page85_i111:DQ(56)" )
				( attribute "RELATIVE_PROPAGATION_DELAY_SCOPE" "G"
					( Parent
						( matchGroupRef "@baseboard_fab2_lib.baseboard_fab2(sch_1):\MG_DQ-DQS_FAR_DIMM_NG_M_L_BYTE7\" )
					)
					( Status sCSetFlattened )
					( Origin gBackEnd )
				)
				( attribute "RELATIVE_PROPAGATION_DELAY" "0.00 MIL,195.00 MIL"
					( Parent
						( matchGroupRef "@baseboard_fab2_lib.baseboard_fab2(sch_1):\MG_DQ-DQS_FAR_DIMM_NG_M_L_BYTE7\" )
					)
					( Units "uMatchProp" "ns" 1.000000)
					( Status sCSetFlattened )
					( Origin gBackEnd )
				)
				( attribute "RELATIVE_PROPAGATION_DELAY_SCOPE" "G"
					( Parent
						( matchGroupRef "@baseboard_fab2_lib.baseboard_fab2(sch_1):\MG_DQ_FAR_DIMM_NG_M_L_BYTE7\" )
					)
					( Status sCSetFlattened )
					( Origin gBackEnd )
				)
				( attribute "RELATIVE_PROPAGATION_DELAY" "-50.00 MIL,50.00 MIL"
					( Parent
						( matchGroupRef "@baseboard_fab2_lib.baseboard_fab2(sch_1):\MG_DQ_FAR_DIMM_NG_M_L_BYTE7\" )
					)
					( Units "uMatchProp" "ns" 1.000000)
					( Status sCSetFlattened )
					( Origin gBackEnd )
				)
			)
			( pinPair "@baseboard_fab2_lib.baseboard_fab2(sch_1):\PP1896\"
				( pinRef "@baseboard_fab2_lib.baseboard_fab2(sch_1):page86_i12:DQ(57)" )
				( pinRef "@baseboard_fab2_lib.baseboard_fab2(sch_1):page61_i172:DDR4_DQ(57)" )
				( attribute "RELATIVE_PROPAGATION_DELAY_SCOPE" "G"
					( Parent
						( matchGroupRef "@baseboard_fab2_lib.baseboard_fab2(sch_1):\MG_DQ-DQS_NEAR_DIMM_NG_M_L_BYTE7\" )
					)
					( Status sCSetFlattened )
					( Origin gBackEnd )
				)
				( attribute "RELATIVE_PROPAGATION_DELAY" "0.00 MIL,195.00 MIL"
					( Parent
						( matchGroupRef "@baseboard_fab2_lib.baseboard_fab2(sch_1):\MG_DQ-DQS_NEAR_DIMM_NG_M_L_BYTE7\" )
					)
					( Units "uMatchProp" "ns" 1.000000)
					( Status sCSetFlattened )
					( Origin gBackEnd )
				)
				( attribute "RELATIVE_PROPAGATION_DELAY_SCOPE" "G"
					( Parent
						( matchGroupRef "@baseboard_fab2_lib.baseboard_fab2(sch_1):\MG_DQ_NEAR_DIMM_NG_M_L_BYTE7\" )
					)
					( Status sCSetFlattened )
					( Origin gBackEnd )
				)
				( attribute "RELATIVE_PROPAGATION_DELAY" "-50.00 MIL,50.00 MIL"
					( Parent
						( matchGroupRef "@baseboard_fab2_lib.baseboard_fab2(sch_1):\MG_DQ_NEAR_DIMM_NG_M_L_BYTE7\" )
					)
					( Units "uMatchProp" "ns" 1.000000)
					( Status sCSetFlattened )
					( Origin gBackEnd )
				)
			)
			( pinPair "@baseboard_fab2_lib.baseboard_fab2(sch_1):\PP1897\"
				( pinRef "@baseboard_fab2_lib.baseboard_fab2(sch_1):page61_i172:DDR4_DQ(58)" )
				( pinRef "@baseboard_fab2_lib.baseboard_fab2(sch_1):page85_i111:DQ(59)" )
				( attribute "RELATIVE_PROPAGATION_DELAY_SCOPE" "G"
					( Parent
						( matchGroupRef "@baseboard_fab2_lib.baseboard_fab2(sch_1):\MG_DQ-DQS_FAR_DIMM_NG_M_L_BYTE7\" )
					)
					( Status sCSetFlattened )
					( Origin gBackEnd )
				)
				( attribute "RELATIVE_PROPAGATION_DELAY" "0.00 MIL,195.00 MIL"
					( Parent
						( matchGroupRef "@baseboard_fab2_lib.baseboard_fab2(sch_1):\MG_DQ-DQS_FAR_DIMM_NG_M_L_BYTE7\" )
					)
					( Units "uMatchProp" "ns" 1.000000)
					( Status sCSetFlattened )
					( Origin gBackEnd )
				)
				( attribute "RELATIVE_PROPAGATION_DELAY_SCOPE" "G"
					( Parent
						( matchGroupRef "@baseboard_fab2_lib.baseboard_fab2(sch_1):\MG_DQ_FAR_DIMM_NG_M_L_BYTE7\" )
					)
					( Status sCSetFlattened )
					( Origin gBackEnd )
				)
				( attribute "RELATIVE_PROPAGATION_DELAY" "-50.00 MIL,50.00 MIL"
					( Parent
						( matchGroupRef "@baseboard_fab2_lib.baseboard_fab2(sch_1):\MG_DQ_FAR_DIMM_NG_M_L_BYTE7\" )
					)
					( Units "uMatchProp" "ns" 1.000000)
					( Status sCSetFlattened )
					( Origin gBackEnd )
				)
			)
			( pinPair "@baseboard_fab2_lib.baseboard_fab2(sch_1):\PP1899\"
				( pinRef "@baseboard_fab2_lib.baseboard_fab2(sch_1):page61_i172:DDR4_DQ(58)" )
				( pinRef "@baseboard_fab2_lib.baseboard_fab2(sch_1):page86_i12:DQ(58)" )
				( attribute "RELATIVE_PROPAGATION_DELAY_SCOPE" "G"
					( Parent
						( matchGroupRef "@baseboard_fab2_lib.baseboard_fab2(sch_1):\MG_DQ-DQS_NEAR_DIMM_NG_M_L_BYTE7\" )
					)
					( Status sCSetFlattened )
					( Origin gBackEnd )
				)
				( attribute "RELATIVE_PROPAGATION_DELAY" "0.00 MIL,195.00 MIL"
					( Parent
						( matchGroupRef "@baseboard_fab2_lib.baseboard_fab2(sch_1):\MG_DQ-DQS_NEAR_DIMM_NG_M_L_BYTE7\" )
					)
					( Units "uMatchProp" "ns" 1.000000)
					( Status sCSetFlattened )
					( Origin gBackEnd )
				)
				( attribute "RELATIVE_PROPAGATION_DELAY_SCOPE" "G"
					( Parent
						( matchGroupRef "@baseboard_fab2_lib.baseboard_fab2(sch_1):\MG_DQ_NEAR_DIMM_NG_M_L_BYTE7\" )
					)
					( Status sCSetFlattened )
					( Origin gBackEnd )
				)
				( attribute "RELATIVE_PROPAGATION_DELAY" "-50.00 MIL,50.00 MIL"
					( Parent
						( matchGroupRef "@baseboard_fab2_lib.baseboard_fab2(sch_1):\MG_DQ_NEAR_DIMM_NG_M_L_BYTE7\" )
					)
					( Units "uMatchProp" "ns" 1.000000)
					( Status sCSetFlattened )
					( Origin gBackEnd )
				)
			)
			( pinPair "@baseboard_fab2_lib.baseboard_fab2(sch_1):\PP1900\"
				( pinRef "@baseboard_fab2_lib.baseboard_fab2(sch_1):page61_i172:DDR4_DQ(59)" )
				( pinRef "@baseboard_fab2_lib.baseboard_fab2(sch_1):page85_i111:DQ(58)" )
				( attribute "RELATIVE_PROPAGATION_DELAY_SCOPE" "G"
					( Parent
						( matchGroupRef "@baseboard_fab2_lib.baseboard_fab2(sch_1):\MG_DQ-DQS_FAR_DIMM_NG_M_L_BYTE7\" )
					)
					( Status sCSetFlattened )
					( Origin gBackEnd )
				)
				( attribute "RELATIVE_PROPAGATION_DELAY" "0.00 MIL,195.00 MIL"
					( Parent
						( matchGroupRef "@baseboard_fab2_lib.baseboard_fab2(sch_1):\MG_DQ-DQS_FAR_DIMM_NG_M_L_BYTE7\" )
					)
					( Units "uMatchProp" "ns" 1.000000)
					( Status sCSetFlattened )
					( Origin gBackEnd )
				)
				( attribute "RELATIVE_PROPAGATION_DELAY_SCOPE" "G"
					( Parent
						( matchGroupRef "@baseboard_fab2_lib.baseboard_fab2(sch_1):\MG_DQ_FAR_DIMM_NG_M_L_BYTE7\" )
					)
					( Status sCSetFlattened )
					( Origin gBackEnd )
				)
				( attribute "RELATIVE_PROPAGATION_DELAY" "-50.00 MIL,50.00 MIL"
					( Parent
						( matchGroupRef "@baseboard_fab2_lib.baseboard_fab2(sch_1):\MG_DQ_FAR_DIMM_NG_M_L_BYTE7\" )
					)
					( Units "uMatchProp" "ns" 1.000000)
					( Status sCSetFlattened )
					( Origin gBackEnd )
				)
			)
			( pinPair "@baseboard_fab2_lib.baseboard_fab2(sch_1):\PP1902\"
				( pinRef "@baseboard_fab2_lib.baseboard_fab2(sch_1):page61_i172:DDR4_DQ(59)" )
				( pinRef "@baseboard_fab2_lib.baseboard_fab2(sch_1):page86_i12:DQ(59)" )
				( attribute "RELATIVE_PROPAGATION_DELAY_SCOPE" "G"
					( Parent
						( matchGroupRef "@baseboard_fab2_lib.baseboard_fab2(sch_1):\MG_DQ-DQS_NEAR_DIMM_NG_M_L_BYTE7\" )
					)
					( Status sCSetFlattened )
					( Origin gBackEnd )
				)
				( attribute "RELATIVE_PROPAGATION_DELAY" "0.00 MIL,195.00 MIL"
					( Parent
						( matchGroupRef "@baseboard_fab2_lib.baseboard_fab2(sch_1):\MG_DQ-DQS_NEAR_DIMM_NG_M_L_BYTE7\" )
					)
					( Units "uMatchProp" "ns" 1.000000)
					( Status sCSetFlattened )
					( Origin gBackEnd )
				)
				( attribute "RELATIVE_PROPAGATION_DELAY_SCOPE" "G"
					( Parent
						( matchGroupRef "@baseboard_fab2_lib.baseboard_fab2(sch_1):\MG_DQ_NEAR_DIMM_NG_M_L_BYTE7\" )
					)
					( Status sCSetFlattened )
					( Origin gBackEnd )
				)
				( attribute "RELATIVE_PROPAGATION_DELAY" "-50.00 MIL,50.00 MIL"
					( Parent
						( matchGroupRef "@baseboard_fab2_lib.baseboard_fab2(sch_1):\MG_DQ_NEAR_DIMM_NG_M_L_BYTE7\" )
					)
					( Units "uMatchProp" "ns" 1.000000)
					( Status sCSetFlattened )
					( Origin gBackEnd )
				)
			)
			( pinPair "@baseboard_fab2_lib.baseboard_fab2(sch_1):\PP1903\"
				( pinRef "@baseboard_fab2_lib.baseboard_fab2(sch_1):page61_i172:DDR4_DQ(60)" )
				( pinRef "@baseboard_fab2_lib.baseboard_fab2(sch_1):page85_i111:DQ(61)" )
				( attribute "RELATIVE_PROPAGATION_DELAY_SCOPE" "G"
					( Parent
						( matchGroupRef "@baseboard_fab2_lib.baseboard_fab2(sch_1):\MG_DQ-DQS_FAR_DIMM_NG_M_L_BYTE7\" )
					)
					( Status sCSetFlattened )
					( Origin gBackEnd )
				)
				( attribute "RELATIVE_PROPAGATION_DELAY" "0.00 MIL,195.00 MIL"
					( Parent
						( matchGroupRef "@baseboard_fab2_lib.baseboard_fab2(sch_1):\MG_DQ-DQS_FAR_DIMM_NG_M_L_BYTE7\" )
					)
					( Units "uMatchProp" "ns" 1.000000)
					( Status sCSetFlattened )
					( Origin gBackEnd )
				)
				( attribute "RELATIVE_PROPAGATION_DELAY_SCOPE" "G"
					( Parent
						( matchGroupRef "@baseboard_fab2_lib.baseboard_fab2(sch_1):\MG_DQ_FAR_DIMM_NG_M_L_BYTE7\" )
					)
					( Status sCSetFlattened )
					( Origin gBackEnd )
				)
				( attribute "RELATIVE_PROPAGATION_DELAY" "-50.00 MIL,50.00 MIL"
					( Parent
						( matchGroupRef "@baseboard_fab2_lib.baseboard_fab2(sch_1):\MG_DQ_FAR_DIMM_NG_M_L_BYTE7\" )
					)
					( Units "uMatchProp" "ns" 1.000000)
					( Status sCSetFlattened )
					( Origin gBackEnd )
				)
			)
			( pinPair "@baseboard_fab2_lib.baseboard_fab2(sch_1):\PP1905\"
				( pinRef "@baseboard_fab2_lib.baseboard_fab2(sch_1):page61_i172:DDR4_DQ(60)" )
				( pinRef "@baseboard_fab2_lib.baseboard_fab2(sch_1):page86_i12:DQ(60)" )
				( attribute "RELATIVE_PROPAGATION_DELAY_SCOPE" "G"
					( Parent
						( matchGroupRef "@baseboard_fab2_lib.baseboard_fab2(sch_1):\MG_DQ-DQS_NEAR_DIMM_NG_M_L_BYTE7\" )
					)
					( Status sCSetFlattened )
					( Origin gBackEnd )
				)
				( attribute "RELATIVE_PROPAGATION_DELAY" "0.00 MIL,195.00 MIL"
					( Parent
						( matchGroupRef "@baseboard_fab2_lib.baseboard_fab2(sch_1):\MG_DQ-DQS_NEAR_DIMM_NG_M_L_BYTE7\" )
					)
					( Units "uMatchProp" "ns" 1.000000)
					( Status sCSetFlattened )
					( Origin gBackEnd )
				)
				( attribute "RELATIVE_PROPAGATION_DELAY_SCOPE" "G"
					( Parent
						( matchGroupRef "@baseboard_fab2_lib.baseboard_fab2(sch_1):\MG_DQ_NEAR_DIMM_NG_M_L_BYTE7\" )
					)
					( Status sCSetFlattened )
					( Origin gBackEnd )
				)
				( attribute "RELATIVE_PROPAGATION_DELAY" "-50.00 MIL,50.00 MIL"
					( Parent
						( matchGroupRef "@baseboard_fab2_lib.baseboard_fab2(sch_1):\MG_DQ_NEAR_DIMM_NG_M_L_BYTE7\" )
					)
					( Units "uMatchProp" "ns" 1.000000)
					( Status sCSetFlattened )
					( Origin gBackEnd )
				)
			)
			( pinPair "@baseboard_fab2_lib.baseboard_fab2(sch_1):\PP1906\"
				( pinRef "@baseboard_fab2_lib.baseboard_fab2(sch_1):page61_i172:DDR4_DQ(61)" )
				( pinRef "@baseboard_fab2_lib.baseboard_fab2(sch_1):page85_i111:DQ(60)" )
				( attribute "RELATIVE_PROPAGATION_DELAY_SCOPE" "G"
					( Parent
						( matchGroupRef "@baseboard_fab2_lib.baseboard_fab2(sch_1):\MG_DQ-DQS_FAR_DIMM_NG_M_L_BYTE7\" )
					)
					( Status sCSetFlattened )
					( Origin gBackEnd )
				)
				( attribute "RELATIVE_PROPAGATION_DELAY" "0.00 MIL,195.00 MIL"
					( Parent
						( matchGroupRef "@baseboard_fab2_lib.baseboard_fab2(sch_1):\MG_DQ-DQS_FAR_DIMM_NG_M_L_BYTE7\" )
					)
					( Units "uMatchProp" "ns" 1.000000)
					( Status sCSetFlattened )
					( Origin gBackEnd )
				)
				( attribute "RELATIVE_PROPAGATION_DELAY_SCOPE" "G"
					( Parent
						( matchGroupRef "@baseboard_fab2_lib.baseboard_fab2(sch_1):\MG_DQ_FAR_DIMM_NG_M_L_BYTE7\" )
					)
					( Status sCSetFlattened )
					( Origin gBackEnd )
				)
				( attribute "RELATIVE_PROPAGATION_DELAY" "-50.00 MIL,50.00 MIL"
					( Parent
						( matchGroupRef "@baseboard_fab2_lib.baseboard_fab2(sch_1):\MG_DQ_FAR_DIMM_NG_M_L_BYTE7\" )
					)
					( Units "uMatchProp" "ns" 1.000000)
					( Status sCSetFlattened )
					( Origin gBackEnd )
				)
			)
			( pinPair "@baseboard_fab2_lib.baseboard_fab2(sch_1):\PP1908\"
				( pinRef "@baseboard_fab2_lib.baseboard_fab2(sch_1):page61_i172:DDR4_DQ(61)" )
				( pinRef "@baseboard_fab2_lib.baseboard_fab2(sch_1):page86_i12:DQ(61)" )
				( attribute "RELATIVE_PROPAGATION_DELAY_SCOPE" "G"
					( Parent
						( matchGroupRef "@baseboard_fab2_lib.baseboard_fab2(sch_1):\MG_DQ-DQS_NEAR_DIMM_NG_M_L_BYTE7\" )
					)
					( Status sCSetFlattened )
					( Origin gBackEnd )
				)
				( attribute "RELATIVE_PROPAGATION_DELAY" "0.00 MIL,195.00 MIL"
					( Parent
						( matchGroupRef "@baseboard_fab2_lib.baseboard_fab2(sch_1):\MG_DQ-DQS_NEAR_DIMM_NG_M_L_BYTE7\" )
					)
					( Units "uMatchProp" "ns" 1.000000)
					( Status sCSetFlattened )
					( Origin gBackEnd )
				)
				( attribute "RELATIVE_PROPAGATION_DELAY_SCOPE" "G"
					( Parent
						( matchGroupRef "@baseboard_fab2_lib.baseboard_fab2(sch_1):\MG_DQ_NEAR_DIMM_NG_M_L_BYTE7\" )
					)
					( Status sCSetFlattened )
					( Origin gBackEnd )
				)
				( attribute "RELATIVE_PROPAGATION_DELAY" "-50.00 MIL,50.00 MIL"
					( Parent
						( matchGroupRef "@baseboard_fab2_lib.baseboard_fab2(sch_1):\MG_DQ_NEAR_DIMM_NG_M_L_BYTE7\" )
					)
					( Units "uMatchProp" "ns" 1.000000)
					( Status sCSetFlattened )
					( Origin gBackEnd )
				)
			)
			( pinPair "@baseboard_fab2_lib.baseboard_fab2(sch_1):\PP1909\"
				( pinRef "@baseboard_fab2_lib.baseboard_fab2(sch_1):page61_i172:DDR4_DQ(62)" )
				( pinRef "@baseboard_fab2_lib.baseboard_fab2(sch_1):page85_i111:DQ(63)" )
				( attribute "RELATIVE_PROPAGATION_DELAY_SCOPE" "G"
					( Parent
						( matchGroupRef "@baseboard_fab2_lib.baseboard_fab2(sch_1):\MG_DQ-DQS_FAR_DIMM_NG_M_L_BYTE7\" )
					)
					( Status sCSetFlattened )
					( Origin gBackEnd )
				)
				( attribute "RELATIVE_PROPAGATION_DELAY" "0.00 MIL,195.00 MIL"
					( Parent
						( matchGroupRef "@baseboard_fab2_lib.baseboard_fab2(sch_1):\MG_DQ-DQS_FAR_DIMM_NG_M_L_BYTE7\" )
					)
					( Units "uMatchProp" "ns" 1.000000)
					( Status sCSetFlattened )
					( Origin gBackEnd )
				)
				( attribute "RELATIVE_PROPAGATION_DELAY_SCOPE" "G"
					( Parent
						( matchGroupRef "@baseboard_fab2_lib.baseboard_fab2(sch_1):\MG_DQ_FAR_DIMM_NG_M_L_BYTE7\" )
					)
					( Status sCSetFlattened )
					( Origin gBackEnd )
				)
				( attribute "RELATIVE_PROPAGATION_DELAY" "-50.00 MIL,50.00 MIL"
					( Parent
						( matchGroupRef "@baseboard_fab2_lib.baseboard_fab2(sch_1):\MG_DQ_FAR_DIMM_NG_M_L_BYTE7\" )
					)
					( Units "uMatchProp" "ns" 1.000000)
					( Status sCSetFlattened )
					( Origin gBackEnd )
				)
			)
			( pinPair "@baseboard_fab2_lib.baseboard_fab2(sch_1):\PP1911\"
				( pinRef "@baseboard_fab2_lib.baseboard_fab2(sch_1):page61_i172:DDR4_DQ(62)" )
				( pinRef "@baseboard_fab2_lib.baseboard_fab2(sch_1):page86_i12:DQ(62)" )
				( attribute "RELATIVE_PROPAGATION_DELAY_SCOPE" "G"
					( Parent
						( matchGroupRef "@baseboard_fab2_lib.baseboard_fab2(sch_1):\MG_DQ-DQS_NEAR_DIMM_NG_M_L_BYTE7\" )
					)
					( Status sCSetFlattened )
					( Origin gBackEnd )
				)
				( attribute "RELATIVE_PROPAGATION_DELAY" "0.00 MIL,195.00 MIL"
					( Parent
						( matchGroupRef "@baseboard_fab2_lib.baseboard_fab2(sch_1):\MG_DQ-DQS_NEAR_DIMM_NG_M_L_BYTE7\" )
					)
					( Units "uMatchProp" "ns" 1.000000)
					( Status sCSetFlattened )
					( Origin gBackEnd )
				)
				( attribute "RELATIVE_PROPAGATION_DELAY_SCOPE" "G"
					( Parent
						( matchGroupRef "@baseboard_fab2_lib.baseboard_fab2(sch_1):\MG_DQ_NEAR_DIMM_NG_M_L_BYTE7\" )
					)
					( Status sCSetFlattened )
					( Origin gBackEnd )
				)
				( attribute "RELATIVE_PROPAGATION_DELAY" "-50.00 MIL,50.00 MIL"
					( Parent
						( matchGroupRef "@baseboard_fab2_lib.baseboard_fab2(sch_1):\MG_DQ_NEAR_DIMM_NG_M_L_BYTE7\" )
					)
					( Units "uMatchProp" "ns" 1.000000)
					( Status sCSetFlattened )
					( Origin gBackEnd )
				)
			)
			( pinPair "@baseboard_fab2_lib.baseboard_fab2(sch_1):\PP1912\"
				( pinRef "@baseboard_fab2_lib.baseboard_fab2(sch_1):page61_i172:DDR4_DQ(63)" )
				( pinRef "@baseboard_fab2_lib.baseboard_fab2(sch_1):page85_i111:DQ(62)" )
				( attribute "RELATIVE_PROPAGATION_DELAY_SCOPE" "G"
					( Parent
						( matchGroupRef "@baseboard_fab2_lib.baseboard_fab2(sch_1):\MG_DQ-DQS_FAR_DIMM_NG_M_L_BYTE7\" )
					)
					( Status sCSetFlattened )
					( Origin gBackEnd )
				)
				( attribute "RELATIVE_PROPAGATION_DELAY" "0.00 MIL,195.00 MIL"
					( Parent
						( matchGroupRef "@baseboard_fab2_lib.baseboard_fab2(sch_1):\MG_DQ-DQS_FAR_DIMM_NG_M_L_BYTE7\" )
					)
					( Units "uMatchProp" "ns" 1.000000)
					( Status sCSetFlattened )
					( Origin gBackEnd )
				)
				( attribute "RELATIVE_PROPAGATION_DELAY_SCOPE" "G"
					( Parent
						( matchGroupRef "@baseboard_fab2_lib.baseboard_fab2(sch_1):\MG_DQ_FAR_DIMM_NG_M_L_BYTE7\" )
					)
					( Status sCSetFlattened )
					( Origin gBackEnd )
				)
				( attribute "RELATIVE_PROPAGATION_DELAY" "-50.00 MIL,50.00 MIL"
					( Parent
						( matchGroupRef "@baseboard_fab2_lib.baseboard_fab2(sch_1):\MG_DQ_FAR_DIMM_NG_M_L_BYTE7\" )
					)
					( Units "uMatchProp" "ns" 1.000000)
					( Status sCSetFlattened )
					( Origin gBackEnd )
				)
			)
			( pinPair "@baseboard_fab2_lib.baseboard_fab2(sch_1):\PP1914\"
				( pinRef "@baseboard_fab2_lib.baseboard_fab2(sch_1):page61_i172:DDR4_DQ(63)" )
				( pinRef "@baseboard_fab2_lib.baseboard_fab2(sch_1):page86_i12:DQ(63)" )
				( attribute "RELATIVE_PROPAGATION_DELAY_SCOPE" "G"
					( Parent
						( matchGroupRef "@baseboard_fab2_lib.baseboard_fab2(sch_1):\MG_DQ-DQS_NEAR_DIMM_NG_M_L_BYTE7\" )
					)
					( Status sCSetFlattened )
					( Origin gBackEnd )
				)
				( attribute "RELATIVE_PROPAGATION_DELAY" "0.00 MIL,195.00 MIL"
					( Parent
						( matchGroupRef "@baseboard_fab2_lib.baseboard_fab2(sch_1):\MG_DQ-DQS_NEAR_DIMM_NG_M_L_BYTE7\" )
					)
					( Units "uMatchProp" "ns" 1.000000)
					( Status sCSetFlattened )
					( Origin gBackEnd )
				)
				( attribute "RELATIVE_PROPAGATION_DELAY_SCOPE" "G"
					( Parent
						( matchGroupRef "@baseboard_fab2_lib.baseboard_fab2(sch_1):\MG_DQ_NEAR_DIMM_NG_M_L_BYTE7\" )
					)
					( Status sCSetFlattened )
					( Origin gBackEnd )
				)
				( attribute "RELATIVE_PROPAGATION_DELAY" "-50.00 MIL,50.00 MIL"
					( Parent
						( matchGroupRef "@baseboard_fab2_lib.baseboard_fab2(sch_1):\MG_DQ_NEAR_DIMM_NG_M_L_BYTE7\" )
					)
					( Units "uMatchProp" "ns" 1.000000)
					( Status sCSetFlattened )
					( Origin gBackEnd )
				)
			)
			( pinPair "@baseboard_fab2_lib.baseboard_fab2(sch_1):\PP1843\"
				( pinRef "@baseboard_fab2_lib.baseboard_fab2(sch_1):page62_i172:DDR5_DQ(0)" )
				( pinRef "@baseboard_fab2_lib.baseboard_fab2(sch_1):page87_i186:DQ(1)" )
				( attribute "RELATIVE_PROPAGATION_DELAY_SCOPE" "G"
					( Parent
						( matchGroupRef "@baseboard_fab2_lib.baseboard_fab2(sch_1):\MG_DQ-DQS_FAR_DIMM_NG_M_M_BYTE0\" )
					)
					( Status sCSetFlattened )
					( Origin gBackEnd )
				)
				( attribute "RELATIVE_PROPAGATION_DELAY" "0.00 MIL,195.00 MIL"
					( Parent
						( matchGroupRef "@baseboard_fab2_lib.baseboard_fab2(sch_1):\MG_DQ-DQS_FAR_DIMM_NG_M_M_BYTE0\" )
					)
					( Units "uMatchProp" "ns" 1.000000)
					( Status sCSetFlattened )
					( Origin gBackEnd )
				)
				( attribute "RELATIVE_PROPAGATION_DELAY_SCOPE" "G"
					( Parent
						( matchGroupRef "@baseboard_fab2_lib.baseboard_fab2(sch_1):\MG_DQ_FAR_DIMM_NG_M_M_BYTE0\" )
					)
					( Status sCSetFlattened )
					( Origin gBackEnd )
				)
				( attribute "RELATIVE_PROPAGATION_DELAY" "-50.00 MIL,50.00 MIL"
					( Parent
						( matchGroupRef "@baseboard_fab2_lib.baseboard_fab2(sch_1):\MG_DQ_FAR_DIMM_NG_M_M_BYTE0\" )
					)
					( Units "uMatchProp" "ns" 1.000000)
					( Status sCSetFlattened )
					( Origin gBackEnd )
				)
			)
			( pinPair "@baseboard_fab2_lib.baseboard_fab2(sch_1):\PP1844\"
				( pinRef "@baseboard_fab2_lib.baseboard_fab2(sch_1):page62_i172:DDR5_DQ(0)" )
				( pinRef "@baseboard_fab2_lib.baseboard_fab2(sch_1):page88_i111:DQ(0)" )
				( attribute "RELATIVE_PROPAGATION_DELAY_SCOPE" "G"
					( Parent
						( matchGroupRef "@baseboard_fab2_lib.baseboard_fab2(sch_1):\MG_DQ-DQS_NEAR_DIMM_NG_M_M_BYTE0\" )
					)
					( Status sCSetFlattened )
					( Origin gBackEnd )
				)
				( attribute "RELATIVE_PROPAGATION_DELAY" "0.00 MIL,195.00 MIL"
					( Parent
						( matchGroupRef "@baseboard_fab2_lib.baseboard_fab2(sch_1):\MG_DQ-DQS_NEAR_DIMM_NG_M_M_BYTE0\" )
					)
					( Units "uMatchProp" "ns" 1.000000)
					( Status sCSetFlattened )
					( Origin gBackEnd )
				)
				( attribute "RELATIVE_PROPAGATION_DELAY_SCOPE" "G"
					( Parent
						( matchGroupRef "@baseboard_fab2_lib.baseboard_fab2(sch_1):\MG_DQ_NEAR_DIMM_NG_M_M_BYTE0\" )
					)
					( Status sCSetFlattened )
					( Origin gBackEnd )
				)
				( attribute "RELATIVE_PROPAGATION_DELAY" "-50.00 MIL,50.00 MIL"
					( Parent
						( matchGroupRef "@baseboard_fab2_lib.baseboard_fab2(sch_1):\MG_DQ_NEAR_DIMM_NG_M_M_BYTE0\" )
					)
					( Units "uMatchProp" "ns" 1.000000)
					( Status sCSetFlattened )
					( Origin gBackEnd )
				)
			)
			( pinPair "@baseboard_fab2_lib.baseboard_fab2(sch_1):\PP1846\"
				( pinRef "@baseboard_fab2_lib.baseboard_fab2(sch_1):page62_i172:DDR5_DQ(1)" )
				( pinRef "@baseboard_fab2_lib.baseboard_fab2(sch_1):page87_i186:DQ(0)" )
				( attribute "RELATIVE_PROPAGATION_DELAY_SCOPE" "G"
					( Parent
						( matchGroupRef "@baseboard_fab2_lib.baseboard_fab2(sch_1):\MG_DQ-DQS_FAR_DIMM_NG_M_M_BYTE0\" )
					)
					( Status sCSetFlattened )
					( Origin gBackEnd )
				)
				( attribute "RELATIVE_PROPAGATION_DELAY" "0.00 MIL,195.00 MIL"
					( Parent
						( matchGroupRef "@baseboard_fab2_lib.baseboard_fab2(sch_1):\MG_DQ-DQS_FAR_DIMM_NG_M_M_BYTE0\" )
					)
					( Units "uMatchProp" "ns" 1.000000)
					( Status sCSetFlattened )
					( Origin gBackEnd )
				)
				( attribute "RELATIVE_PROPAGATION_DELAY_SCOPE" "G"
					( Parent
						( matchGroupRef "@baseboard_fab2_lib.baseboard_fab2(sch_1):\MG_DQ_FAR_DIMM_NG_M_M_BYTE0\" )
					)
					( Status sCSetFlattened )
					( Origin gBackEnd )
				)
				( attribute "RELATIVE_PROPAGATION_DELAY" "-50.00 MIL,50.00 MIL"
					( Parent
						( matchGroupRef "@baseboard_fab2_lib.baseboard_fab2(sch_1):\MG_DQ_FAR_DIMM_NG_M_M_BYTE0\" )
					)
					( Units "uMatchProp" "ns" 1.000000)
					( Status sCSetFlattened )
					( Origin gBackEnd )
				)
			)
			( pinPair "@baseboard_fab2_lib.baseboard_fab2(sch_1):\PP1847\"
				( pinRef "@baseboard_fab2_lib.baseboard_fab2(sch_1):page62_i172:DDR5_DQ(1)" )
				( pinRef "@baseboard_fab2_lib.baseboard_fab2(sch_1):page88_i111:DQ(1)" )
				( attribute "RELATIVE_PROPAGATION_DELAY_SCOPE" "G"
					( Parent
						( matchGroupRef "@baseboard_fab2_lib.baseboard_fab2(sch_1):\MG_DQ-DQS_NEAR_DIMM_NG_M_M_BYTE0\" )
					)
					( Status sCSetFlattened )
					( Origin gBackEnd )
				)
				( attribute "RELATIVE_PROPAGATION_DELAY" "0.00 MIL,195.00 MIL"
					( Parent
						( matchGroupRef "@baseboard_fab2_lib.baseboard_fab2(sch_1):\MG_DQ-DQS_NEAR_DIMM_NG_M_M_BYTE0\" )
					)
					( Units "uMatchProp" "ns" 1.000000)
					( Status sCSetFlattened )
					( Origin gBackEnd )
				)
				( attribute "RELATIVE_PROPAGATION_DELAY_SCOPE" "G"
					( Parent
						( matchGroupRef "@baseboard_fab2_lib.baseboard_fab2(sch_1):\MG_DQ_NEAR_DIMM_NG_M_M_BYTE0\" )
					)
					( Status sCSetFlattened )
					( Origin gBackEnd )
				)
				( attribute "RELATIVE_PROPAGATION_DELAY" "-50.00 MIL,50.00 MIL"
					( Parent
						( matchGroupRef "@baseboard_fab2_lib.baseboard_fab2(sch_1):\MG_DQ_NEAR_DIMM_NG_M_M_BYTE0\" )
					)
					( Units "uMatchProp" "ns" 1.000000)
					( Status sCSetFlattened )
					( Origin gBackEnd )
				)
			)
			( pinPair "@baseboard_fab2_lib.baseboard_fab2(sch_1):\PP1849\"
				( pinRef "@baseboard_fab2_lib.baseboard_fab2(sch_1):page62_i172:DDR5_DQ(2)" )
				( pinRef "@baseboard_fab2_lib.baseboard_fab2(sch_1):page87_i186:DQ(3)" )
				( attribute "RELATIVE_PROPAGATION_DELAY_SCOPE" "G"
					( Parent
						( matchGroupRef "@baseboard_fab2_lib.baseboard_fab2(sch_1):\MG_DQ-DQS_FAR_DIMM_NG_M_M_BYTE0\" )
					)
					( Status sCSetFlattened )
					( Origin gBackEnd )
				)
				( attribute "RELATIVE_PROPAGATION_DELAY" "0.00 MIL,195.00 MIL"
					( Parent
						( matchGroupRef "@baseboard_fab2_lib.baseboard_fab2(sch_1):\MG_DQ-DQS_FAR_DIMM_NG_M_M_BYTE0\" )
					)
					( Units "uMatchProp" "ns" 1.000000)
					( Status sCSetFlattened )
					( Origin gBackEnd )
				)
				( attribute "RELATIVE_PROPAGATION_DELAY_SCOPE" "G"
					( Parent
						( matchGroupRef "@baseboard_fab2_lib.baseboard_fab2(sch_1):\MG_DQ_FAR_DIMM_NG_M_M_BYTE0\" )
					)
					( Status sCSetFlattened )
					( Origin gBackEnd )
				)
				( attribute "RELATIVE_PROPAGATION_DELAY" "-50.00 MIL,50.00 MIL"
					( Parent
						( matchGroupRef "@baseboard_fab2_lib.baseboard_fab2(sch_1):\MG_DQ_FAR_DIMM_NG_M_M_BYTE0\" )
					)
					( Units "uMatchProp" "ns" 1.000000)
					( Status sCSetFlattened )
					( Origin gBackEnd )
				)
			)
			( pinPair "@baseboard_fab2_lib.baseboard_fab2(sch_1):\PP1850\"
				( pinRef "@baseboard_fab2_lib.baseboard_fab2(sch_1):page62_i172:DDR5_DQ(2)" )
				( pinRef "@baseboard_fab2_lib.baseboard_fab2(sch_1):page88_i111:DQ(2)" )
				( attribute "RELATIVE_PROPAGATION_DELAY_SCOPE" "G"
					( Parent
						( matchGroupRef "@baseboard_fab2_lib.baseboard_fab2(sch_1):\MG_DQ-DQS_NEAR_DIMM_NG_M_M_BYTE0\" )
					)
					( Status sCSetFlattened )
					( Origin gBackEnd )
				)
				( attribute "RELATIVE_PROPAGATION_DELAY" "0.00 MIL,195.00 MIL"
					( Parent
						( matchGroupRef "@baseboard_fab2_lib.baseboard_fab2(sch_1):\MG_DQ-DQS_NEAR_DIMM_NG_M_M_BYTE0\" )
					)
					( Units "uMatchProp" "ns" 1.000000)
					( Status sCSetFlattened )
					( Origin gBackEnd )
				)
				( attribute "RELATIVE_PROPAGATION_DELAY_SCOPE" "G"
					( Parent
						( matchGroupRef "@baseboard_fab2_lib.baseboard_fab2(sch_1):\MG_DQ_NEAR_DIMM_NG_M_M_BYTE0\" )
					)
					( Status sCSetFlattened )
					( Origin gBackEnd )
				)
				( attribute "RELATIVE_PROPAGATION_DELAY" "-50.00 MIL,50.00 MIL"
					( Parent
						( matchGroupRef "@baseboard_fab2_lib.baseboard_fab2(sch_1):\MG_DQ_NEAR_DIMM_NG_M_M_BYTE0\" )
					)
					( Units "uMatchProp" "ns" 1.000000)
					( Status sCSetFlattened )
					( Origin gBackEnd )
				)
			)
			( pinPair "@baseboard_fab2_lib.baseboard_fab2(sch_1):\PP1852\"
				( pinRef "@baseboard_fab2_lib.baseboard_fab2(sch_1):page62_i172:DDR5_DQ(3)" )
				( pinRef "@baseboard_fab2_lib.baseboard_fab2(sch_1):page87_i186:DQ(2)" )
				( attribute "RELATIVE_PROPAGATION_DELAY_SCOPE" "G"
					( Parent
						( matchGroupRef "@baseboard_fab2_lib.baseboard_fab2(sch_1):\MG_DQ-DQS_FAR_DIMM_NG_M_M_BYTE0\" )
					)
					( Status sCSetFlattened )
					( Origin gBackEnd )
				)
				( attribute "RELATIVE_PROPAGATION_DELAY" "0.00 MIL,195.00 MIL"
					( Parent
						( matchGroupRef "@baseboard_fab2_lib.baseboard_fab2(sch_1):\MG_DQ-DQS_FAR_DIMM_NG_M_M_BYTE0\" )
					)
					( Units "uMatchProp" "ns" 1.000000)
					( Status sCSetFlattened )
					( Origin gBackEnd )
				)
				( attribute "RELATIVE_PROPAGATION_DELAY_SCOPE" "G"
					( Parent
						( matchGroupRef "@baseboard_fab2_lib.baseboard_fab2(sch_1):\MG_DQ_FAR_DIMM_NG_M_M_BYTE0\" )
					)
					( Status sCSetFlattened )
					( Origin gBackEnd )
				)
				( attribute "RELATIVE_PROPAGATION_DELAY" "-50.00 MIL,50.00 MIL"
					( Parent
						( matchGroupRef "@baseboard_fab2_lib.baseboard_fab2(sch_1):\MG_DQ_FAR_DIMM_NG_M_M_BYTE0\" )
					)
					( Units "uMatchProp" "ns" 1.000000)
					( Status sCSetFlattened )
					( Origin gBackEnd )
				)
			)
			( pinPair "@baseboard_fab2_lib.baseboard_fab2(sch_1):\PP1853\"
				( pinRef "@baseboard_fab2_lib.baseboard_fab2(sch_1):page62_i172:DDR5_DQ(3)" )
				( pinRef "@baseboard_fab2_lib.baseboard_fab2(sch_1):page88_i111:DQ(3)" )
				( attribute "RELATIVE_PROPAGATION_DELAY_SCOPE" "G"
					( Parent
						( matchGroupRef "@baseboard_fab2_lib.baseboard_fab2(sch_1):\MG_DQ-DQS_NEAR_DIMM_NG_M_M_BYTE0\" )
					)
					( Status sCSetFlattened )
					( Origin gBackEnd )
				)
				( attribute "RELATIVE_PROPAGATION_DELAY" "0.00 MIL,195.00 MIL"
					( Parent
						( matchGroupRef "@baseboard_fab2_lib.baseboard_fab2(sch_1):\MG_DQ-DQS_NEAR_DIMM_NG_M_M_BYTE0\" )
					)
					( Units "uMatchProp" "ns" 1.000000)
					( Status sCSetFlattened )
					( Origin gBackEnd )
				)
				( attribute "RELATIVE_PROPAGATION_DELAY_SCOPE" "G"
					( Parent
						( matchGroupRef "@baseboard_fab2_lib.baseboard_fab2(sch_1):\MG_DQ_NEAR_DIMM_NG_M_M_BYTE0\" )
					)
					( Status sCSetFlattened )
					( Origin gBackEnd )
				)
				( attribute "RELATIVE_PROPAGATION_DELAY" "-50.00 MIL,50.00 MIL"
					( Parent
						( matchGroupRef "@baseboard_fab2_lib.baseboard_fab2(sch_1):\MG_DQ_NEAR_DIMM_NG_M_M_BYTE0\" )
					)
					( Units "uMatchProp" "ns" 1.000000)
					( Status sCSetFlattened )
					( Origin gBackEnd )
				)
			)
			( pinPair "@baseboard_fab2_lib.baseboard_fab2(sch_1):\PP1855\"
				( pinRef "@baseboard_fab2_lib.baseboard_fab2(sch_1):page62_i172:DDR5_DQ(4)" )
				( pinRef "@baseboard_fab2_lib.baseboard_fab2(sch_1):page87_i186:DQ(5)" )
				( attribute "RELATIVE_PROPAGATION_DELAY_SCOPE" "G"
					( Parent
						( matchGroupRef "@baseboard_fab2_lib.baseboard_fab2(sch_1):\MG_DQ-DQS_FAR_DIMM_NG_M_M_BYTE0\" )
					)
					( Status sCSetFlattened )
					( Origin gBackEnd )
				)
				( attribute "RELATIVE_PROPAGATION_DELAY" "0.00 MIL,195.00 MIL"
					( Parent
						( matchGroupRef "@baseboard_fab2_lib.baseboard_fab2(sch_1):\MG_DQ-DQS_FAR_DIMM_NG_M_M_BYTE0\" )
					)
					( Units "uMatchProp" "ns" 1.000000)
					( Status sCSetFlattened )
					( Origin gBackEnd )
				)
				( attribute "RELATIVE_PROPAGATION_DELAY_SCOPE" "G"
					( Parent
						( matchGroupRef "@baseboard_fab2_lib.baseboard_fab2(sch_1):\MG_DQ_FAR_DIMM_NG_M_M_BYTE0\" )
					)
					( Status sCSetFlattened )
					( Origin gBackEnd )
				)
				( attribute "RELATIVE_PROPAGATION_DELAY" "-50.00 MIL,50.00 MIL"
					( Parent
						( matchGroupRef "@baseboard_fab2_lib.baseboard_fab2(sch_1):\MG_DQ_FAR_DIMM_NG_M_M_BYTE0\" )
					)
					( Units "uMatchProp" "ns" 1.000000)
					( Status sCSetFlattened )
					( Origin gBackEnd )
				)
			)
			( pinPair "@baseboard_fab2_lib.baseboard_fab2(sch_1):\PP1856\"
				( pinRef "@baseboard_fab2_lib.baseboard_fab2(sch_1):page62_i172:DDR5_DQ(4)" )
				( pinRef "@baseboard_fab2_lib.baseboard_fab2(sch_1):page88_i111:DQ(4)" )
				( attribute "RELATIVE_PROPAGATION_DELAY_SCOPE" "G"
					( Parent
						( matchGroupRef "@baseboard_fab2_lib.baseboard_fab2(sch_1):\MG_DQ-DQS_NEAR_DIMM_NG_M_M_BYTE0\" )
					)
					( Status sCSetFlattened )
					( Origin gBackEnd )
				)
				( attribute "RELATIVE_PROPAGATION_DELAY" "0.00 MIL,195.00 MIL"
					( Parent
						( matchGroupRef "@baseboard_fab2_lib.baseboard_fab2(sch_1):\MG_DQ-DQS_NEAR_DIMM_NG_M_M_BYTE0\" )
					)
					( Units "uMatchProp" "ns" 1.000000)
					( Status sCSetFlattened )
					( Origin gBackEnd )
				)
				( attribute "RELATIVE_PROPAGATION_DELAY_SCOPE" "G"
					( Parent
						( matchGroupRef "@baseboard_fab2_lib.baseboard_fab2(sch_1):\MG_DQ_NEAR_DIMM_NG_M_M_BYTE0\" )
					)
					( Status sCSetFlattened )
					( Origin gBackEnd )
				)
				( attribute "RELATIVE_PROPAGATION_DELAY" "-50.00 MIL,50.00 MIL"
					( Parent
						( matchGroupRef "@baseboard_fab2_lib.baseboard_fab2(sch_1):\MG_DQ_NEAR_DIMM_NG_M_M_BYTE0\" )
					)
					( Units "uMatchProp" "ns" 1.000000)
					( Status sCSetFlattened )
					( Origin gBackEnd )
				)
			)
			( pinPair "@baseboard_fab2_lib.baseboard_fab2(sch_1):\PP1858\"
				( pinRef "@baseboard_fab2_lib.baseboard_fab2(sch_1):page62_i172:DDR5_DQ(5)" )
				( pinRef "@baseboard_fab2_lib.baseboard_fab2(sch_1):page87_i186:DQ(4)" )
				( attribute "RELATIVE_PROPAGATION_DELAY_SCOPE" "G"
					( Parent
						( matchGroupRef "@baseboard_fab2_lib.baseboard_fab2(sch_1):\MG_DQ-DQS_FAR_DIMM_NG_M_M_BYTE0\" )
					)
					( Status sCSetFlattened )
					( Origin gBackEnd )
				)
				( attribute "RELATIVE_PROPAGATION_DELAY" "0.00 MIL,195.00 MIL"
					( Parent
						( matchGroupRef "@baseboard_fab2_lib.baseboard_fab2(sch_1):\MG_DQ-DQS_FAR_DIMM_NG_M_M_BYTE0\" )
					)
					( Units "uMatchProp" "ns" 1.000000)
					( Status sCSetFlattened )
					( Origin gBackEnd )
				)
				( attribute "RELATIVE_PROPAGATION_DELAY_SCOPE" "G"
					( Parent
						( matchGroupRef "@baseboard_fab2_lib.baseboard_fab2(sch_1):\MG_DQ_FAR_DIMM_NG_M_M_BYTE0\" )
					)
					( Status sCSetFlattened )
					( Origin gBackEnd )
				)
				( attribute "RELATIVE_PROPAGATION_DELAY" "-50.00 MIL,50.00 MIL"
					( Parent
						( matchGroupRef "@baseboard_fab2_lib.baseboard_fab2(sch_1):\MG_DQ_FAR_DIMM_NG_M_M_BYTE0\" )
					)
					( Units "uMatchProp" "ns" 1.000000)
					( Status sCSetFlattened )
					( Origin gBackEnd )
				)
			)
			( pinPair "@baseboard_fab2_lib.baseboard_fab2(sch_1):\PP1859\"
				( pinRef "@baseboard_fab2_lib.baseboard_fab2(sch_1):page62_i172:DDR5_DQ(5)" )
				( pinRef "@baseboard_fab2_lib.baseboard_fab2(sch_1):page88_i111:DQ(5)" )
				( attribute "RELATIVE_PROPAGATION_DELAY_SCOPE" "G"
					( Parent
						( matchGroupRef "@baseboard_fab2_lib.baseboard_fab2(sch_1):\MG_DQ-DQS_NEAR_DIMM_NG_M_M_BYTE0\" )
					)
					( Status sCSetFlattened )
					( Origin gBackEnd )
				)
				( attribute "RELATIVE_PROPAGATION_DELAY" "0.00 MIL,195.00 MIL"
					( Parent
						( matchGroupRef "@baseboard_fab2_lib.baseboard_fab2(sch_1):\MG_DQ-DQS_NEAR_DIMM_NG_M_M_BYTE0\" )
					)
					( Units "uMatchProp" "ns" 1.000000)
					( Status sCSetFlattened )
					( Origin gBackEnd )
				)
				( attribute "RELATIVE_PROPAGATION_DELAY_SCOPE" "G"
					( Parent
						( matchGroupRef "@baseboard_fab2_lib.baseboard_fab2(sch_1):\MG_DQ_NEAR_DIMM_NG_M_M_BYTE0\" )
					)
					( Status sCSetFlattened )
					( Origin gBackEnd )
				)
				( attribute "RELATIVE_PROPAGATION_DELAY" "-50.00 MIL,50.00 MIL"
					( Parent
						( matchGroupRef "@baseboard_fab2_lib.baseboard_fab2(sch_1):\MG_DQ_NEAR_DIMM_NG_M_M_BYTE0\" )
					)
					( Units "uMatchProp" "ns" 1.000000)
					( Status sCSetFlattened )
					( Origin gBackEnd )
				)
			)
			( pinPair "@baseboard_fab2_lib.baseboard_fab2(sch_1):\PP1861\"
				( pinRef "@baseboard_fab2_lib.baseboard_fab2(sch_1):page62_i172:DDR5_DQ(6)" )
				( pinRef "@baseboard_fab2_lib.baseboard_fab2(sch_1):page87_i186:DQ(7)" )
				( attribute "RELATIVE_PROPAGATION_DELAY_SCOPE" "G"
					( Parent
						( matchGroupRef "@baseboard_fab2_lib.baseboard_fab2(sch_1):\MG_DQ-DQS_FAR_DIMM_NG_M_M_BYTE0\" )
					)
					( Status sCSetFlattened )
					( Origin gBackEnd )
				)
				( attribute "RELATIVE_PROPAGATION_DELAY" "0.00 MIL,195.00 MIL"
					( Parent
						( matchGroupRef "@baseboard_fab2_lib.baseboard_fab2(sch_1):\MG_DQ-DQS_FAR_DIMM_NG_M_M_BYTE0\" )
					)
					( Units "uMatchProp" "ns" 1.000000)
					( Status sCSetFlattened )
					( Origin gBackEnd )
				)
				( attribute "RELATIVE_PROPAGATION_DELAY_SCOPE" "G"
					( Parent
						( matchGroupRef "@baseboard_fab2_lib.baseboard_fab2(sch_1):\MG_DQ_FAR_DIMM_NG_M_M_BYTE0\" )
					)
					( Status sCSetFlattened )
					( Origin gBackEnd )
				)
				( attribute "RELATIVE_PROPAGATION_DELAY" "-50.00 MIL,50.00 MIL"
					( Parent
						( matchGroupRef "@baseboard_fab2_lib.baseboard_fab2(sch_1):\MG_DQ_FAR_DIMM_NG_M_M_BYTE0\" )
					)
					( Units "uMatchProp" "ns" 1.000000)
					( Status sCSetFlattened )
					( Origin gBackEnd )
				)
			)
			( pinPair "@baseboard_fab2_lib.baseboard_fab2(sch_1):\PP1862\"
				( pinRef "@baseboard_fab2_lib.baseboard_fab2(sch_1):page62_i172:DDR5_DQ(6)" )
				( pinRef "@baseboard_fab2_lib.baseboard_fab2(sch_1):page88_i111:DQ(6)" )
				( attribute "RELATIVE_PROPAGATION_DELAY_SCOPE" "G"
					( Parent
						( matchGroupRef "@baseboard_fab2_lib.baseboard_fab2(sch_1):\MG_DQ-DQS_NEAR_DIMM_NG_M_M_BYTE0\" )
					)
					( Status sCSetFlattened )
					( Origin gBackEnd )
				)
				( attribute "RELATIVE_PROPAGATION_DELAY" "0.00 MIL,195.00 MIL"
					( Parent
						( matchGroupRef "@baseboard_fab2_lib.baseboard_fab2(sch_1):\MG_DQ-DQS_NEAR_DIMM_NG_M_M_BYTE0\" )
					)
					( Units "uMatchProp" "ns" 1.000000)
					( Status sCSetFlattened )
					( Origin gBackEnd )
				)
				( attribute "RELATIVE_PROPAGATION_DELAY_SCOPE" "G"
					( Parent
						( matchGroupRef "@baseboard_fab2_lib.baseboard_fab2(sch_1):\MG_DQ_NEAR_DIMM_NG_M_M_BYTE0\" )
					)
					( Status sCSetFlattened )
					( Origin gBackEnd )
				)
				( attribute "RELATIVE_PROPAGATION_DELAY" "-50.00 MIL,50.00 MIL"
					( Parent
						( matchGroupRef "@baseboard_fab2_lib.baseboard_fab2(sch_1):\MG_DQ_NEAR_DIMM_NG_M_M_BYTE0\" )
					)
					( Units "uMatchProp" "ns" 1.000000)
					( Status sCSetFlattened )
					( Origin gBackEnd )
				)
			)
			( pinPair "@baseboard_fab2_lib.baseboard_fab2(sch_1):\PP1864\"
				( pinRef "@baseboard_fab2_lib.baseboard_fab2(sch_1):page62_i172:DDR5_DQ(7)" )
				( pinRef "@baseboard_fab2_lib.baseboard_fab2(sch_1):page87_i186:DQ(6)" )
				( attribute "RELATIVE_PROPAGATION_DELAY_SCOPE" "G"
					( Parent
						( matchGroupRef "@baseboard_fab2_lib.baseboard_fab2(sch_1):\MG_DQ-DQS_FAR_DIMM_NG_M_M_BYTE0\" )
					)
					( Status sCSetFlattened )
					( Origin gBackEnd )
				)
				( attribute "RELATIVE_PROPAGATION_DELAY" "0.00 MIL,195.00 MIL"
					( Parent
						( matchGroupRef "@baseboard_fab2_lib.baseboard_fab2(sch_1):\MG_DQ-DQS_FAR_DIMM_NG_M_M_BYTE0\" )
					)
					( Units "uMatchProp" "ns" 1.000000)
					( Status sCSetFlattened )
					( Origin gBackEnd )
				)
				( attribute "RELATIVE_PROPAGATION_DELAY_SCOPE" "G"
					( Parent
						( matchGroupRef "@baseboard_fab2_lib.baseboard_fab2(sch_1):\MG_DQ_FAR_DIMM_NG_M_M_BYTE0\" )
					)
					( Status sCSetFlattened )
					( Origin gBackEnd )
				)
				( attribute "RELATIVE_PROPAGATION_DELAY" "-50.00 MIL,50.00 MIL"
					( Parent
						( matchGroupRef "@baseboard_fab2_lib.baseboard_fab2(sch_1):\MG_DQ_FAR_DIMM_NG_M_M_BYTE0\" )
					)
					( Units "uMatchProp" "ns" 1.000000)
					( Status sCSetFlattened )
					( Origin gBackEnd )
				)
			)
			( pinPair "@baseboard_fab2_lib.baseboard_fab2(sch_1):\PP1865\"
				( pinRef "@baseboard_fab2_lib.baseboard_fab2(sch_1):page62_i172:DDR5_DQ(7)" )
				( pinRef "@baseboard_fab2_lib.baseboard_fab2(sch_1):page88_i111:DQ(7)" )
				( attribute "RELATIVE_PROPAGATION_DELAY_SCOPE" "G"
					( Parent
						( matchGroupRef "@baseboard_fab2_lib.baseboard_fab2(sch_1):\MG_DQ-DQS_NEAR_DIMM_NG_M_M_BYTE0\" )
					)
					( Status sCSetFlattened )
					( Origin gBackEnd )
				)
				( attribute "RELATIVE_PROPAGATION_DELAY" "0.00 MIL,195.00 MIL"
					( Parent
						( matchGroupRef "@baseboard_fab2_lib.baseboard_fab2(sch_1):\MG_DQ-DQS_NEAR_DIMM_NG_M_M_BYTE0\" )
					)
					( Units "uMatchProp" "ns" 1.000000)
					( Status sCSetFlattened )
					( Origin gBackEnd )
				)
				( attribute "RELATIVE_PROPAGATION_DELAY_SCOPE" "G"
					( Parent
						( matchGroupRef "@baseboard_fab2_lib.baseboard_fab2(sch_1):\MG_DQ_NEAR_DIMM_NG_M_M_BYTE0\" )
					)
					( Status sCSetFlattened )
					( Origin gBackEnd )
				)
				( attribute "RELATIVE_PROPAGATION_DELAY" "-50.00 MIL,50.00 MIL"
					( Parent
						( matchGroupRef "@baseboard_fab2_lib.baseboard_fab2(sch_1):\MG_DQ_NEAR_DIMM_NG_M_M_BYTE0\" )
					)
					( Units "uMatchProp" "ns" 1.000000)
					( Status sCSetFlattened )
					( Origin gBackEnd )
				)
			)
			( pinPair "@baseboard_fab2_lib.baseboard_fab2(sch_1):\PP1819\"
				( pinRef "@baseboard_fab2_lib.baseboard_fab2(sch_1):page62_i172:DDR5_DQ(8)" )
				( pinRef "@baseboard_fab2_lib.baseboard_fab2(sch_1):page87_i186:DQ(9)" )
				( attribute "RELATIVE_PROPAGATION_DELAY_SCOPE" "G"
					( Parent
						( matchGroupRef "@baseboard_fab2_lib.baseboard_fab2(sch_1):\MG_DQ-DQS_FAR_DIMM_NG_M_M_BYTE1\" )
					)
					( Status sCSetFlattened )
					( Origin gBackEnd )
				)
				( attribute "RELATIVE_PROPAGATION_DELAY" "0.00 MIL,195.00 MIL"
					( Parent
						( matchGroupRef "@baseboard_fab2_lib.baseboard_fab2(sch_1):\MG_DQ-DQS_FAR_DIMM_NG_M_M_BYTE1\" )
					)
					( Units "uMatchProp" "ns" 1.000000)
					( Status sCSetFlattened )
					( Origin gBackEnd )
				)
				( attribute "RELATIVE_PROPAGATION_DELAY_SCOPE" "G"
					( Parent
						( matchGroupRef "@baseboard_fab2_lib.baseboard_fab2(sch_1):\MG_DQ_FAR_DIMM_NG_M_M_BYTE1\" )
					)
					( Status sCSetFlattened )
					( Origin gBackEnd )
				)
				( attribute "RELATIVE_PROPAGATION_DELAY" "-50.00 MIL,50.00 MIL"
					( Parent
						( matchGroupRef "@baseboard_fab2_lib.baseboard_fab2(sch_1):\MG_DQ_FAR_DIMM_NG_M_M_BYTE1\" )
					)
					( Units "uMatchProp" "ns" 1.000000)
					( Status sCSetFlattened )
					( Origin gBackEnd )
				)
			)
			( pinPair "@baseboard_fab2_lib.baseboard_fab2(sch_1):\PP1820\"
				( pinRef "@baseboard_fab2_lib.baseboard_fab2(sch_1):page62_i172:DDR5_DQ(8)" )
				( pinRef "@baseboard_fab2_lib.baseboard_fab2(sch_1):page88_i111:DQ(8)" )
				( attribute "RELATIVE_PROPAGATION_DELAY_SCOPE" "G"
					( Parent
						( matchGroupRef "@baseboard_fab2_lib.baseboard_fab2(sch_1):\MG_DQ-DQS_NEAR_DIMM_NG_M_M_BYTE1\" )
					)
					( Status sCSetFlattened )
					( Origin gBackEnd )
				)
				( attribute "RELATIVE_PROPAGATION_DELAY" "0.00 MIL,195.00 MIL"
					( Parent
						( matchGroupRef "@baseboard_fab2_lib.baseboard_fab2(sch_1):\MG_DQ-DQS_NEAR_DIMM_NG_M_M_BYTE1\" )
					)
					( Units "uMatchProp" "ns" 1.000000)
					( Status sCSetFlattened )
					( Origin gBackEnd )
				)
				( attribute "RELATIVE_PROPAGATION_DELAY_SCOPE" "G"
					( Parent
						( matchGroupRef "@baseboard_fab2_lib.baseboard_fab2(sch_1):\MG_DQ_NEAR_DIMM_NG_M_M_BYTE1\" )
					)
					( Status sCSetFlattened )
					( Origin gBackEnd )
				)
				( attribute "RELATIVE_PROPAGATION_DELAY" "-50.00 MIL,50.00 MIL"
					( Parent
						( matchGroupRef "@baseboard_fab2_lib.baseboard_fab2(sch_1):\MG_DQ_NEAR_DIMM_NG_M_M_BYTE1\" )
					)
					( Units "uMatchProp" "ns" 1.000000)
					( Status sCSetFlattened )
					( Origin gBackEnd )
				)
			)
			( pinPair "@baseboard_fab2_lib.baseboard_fab2(sch_1):\PP1822\"
				( pinRef "@baseboard_fab2_lib.baseboard_fab2(sch_1):page62_i172:DDR5_DQ(9)" )
				( pinRef "@baseboard_fab2_lib.baseboard_fab2(sch_1):page87_i186:DQ(8)" )
				( attribute "RELATIVE_PROPAGATION_DELAY_SCOPE" "G"
					( Parent
						( matchGroupRef "@baseboard_fab2_lib.baseboard_fab2(sch_1):\MG_DQ-DQS_FAR_DIMM_NG_M_M_BYTE1\" )
					)
					( Status sCSetFlattened )
					( Origin gBackEnd )
				)
				( attribute "RELATIVE_PROPAGATION_DELAY" "0.00 MIL,195.00 MIL"
					( Parent
						( matchGroupRef "@baseboard_fab2_lib.baseboard_fab2(sch_1):\MG_DQ-DQS_FAR_DIMM_NG_M_M_BYTE1\" )
					)
					( Units "uMatchProp" "ns" 1.000000)
					( Status sCSetFlattened )
					( Origin gBackEnd )
				)
				( attribute "RELATIVE_PROPAGATION_DELAY_SCOPE" "G"
					( Parent
						( matchGroupRef "@baseboard_fab2_lib.baseboard_fab2(sch_1):\MG_DQ_FAR_DIMM_NG_M_M_BYTE1\" )
					)
					( Status sCSetFlattened )
					( Origin gBackEnd )
				)
				( attribute "RELATIVE_PROPAGATION_DELAY" "-50.00 MIL,50.00 MIL"
					( Parent
						( matchGroupRef "@baseboard_fab2_lib.baseboard_fab2(sch_1):\MG_DQ_FAR_DIMM_NG_M_M_BYTE1\" )
					)
					( Units "uMatchProp" "ns" 1.000000)
					( Status sCSetFlattened )
					( Origin gBackEnd )
				)
			)
			( pinPair "@baseboard_fab2_lib.baseboard_fab2(sch_1):\PP1823\"
				( pinRef "@baseboard_fab2_lib.baseboard_fab2(sch_1):page62_i172:DDR5_DQ(9)" )
				( pinRef "@baseboard_fab2_lib.baseboard_fab2(sch_1):page88_i111:DQ(9)" )
				( attribute "RELATIVE_PROPAGATION_DELAY_SCOPE" "G"
					( Parent
						( matchGroupRef "@baseboard_fab2_lib.baseboard_fab2(sch_1):\MG_DQ-DQS_NEAR_DIMM_NG_M_M_BYTE1\" )
					)
					( Status sCSetFlattened )
					( Origin gBackEnd )
				)
				( attribute "RELATIVE_PROPAGATION_DELAY" "0.00 MIL,195.00 MIL"
					( Parent
						( matchGroupRef "@baseboard_fab2_lib.baseboard_fab2(sch_1):\MG_DQ-DQS_NEAR_DIMM_NG_M_M_BYTE1\" )
					)
					( Units "uMatchProp" "ns" 1.000000)
					( Status sCSetFlattened )
					( Origin gBackEnd )
				)
				( attribute "RELATIVE_PROPAGATION_DELAY_SCOPE" "G"
					( Parent
						( matchGroupRef "@baseboard_fab2_lib.baseboard_fab2(sch_1):\MG_DQ_NEAR_DIMM_NG_M_M_BYTE1\" )
					)
					( Status sCSetFlattened )
					( Origin gBackEnd )
				)
				( attribute "RELATIVE_PROPAGATION_DELAY" "-50.00 MIL,50.00 MIL"
					( Parent
						( matchGroupRef "@baseboard_fab2_lib.baseboard_fab2(sch_1):\MG_DQ_NEAR_DIMM_NG_M_M_BYTE1\" )
					)
					( Units "uMatchProp" "ns" 1.000000)
					( Status sCSetFlattened )
					( Origin gBackEnd )
				)
			)
			( pinPair "@baseboard_fab2_lib.baseboard_fab2(sch_1):\PP1825\"
				( pinRef "@baseboard_fab2_lib.baseboard_fab2(sch_1):page62_i172:DDR5_DQ(10)" )
				( pinRef "@baseboard_fab2_lib.baseboard_fab2(sch_1):page87_i186:DQ(11)" )
				( attribute "RELATIVE_PROPAGATION_DELAY_SCOPE" "G"
					( Parent
						( matchGroupRef "@baseboard_fab2_lib.baseboard_fab2(sch_1):\MG_DQ-DQS_FAR_DIMM_NG_M_M_BYTE1\" )
					)
					( Status sCSetFlattened )
					( Origin gBackEnd )
				)
				( attribute "RELATIVE_PROPAGATION_DELAY" "0.00 MIL,195.00 MIL"
					( Parent
						( matchGroupRef "@baseboard_fab2_lib.baseboard_fab2(sch_1):\MG_DQ-DQS_FAR_DIMM_NG_M_M_BYTE1\" )
					)
					( Units "uMatchProp" "ns" 1.000000)
					( Status sCSetFlattened )
					( Origin gBackEnd )
				)
				( attribute "RELATIVE_PROPAGATION_DELAY_SCOPE" "G"
					( Parent
						( matchGroupRef "@baseboard_fab2_lib.baseboard_fab2(sch_1):\MG_DQ_FAR_DIMM_NG_M_M_BYTE1\" )
					)
					( Status sCSetFlattened )
					( Origin gBackEnd )
				)
				( attribute "RELATIVE_PROPAGATION_DELAY" "-50.00 MIL,50.00 MIL"
					( Parent
						( matchGroupRef "@baseboard_fab2_lib.baseboard_fab2(sch_1):\MG_DQ_FAR_DIMM_NG_M_M_BYTE1\" )
					)
					( Units "uMatchProp" "ns" 1.000000)
					( Status sCSetFlattened )
					( Origin gBackEnd )
				)
			)
			( pinPair "@baseboard_fab2_lib.baseboard_fab2(sch_1):\PP1826\"
				( pinRef "@baseboard_fab2_lib.baseboard_fab2(sch_1):page62_i172:DDR5_DQ(10)" )
				( pinRef "@baseboard_fab2_lib.baseboard_fab2(sch_1):page88_i111:DQ(10)" )
				( attribute "RELATIVE_PROPAGATION_DELAY_SCOPE" "G"
					( Parent
						( matchGroupRef "@baseboard_fab2_lib.baseboard_fab2(sch_1):\MG_DQ-DQS_NEAR_DIMM_NG_M_M_BYTE1\" )
					)
					( Status sCSetFlattened )
					( Origin gBackEnd )
				)
				( attribute "RELATIVE_PROPAGATION_DELAY" "0.00 MIL,195.00 MIL"
					( Parent
						( matchGroupRef "@baseboard_fab2_lib.baseboard_fab2(sch_1):\MG_DQ-DQS_NEAR_DIMM_NG_M_M_BYTE1\" )
					)
					( Units "uMatchProp" "ns" 1.000000)
					( Status sCSetFlattened )
					( Origin gBackEnd )
				)
				( attribute "RELATIVE_PROPAGATION_DELAY_SCOPE" "G"
					( Parent
						( matchGroupRef "@baseboard_fab2_lib.baseboard_fab2(sch_1):\MG_DQ_NEAR_DIMM_NG_M_M_BYTE1\" )
					)
					( Status sCSetFlattened )
					( Origin gBackEnd )
				)
				( attribute "RELATIVE_PROPAGATION_DELAY" "-50.00 MIL,50.00 MIL"
					( Parent
						( matchGroupRef "@baseboard_fab2_lib.baseboard_fab2(sch_1):\MG_DQ_NEAR_DIMM_NG_M_M_BYTE1\" )
					)
					( Units "uMatchProp" "ns" 1.000000)
					( Status sCSetFlattened )
					( Origin gBackEnd )
				)
			)
			( pinPair "@baseboard_fab2_lib.baseboard_fab2(sch_1):\PP1828\"
				( pinRef "@baseboard_fab2_lib.baseboard_fab2(sch_1):page62_i172:DDR5_DQ(11)" )
				( pinRef "@baseboard_fab2_lib.baseboard_fab2(sch_1):page87_i186:DQ(10)" )
				( attribute "RELATIVE_PROPAGATION_DELAY_SCOPE" "G"
					( Parent
						( matchGroupRef "@baseboard_fab2_lib.baseboard_fab2(sch_1):\MG_DQ-DQS_FAR_DIMM_NG_M_M_BYTE1\" )
					)
					( Status sCSetFlattened )
					( Origin gBackEnd )
				)
				( attribute "RELATIVE_PROPAGATION_DELAY" "0.00 MIL,195.00 MIL"
					( Parent
						( matchGroupRef "@baseboard_fab2_lib.baseboard_fab2(sch_1):\MG_DQ-DQS_FAR_DIMM_NG_M_M_BYTE1\" )
					)
					( Units "uMatchProp" "ns" 1.000000)
					( Status sCSetFlattened )
					( Origin gBackEnd )
				)
				( attribute "RELATIVE_PROPAGATION_DELAY_SCOPE" "G"
					( Parent
						( matchGroupRef "@baseboard_fab2_lib.baseboard_fab2(sch_1):\MG_DQ_FAR_DIMM_NG_M_M_BYTE1\" )
					)
					( Status sCSetFlattened )
					( Origin gBackEnd )
				)
				( attribute "RELATIVE_PROPAGATION_DELAY" "-50.00 MIL,50.00 MIL"
					( Parent
						( matchGroupRef "@baseboard_fab2_lib.baseboard_fab2(sch_1):\MG_DQ_FAR_DIMM_NG_M_M_BYTE1\" )
					)
					( Units "uMatchProp" "ns" 1.000000)
					( Status sCSetFlattened )
					( Origin gBackEnd )
				)
			)
			( pinPair "@baseboard_fab2_lib.baseboard_fab2(sch_1):\PP1829\"
				( pinRef "@baseboard_fab2_lib.baseboard_fab2(sch_1):page62_i172:DDR5_DQ(11)" )
				( pinRef "@baseboard_fab2_lib.baseboard_fab2(sch_1):page88_i111:DQ(11)" )
				( attribute "RELATIVE_PROPAGATION_DELAY_SCOPE" "G"
					( Parent
						( matchGroupRef "@baseboard_fab2_lib.baseboard_fab2(sch_1):\MG_DQ-DQS_NEAR_DIMM_NG_M_M_BYTE1\" )
					)
					( Status sCSetFlattened )
					( Origin gBackEnd )
				)
				( attribute "RELATIVE_PROPAGATION_DELAY" "0.00 MIL,195.00 MIL"
					( Parent
						( matchGroupRef "@baseboard_fab2_lib.baseboard_fab2(sch_1):\MG_DQ-DQS_NEAR_DIMM_NG_M_M_BYTE1\" )
					)
					( Units "uMatchProp" "ns" 1.000000)
					( Status sCSetFlattened )
					( Origin gBackEnd )
				)
				( attribute "RELATIVE_PROPAGATION_DELAY_SCOPE" "G"
					( Parent
						( matchGroupRef "@baseboard_fab2_lib.baseboard_fab2(sch_1):\MG_DQ_NEAR_DIMM_NG_M_M_BYTE1\" )
					)
					( Status sCSetFlattened )
					( Origin gBackEnd )
				)
				( attribute "RELATIVE_PROPAGATION_DELAY" "-50.00 MIL,50.00 MIL"
					( Parent
						( matchGroupRef "@baseboard_fab2_lib.baseboard_fab2(sch_1):\MG_DQ_NEAR_DIMM_NG_M_M_BYTE1\" )
					)
					( Units "uMatchProp" "ns" 1.000000)
					( Status sCSetFlattened )
					( Origin gBackEnd )
				)
			)
			( pinPair "@baseboard_fab2_lib.baseboard_fab2(sch_1):\PP1831\"
				( pinRef "@baseboard_fab2_lib.baseboard_fab2(sch_1):page62_i172:DDR5_DQ(12)" )
				( pinRef "@baseboard_fab2_lib.baseboard_fab2(sch_1):page87_i186:DQ(13)" )
				( attribute "RELATIVE_PROPAGATION_DELAY_SCOPE" "G"
					( Parent
						( matchGroupRef "@baseboard_fab2_lib.baseboard_fab2(sch_1):\MG_DQ-DQS_FAR_DIMM_NG_M_M_BYTE1\" )
					)
					( Status sCSetFlattened )
					( Origin gBackEnd )
				)
				( attribute "RELATIVE_PROPAGATION_DELAY" "0.00 MIL,195.00 MIL"
					( Parent
						( matchGroupRef "@baseboard_fab2_lib.baseboard_fab2(sch_1):\MG_DQ-DQS_FAR_DIMM_NG_M_M_BYTE1\" )
					)
					( Units "uMatchProp" "ns" 1.000000)
					( Status sCSetFlattened )
					( Origin gBackEnd )
				)
				( attribute "RELATIVE_PROPAGATION_DELAY_SCOPE" "G"
					( Parent
						( matchGroupRef "@baseboard_fab2_lib.baseboard_fab2(sch_1):\MG_DQ_FAR_DIMM_NG_M_M_BYTE1\" )
					)
					( Status sCSetFlattened )
					( Origin gBackEnd )
				)
				( attribute "RELATIVE_PROPAGATION_DELAY" "-50.00 MIL,50.00 MIL"
					( Parent
						( matchGroupRef "@baseboard_fab2_lib.baseboard_fab2(sch_1):\MG_DQ_FAR_DIMM_NG_M_M_BYTE1\" )
					)
					( Units "uMatchProp" "ns" 1.000000)
					( Status sCSetFlattened )
					( Origin gBackEnd )
				)
			)
			( pinPair "@baseboard_fab2_lib.baseboard_fab2(sch_1):\PP1832\"
				( pinRef "@baseboard_fab2_lib.baseboard_fab2(sch_1):page62_i172:DDR5_DQ(12)" )
				( pinRef "@baseboard_fab2_lib.baseboard_fab2(sch_1):page88_i111:DQ(12)" )
				( attribute "RELATIVE_PROPAGATION_DELAY_SCOPE" "G"
					( Parent
						( matchGroupRef "@baseboard_fab2_lib.baseboard_fab2(sch_1):\MG_DQ-DQS_NEAR_DIMM_NG_M_M_BYTE1\" )
					)
					( Status sCSetFlattened )
					( Origin gBackEnd )
				)
				( attribute "RELATIVE_PROPAGATION_DELAY" "0.00 MIL,195.00 MIL"
					( Parent
						( matchGroupRef "@baseboard_fab2_lib.baseboard_fab2(sch_1):\MG_DQ-DQS_NEAR_DIMM_NG_M_M_BYTE1\" )
					)
					( Units "uMatchProp" "ns" 1.000000)
					( Status sCSetFlattened )
					( Origin gBackEnd )
				)
				( attribute "RELATIVE_PROPAGATION_DELAY_SCOPE" "G"
					( Parent
						( matchGroupRef "@baseboard_fab2_lib.baseboard_fab2(sch_1):\MG_DQ_NEAR_DIMM_NG_M_M_BYTE1\" )
					)
					( Status sCSetFlattened )
					( Origin gBackEnd )
				)
				( attribute "RELATIVE_PROPAGATION_DELAY" "-50.00 MIL,50.00 MIL"
					( Parent
						( matchGroupRef "@baseboard_fab2_lib.baseboard_fab2(sch_1):\MG_DQ_NEAR_DIMM_NG_M_M_BYTE1\" )
					)
					( Units "uMatchProp" "ns" 1.000000)
					( Status sCSetFlattened )
					( Origin gBackEnd )
				)
			)
			( pinPair "@baseboard_fab2_lib.baseboard_fab2(sch_1):\PP1834\"
				( pinRef "@baseboard_fab2_lib.baseboard_fab2(sch_1):page62_i172:DDR5_DQ(13)" )
				( pinRef "@baseboard_fab2_lib.baseboard_fab2(sch_1):page87_i186:DQ(12)" )
				( attribute "RELATIVE_PROPAGATION_DELAY_SCOPE" "G"
					( Parent
						( matchGroupRef "@baseboard_fab2_lib.baseboard_fab2(sch_1):\MG_DQ-DQS_FAR_DIMM_NG_M_M_BYTE1\" )
					)
					( Status sCSetFlattened )
					( Origin gBackEnd )
				)
				( attribute "RELATIVE_PROPAGATION_DELAY" "0.00 MIL,195.00 MIL"
					( Parent
						( matchGroupRef "@baseboard_fab2_lib.baseboard_fab2(sch_1):\MG_DQ-DQS_FAR_DIMM_NG_M_M_BYTE1\" )
					)
					( Units "uMatchProp" "ns" 1.000000)
					( Status sCSetFlattened )
					( Origin gBackEnd )
				)
				( attribute "RELATIVE_PROPAGATION_DELAY_SCOPE" "G"
					( Parent
						( matchGroupRef "@baseboard_fab2_lib.baseboard_fab2(sch_1):\MG_DQ_FAR_DIMM_NG_M_M_BYTE1\" )
					)
					( Status sCSetFlattened )
					( Origin gBackEnd )
				)
				( attribute "RELATIVE_PROPAGATION_DELAY" "-50.00 MIL,50.00 MIL"
					( Parent
						( matchGroupRef "@baseboard_fab2_lib.baseboard_fab2(sch_1):\MG_DQ_FAR_DIMM_NG_M_M_BYTE1\" )
					)
					( Units "uMatchProp" "ns" 1.000000)
					( Status sCSetFlattened )
					( Origin gBackEnd )
				)
			)
			( pinPair "@baseboard_fab2_lib.baseboard_fab2(sch_1):\PP1835\"
				( pinRef "@baseboard_fab2_lib.baseboard_fab2(sch_1):page62_i172:DDR5_DQ(13)" )
				( pinRef "@baseboard_fab2_lib.baseboard_fab2(sch_1):page88_i111:DQ(13)" )
				( attribute "RELATIVE_PROPAGATION_DELAY_SCOPE" "G"
					( Parent
						( matchGroupRef "@baseboard_fab2_lib.baseboard_fab2(sch_1):\MG_DQ-DQS_NEAR_DIMM_NG_M_M_BYTE1\" )
					)
					( Status sCSetFlattened )
					( Origin gBackEnd )
				)
				( attribute "RELATIVE_PROPAGATION_DELAY" "0.00 MIL,195.00 MIL"
					( Parent
						( matchGroupRef "@baseboard_fab2_lib.baseboard_fab2(sch_1):\MG_DQ-DQS_NEAR_DIMM_NG_M_M_BYTE1\" )
					)
					( Units "uMatchProp" "ns" 1.000000)
					( Status sCSetFlattened )
					( Origin gBackEnd )
				)
				( attribute "RELATIVE_PROPAGATION_DELAY_SCOPE" "G"
					( Parent
						( matchGroupRef "@baseboard_fab2_lib.baseboard_fab2(sch_1):\MG_DQ_NEAR_DIMM_NG_M_M_BYTE1\" )
					)
					( Status sCSetFlattened )
					( Origin gBackEnd )
				)
				( attribute "RELATIVE_PROPAGATION_DELAY" "-50.00 MIL,50.00 MIL"
					( Parent
						( matchGroupRef "@baseboard_fab2_lib.baseboard_fab2(sch_1):\MG_DQ_NEAR_DIMM_NG_M_M_BYTE1\" )
					)
					( Units "uMatchProp" "ns" 1.000000)
					( Status sCSetFlattened )
					( Origin gBackEnd )
				)
			)
			( pinPair "@baseboard_fab2_lib.baseboard_fab2(sch_1):\PP1837\"
				( pinRef "@baseboard_fab2_lib.baseboard_fab2(sch_1):page62_i172:DDR5_DQ(14)" )
				( pinRef "@baseboard_fab2_lib.baseboard_fab2(sch_1):page87_i186:DQ(15)" )
				( attribute "RELATIVE_PROPAGATION_DELAY_SCOPE" "G"
					( Parent
						( matchGroupRef "@baseboard_fab2_lib.baseboard_fab2(sch_1):\MG_DQ-DQS_FAR_DIMM_NG_M_M_BYTE1\" )
					)
					( Status sCSetFlattened )
					( Origin gBackEnd )
				)
				( attribute "RELATIVE_PROPAGATION_DELAY" "0.00 MIL,195.00 MIL"
					( Parent
						( matchGroupRef "@baseboard_fab2_lib.baseboard_fab2(sch_1):\MG_DQ-DQS_FAR_DIMM_NG_M_M_BYTE1\" )
					)
					( Units "uMatchProp" "ns" 1.000000)
					( Status sCSetFlattened )
					( Origin gBackEnd )
				)
				( attribute "RELATIVE_PROPAGATION_DELAY_SCOPE" "G"
					( Parent
						( matchGroupRef "@baseboard_fab2_lib.baseboard_fab2(sch_1):\MG_DQ_FAR_DIMM_NG_M_M_BYTE1\" )
					)
					( Status sCSetFlattened )
					( Origin gBackEnd )
				)
				( attribute "RELATIVE_PROPAGATION_DELAY" "-50.00 MIL,50.00 MIL"
					( Parent
						( matchGroupRef "@baseboard_fab2_lib.baseboard_fab2(sch_1):\MG_DQ_FAR_DIMM_NG_M_M_BYTE1\" )
					)
					( Units "uMatchProp" "ns" 1.000000)
					( Status sCSetFlattened )
					( Origin gBackEnd )
				)
			)
			( pinPair "@baseboard_fab2_lib.baseboard_fab2(sch_1):\PP1838\"
				( pinRef "@baseboard_fab2_lib.baseboard_fab2(sch_1):page62_i172:DDR5_DQ(14)" )
				( pinRef "@baseboard_fab2_lib.baseboard_fab2(sch_1):page88_i111:DQ(14)" )
				( attribute "RELATIVE_PROPAGATION_DELAY_SCOPE" "G"
					( Parent
						( matchGroupRef "@baseboard_fab2_lib.baseboard_fab2(sch_1):\MG_DQ-DQS_NEAR_DIMM_NG_M_M_BYTE1\" )
					)
					( Status sCSetFlattened )
					( Origin gBackEnd )
				)
				( attribute "RELATIVE_PROPAGATION_DELAY" "0.00 MIL,195.00 MIL"
					( Parent
						( matchGroupRef "@baseboard_fab2_lib.baseboard_fab2(sch_1):\MG_DQ-DQS_NEAR_DIMM_NG_M_M_BYTE1\" )
					)
					( Units "uMatchProp" "ns" 1.000000)
					( Status sCSetFlattened )
					( Origin gBackEnd )
				)
				( attribute "RELATIVE_PROPAGATION_DELAY_SCOPE" "G"
					( Parent
						( matchGroupRef "@baseboard_fab2_lib.baseboard_fab2(sch_1):\MG_DQ_NEAR_DIMM_NG_M_M_BYTE1\" )
					)
					( Status sCSetFlattened )
					( Origin gBackEnd )
				)
				( attribute "RELATIVE_PROPAGATION_DELAY" "-50.00 MIL,50.00 MIL"
					( Parent
						( matchGroupRef "@baseboard_fab2_lib.baseboard_fab2(sch_1):\MG_DQ_NEAR_DIMM_NG_M_M_BYTE1\" )
					)
					( Units "uMatchProp" "ns" 1.000000)
					( Status sCSetFlattened )
					( Origin gBackEnd )
				)
			)
			( pinPair "@baseboard_fab2_lib.baseboard_fab2(sch_1):\PP1840\"
				( pinRef "@baseboard_fab2_lib.baseboard_fab2(sch_1):page62_i172:DDR5_DQ(15)" )
				( pinRef "@baseboard_fab2_lib.baseboard_fab2(sch_1):page87_i186:DQ(14)" )
				( attribute "RELATIVE_PROPAGATION_DELAY_SCOPE" "G"
					( Parent
						( matchGroupRef "@baseboard_fab2_lib.baseboard_fab2(sch_1):\MG_DQ-DQS_FAR_DIMM_NG_M_M_BYTE1\" )
					)
					( Status sCSetFlattened )
					( Origin gBackEnd )
				)
				( attribute "RELATIVE_PROPAGATION_DELAY" "0.00 MIL,195.00 MIL"
					( Parent
						( matchGroupRef "@baseboard_fab2_lib.baseboard_fab2(sch_1):\MG_DQ-DQS_FAR_DIMM_NG_M_M_BYTE1\" )
					)
					( Units "uMatchProp" "ns" 1.000000)
					( Status sCSetFlattened )
					( Origin gBackEnd )
				)
				( attribute "RELATIVE_PROPAGATION_DELAY_SCOPE" "G"
					( Parent
						( matchGroupRef "@baseboard_fab2_lib.baseboard_fab2(sch_1):\MG_DQ_FAR_DIMM_NG_M_M_BYTE1\" )
					)
					( Status sCSetFlattened )
					( Origin gBackEnd )
				)
				( attribute "RELATIVE_PROPAGATION_DELAY" "-50.00 MIL,50.00 MIL"
					( Parent
						( matchGroupRef "@baseboard_fab2_lib.baseboard_fab2(sch_1):\MG_DQ_FAR_DIMM_NG_M_M_BYTE1\" )
					)
					( Units "uMatchProp" "ns" 1.000000)
					( Status sCSetFlattened )
					( Origin gBackEnd )
				)
			)
			( pinPair "@baseboard_fab2_lib.baseboard_fab2(sch_1):\PP1841\"
				( pinRef "@baseboard_fab2_lib.baseboard_fab2(sch_1):page62_i172:DDR5_DQ(15)" )
				( pinRef "@baseboard_fab2_lib.baseboard_fab2(sch_1):page88_i111:DQ(15)" )
				( attribute "RELATIVE_PROPAGATION_DELAY_SCOPE" "G"
					( Parent
						( matchGroupRef "@baseboard_fab2_lib.baseboard_fab2(sch_1):\MG_DQ-DQS_NEAR_DIMM_NG_M_M_BYTE1\" )
					)
					( Status sCSetFlattened )
					( Origin gBackEnd )
				)
				( attribute "RELATIVE_PROPAGATION_DELAY" "0.00 MIL,195.00 MIL"
					( Parent
						( matchGroupRef "@baseboard_fab2_lib.baseboard_fab2(sch_1):\MG_DQ-DQS_NEAR_DIMM_NG_M_M_BYTE1\" )
					)
					( Units "uMatchProp" "ns" 1.000000)
					( Status sCSetFlattened )
					( Origin gBackEnd )
				)
				( attribute "RELATIVE_PROPAGATION_DELAY_SCOPE" "G"
					( Parent
						( matchGroupRef "@baseboard_fab2_lib.baseboard_fab2(sch_1):\MG_DQ_NEAR_DIMM_NG_M_M_BYTE1\" )
					)
					( Status sCSetFlattened )
					( Origin gBackEnd )
				)
				( attribute "RELATIVE_PROPAGATION_DELAY" "-50.00 MIL,50.00 MIL"
					( Parent
						( matchGroupRef "@baseboard_fab2_lib.baseboard_fab2(sch_1):\MG_DQ_NEAR_DIMM_NG_M_M_BYTE1\" )
					)
					( Units "uMatchProp" "ns" 1.000000)
					( Status sCSetFlattened )
					( Origin gBackEnd )
				)
			)
			( pinPair "@baseboard_fab2_lib.baseboard_fab2(sch_1):\PP1795\"
				( pinRef "@baseboard_fab2_lib.baseboard_fab2(sch_1):page62_i172:DDR5_DQ(16)" )
				( pinRef "@baseboard_fab2_lib.baseboard_fab2(sch_1):page87_i186:DQ(17)" )
				( attribute "RELATIVE_PROPAGATION_DELAY_SCOPE" "G"
					( Parent
						( matchGroupRef "@baseboard_fab2_lib.baseboard_fab2(sch_1):\MG_DQ-DQS_FAR_DIMM_NG_M_M_BYTE2\" )
					)
					( Status sCSetFlattened )
					( Origin gBackEnd )
				)
				( attribute "RELATIVE_PROPAGATION_DELAY" "0.00 MIL,195.00 MIL"
					( Parent
						( matchGroupRef "@baseboard_fab2_lib.baseboard_fab2(sch_1):\MG_DQ-DQS_FAR_DIMM_NG_M_M_BYTE2\" )
					)
					( Units "uMatchProp" "ns" 1.000000)
					( Status sCSetFlattened )
					( Origin gBackEnd )
				)
				( attribute "RELATIVE_PROPAGATION_DELAY_SCOPE" "G"
					( Parent
						( matchGroupRef "@baseboard_fab2_lib.baseboard_fab2(sch_1):\MG_DQ_FAR_DIMM_NG_M_M_BYTE2\" )
					)
					( Status sCSetFlattened )
					( Origin gBackEnd )
				)
				( attribute "RELATIVE_PROPAGATION_DELAY" "-50.00 MIL,50.00 MIL"
					( Parent
						( matchGroupRef "@baseboard_fab2_lib.baseboard_fab2(sch_1):\MG_DQ_FAR_DIMM_NG_M_M_BYTE2\" )
					)
					( Units "uMatchProp" "ns" 1.000000)
					( Status sCSetFlattened )
					( Origin gBackEnd )
				)
			)
			( pinPair "@baseboard_fab2_lib.baseboard_fab2(sch_1):\PP1796\"
				( pinRef "@baseboard_fab2_lib.baseboard_fab2(sch_1):page62_i172:DDR5_DQ(16)" )
				( pinRef "@baseboard_fab2_lib.baseboard_fab2(sch_1):page88_i111:DQ(16)" )
				( attribute "RELATIVE_PROPAGATION_DELAY_SCOPE" "G"
					( Parent
						( matchGroupRef "@baseboard_fab2_lib.baseboard_fab2(sch_1):\MG_DQ-DQS_NEAR_DIMM_NG_M_M_BYTE2\" )
					)
					( Status sCSetFlattened )
					( Origin gBackEnd )
				)
				( attribute "RELATIVE_PROPAGATION_DELAY" "0.00 MIL,195.00 MIL"
					( Parent
						( matchGroupRef "@baseboard_fab2_lib.baseboard_fab2(sch_1):\MG_DQ-DQS_NEAR_DIMM_NG_M_M_BYTE2\" )
					)
					( Units "uMatchProp" "ns" 1.000000)
					( Status sCSetFlattened )
					( Origin gBackEnd )
				)
				( attribute "RELATIVE_PROPAGATION_DELAY_SCOPE" "G"
					( Parent
						( matchGroupRef "@baseboard_fab2_lib.baseboard_fab2(sch_1):\MG_DQ_NEAR_DIMM_NG_M_M_BYTE2\" )
					)
					( Status sCSetFlattened )
					( Origin gBackEnd )
				)
				( attribute "RELATIVE_PROPAGATION_DELAY" "-50.00 MIL,50.00 MIL"
					( Parent
						( matchGroupRef "@baseboard_fab2_lib.baseboard_fab2(sch_1):\MG_DQ_NEAR_DIMM_NG_M_M_BYTE2\" )
					)
					( Units "uMatchProp" "ns" 1.000000)
					( Status sCSetFlattened )
					( Origin gBackEnd )
				)
			)
			( pinPair "@baseboard_fab2_lib.baseboard_fab2(sch_1):\PP1798\"
				( pinRef "@baseboard_fab2_lib.baseboard_fab2(sch_1):page62_i172:DDR5_DQ(17)" )
				( pinRef "@baseboard_fab2_lib.baseboard_fab2(sch_1):page87_i186:DQ(16)" )
				( attribute "RELATIVE_PROPAGATION_DELAY_SCOPE" "G"
					( Parent
						( matchGroupRef "@baseboard_fab2_lib.baseboard_fab2(sch_1):\MG_DQ-DQS_FAR_DIMM_NG_M_M_BYTE2\" )
					)
					( Status sCSetFlattened )
					( Origin gBackEnd )
				)
				( attribute "RELATIVE_PROPAGATION_DELAY" "0.00 MIL,195.00 MIL"
					( Parent
						( matchGroupRef "@baseboard_fab2_lib.baseboard_fab2(sch_1):\MG_DQ-DQS_FAR_DIMM_NG_M_M_BYTE2\" )
					)
					( Units "uMatchProp" "ns" 1.000000)
					( Status sCSetFlattened )
					( Origin gBackEnd )
				)
				( attribute "RELATIVE_PROPAGATION_DELAY_SCOPE" "G"
					( Parent
						( matchGroupRef "@baseboard_fab2_lib.baseboard_fab2(sch_1):\MG_DQ_FAR_DIMM_NG_M_M_BYTE2\" )
					)
					( Status sCSetFlattened )
					( Origin gBackEnd )
				)
				( attribute "RELATIVE_PROPAGATION_DELAY" "-50.00 MIL,50.00 MIL"
					( Parent
						( matchGroupRef "@baseboard_fab2_lib.baseboard_fab2(sch_1):\MG_DQ_FAR_DIMM_NG_M_M_BYTE2\" )
					)
					( Units "uMatchProp" "ns" 1.000000)
					( Status sCSetFlattened )
					( Origin gBackEnd )
				)
			)
			( pinPair "@baseboard_fab2_lib.baseboard_fab2(sch_1):\PP1799\"
				( pinRef "@baseboard_fab2_lib.baseboard_fab2(sch_1):page62_i172:DDR5_DQ(17)" )
				( pinRef "@baseboard_fab2_lib.baseboard_fab2(sch_1):page88_i111:DQ(17)" )
				( attribute "RELATIVE_PROPAGATION_DELAY_SCOPE" "G"
					( Parent
						( matchGroupRef "@baseboard_fab2_lib.baseboard_fab2(sch_1):\MG_DQ-DQS_NEAR_DIMM_NG_M_M_BYTE2\" )
					)
					( Status sCSetFlattened )
					( Origin gBackEnd )
				)
				( attribute "RELATIVE_PROPAGATION_DELAY" "0.00 MIL,195.00 MIL"
					( Parent
						( matchGroupRef "@baseboard_fab2_lib.baseboard_fab2(sch_1):\MG_DQ-DQS_NEAR_DIMM_NG_M_M_BYTE2\" )
					)
					( Units "uMatchProp" "ns" 1.000000)
					( Status sCSetFlattened )
					( Origin gBackEnd )
				)
				( attribute "RELATIVE_PROPAGATION_DELAY_SCOPE" "G"
					( Parent
						( matchGroupRef "@baseboard_fab2_lib.baseboard_fab2(sch_1):\MG_DQ_NEAR_DIMM_NG_M_M_BYTE2\" )
					)
					( Status sCSetFlattened )
					( Origin gBackEnd )
				)
				( attribute "RELATIVE_PROPAGATION_DELAY" "-50.00 MIL,50.00 MIL"
					( Parent
						( matchGroupRef "@baseboard_fab2_lib.baseboard_fab2(sch_1):\MG_DQ_NEAR_DIMM_NG_M_M_BYTE2\" )
					)
					( Units "uMatchProp" "ns" 1.000000)
					( Status sCSetFlattened )
					( Origin gBackEnd )
				)
			)
			( pinPair "@baseboard_fab2_lib.baseboard_fab2(sch_1):\PP1801\"
				( pinRef "@baseboard_fab2_lib.baseboard_fab2(sch_1):page62_i172:DDR5_DQ(18)" )
				( pinRef "@baseboard_fab2_lib.baseboard_fab2(sch_1):page87_i186:DQ(19)" )
				( attribute "RELATIVE_PROPAGATION_DELAY_SCOPE" "G"
					( Parent
						( matchGroupRef "@baseboard_fab2_lib.baseboard_fab2(sch_1):\MG_DQ-DQS_FAR_DIMM_NG_M_M_BYTE2\" )
					)
					( Status sCSetFlattened )
					( Origin gBackEnd )
				)
				( attribute "RELATIVE_PROPAGATION_DELAY" "0.00 MIL,195.00 MIL"
					( Parent
						( matchGroupRef "@baseboard_fab2_lib.baseboard_fab2(sch_1):\MG_DQ-DQS_FAR_DIMM_NG_M_M_BYTE2\" )
					)
					( Units "uMatchProp" "ns" 1.000000)
					( Status sCSetFlattened )
					( Origin gBackEnd )
				)
				( attribute "RELATIVE_PROPAGATION_DELAY_SCOPE" "G"
					( Parent
						( matchGroupRef "@baseboard_fab2_lib.baseboard_fab2(sch_1):\MG_DQ_FAR_DIMM_NG_M_M_BYTE2\" )
					)
					( Status sCSetFlattened )
					( Origin gBackEnd )
				)
				( attribute "RELATIVE_PROPAGATION_DELAY" "-50.00 MIL,50.00 MIL"
					( Parent
						( matchGroupRef "@baseboard_fab2_lib.baseboard_fab2(sch_1):\MG_DQ_FAR_DIMM_NG_M_M_BYTE2\" )
					)
					( Units "uMatchProp" "ns" 1.000000)
					( Status sCSetFlattened )
					( Origin gBackEnd )
				)
			)
			( pinPair "@baseboard_fab2_lib.baseboard_fab2(sch_1):\PP1802\"
				( pinRef "@baseboard_fab2_lib.baseboard_fab2(sch_1):page62_i172:DDR5_DQ(18)" )
				( pinRef "@baseboard_fab2_lib.baseboard_fab2(sch_1):page88_i111:DQ(18)" )
				( attribute "RELATIVE_PROPAGATION_DELAY_SCOPE" "G"
					( Parent
						( matchGroupRef "@baseboard_fab2_lib.baseboard_fab2(sch_1):\MG_DQ-DQS_NEAR_DIMM_NG_M_M_BYTE2\" )
					)
					( Status sCSetFlattened )
					( Origin gBackEnd )
				)
				( attribute "RELATIVE_PROPAGATION_DELAY" "0.00 MIL,195.00 MIL"
					( Parent
						( matchGroupRef "@baseboard_fab2_lib.baseboard_fab2(sch_1):\MG_DQ-DQS_NEAR_DIMM_NG_M_M_BYTE2\" )
					)
					( Units "uMatchProp" "ns" 1.000000)
					( Status sCSetFlattened )
					( Origin gBackEnd )
				)
				( attribute "RELATIVE_PROPAGATION_DELAY_SCOPE" "G"
					( Parent
						( matchGroupRef "@baseboard_fab2_lib.baseboard_fab2(sch_1):\MG_DQ_NEAR_DIMM_NG_M_M_BYTE2\" )
					)
					( Status sCSetFlattened )
					( Origin gBackEnd )
				)
				( attribute "RELATIVE_PROPAGATION_DELAY" "-50.00 MIL,50.00 MIL"
					( Parent
						( matchGroupRef "@baseboard_fab2_lib.baseboard_fab2(sch_1):\MG_DQ_NEAR_DIMM_NG_M_M_BYTE2\" )
					)
					( Units "uMatchProp" "ns" 1.000000)
					( Status sCSetFlattened )
					( Origin gBackEnd )
				)
			)
			( pinPair "@baseboard_fab2_lib.baseboard_fab2(sch_1):\PP1804\"
				( pinRef "@baseboard_fab2_lib.baseboard_fab2(sch_1):page62_i172:DDR5_DQ(19)" )
				( pinRef "@baseboard_fab2_lib.baseboard_fab2(sch_1):page87_i186:DQ(18)" )
				( attribute "RELATIVE_PROPAGATION_DELAY_SCOPE" "G"
					( Parent
						( matchGroupRef "@baseboard_fab2_lib.baseboard_fab2(sch_1):\MG_DQ-DQS_FAR_DIMM_NG_M_M_BYTE2\" )
					)
					( Status sCSetFlattened )
					( Origin gBackEnd )
				)
				( attribute "RELATIVE_PROPAGATION_DELAY" "0.00 MIL,195.00 MIL"
					( Parent
						( matchGroupRef "@baseboard_fab2_lib.baseboard_fab2(sch_1):\MG_DQ-DQS_FAR_DIMM_NG_M_M_BYTE2\" )
					)
					( Units "uMatchProp" "ns" 1.000000)
					( Status sCSetFlattened )
					( Origin gBackEnd )
				)
				( attribute "RELATIVE_PROPAGATION_DELAY_SCOPE" "G"
					( Parent
						( matchGroupRef "@baseboard_fab2_lib.baseboard_fab2(sch_1):\MG_DQ_FAR_DIMM_NG_M_M_BYTE2\" )
					)
					( Status sCSetFlattened )
					( Origin gBackEnd )
				)
				( attribute "RELATIVE_PROPAGATION_DELAY" "-50.00 MIL,50.00 MIL"
					( Parent
						( matchGroupRef "@baseboard_fab2_lib.baseboard_fab2(sch_1):\MG_DQ_FAR_DIMM_NG_M_M_BYTE2\" )
					)
					( Units "uMatchProp" "ns" 1.000000)
					( Status sCSetFlattened )
					( Origin gBackEnd )
				)
			)
			( pinPair "@baseboard_fab2_lib.baseboard_fab2(sch_1):\PP1805\"
				( pinRef "@baseboard_fab2_lib.baseboard_fab2(sch_1):page62_i172:DDR5_DQ(19)" )
				( pinRef "@baseboard_fab2_lib.baseboard_fab2(sch_1):page88_i111:DQ(19)" )
				( attribute "RELATIVE_PROPAGATION_DELAY_SCOPE" "G"
					( Parent
						( matchGroupRef "@baseboard_fab2_lib.baseboard_fab2(sch_1):\MG_DQ-DQS_NEAR_DIMM_NG_M_M_BYTE2\" )
					)
					( Status sCSetFlattened )
					( Origin gBackEnd )
				)
				( attribute "RELATIVE_PROPAGATION_DELAY" "0.00 MIL,195.00 MIL"
					( Parent
						( matchGroupRef "@baseboard_fab2_lib.baseboard_fab2(sch_1):\MG_DQ-DQS_NEAR_DIMM_NG_M_M_BYTE2\" )
					)
					( Units "uMatchProp" "ns" 1.000000)
					( Status sCSetFlattened )
					( Origin gBackEnd )
				)
				( attribute "RELATIVE_PROPAGATION_DELAY_SCOPE" "G"
					( Parent
						( matchGroupRef "@baseboard_fab2_lib.baseboard_fab2(sch_1):\MG_DQ_NEAR_DIMM_NG_M_M_BYTE2\" )
					)
					( Status sCSetFlattened )
					( Origin gBackEnd )
				)
				( attribute "RELATIVE_PROPAGATION_DELAY" "-50.00 MIL,50.00 MIL"
					( Parent
						( matchGroupRef "@baseboard_fab2_lib.baseboard_fab2(sch_1):\MG_DQ_NEAR_DIMM_NG_M_M_BYTE2\" )
					)
					( Units "uMatchProp" "ns" 1.000000)
					( Status sCSetFlattened )
					( Origin gBackEnd )
				)
			)
			( pinPair "@baseboard_fab2_lib.baseboard_fab2(sch_1):\PP1807\"
				( pinRef "@baseboard_fab2_lib.baseboard_fab2(sch_1):page62_i172:DDR5_DQ(20)" )
				( pinRef "@baseboard_fab2_lib.baseboard_fab2(sch_1):page87_i186:DQ(21)" )
				( attribute "RELATIVE_PROPAGATION_DELAY_SCOPE" "G"
					( Parent
						( matchGroupRef "@baseboard_fab2_lib.baseboard_fab2(sch_1):\MG_DQ-DQS_FAR_DIMM_NG_M_M_BYTE2\" )
					)
					( Status sCSetFlattened )
					( Origin gBackEnd )
				)
				( attribute "RELATIVE_PROPAGATION_DELAY" "0.00 MIL,195.00 MIL"
					( Parent
						( matchGroupRef "@baseboard_fab2_lib.baseboard_fab2(sch_1):\MG_DQ-DQS_FAR_DIMM_NG_M_M_BYTE2\" )
					)
					( Units "uMatchProp" "ns" 1.000000)
					( Status sCSetFlattened )
					( Origin gBackEnd )
				)
				( attribute "RELATIVE_PROPAGATION_DELAY_SCOPE" "G"
					( Parent
						( matchGroupRef "@baseboard_fab2_lib.baseboard_fab2(sch_1):\MG_DQ_FAR_DIMM_NG_M_M_BYTE2\" )
					)
					( Status sCSetFlattened )
					( Origin gBackEnd )
				)
				( attribute "RELATIVE_PROPAGATION_DELAY" "-50.00 MIL,50.00 MIL"
					( Parent
						( matchGroupRef "@baseboard_fab2_lib.baseboard_fab2(sch_1):\MG_DQ_FAR_DIMM_NG_M_M_BYTE2\" )
					)
					( Units "uMatchProp" "ns" 1.000000)
					( Status sCSetFlattened )
					( Origin gBackEnd )
				)
			)
			( pinPair "@baseboard_fab2_lib.baseboard_fab2(sch_1):\PP1808\"
				( pinRef "@baseboard_fab2_lib.baseboard_fab2(sch_1):page62_i172:DDR5_DQ(20)" )
				( pinRef "@baseboard_fab2_lib.baseboard_fab2(sch_1):page88_i111:DQ(20)" )
				( attribute "RELATIVE_PROPAGATION_DELAY_SCOPE" "G"
					( Parent
						( matchGroupRef "@baseboard_fab2_lib.baseboard_fab2(sch_1):\MG_DQ-DQS_NEAR_DIMM_NG_M_M_BYTE2\" )
					)
					( Status sCSetFlattened )
					( Origin gBackEnd )
				)
				( attribute "RELATIVE_PROPAGATION_DELAY" "0.00 MIL,195.00 MIL"
					( Parent
						( matchGroupRef "@baseboard_fab2_lib.baseboard_fab2(sch_1):\MG_DQ-DQS_NEAR_DIMM_NG_M_M_BYTE2\" )
					)
					( Units "uMatchProp" "ns" 1.000000)
					( Status sCSetFlattened )
					( Origin gBackEnd )
				)
				( attribute "RELATIVE_PROPAGATION_DELAY_SCOPE" "G"
					( Parent
						( matchGroupRef "@baseboard_fab2_lib.baseboard_fab2(sch_1):\MG_DQ_NEAR_DIMM_NG_M_M_BYTE2\" )
					)
					( Status sCSetFlattened )
					( Origin gBackEnd )
				)
				( attribute "RELATIVE_PROPAGATION_DELAY" "-50.00 MIL,50.00 MIL"
					( Parent
						( matchGroupRef "@baseboard_fab2_lib.baseboard_fab2(sch_1):\MG_DQ_NEAR_DIMM_NG_M_M_BYTE2\" )
					)
					( Units "uMatchProp" "ns" 1.000000)
					( Status sCSetFlattened )
					( Origin gBackEnd )
				)
			)
			( pinPair "@baseboard_fab2_lib.baseboard_fab2(sch_1):\PP1810\"
				( pinRef "@baseboard_fab2_lib.baseboard_fab2(sch_1):page62_i172:DDR5_DQ(21)" )
				( pinRef "@baseboard_fab2_lib.baseboard_fab2(sch_1):page87_i186:DQ(20)" )
				( attribute "RELATIVE_PROPAGATION_DELAY_SCOPE" "G"
					( Parent
						( matchGroupRef "@baseboard_fab2_lib.baseboard_fab2(sch_1):\MG_DQ-DQS_FAR_DIMM_NG_M_M_BYTE2\" )
					)
					( Status sCSetFlattened )
					( Origin gBackEnd )
				)
				( attribute "RELATIVE_PROPAGATION_DELAY" "0.00 MIL,195.00 MIL"
					( Parent
						( matchGroupRef "@baseboard_fab2_lib.baseboard_fab2(sch_1):\MG_DQ-DQS_FAR_DIMM_NG_M_M_BYTE2\" )
					)
					( Units "uMatchProp" "ns" 1.000000)
					( Status sCSetFlattened )
					( Origin gBackEnd )
				)
				( attribute "RELATIVE_PROPAGATION_DELAY_SCOPE" "G"
					( Parent
						( matchGroupRef "@baseboard_fab2_lib.baseboard_fab2(sch_1):\MG_DQ_FAR_DIMM_NG_M_M_BYTE2\" )
					)
					( Status sCSetFlattened )
					( Origin gBackEnd )
				)
				( attribute "RELATIVE_PROPAGATION_DELAY" "-50.00 MIL,50.00 MIL"
					( Parent
						( matchGroupRef "@baseboard_fab2_lib.baseboard_fab2(sch_1):\MG_DQ_FAR_DIMM_NG_M_M_BYTE2\" )
					)
					( Units "uMatchProp" "ns" 1.000000)
					( Status sCSetFlattened )
					( Origin gBackEnd )
				)
			)
			( pinPair "@baseboard_fab2_lib.baseboard_fab2(sch_1):\PP1811\"
				( pinRef "@baseboard_fab2_lib.baseboard_fab2(sch_1):page62_i172:DDR5_DQ(21)" )
				( pinRef "@baseboard_fab2_lib.baseboard_fab2(sch_1):page88_i111:DQ(21)" )
				( attribute "RELATIVE_PROPAGATION_DELAY_SCOPE" "G"
					( Parent
						( matchGroupRef "@baseboard_fab2_lib.baseboard_fab2(sch_1):\MG_DQ-DQS_NEAR_DIMM_NG_M_M_BYTE2\" )
					)
					( Status sCSetFlattened )
					( Origin gBackEnd )
				)
				( attribute "RELATIVE_PROPAGATION_DELAY" "0.00 MIL,195.00 MIL"
					( Parent
						( matchGroupRef "@baseboard_fab2_lib.baseboard_fab2(sch_1):\MG_DQ-DQS_NEAR_DIMM_NG_M_M_BYTE2\" )
					)
					( Units "uMatchProp" "ns" 1.000000)
					( Status sCSetFlattened )
					( Origin gBackEnd )
				)
				( attribute "RELATIVE_PROPAGATION_DELAY_SCOPE" "G"
					( Parent
						( matchGroupRef "@baseboard_fab2_lib.baseboard_fab2(sch_1):\MG_DQ_NEAR_DIMM_NG_M_M_BYTE2\" )
					)
					( Status sCSetFlattened )
					( Origin gBackEnd )
				)
				( attribute "RELATIVE_PROPAGATION_DELAY" "-50.00 MIL,50.00 MIL"
					( Parent
						( matchGroupRef "@baseboard_fab2_lib.baseboard_fab2(sch_1):\MG_DQ_NEAR_DIMM_NG_M_M_BYTE2\" )
					)
					( Units "uMatchProp" "ns" 1.000000)
					( Status sCSetFlattened )
					( Origin gBackEnd )
				)
			)
			( pinPair "@baseboard_fab2_lib.baseboard_fab2(sch_1):\PP1813\"
				( pinRef "@baseboard_fab2_lib.baseboard_fab2(sch_1):page62_i172:DDR5_DQ(22)" )
				( pinRef "@baseboard_fab2_lib.baseboard_fab2(sch_1):page87_i186:DQ(23)" )
				( attribute "RELATIVE_PROPAGATION_DELAY_SCOPE" "G"
					( Parent
						( matchGroupRef "@baseboard_fab2_lib.baseboard_fab2(sch_1):\MG_DQ-DQS_FAR_DIMM_NG_M_M_BYTE2\" )
					)
					( Status sCSetFlattened )
					( Origin gBackEnd )
				)
				( attribute "RELATIVE_PROPAGATION_DELAY" "0.00 MIL,195.00 MIL"
					( Parent
						( matchGroupRef "@baseboard_fab2_lib.baseboard_fab2(sch_1):\MG_DQ-DQS_FAR_DIMM_NG_M_M_BYTE2\" )
					)
					( Units "uMatchProp" "ns" 1.000000)
					( Status sCSetFlattened )
					( Origin gBackEnd )
				)
				( attribute "RELATIVE_PROPAGATION_DELAY_SCOPE" "G"
					( Parent
						( matchGroupRef "@baseboard_fab2_lib.baseboard_fab2(sch_1):\MG_DQ_FAR_DIMM_NG_M_M_BYTE2\" )
					)
					( Status sCSetFlattened )
					( Origin gBackEnd )
				)
				( attribute "RELATIVE_PROPAGATION_DELAY" "-50.00 MIL,50.00 MIL"
					( Parent
						( matchGroupRef "@baseboard_fab2_lib.baseboard_fab2(sch_1):\MG_DQ_FAR_DIMM_NG_M_M_BYTE2\" )
					)
					( Units "uMatchProp" "ns" 1.000000)
					( Status sCSetFlattened )
					( Origin gBackEnd )
				)
			)
			( pinPair "@baseboard_fab2_lib.baseboard_fab2(sch_1):\PP1814\"
				( pinRef "@baseboard_fab2_lib.baseboard_fab2(sch_1):page62_i172:DDR5_DQ(22)" )
				( pinRef "@baseboard_fab2_lib.baseboard_fab2(sch_1):page88_i111:DQ(22)" )
				( attribute "RELATIVE_PROPAGATION_DELAY_SCOPE" "G"
					( Parent
						( matchGroupRef "@baseboard_fab2_lib.baseboard_fab2(sch_1):\MG_DQ-DQS_NEAR_DIMM_NG_M_M_BYTE2\" )
					)
					( Status sCSetFlattened )
					( Origin gBackEnd )
				)
				( attribute "RELATIVE_PROPAGATION_DELAY" "0.00 MIL,195.00 MIL"
					( Parent
						( matchGroupRef "@baseboard_fab2_lib.baseboard_fab2(sch_1):\MG_DQ-DQS_NEAR_DIMM_NG_M_M_BYTE2\" )
					)
					( Units "uMatchProp" "ns" 1.000000)
					( Status sCSetFlattened )
					( Origin gBackEnd )
				)
				( attribute "RELATIVE_PROPAGATION_DELAY_SCOPE" "G"
					( Parent
						( matchGroupRef "@baseboard_fab2_lib.baseboard_fab2(sch_1):\MG_DQ_NEAR_DIMM_NG_M_M_BYTE2\" )
					)
					( Status sCSetFlattened )
					( Origin gBackEnd )
				)
				( attribute "RELATIVE_PROPAGATION_DELAY" "-50.00 MIL,50.00 MIL"
					( Parent
						( matchGroupRef "@baseboard_fab2_lib.baseboard_fab2(sch_1):\MG_DQ_NEAR_DIMM_NG_M_M_BYTE2\" )
					)
					( Units "uMatchProp" "ns" 1.000000)
					( Status sCSetFlattened )
					( Origin gBackEnd )
				)
			)
			( pinPair "@baseboard_fab2_lib.baseboard_fab2(sch_1):\PP1816\"
				( pinRef "@baseboard_fab2_lib.baseboard_fab2(sch_1):page62_i172:DDR5_DQ(23)" )
				( pinRef "@baseboard_fab2_lib.baseboard_fab2(sch_1):page87_i186:DQ(22)" )
				( attribute "RELATIVE_PROPAGATION_DELAY_SCOPE" "G"
					( Parent
						( matchGroupRef "@baseboard_fab2_lib.baseboard_fab2(sch_1):\MG_DQ-DQS_FAR_DIMM_NG_M_M_BYTE2\" )
					)
					( Status sCSetFlattened )
					( Origin gBackEnd )
				)
				( attribute "RELATIVE_PROPAGATION_DELAY" "0.00 MIL,195.00 MIL"
					( Parent
						( matchGroupRef "@baseboard_fab2_lib.baseboard_fab2(sch_1):\MG_DQ-DQS_FAR_DIMM_NG_M_M_BYTE2\" )
					)
					( Units "uMatchProp" "ns" 1.000000)
					( Status sCSetFlattened )
					( Origin gBackEnd )
				)
				( attribute "RELATIVE_PROPAGATION_DELAY_SCOPE" "G"
					( Parent
						( matchGroupRef "@baseboard_fab2_lib.baseboard_fab2(sch_1):\MG_DQ_FAR_DIMM_NG_M_M_BYTE2\" )
					)
					( Status sCSetFlattened )
					( Origin gBackEnd )
				)
				( attribute "RELATIVE_PROPAGATION_DELAY" "-50.00 MIL,50.00 MIL"
					( Parent
						( matchGroupRef "@baseboard_fab2_lib.baseboard_fab2(sch_1):\MG_DQ_FAR_DIMM_NG_M_M_BYTE2\" )
					)
					( Units "uMatchProp" "ns" 1.000000)
					( Status sCSetFlattened )
					( Origin gBackEnd )
				)
			)
			( pinPair "@baseboard_fab2_lib.baseboard_fab2(sch_1):\PP1817\"
				( pinRef "@baseboard_fab2_lib.baseboard_fab2(sch_1):page62_i172:DDR5_DQ(23)" )
				( pinRef "@baseboard_fab2_lib.baseboard_fab2(sch_1):page88_i111:DQ(23)" )
				( attribute "RELATIVE_PROPAGATION_DELAY_SCOPE" "G"
					( Parent
						( matchGroupRef "@baseboard_fab2_lib.baseboard_fab2(sch_1):\MG_DQ-DQS_NEAR_DIMM_NG_M_M_BYTE2\" )
					)
					( Status sCSetFlattened )
					( Origin gBackEnd )
				)
				( attribute "RELATIVE_PROPAGATION_DELAY" "0.00 MIL,195.00 MIL"
					( Parent
						( matchGroupRef "@baseboard_fab2_lib.baseboard_fab2(sch_1):\MG_DQ-DQS_NEAR_DIMM_NG_M_M_BYTE2\" )
					)
					( Units "uMatchProp" "ns" 1.000000)
					( Status sCSetFlattened )
					( Origin gBackEnd )
				)
				( attribute "RELATIVE_PROPAGATION_DELAY_SCOPE" "G"
					( Parent
						( matchGroupRef "@baseboard_fab2_lib.baseboard_fab2(sch_1):\MG_DQ_NEAR_DIMM_NG_M_M_BYTE2\" )
					)
					( Status sCSetFlattened )
					( Origin gBackEnd )
				)
				( attribute "RELATIVE_PROPAGATION_DELAY" "-50.00 MIL,50.00 MIL"
					( Parent
						( matchGroupRef "@baseboard_fab2_lib.baseboard_fab2(sch_1):\MG_DQ_NEAR_DIMM_NG_M_M_BYTE2\" )
					)
					( Units "uMatchProp" "ns" 1.000000)
					( Status sCSetFlattened )
					( Origin gBackEnd )
				)
			)
			( pinPair "@baseboard_fab2_lib.baseboard_fab2(sch_1):\PP1771\"
				( pinRef "@baseboard_fab2_lib.baseboard_fab2(sch_1):page62_i172:DDR5_DQ(24)" )
				( pinRef "@baseboard_fab2_lib.baseboard_fab2(sch_1):page87_i186:DQ(25)" )
				( attribute "RELATIVE_PROPAGATION_DELAY_SCOPE" "G"
					( Parent
						( matchGroupRef "@baseboard_fab2_lib.baseboard_fab2(sch_1):\MG_DQ-DQS_FAR_DIMM_NG_M_M_BYTE3\" )
					)
					( Status sCSetFlattened )
					( Origin gBackEnd )
				)
				( attribute "RELATIVE_PROPAGATION_DELAY" "0.00 MIL,195.00 MIL"
					( Parent
						( matchGroupRef "@baseboard_fab2_lib.baseboard_fab2(sch_1):\MG_DQ-DQS_FAR_DIMM_NG_M_M_BYTE3\" )
					)
					( Units "uMatchProp" "ns" 1.000000)
					( Status sCSetFlattened )
					( Origin gBackEnd )
				)
				( attribute "RELATIVE_PROPAGATION_DELAY_SCOPE" "G"
					( Parent
						( matchGroupRef "@baseboard_fab2_lib.baseboard_fab2(sch_1):\MG_DQ_FAR_DIMM_NG_M_M_BYTE3\" )
					)
					( Status sCSetFlattened )
					( Origin gBackEnd )
				)
				( attribute "RELATIVE_PROPAGATION_DELAY" "-50.00 MIL,50.00 MIL"
					( Parent
						( matchGroupRef "@baseboard_fab2_lib.baseboard_fab2(sch_1):\MG_DQ_FAR_DIMM_NG_M_M_BYTE3\" )
					)
					( Units "uMatchProp" "ns" 1.000000)
					( Status sCSetFlattened )
					( Origin gBackEnd )
				)
			)
			( pinPair "@baseboard_fab2_lib.baseboard_fab2(sch_1):\PP1772\"
				( pinRef "@baseboard_fab2_lib.baseboard_fab2(sch_1):page62_i172:DDR5_DQ(24)" )
				( pinRef "@baseboard_fab2_lib.baseboard_fab2(sch_1):page88_i111:DQ(24)" )
				( attribute "RELATIVE_PROPAGATION_DELAY_SCOPE" "G"
					( Parent
						( matchGroupRef "@baseboard_fab2_lib.baseboard_fab2(sch_1):\MG_DQ-DQS_NEAR_DIMM_NG_M_M_BYTE3\" )
					)
					( Status sCSetFlattened )
					( Origin gBackEnd )
				)
				( attribute "RELATIVE_PROPAGATION_DELAY" "0.00 MIL,195.00 MIL"
					( Parent
						( matchGroupRef "@baseboard_fab2_lib.baseboard_fab2(sch_1):\MG_DQ-DQS_NEAR_DIMM_NG_M_M_BYTE3\" )
					)
					( Units "uMatchProp" "ns" 1.000000)
					( Status sCSetFlattened )
					( Origin gBackEnd )
				)
				( attribute "RELATIVE_PROPAGATION_DELAY_SCOPE" "G"
					( Parent
						( matchGroupRef "@crescent_city_bb_fab1_lib.crescent_city_bb_fab1(sch_1):\MG_DQ_NEAR_DIMM_NG_M_M_BYTE3\" )
					)
					( Status sCSetFlattened )
					( Origin gBackEnd )
				)
				( attribute "RELATIVE_PROPAGATION_DELAY" "-50.00 MIL,50.00 MIL"
					( Parent
						( matchGroupRef "@crescent_city_bb_fab1_lib.crescent_city_bb_fab1(sch_1):\MG_DQ_NEAR_DIMM_NG_M_M_BYTE3\" )
					)
					( Units "uMatchProp" "ns" 1.000000)
					( Status sCSetFlattened )
					( Origin gBackEnd )
				)
			)
			( pinPair "@baseboard_fab2_lib.baseboard_fab2(sch_1):\PP1774\"
				( pinRef "@baseboard_fab2_lib.baseboard_fab2(sch_1):page62_i172:DDR5_DQ(25)" )
				( pinRef "@baseboard_fab2_lib.baseboard_fab2(sch_1):page87_i186:DQ(24)" )
				( attribute "RELATIVE_PROPAGATION_DELAY_SCOPE" "G"
					( Parent
						( matchGroupRef "@baseboard_fab2_lib.baseboard_fab2(sch_1):\MG_DQ-DQS_FAR_DIMM_NG_M_M_BYTE3\" )
					)
					( Status sCSetFlattened )
					( Origin gBackEnd )
				)
				( attribute "RELATIVE_PROPAGATION_DELAY" "0.00 MIL,195.00 MIL"
					( Parent
						( matchGroupRef "@baseboard_fab2_lib.baseboard_fab2(sch_1):\MG_DQ-DQS_FAR_DIMM_NG_M_M_BYTE3\" )
					)
					( Units "uMatchProp" "ns" 1.000000)
					( Status sCSetFlattened )
					( Origin gBackEnd )
				)
				( attribute "RELATIVE_PROPAGATION_DELAY_SCOPE" "G"
					( Parent
						( matchGroupRef "@baseboard_fab2_lib.baseboard_fab2(sch_1):\MG_DQ_FAR_DIMM_NG_M_M_BYTE3\" )
					)
					( Status sCSetFlattened )
					( Origin gBackEnd )
				)
				( attribute "RELATIVE_PROPAGATION_DELAY" "-50.00 MIL,50.00 MIL"
					( Parent
						( matchGroupRef "@baseboard_fab2_lib.baseboard_fab2(sch_1):\MG_DQ_FAR_DIMM_NG_M_M_BYTE3\" )
					)
					( Units "uMatchProp" "ns" 1.000000)
					( Status sCSetFlattened )
					( Origin gBackEnd )
				)
			)
			( pinPair "@baseboard_fab2_lib.baseboard_fab2(sch_1):\PP1775\"
				( pinRef "@baseboard_fab2_lib.baseboard_fab2(sch_1):page62_i172:DDR5_DQ(25)" )
				( pinRef "@baseboard_fab2_lib.baseboard_fab2(sch_1):page88_i111:DQ(25)" )
				( attribute "RELATIVE_PROPAGATION_DELAY_SCOPE" "G"
					( Parent
						( matchGroupRef "@baseboard_fab2_lib.baseboard_fab2(sch_1):\MG_DQ-DQS_NEAR_DIMM_NG_M_M_BYTE3\" )
					)
					( Status sCSetFlattened )
					( Origin gBackEnd )
				)
				( attribute "RELATIVE_PROPAGATION_DELAY" "0.00 MIL,195.00 MIL"
					( Parent
						( matchGroupRef "@baseboard_fab2_lib.baseboard_fab2(sch_1):\MG_DQ-DQS_NEAR_DIMM_NG_M_M_BYTE3\" )
					)
					( Units "uMatchProp" "ns" 1.000000)
					( Status sCSetFlattened )
					( Origin gBackEnd )
				)
				( attribute "RELATIVE_PROPAGATION_DELAY_SCOPE" "G"
					( Parent
						( matchGroupRef "@crescent_city_bb_fab1_lib.crescent_city_bb_fab1(sch_1):\MG_DQ_NEAR_DIMM_NG_M_M_BYTE3\" )
					)
					( Status sCSetFlattened )
					( Origin gBackEnd )
				)
				( attribute "RELATIVE_PROPAGATION_DELAY" "-50.00 MIL,50.00 MIL"
					( Parent
						( matchGroupRef "@crescent_city_bb_fab1_lib.crescent_city_bb_fab1(sch_1):\MG_DQ_NEAR_DIMM_NG_M_M_BYTE3\" )
					)
					( Units "uMatchProp" "ns" 1.000000)
					( Status sCSetFlattened )
					( Origin gBackEnd )
				)
			)
			( pinPair "@baseboard_fab2_lib.baseboard_fab2(sch_1):\PP1777\"
				( pinRef "@baseboard_fab2_lib.baseboard_fab2(sch_1):page62_i172:DDR5_DQ(26)" )
				( pinRef "@baseboard_fab2_lib.baseboard_fab2(sch_1):page87_i186:DQ(27)" )
				( attribute "RELATIVE_PROPAGATION_DELAY_SCOPE" "G"
					( Parent
						( matchGroupRef "@baseboard_fab2_lib.baseboard_fab2(sch_1):\MG_DQ-DQS_FAR_DIMM_NG_M_M_BYTE3\" )
					)
					( Status sCSetFlattened )
					( Origin gBackEnd )
				)
				( attribute "RELATIVE_PROPAGATION_DELAY" "0.00 MIL,195.00 MIL"
					( Parent
						( matchGroupRef "@baseboard_fab2_lib.baseboard_fab2(sch_1):\MG_DQ-DQS_FAR_DIMM_NG_M_M_BYTE3\" )
					)
					( Units "uMatchProp" "ns" 1.000000)
					( Status sCSetFlattened )
					( Origin gBackEnd )
				)
				( attribute "RELATIVE_PROPAGATION_DELAY_SCOPE" "G"
					( Parent
						( matchGroupRef "@baseboard_fab2_lib.baseboard_fab2(sch_1):\MG_DQ_FAR_DIMM_NG_M_M_BYTE3\" )
					)
					( Status sCSetFlattened )
					( Origin gBackEnd )
				)
				( attribute "RELATIVE_PROPAGATION_DELAY" "-50.00 MIL,50.00 MIL"
					( Parent
						( matchGroupRef "@baseboard_fab2_lib.baseboard_fab2(sch_1):\MG_DQ_FAR_DIMM_NG_M_M_BYTE3\" )
					)
					( Units "uMatchProp" "ns" 1.000000)
					( Status sCSetFlattened )
					( Origin gBackEnd )
				)
			)
			( pinPair "@baseboard_fab2_lib.baseboard_fab2(sch_1):\PP1778\"
				( pinRef "@baseboard_fab2_lib.baseboard_fab2(sch_1):page62_i172:DDR5_DQ(26)" )
				( pinRef "@baseboard_fab2_lib.baseboard_fab2(sch_1):page88_i111:DQ(26)" )
				( attribute "RELATIVE_PROPAGATION_DELAY_SCOPE" "G"
					( Parent
						( matchGroupRef "@baseboard_fab2_lib.baseboard_fab2(sch_1):\MG_DQ-DQS_NEAR_DIMM_NG_M_M_BYTE3\" )
					)
					( Status sCSetFlattened )
					( Origin gBackEnd )
				)
				( attribute "RELATIVE_PROPAGATION_DELAY" "0.00 MIL,195.00 MIL"
					( Parent
						( matchGroupRef "@baseboard_fab2_lib.baseboard_fab2(sch_1):\MG_DQ-DQS_NEAR_DIMM_NG_M_M_BYTE3\" )
					)
					( Units "uMatchProp" "ns" 1.000000)
					( Status sCSetFlattened )
					( Origin gBackEnd )
				)
				( attribute "RELATIVE_PROPAGATION_DELAY_SCOPE" "G"
					( Parent
						( matchGroupRef "@crescent_city_bb_fab1_lib.crescent_city_bb_fab1(sch_1):\MG_DQ_NEAR_DIMM_NG_M_M_BYTE3\" )
					)
					( Status sCSetFlattened )
					( Origin gBackEnd )
				)
				( attribute "RELATIVE_PROPAGATION_DELAY" "-50.00 MIL,50.00 MIL"
					( Parent
						( matchGroupRef "@crescent_city_bb_fab1_lib.crescent_city_bb_fab1(sch_1):\MG_DQ_NEAR_DIMM_NG_M_M_BYTE3\" )
					)
					( Units "uMatchProp" "ns" 1.000000)
					( Status sCSetFlattened )
					( Origin gBackEnd )
				)
			)
			( pinPair "@baseboard_fab2_lib.baseboard_fab2(sch_1):\PP1780\"
				( pinRef "@baseboard_fab2_lib.baseboard_fab2(sch_1):page62_i172:DDR5_DQ(27)" )
				( pinRef "@baseboard_fab2_lib.baseboard_fab2(sch_1):page87_i186:DQ(26)" )
				( attribute "RELATIVE_PROPAGATION_DELAY_SCOPE" "G"
					( Parent
						( matchGroupRef "@baseboard_fab2_lib.baseboard_fab2(sch_1):\MG_DQ-DQS_FAR_DIMM_NG_M_M_BYTE3\" )
					)
					( Status sCSetFlattened )
					( Origin gBackEnd )
				)
				( attribute "RELATIVE_PROPAGATION_DELAY" "0.00 MIL,195.00 MIL"
					( Parent
						( matchGroupRef "@baseboard_fab2_lib.baseboard_fab2(sch_1):\MG_DQ-DQS_FAR_DIMM_NG_M_M_BYTE3\" )
					)
					( Units "uMatchProp" "ns" 1.000000)
					( Status sCSetFlattened )
					( Origin gBackEnd )
				)
				( attribute "RELATIVE_PROPAGATION_DELAY_SCOPE" "G"
					( Parent
						( matchGroupRef "@baseboard_fab2_lib.baseboard_fab2(sch_1):\MG_DQ_FAR_DIMM_NG_M_M_BYTE3\" )
					)
					( Status sCSetFlattened )
					( Origin gBackEnd )
				)
				( attribute "RELATIVE_PROPAGATION_DELAY" "-50.00 MIL,50.00 MIL"
					( Parent
						( matchGroupRef "@baseboard_fab2_lib.baseboard_fab2(sch_1):\MG_DQ_FAR_DIMM_NG_M_M_BYTE3\" )
					)
					( Units "uMatchProp" "ns" 1.000000)
					( Status sCSetFlattened )
					( Origin gBackEnd )
				)
			)
			( pinPair "@baseboard_fab2_lib.baseboard_fab2(sch_1):\PP1781\"
				( pinRef "@baseboard_fab2_lib.baseboard_fab2(sch_1):page62_i172:DDR5_DQ(27)" )
				( pinRef "@baseboard_fab2_lib.baseboard_fab2(sch_1):page88_i111:DQ(27)" )
				( attribute "RELATIVE_PROPAGATION_DELAY_SCOPE" "G"
					( Parent
						( matchGroupRef "@baseboard_fab2_lib.baseboard_fab2(sch_1):\MG_DQ-DQS_NEAR_DIMM_NG_M_M_BYTE3\" )
					)
					( Status sCSetFlattened )
					( Origin gBackEnd )
				)
				( attribute "RELATIVE_PROPAGATION_DELAY" "0.00 MIL,195.00 MIL"
					( Parent
						( matchGroupRef "@baseboard_fab2_lib.baseboard_fab2(sch_1):\MG_DQ-DQS_NEAR_DIMM_NG_M_M_BYTE3\" )
					)
					( Units "uMatchProp" "ns" 1.000000)
					( Status sCSetFlattened )
					( Origin gBackEnd )
				)
				( attribute "RELATIVE_PROPAGATION_DELAY_SCOPE" "G"
					( Parent
						( matchGroupRef "@crescent_city_bb_fab1_lib.crescent_city_bb_fab1(sch_1):\MG_DQ_NEAR_DIMM_NG_M_M_BYTE3\" )
					)
					( Status sCSetFlattened )
					( Origin gBackEnd )
				)
				( attribute "RELATIVE_PROPAGATION_DELAY" "-50.00 MIL,50.00 MIL"
					( Parent
						( matchGroupRef "@crescent_city_bb_fab1_lib.crescent_city_bb_fab1(sch_1):\MG_DQ_NEAR_DIMM_NG_M_M_BYTE3\" )
					)
					( Units "uMatchProp" "ns" 1.000000)
					( Status sCSetFlattened )
					( Origin gBackEnd )
				)
			)
			( pinPair "@baseboard_fab2_lib.baseboard_fab2(sch_1):\PP1783\"
				( pinRef "@baseboard_fab2_lib.baseboard_fab2(sch_1):page62_i172:DDR5_DQ(28)" )
				( pinRef "@baseboard_fab2_lib.baseboard_fab2(sch_1):page87_i186:DQ(29)" )
				( attribute "RELATIVE_PROPAGATION_DELAY_SCOPE" "G"
					( Parent
						( matchGroupRef "@baseboard_fab2_lib.baseboard_fab2(sch_1):\MG_DQ-DQS_FAR_DIMM_NG_M_M_BYTE3\" )
					)
					( Status sCSetFlattened )
					( Origin gBackEnd )
				)
				( attribute "RELATIVE_PROPAGATION_DELAY" "0.00 MIL,195.00 MIL"
					( Parent
						( matchGroupRef "@baseboard_fab2_lib.baseboard_fab2(sch_1):\MG_DQ-DQS_FAR_DIMM_NG_M_M_BYTE3\" )
					)
					( Units "uMatchProp" "ns" 1.000000)
					( Status sCSetFlattened )
					( Origin gBackEnd )
				)
				( attribute "RELATIVE_PROPAGATION_DELAY_SCOPE" "G"
					( Parent
						( matchGroupRef "@baseboard_fab2_lib.baseboard_fab2(sch_1):\MG_DQ_FAR_DIMM_NG_M_M_BYTE3\" )
					)
					( Status sCSetFlattened )
					( Origin gBackEnd )
				)
				( attribute "RELATIVE_PROPAGATION_DELAY" "-50.00 MIL,50.00 MIL"
					( Parent
						( matchGroupRef "@baseboard_fab2_lib.baseboard_fab2(sch_1):\MG_DQ_FAR_DIMM_NG_M_M_BYTE3\" )
					)
					( Units "uMatchProp" "ns" 1.000000)
					( Status sCSetFlattened )
					( Origin gBackEnd )
				)
			)
			( pinPair "@baseboard_fab2_lib.baseboard_fab2(sch_1):\PP1784\"
				( pinRef "@baseboard_fab2_lib.baseboard_fab2(sch_1):page62_i172:DDR5_DQ(28)" )
				( pinRef "@baseboard_fab2_lib.baseboard_fab2(sch_1):page88_i111:DQ(28)" )
				( attribute "RELATIVE_PROPAGATION_DELAY_SCOPE" "G"
					( Parent
						( matchGroupRef "@baseboard_fab2_lib.baseboard_fab2(sch_1):\MG_DQ-DQS_NEAR_DIMM_NG_M_M_BYTE3\" )
					)
					( Status sCSetFlattened )
					( Origin gBackEnd )
				)
				( attribute "RELATIVE_PROPAGATION_DELAY" "0.00 MIL,195.00 MIL"
					( Parent
						( matchGroupRef "@baseboard_fab2_lib.baseboard_fab2(sch_1):\MG_DQ-DQS_NEAR_DIMM_NG_M_M_BYTE3\" )
					)
					( Units "uMatchProp" "ns" 1.000000)
					( Status sCSetFlattened )
					( Origin gBackEnd )
				)
				( attribute "RELATIVE_PROPAGATION_DELAY_SCOPE" "G"
					( Parent
						( matchGroupRef "@crescent_city_bb_fab1_lib.crescent_city_bb_fab1(sch_1):\MG_DQ_NEAR_DIMM_NG_M_M_BYTE3\" )
					)
					( Status sCSetFlattened )
					( Origin gBackEnd )
				)
				( attribute "RELATIVE_PROPAGATION_DELAY" "-50.00 MIL,50.00 MIL"
					( Parent
						( matchGroupRef "@crescent_city_bb_fab1_lib.crescent_city_bb_fab1(sch_1):\MG_DQ_NEAR_DIMM_NG_M_M_BYTE3\" )
					)
					( Units "uMatchProp" "ns" 1.000000)
					( Status sCSetFlattened )
					( Origin gBackEnd )
				)
			)
			( pinPair "@baseboard_fab2_lib.baseboard_fab2(sch_1):\PP2458\"
				( pinRef "@baseboard_fab2_lib.baseboard_fab2(sch_1):page59_i172:DDR2_DQ(21)" )
				( pinRef "@baseboard_fab2_lib.baseboard_fab2(sch_1):page81_i186:DQ(20)" )
				( attribute "RELATIVE_PROPAGATION_DELAY_SCOPE" "G"
					( Parent
						( matchGroupRef "@baseboard_fab2_lib.baseboard_fab2(sch_1):\MG_DQ-DQS_FAR_DIMM_NG_M_J_BYTE2\" )
					)
					( Status sCSetFlattened )
					( Origin gBackEnd )
				)
				( attribute "RELATIVE_PROPAGATION_DELAY" "0.00 MIL,195.00 MIL"
					( Parent
						( matchGroupRef "@baseboard_fab2_lib.baseboard_fab2(sch_1):\MG_DQ-DQS_FAR_DIMM_NG_M_J_BYTE2\" )
					)
					( Units "uMatchProp" "ns" 1.000000)
					( Status sCSetFlattened )
					( Origin gBackEnd )
				)
				( attribute "RELATIVE_PROPAGATION_DELAY_SCOPE" "G"
					( Parent
						( matchGroupRef "@baseboard_fab2_lib.baseboard_fab2(sch_1):\MG_DQ_FAR_DIMM_NG_M_J_BYTE2\" )
					)
					( Status sCSetFlattened )
					( Origin gBackEnd )
				)
				( attribute "RELATIVE_PROPAGATION_DELAY" "-50.00 MIL,50.00 MIL"
					( Parent
						( matchGroupRef "@baseboard_fab2_lib.baseboard_fab2(sch_1):\MG_DQ_FAR_DIMM_NG_M_J_BYTE2\" )
					)
					( Units "uMatchProp" "ns" 1.000000)
					( Status sCSetFlattened )
					( Origin gBackEnd )
				)
			)
			( pinPair "@baseboard_fab2_lib.baseboard_fab2(sch_1):\PP2459\"
				( pinRef "@baseboard_fab2_lib.baseboard_fab2(sch_1):page59_i172:DDR2_DQ(21)" )
				( pinRef "@baseboard_fab2_lib.baseboard_fab2(sch_1):page82_i187:DQ(21)" )
				( attribute "RELATIVE_PROPAGATION_DELAY_SCOPE" "G"
					( Parent
						( matchGroupRef "@baseboard_fab2_lib.baseboard_fab2(sch_1):\MG_DQ-DQS_NEAR_DIMM_NG_M_J_BYTE2\" )
					)
					( Status sCSetFlattened )
					( Origin gBackEnd )
				)
				( attribute "RELATIVE_PROPAGATION_DELAY" "0.00 MIL,195.00 MIL"
					( Parent
						( matchGroupRef "@baseboard_fab2_lib.baseboard_fab2(sch_1):\MG_DQ-DQS_NEAR_DIMM_NG_M_J_BYTE2\" )
					)
					( Units "uMatchProp" "ns" 1.000000)
					( Status sCSetFlattened )
					( Origin gBackEnd )
				)
				( attribute "RELATIVE_PROPAGATION_DELAY_SCOPE" "G"
					( Parent
						( matchGroupRef "@baseboard_fab2_lib.baseboard_fab2(sch_1):\MG_DQ_NEAR_DIMM_NG_M_J_BYTE2\" )
					)
					( Status sCSetFlattened )
					( Origin gBackEnd )
				)
				( attribute "RELATIVE_PROPAGATION_DELAY" "-50.00 MIL,50.00 MIL"
					( Parent
						( matchGroupRef "@baseboard_fab2_lib.baseboard_fab2(sch_1):\MG_DQ_NEAR_DIMM_NG_M_J_BYTE2\" )
					)
					( Units "uMatchProp" "ns" 1.000000)
					( Status sCSetFlattened )
					( Origin gBackEnd )
				)
			)
			( pinPair "@baseboard_fab2_lib.baseboard_fab2(sch_1):\PP2461\"
				( pinRef "@baseboard_fab2_lib.baseboard_fab2(sch_1):page59_i172:DDR2_DQ(22)" )
				( pinRef "@baseboard_fab2_lib.baseboard_fab2(sch_1):page81_i186:DQ(23)" )
				( attribute "RELATIVE_PROPAGATION_DELAY_SCOPE" "G"
					( Parent
						( matchGroupRef "@baseboard_fab2_lib.baseboard_fab2(sch_1):\MG_DQ-DQS_FAR_DIMM_NG_M_J_BYTE2\" )
					)
					( Status sCSetFlattened )
					( Origin gBackEnd )
				)
				( attribute "RELATIVE_PROPAGATION_DELAY" "0.00 MIL,195.00 MIL"
					( Parent
						( matchGroupRef "@baseboard_fab2_lib.baseboard_fab2(sch_1):\MG_DQ-DQS_FAR_DIMM_NG_M_J_BYTE2\" )
					)
					( Units "uMatchProp" "ns" 1.000000)
					( Status sCSetFlattened )
					( Origin gBackEnd )
				)
				( attribute "RELATIVE_PROPAGATION_DELAY_SCOPE" "G"
					( Parent
						( matchGroupRef "@baseboard_fab2_lib.baseboard_fab2(sch_1):\MG_DQ_FAR_DIMM_NG_M_J_BYTE2\" )
					)
					( Status sCSetFlattened )
					( Origin gBackEnd )
				)
				( attribute "RELATIVE_PROPAGATION_DELAY" "-50.00 MIL,50.00 MIL"
					( Parent
						( matchGroupRef "@baseboard_fab2_lib.baseboard_fab2(sch_1):\MG_DQ_FAR_DIMM_NG_M_J_BYTE2\" )
					)
					( Units "uMatchProp" "ns" 1.000000)
					( Status sCSetFlattened )
					( Origin gBackEnd )
				)
			)
			( pinPair "@baseboard_fab2_lib.baseboard_fab2(sch_1):\PP2462\"
				( pinRef "@baseboard_fab2_lib.baseboard_fab2(sch_1):page59_i172:DDR2_DQ(22)" )
				( pinRef "@baseboard_fab2_lib.baseboard_fab2(sch_1):page82_i187:DQ(22)" )
				( attribute "RELATIVE_PROPAGATION_DELAY_SCOPE" "G"
					( Parent
						( matchGroupRef "@baseboard_fab2_lib.baseboard_fab2(sch_1):\MG_DQ-DQS_NEAR_DIMM_NG_M_J_BYTE2\" )
					)
					( Status sCSetFlattened )
					( Origin gBackEnd )
				)
				( attribute "RELATIVE_PROPAGATION_DELAY" "0.00 MIL,195.00 MIL"
					( Parent
						( matchGroupRef "@baseboard_fab2_lib.baseboard_fab2(sch_1):\MG_DQ-DQS_NEAR_DIMM_NG_M_J_BYTE2\" )
					)
					( Units "uMatchProp" "ns" 1.000000)
					( Status sCSetFlattened )
					( Origin gBackEnd )
				)
				( attribute "RELATIVE_PROPAGATION_DELAY_SCOPE" "G"
					( Parent
						( matchGroupRef "@baseboard_fab2_lib.baseboard_fab2(sch_1):\MG_DQ_NEAR_DIMM_NG_M_J_BYTE2\" )
					)
					( Status sCSetFlattened )
					( Origin gBackEnd )
				)
				( attribute "RELATIVE_PROPAGATION_DELAY" "-50.00 MIL,50.00 MIL"
					( Parent
						( matchGroupRef "@baseboard_fab2_lib.baseboard_fab2(sch_1):\MG_DQ_NEAR_DIMM_NG_M_J_BYTE2\" )
					)
					( Units "uMatchProp" "ns" 1.000000)
					( Status sCSetFlattened )
					( Origin gBackEnd )
				)
			)
			( pinPair "@baseboard_fab2_lib.baseboard_fab2(sch_1):\PP2464\"
				( pinRef "@baseboard_fab2_lib.baseboard_fab2(sch_1):page59_i172:DDR2_DQ(23)" )
				( pinRef "@baseboard_fab2_lib.baseboard_fab2(sch_1):page81_i186:DQ(22)" )
				( attribute "RELATIVE_PROPAGATION_DELAY_SCOPE" "G"
					( Parent
						( matchGroupRef "@baseboard_fab2_lib.baseboard_fab2(sch_1):\MG_DQ-DQS_FAR_DIMM_NG_M_J_BYTE2\" )
					)
					( Status sCSetFlattened )
					( Origin gBackEnd )
				)
				( attribute "RELATIVE_PROPAGATION_DELAY" "0.00 MIL,195.00 MIL"
					( Parent
						( matchGroupRef "@baseboard_fab2_lib.baseboard_fab2(sch_1):\MG_DQ-DQS_FAR_DIMM_NG_M_J_BYTE2\" )
					)
					( Units "uMatchProp" "ns" 1.000000)
					( Status sCSetFlattened )
					( Origin gBackEnd )
				)
				( attribute "RELATIVE_PROPAGATION_DELAY_SCOPE" "G"
					( Parent
						( matchGroupRef "@baseboard_fab2_lib.baseboard_fab2(sch_1):\MG_DQ_FAR_DIMM_NG_M_J_BYTE2\" )
					)
					( Status sCSetFlattened )
					( Origin gBackEnd )
				)
				( attribute "RELATIVE_PROPAGATION_DELAY" "-50.00 MIL,50.00 MIL"
					( Parent
						( matchGroupRef "@baseboard_fab2_lib.baseboard_fab2(sch_1):\MG_DQ_FAR_DIMM_NG_M_J_BYTE2\" )
					)
					( Units "uMatchProp" "ns" 1.000000)
					( Status sCSetFlattened )
					( Origin gBackEnd )
				)
			)
			( pinPair "@baseboard_fab2_lib.baseboard_fab2(sch_1):\PP2465\"
				( pinRef "@baseboard_fab2_lib.baseboard_fab2(sch_1):page59_i172:DDR2_DQ(23)" )
				( pinRef "@baseboard_fab2_lib.baseboard_fab2(sch_1):page82_i187:DQ(23)" )
				( attribute "RELATIVE_PROPAGATION_DELAY_SCOPE" "G"
					( Parent
						( matchGroupRef "@baseboard_fab2_lib.baseboard_fab2(sch_1):\MG_DQ-DQS_NEAR_DIMM_NG_M_J_BYTE2\" )
					)
					( Status sCSetFlattened )
					( Origin gBackEnd )
				)
				( attribute "RELATIVE_PROPAGATION_DELAY" "0.00 MIL,195.00 MIL"
					( Parent
						( matchGroupRef "@baseboard_fab2_lib.baseboard_fab2(sch_1):\MG_DQ-DQS_NEAR_DIMM_NG_M_J_BYTE2\" )
					)
					( Units "uMatchProp" "ns" 1.000000)
					( Status sCSetFlattened )
					( Origin gBackEnd )
				)
				( attribute "RELATIVE_PROPAGATION_DELAY_SCOPE" "G"
					( Parent
						( matchGroupRef "@baseboard_fab2_lib.baseboard_fab2(sch_1):\MG_DQ_NEAR_DIMM_NG_M_J_BYTE2\" )
					)
					( Status sCSetFlattened )
					( Origin gBackEnd )
				)
				( attribute "RELATIVE_PROPAGATION_DELAY" "-50.00 MIL,50.00 MIL"
					( Parent
						( matchGroupRef "@baseboard_fab2_lib.baseboard_fab2(sch_1):\MG_DQ_NEAR_DIMM_NG_M_J_BYTE2\" )
					)
					( Units "uMatchProp" "ns" 1.000000)
					( Status sCSetFlattened )
					( Origin gBackEnd )
				)
			)
			( pinPair "@baseboard_fab2_lib.baseboard_fab2(sch_1):\PP2419\"
				( pinRef "@baseboard_fab2_lib.baseboard_fab2(sch_1):page59_i172:DDR2_DQ(24)" )
				( pinRef "@baseboard_fab2_lib.baseboard_fab2(sch_1):page81_i186:DQ(25)" )
				( attribute "RELATIVE_PROPAGATION_DELAY_SCOPE" "G"
					( Parent
						( matchGroupRef "@baseboard_fab2_lib.baseboard_fab2(sch_1):\MG_DQ-DQS_FAR_DIMM_NG_M_J_BYTE3\" )
					)
					( Status sCSetFlattened )
					( Origin gBackEnd )
				)
				( attribute "RELATIVE_PROPAGATION_DELAY" "0.00 MIL,195.00 MIL"
					( Parent
						( matchGroupRef "@baseboard_fab2_lib.baseboard_fab2(sch_1):\MG_DQ-DQS_FAR_DIMM_NG_M_J_BYTE3\" )
					)
					( Units "uMatchProp" "ns" 1.000000)
					( Status sCSetFlattened )
					( Origin gBackEnd )
				)
				( attribute "RELATIVE_PROPAGATION_DELAY_SCOPE" "G"
					( Parent
						( matchGroupRef "@baseboard_fab2_lib.baseboard_fab2(sch_1):\MG_DQ_FAR_DIMM_NG_M_J_BYTE3\" )
					)
					( Status sCSetFlattened )
					( Origin gBackEnd )
				)
				( attribute "RELATIVE_PROPAGATION_DELAY" "-50.00 MIL,50.00 MIL"
					( Parent
						( matchGroupRef "@baseboard_fab2_lib.baseboard_fab2(sch_1):\MG_DQ_FAR_DIMM_NG_M_J_BYTE3\" )
					)
					( Units "uMatchProp" "ns" 1.000000)
					( Status sCSetFlattened )
					( Origin gBackEnd )
				)
			)
			( pinPair "@baseboard_fab2_lib.baseboard_fab2(sch_1):\PP2420\"
				( pinRef "@baseboard_fab2_lib.baseboard_fab2(sch_1):page59_i172:DDR2_DQ(24)" )
				( pinRef "@baseboard_fab2_lib.baseboard_fab2(sch_1):page82_i187:DQ(24)" )
				( attribute "RELATIVE_PROPAGATION_DELAY_SCOPE" "G"
					( Parent
						( matchGroupRef "@baseboard_fab2_lib.baseboard_fab2(sch_1):\MG_DQ-DQS_NEAR_DIMM_NG_M_J_BYTE3\" )
					)
					( Status sCSetFlattened )
					( Origin gBackEnd )
				)
				( attribute "RELATIVE_PROPAGATION_DELAY" "0.00 MIL,195.00 MIL"
					( Parent
						( matchGroupRef "@baseboard_fab2_lib.baseboard_fab2(sch_1):\MG_DQ-DQS_NEAR_DIMM_NG_M_J_BYTE3\" )
					)
					( Units "uMatchProp" "ns" 1.000000)
					( Status sCSetFlattened )
					( Origin gBackEnd )
				)
				( attribute "RELATIVE_PROPAGATION_DELAY_SCOPE" "G"
					( Parent
						( matchGroupRef "@baseboard_fab2_lib.baseboard_fab2(sch_1):\MG_DQ_NEAR_DIMM_NG_M_J_BYTE3\" )
					)
					( Status sCSetFlattened )
					( Origin gBackEnd )
				)
				( attribute "RELATIVE_PROPAGATION_DELAY" "-50.00 MIL,50.00 MIL"
					( Parent
						( matchGroupRef "@baseboard_fab2_lib.baseboard_fab2(sch_1):\MG_DQ_NEAR_DIMM_NG_M_J_BYTE3\" )
					)
					( Units "uMatchProp" "ns" 1.000000)
					( Status sCSetFlattened )
					( Origin gBackEnd )
				)
			)
			( pinPair "@baseboard_fab2_lib.baseboard_fab2(sch_1):\PP2422\"
				( pinRef "@baseboard_fab2_lib.baseboard_fab2(sch_1):page59_i172:DDR2_DQ(25)" )
				( pinRef "@baseboard_fab2_lib.baseboard_fab2(sch_1):page81_i186:DQ(24)" )
				( attribute "RELATIVE_PROPAGATION_DELAY_SCOPE" "G"
					( Parent
						( matchGroupRef "@baseboard_fab2_lib.baseboard_fab2(sch_1):\MG_DQ-DQS_FAR_DIMM_NG_M_J_BYTE3\" )
					)
					( Status sCSetFlattened )
					( Origin gBackEnd )
				)
				( attribute "RELATIVE_PROPAGATION_DELAY" "0.00 MIL,195.00 MIL"
					( Parent
						( matchGroupRef "@baseboard_fab2_lib.baseboard_fab2(sch_1):\MG_DQ-DQS_FAR_DIMM_NG_M_J_BYTE3\" )
					)
					( Units "uMatchProp" "ns" 1.000000)
					( Status sCSetFlattened )
					( Origin gBackEnd )
				)
				( attribute "RELATIVE_PROPAGATION_DELAY_SCOPE" "G"
					( Parent
						( matchGroupRef "@baseboard_fab2_lib.baseboard_fab2(sch_1):\MG_DQ_FAR_DIMM_NG_M_J_BYTE3\" )
					)
					( Status sCSetFlattened )
					( Origin gBackEnd )
				)
				( attribute "RELATIVE_PROPAGATION_DELAY" "-50.00 MIL,50.00 MIL"
					( Parent
						( matchGroupRef "@baseboard_fab2_lib.baseboard_fab2(sch_1):\MG_DQ_FAR_DIMM_NG_M_J_BYTE3\" )
					)
					( Units "uMatchProp" "ns" 1.000000)
					( Status sCSetFlattened )
					( Origin gBackEnd )
				)
			)
			( pinPair "@baseboard_fab2_lib.baseboard_fab2(sch_1):\PP2423\"
				( pinRef "@baseboard_fab2_lib.baseboard_fab2(sch_1):page59_i172:DDR2_DQ(25)" )
				( pinRef "@baseboard_fab2_lib.baseboard_fab2(sch_1):page82_i187:DQ(25)" )
				( attribute "RELATIVE_PROPAGATION_DELAY_SCOPE" "G"
					( Parent
						( matchGroupRef "@baseboard_fab2_lib.baseboard_fab2(sch_1):\MG_DQ-DQS_NEAR_DIMM_NG_M_J_BYTE3\" )
					)
					( Status sCSetFlattened )
					( Origin gBackEnd )
				)
				( attribute "RELATIVE_PROPAGATION_DELAY" "0.00 MIL,195.00 MIL"
					( Parent
						( matchGroupRef "@baseboard_fab2_lib.baseboard_fab2(sch_1):\MG_DQ-DQS_NEAR_DIMM_NG_M_J_BYTE3\" )
					)
					( Units "uMatchProp" "ns" 1.000000)
					( Status sCSetFlattened )
					( Origin gBackEnd )
				)
				( attribute "RELATIVE_PROPAGATION_DELAY_SCOPE" "G"
					( Parent
						( matchGroupRef "@baseboard_fab2_lib.baseboard_fab2(sch_1):\MG_DQ_NEAR_DIMM_NG_M_J_BYTE3\" )
					)
					( Status sCSetFlattened )
					( Origin gBackEnd )
				)
				( attribute "RELATIVE_PROPAGATION_DELAY" "-50.00 MIL,50.00 MIL"
					( Parent
						( matchGroupRef "@baseboard_fab2_lib.baseboard_fab2(sch_1):\MG_DQ_NEAR_DIMM_NG_M_J_BYTE3\" )
					)
					( Units "uMatchProp" "ns" 1.000000)
					( Status sCSetFlattened )
					( Origin gBackEnd )
				)
			)
			( pinPair "@baseboard_fab2_lib.baseboard_fab2(sch_1):\PP2425\"
				( pinRef "@baseboard_fab2_lib.baseboard_fab2(sch_1):page59_i172:DDR2_DQ(26)" )
				( pinRef "@baseboard_fab2_lib.baseboard_fab2(sch_1):page81_i186:DQ(27)" )
				( attribute "RELATIVE_PROPAGATION_DELAY_SCOPE" "G"
					( Parent
						( matchGroupRef "@baseboard_fab2_lib.baseboard_fab2(sch_1):\MG_DQ-DQS_FAR_DIMM_NG_M_J_BYTE3\" )
					)
					( Status sCSetFlattened )
					( Origin gBackEnd )
				)
				( attribute "RELATIVE_PROPAGATION_DELAY" "0.00 MIL,195.00 MIL"
					( Parent
						( matchGroupRef "@baseboard_fab2_lib.baseboard_fab2(sch_1):\MG_DQ-DQS_FAR_DIMM_NG_M_J_BYTE3\" )
					)
					( Units "uMatchProp" "ns" 1.000000)
					( Status sCSetFlattened )
					( Origin gBackEnd )
				)
				( attribute "RELATIVE_PROPAGATION_DELAY_SCOPE" "G"
					( Parent
						( matchGroupRef "@baseboard_fab2_lib.baseboard_fab2(sch_1):\MG_DQ_FAR_DIMM_NG_M_J_BYTE3\" )
					)
					( Status sCSetFlattened )
					( Origin gBackEnd )
				)
				( attribute "RELATIVE_PROPAGATION_DELAY" "-50.00 MIL,50.00 MIL"
					( Parent
						( matchGroupRef "@baseboard_fab2_lib.baseboard_fab2(sch_1):\MG_DQ_FAR_DIMM_NG_M_J_BYTE3\" )
					)
					( Units "uMatchProp" "ns" 1.000000)
					( Status sCSetFlattened )
					( Origin gBackEnd )
				)
			)
			( pinPair "@baseboard_fab2_lib.baseboard_fab2(sch_1):\PP2426\"
				( pinRef "@baseboard_fab2_lib.baseboard_fab2(sch_1):page59_i172:DDR2_DQ(26)" )
				( pinRef "@baseboard_fab2_lib.baseboard_fab2(sch_1):page82_i187:DQ(26)" )
				( attribute "RELATIVE_PROPAGATION_DELAY_SCOPE" "G"
					( Parent
						( matchGroupRef "@baseboard_fab2_lib.baseboard_fab2(sch_1):\MG_DQ-DQS_NEAR_DIMM_NG_M_J_BYTE3\" )
					)
					( Status sCSetFlattened )
					( Origin gBackEnd )
				)
				( attribute "RELATIVE_PROPAGATION_DELAY" "0.00 MIL,195.00 MIL"
					( Parent
						( matchGroupRef "@baseboard_fab2_lib.baseboard_fab2(sch_1):\MG_DQ-DQS_NEAR_DIMM_NG_M_J_BYTE3\" )
					)
					( Units "uMatchProp" "ns" 1.000000)
					( Status sCSetFlattened )
					( Origin gBackEnd )
				)
				( attribute "RELATIVE_PROPAGATION_DELAY_SCOPE" "G"
					( Parent
						( matchGroupRef "@baseboard_fab2_lib.baseboard_fab2(sch_1):\MG_DQ_NEAR_DIMM_NG_M_J_BYTE3\" )
					)
					( Status sCSetFlattened )
					( Origin gBackEnd )
				)
				( attribute "RELATIVE_PROPAGATION_DELAY" "-50.00 MIL,50.00 MIL"
					( Parent
						( matchGroupRef "@baseboard_fab2_lib.baseboard_fab2(sch_1):\MG_DQ_NEAR_DIMM_NG_M_J_BYTE3\" )
					)
					( Units "uMatchProp" "ns" 1.000000)
					( Status sCSetFlattened )
					( Origin gBackEnd )
				)
			)
			( pinPair "@baseboard_fab2_lib.baseboard_fab2(sch_1):\PP2428\"
				( pinRef "@baseboard_fab2_lib.baseboard_fab2(sch_1):page59_i172:DDR2_DQ(27)" )
				( pinRef "@baseboard_fab2_lib.baseboard_fab2(sch_1):page81_i186:DQ(26)" )
				( attribute "RELATIVE_PROPAGATION_DELAY_SCOPE" "G"
					( Parent
						( matchGroupRef "@baseboard_fab2_lib.baseboard_fab2(sch_1):\MG_DQ-DQS_FAR_DIMM_NG_M_J_BYTE3\" )
					)
					( Status sCSetFlattened )
					( Origin gBackEnd )
				)
				( attribute "RELATIVE_PROPAGATION_DELAY" "0.00 MIL,195.00 MIL"
					( Parent
						( matchGroupRef "@baseboard_fab2_lib.baseboard_fab2(sch_1):\MG_DQ-DQS_FAR_DIMM_NG_M_J_BYTE3\" )
					)
					( Units "uMatchProp" "ns" 1.000000)
					( Status sCSetFlattened )
					( Origin gBackEnd )
				)
				( attribute "RELATIVE_PROPAGATION_DELAY_SCOPE" "G"
					( Parent
						( matchGroupRef "@baseboard_fab2_lib.baseboard_fab2(sch_1):\MG_DQ_FAR_DIMM_NG_M_J_BYTE3\" )
					)
					( Status sCSetFlattened )
					( Origin gBackEnd )
				)
				( attribute "RELATIVE_PROPAGATION_DELAY" "-50.00 MIL,50.00 MIL"
					( Parent
						( matchGroupRef "@baseboard_fab2_lib.baseboard_fab2(sch_1):\MG_DQ_FAR_DIMM_NG_M_J_BYTE3\" )
					)
					( Units "uMatchProp" "ns" 1.000000)
					( Status sCSetFlattened )
					( Origin gBackEnd )
				)
			)
			( pinPair "@baseboard_fab2_lib.baseboard_fab2(sch_1):\PP2429\"
				( pinRef "@baseboard_fab2_lib.baseboard_fab2(sch_1):page59_i172:DDR2_DQ(27)" )
				( pinRef "@baseboard_fab2_lib.baseboard_fab2(sch_1):page82_i187:DQ(27)" )
				( attribute "RELATIVE_PROPAGATION_DELAY_SCOPE" "G"
					( Parent
						( matchGroupRef "@baseboard_fab2_lib.baseboard_fab2(sch_1):\MG_DQ-DQS_NEAR_DIMM_NG_M_J_BYTE3\" )
					)
					( Status sCSetFlattened )
					( Origin gBackEnd )
				)
				( attribute "RELATIVE_PROPAGATION_DELAY" "0.00 MIL,195.00 MIL"
					( Parent
						( matchGroupRef "@baseboard_fab2_lib.baseboard_fab2(sch_1):\MG_DQ-DQS_NEAR_DIMM_NG_M_J_BYTE3\" )
					)
					( Units "uMatchProp" "ns" 1.000000)
					( Status sCSetFlattened )
					( Origin gBackEnd )
				)
				( attribute "RELATIVE_PROPAGATION_DELAY_SCOPE" "G"
					( Parent
						( matchGroupRef "@baseboard_fab2_lib.baseboard_fab2(sch_1):\MG_DQ_NEAR_DIMM_NG_M_J_BYTE3\" )
					)
					( Status sCSetFlattened )
					( Origin gBackEnd )
				)
				( attribute "RELATIVE_PROPAGATION_DELAY" "-50.00 MIL,50.00 MIL"
					( Parent
						( matchGroupRef "@baseboard_fab2_lib.baseboard_fab2(sch_1):\MG_DQ_NEAR_DIMM_NG_M_J_BYTE3\" )
					)
					( Units "uMatchProp" "ns" 1.000000)
					( Status sCSetFlattened )
					( Origin gBackEnd )
				)
			)
			( pinPair "@baseboard_fab2_lib.baseboard_fab2(sch_1):\PP2431\"
				( pinRef "@baseboard_fab2_lib.baseboard_fab2(sch_1):page59_i172:DDR2_DQ(28)" )
				( pinRef "@baseboard_fab2_lib.baseboard_fab2(sch_1):page81_i186:DQ(29)" )
				( attribute "RELATIVE_PROPAGATION_DELAY_SCOPE" "G"
					( Parent
						( matchGroupRef "@baseboard_fab2_lib.baseboard_fab2(sch_1):\MG_DQ-DQS_FAR_DIMM_NG_M_J_BYTE3\" )
					)
					( Status sCSetFlattened )
					( Origin gBackEnd )
				)
				( attribute "RELATIVE_PROPAGATION_DELAY" "0.00 MIL,195.00 MIL"
					( Parent
						( matchGroupRef "@baseboard_fab2_lib.baseboard_fab2(sch_1):\MG_DQ-DQS_FAR_DIMM_NG_M_J_BYTE3\" )
					)
					( Units "uMatchProp" "ns" 1.000000)
					( Status sCSetFlattened )
					( Origin gBackEnd )
				)
				( attribute "RELATIVE_PROPAGATION_DELAY_SCOPE" "G"
					( Parent
						( matchGroupRef "@baseboard_fab2_lib.baseboard_fab2(sch_1):\MG_DQ_FAR_DIMM_NG_M_J_BYTE3\" )
					)
					( Status sCSetFlattened )
					( Origin gBackEnd )
				)
				( attribute "RELATIVE_PROPAGATION_DELAY" "-50.00 MIL,50.00 MIL"
					( Parent
						( matchGroupRef "@baseboard_fab2_lib.baseboard_fab2(sch_1):\MG_DQ_FAR_DIMM_NG_M_J_BYTE3\" )
					)
					( Units "uMatchProp" "ns" 1.000000)
					( Status sCSetFlattened )
					( Origin gBackEnd )
				)
			)
			( pinPair "@baseboard_fab2_lib.baseboard_fab2(sch_1):\PP2432\"
				( pinRef "@baseboard_fab2_lib.baseboard_fab2(sch_1):page59_i172:DDR2_DQ(28)" )
				( pinRef "@baseboard_fab2_lib.baseboard_fab2(sch_1):page82_i187:DQ(28)" )
				( attribute "RELATIVE_PROPAGATION_DELAY_SCOPE" "G"
					( Parent
						( matchGroupRef "@baseboard_fab2_lib.baseboard_fab2(sch_1):\MG_DQ-DQS_NEAR_DIMM_NG_M_J_BYTE3\" )
					)
					( Status sCSetFlattened )
					( Origin gBackEnd )
				)
				( attribute "RELATIVE_PROPAGATION_DELAY" "0.00 MIL,195.00 MIL"
					( Parent
						( matchGroupRef "@baseboard_fab2_lib.baseboard_fab2(sch_1):\MG_DQ-DQS_NEAR_DIMM_NG_M_J_BYTE3\" )
					)
					( Units "uMatchProp" "ns" 1.000000)
					( Status sCSetFlattened )
					( Origin gBackEnd )
				)
				( attribute "RELATIVE_PROPAGATION_DELAY_SCOPE" "G"
					( Parent
						( matchGroupRef "@baseboard_fab2_lib.baseboard_fab2(sch_1):\MG_DQ_NEAR_DIMM_NG_M_J_BYTE3\" )
					)
					( Status sCSetFlattened )
					( Origin gBackEnd )
				)
				( attribute "RELATIVE_PROPAGATION_DELAY" "-50.00 MIL,50.00 MIL"
					( Parent
						( matchGroupRef "@baseboard_fab2_lib.baseboard_fab2(sch_1):\MG_DQ_NEAR_DIMM_NG_M_J_BYTE3\" )
					)
					( Units "uMatchProp" "ns" 1.000000)
					( Status sCSetFlattened )
					( Origin gBackEnd )
				)
			)
			( pinPair "@baseboard_fab2_lib.baseboard_fab2(sch_1):\PP2434\"
				( pinRef "@baseboard_fab2_lib.baseboard_fab2(sch_1):page59_i172:DDR2_DQ(29)" )
				( pinRef "@baseboard_fab2_lib.baseboard_fab2(sch_1):page81_i186:DQ(28)" )
				( attribute "RELATIVE_PROPAGATION_DELAY_SCOPE" "G"
					( Parent
						( matchGroupRef "@baseboard_fab2_lib.baseboard_fab2(sch_1):\MG_DQ-DQS_FAR_DIMM_NG_M_J_BYTE3\" )
					)
					( Status sCSetFlattened )
					( Origin gBackEnd )
				)
				( attribute "RELATIVE_PROPAGATION_DELAY" "0.00 MIL,195.00 MIL"
					( Parent
						( matchGroupRef "@baseboard_fab2_lib.baseboard_fab2(sch_1):\MG_DQ-DQS_FAR_DIMM_NG_M_J_BYTE3\" )
					)
					( Units "uMatchProp" "ns" 1.000000)
					( Status sCSetFlattened )
					( Origin gBackEnd )
				)
				( attribute "RELATIVE_PROPAGATION_DELAY_SCOPE" "G"
					( Parent
						( matchGroupRef "@baseboard_fab2_lib.baseboard_fab2(sch_1):\MG_DQ_FAR_DIMM_NG_M_J_BYTE3\" )
					)
					( Status sCSetFlattened )
					( Origin gBackEnd )
				)
				( attribute "RELATIVE_PROPAGATION_DELAY" "-50.00 MIL,50.00 MIL"
					( Parent
						( matchGroupRef "@baseboard_fab2_lib.baseboard_fab2(sch_1):\MG_DQ_FAR_DIMM_NG_M_J_BYTE3\" )
					)
					( Units "uMatchProp" "ns" 1.000000)
					( Status sCSetFlattened )
					( Origin gBackEnd )
				)
			)
			( pinPair "@baseboard_fab2_lib.baseboard_fab2(sch_1):\PP2435\"
				( pinRef "@baseboard_fab2_lib.baseboard_fab2(sch_1):page59_i172:DDR2_DQ(29)" )
				( pinRef "@baseboard_fab2_lib.baseboard_fab2(sch_1):page82_i187:DQ(29)" )
				( attribute "RELATIVE_PROPAGATION_DELAY_SCOPE" "G"
					( Parent
						( matchGroupRef "@baseboard_fab2_lib.baseboard_fab2(sch_1):\MG_DQ-DQS_NEAR_DIMM_NG_M_J_BYTE3\" )
					)
					( Status sCSetFlattened )
					( Origin gBackEnd )
				)
				( attribute "RELATIVE_PROPAGATION_DELAY" "0.00 MIL,195.00 MIL"
					( Parent
						( matchGroupRef "@baseboard_fab2_lib.baseboard_fab2(sch_1):\MG_DQ-DQS_NEAR_DIMM_NG_M_J_BYTE3\" )
					)
					( Units "uMatchProp" "ns" 1.000000)
					( Status sCSetFlattened )
					( Origin gBackEnd )
				)
				( attribute "RELATIVE_PROPAGATION_DELAY_SCOPE" "G"
					( Parent
						( matchGroupRef "@baseboard_fab2_lib.baseboard_fab2(sch_1):\MG_DQ_NEAR_DIMM_NG_M_J_BYTE3\" )
					)
					( Status sCSetFlattened )
					( Origin gBackEnd )
				)
				( attribute "RELATIVE_PROPAGATION_DELAY" "-50.00 MIL,50.00 MIL"
					( Parent
						( matchGroupRef "@baseboard_fab2_lib.baseboard_fab2(sch_1):\MG_DQ_NEAR_DIMM_NG_M_J_BYTE3\" )
					)
					( Units "uMatchProp" "ns" 1.000000)
					( Status sCSetFlattened )
					( Origin gBackEnd )
				)
			)
			( pinPair "@baseboard_fab2_lib.baseboard_fab2(sch_1):\PP2437\"
				( pinRef "@baseboard_fab2_lib.baseboard_fab2(sch_1):page59_i172:DDR2_DQ(30)" )
				( pinRef "@baseboard_fab2_lib.baseboard_fab2(sch_1):page81_i186:DQ(31)" )
				( attribute "RELATIVE_PROPAGATION_DELAY_SCOPE" "G"
					( Parent
						( matchGroupRef "@baseboard_fab2_lib.baseboard_fab2(sch_1):\MG_DQ-DQS_FAR_DIMM_NG_M_J_BYTE3\" )
					)
					( Status sCSetFlattened )
					( Origin gBackEnd )
				)
				( attribute "RELATIVE_PROPAGATION_DELAY" "0.00 MIL,195.00 MIL"
					( Parent
						( matchGroupRef "@baseboard_fab2_lib.baseboard_fab2(sch_1):\MG_DQ-DQS_FAR_DIMM_NG_M_J_BYTE3\" )
					)
					( Units "uMatchProp" "ns" 1.000000)
					( Status sCSetFlattened )
					( Origin gBackEnd )
				)
				( attribute "RELATIVE_PROPAGATION_DELAY_SCOPE" "G"
					( Parent
						( matchGroupRef "@baseboard_fab2_lib.baseboard_fab2(sch_1):\MG_DQ_FAR_DIMM_NG_M_J_BYTE3\" )
					)
					( Status sCSetFlattened )
					( Origin gBackEnd )
				)
				( attribute "RELATIVE_PROPAGATION_DELAY" "-50.00 MIL,50.00 MIL"
					( Parent
						( matchGroupRef "@baseboard_fab2_lib.baseboard_fab2(sch_1):\MG_DQ_FAR_DIMM_NG_M_J_BYTE3\" )
					)
					( Units "uMatchProp" "ns" 1.000000)
					( Status sCSetFlattened )
					( Origin gBackEnd )
				)
			)
			( pinPair "@baseboard_fab2_lib.baseboard_fab2(sch_1):\PP2438\"
				( pinRef "@baseboard_fab2_lib.baseboard_fab2(sch_1):page59_i172:DDR2_DQ(30)" )
				( pinRef "@baseboard_fab2_lib.baseboard_fab2(sch_1):page82_i187:DQ(30)" )
				( attribute "RELATIVE_PROPAGATION_DELAY_SCOPE" "G"
					( Parent
						( matchGroupRef "@baseboard_fab2_lib.baseboard_fab2(sch_1):\MG_DQ-DQS_NEAR_DIMM_NG_M_J_BYTE3\" )
					)
					( Status sCSetFlattened )
					( Origin gBackEnd )
				)
				( attribute "RELATIVE_PROPAGATION_DELAY" "0.00 MIL,195.00 MIL"
					( Parent
						( matchGroupRef "@baseboard_fab2_lib.baseboard_fab2(sch_1):\MG_DQ-DQS_NEAR_DIMM_NG_M_J_BYTE3\" )
					)
					( Units "uMatchProp" "ns" 1.000000)
					( Status sCSetFlattened )
					( Origin gBackEnd )
				)
				( attribute "RELATIVE_PROPAGATION_DELAY_SCOPE" "G"
					( Parent
						( matchGroupRef "@baseboard_fab2_lib.baseboard_fab2(sch_1):\MG_DQ_NEAR_DIMM_NG_M_J_BYTE3\" )
					)
					( Status sCSetFlattened )
					( Origin gBackEnd )
				)
				( attribute "RELATIVE_PROPAGATION_DELAY" "-50.00 MIL,50.00 MIL"
					( Parent
						( matchGroupRef "@baseboard_fab2_lib.baseboard_fab2(sch_1):\MG_DQ_NEAR_DIMM_NG_M_J_BYTE3\" )
					)
					( Units "uMatchProp" "ns" 1.000000)
					( Status sCSetFlattened )
					( Origin gBackEnd )
				)
			)
			( pinPair "@baseboard_fab2_lib.baseboard_fab2(sch_1):\PP2440\"
				( pinRef "@baseboard_fab2_lib.baseboard_fab2(sch_1):page59_i172:DDR2_DQ(31)" )
				( pinRef "@baseboard_fab2_lib.baseboard_fab2(sch_1):page81_i186:DQ(30)" )
				( attribute "RELATIVE_PROPAGATION_DELAY_SCOPE" "G"
					( Parent
						( matchGroupRef "@baseboard_fab2_lib.baseboard_fab2(sch_1):\MG_DQ-DQS_FAR_DIMM_NG_M_J_BYTE3\" )
					)
					( Status sCSetFlattened )
					( Origin gBackEnd )
				)
				( attribute "RELATIVE_PROPAGATION_DELAY" "0.00 MIL,195.00 MIL"
					( Parent
						( matchGroupRef "@baseboard_fab2_lib.baseboard_fab2(sch_1):\MG_DQ-DQS_FAR_DIMM_NG_M_J_BYTE3\" )
					)
					( Units "uMatchProp" "ns" 1.000000)
					( Status sCSetFlattened )
					( Origin gBackEnd )
				)
				( attribute "RELATIVE_PROPAGATION_DELAY_SCOPE" "G"
					( Parent
						( matchGroupRef "@baseboard_fab2_lib.baseboard_fab2(sch_1):\MG_DQ_FAR_DIMM_NG_M_J_BYTE3\" )
					)
					( Status sCSetFlattened )
					( Origin gBackEnd )
				)
				( attribute "RELATIVE_PROPAGATION_DELAY" "-50.00 MIL,50.00 MIL"
					( Parent
						( matchGroupRef "@baseboard_fab2_lib.baseboard_fab2(sch_1):\MG_DQ_FAR_DIMM_NG_M_J_BYTE3\" )
					)
					( Units "uMatchProp" "ns" 1.000000)
					( Status sCSetFlattened )
					( Origin gBackEnd )
				)
			)
			( pinPair "@baseboard_fab2_lib.baseboard_fab2(sch_1):\PP2441\"
				( pinRef "@baseboard_fab2_lib.baseboard_fab2(sch_1):page59_i172:DDR2_DQ(31)" )
				( pinRef "@baseboard_fab2_lib.baseboard_fab2(sch_1):page82_i187:DQ(31)" )
				( attribute "RELATIVE_PROPAGATION_DELAY_SCOPE" "G"
					( Parent
						( matchGroupRef "@baseboard_fab2_lib.baseboard_fab2(sch_1):\MG_DQ-DQS_NEAR_DIMM_NG_M_J_BYTE3\" )
					)
					( Status sCSetFlattened )
					( Origin gBackEnd )
				)
				( attribute "RELATIVE_PROPAGATION_DELAY" "0.00 MIL,195.00 MIL"
					( Parent
						( matchGroupRef "@baseboard_fab2_lib.baseboard_fab2(sch_1):\MG_DQ-DQS_NEAR_DIMM_NG_M_J_BYTE3\" )
					)
					( Units "uMatchProp" "ns" 1.000000)
					( Status sCSetFlattened )
					( Origin gBackEnd )
				)
				( attribute "RELATIVE_PROPAGATION_DELAY_SCOPE" "G"
					( Parent
						( matchGroupRef "@baseboard_fab2_lib.baseboard_fab2(sch_1):\MG_DQ_NEAR_DIMM_NG_M_J_BYTE3\" )
					)
					( Status sCSetFlattened )
					( Origin gBackEnd )
				)
				( attribute "RELATIVE_PROPAGATION_DELAY" "-50.00 MIL,50.00 MIL"
					( Parent
						( matchGroupRef "@baseboard_fab2_lib.baseboard_fab2(sch_1):\MG_DQ_NEAR_DIMM_NG_M_J_BYTE3\" )
					)
					( Units "uMatchProp" "ns" 1.000000)
					( Status sCSetFlattened )
					( Origin gBackEnd )
				)
			)
			( pinPair "@baseboard_fab2_lib.baseboard_fab2(sch_1):\PP2395\"
				( pinRef "@baseboard_fab2_lib.baseboard_fab2(sch_1):page59_i172:DDR2_DQ(32)" )
				( pinRef "@baseboard_fab2_lib.baseboard_fab2(sch_1):page81_i186:DQ(33)" )
				( attribute "RELATIVE_PROPAGATION_DELAY_SCOPE" "G"
					( Parent
						( matchGroupRef "@baseboard_fab2_lib.baseboard_fab2(sch_1):\MG_DQ-DQS_FAR_DIMM_NG_M_J_BYTE4\" )
					)
					( Status sCSetFlattened )
					( Origin gBackEnd )
				)
				( attribute "RELATIVE_PROPAGATION_DELAY" "0.00 MIL,195.00 MIL"
					( Parent
						( matchGroupRef "@baseboard_fab2_lib.baseboard_fab2(sch_1):\MG_DQ-DQS_FAR_DIMM_NG_M_J_BYTE4\" )
					)
					( Units "uMatchProp" "ns" 1.000000)
					( Status sCSetFlattened )
					( Origin gBackEnd )
				)
				( attribute "RELATIVE_PROPAGATION_DELAY_SCOPE" "G"
					( Parent
						( matchGroupRef "@baseboard_fab2_lib.baseboard_fab2(sch_1):\MG_DQ_FAR_DIMM_NG_M_J_BYTE4\" )
					)
					( Status sCSetFlattened )
					( Origin gBackEnd )
				)
				( attribute "RELATIVE_PROPAGATION_DELAY" "-50.00 MIL,50.00 MIL"
					( Parent
						( matchGroupRef "@baseboard_fab2_lib.baseboard_fab2(sch_1):\MG_DQ_FAR_DIMM_NG_M_J_BYTE4\" )
					)
					( Units "uMatchProp" "ns" 1.000000)
					( Status sCSetFlattened )
					( Origin gBackEnd )
				)
			)
			( pinPair "@baseboard_fab2_lib.baseboard_fab2(sch_1):\PP2397\"
				( pinRef "@baseboard_fab2_lib.baseboard_fab2(sch_1):page59_i172:DDR2_DQ(32)" )
				( pinRef "@baseboard_fab2_lib.baseboard_fab2(sch_1):page82_i187:DQ(32)" )
				( attribute "RELATIVE_PROPAGATION_DELAY_SCOPE" "G"
					( Parent
						( matchGroupRef "@baseboard_fab2_lib.baseboard_fab2(sch_1):\MG_DQ-DQS_NEAR_DIMM_NG_M_J_BYTE4\" )
					)
					( Status sCSetFlattened )
					( Origin gBackEnd )
				)
				( attribute "RELATIVE_PROPAGATION_DELAY" "0.00 MIL,195.00 MIL"
					( Parent
						( matchGroupRef "@baseboard_fab2_lib.baseboard_fab2(sch_1):\MG_DQ-DQS_NEAR_DIMM_NG_M_J_BYTE4\" )
					)
					( Units "uMatchProp" "ns" 1.000000)
					( Status sCSetFlattened )
					( Origin gBackEnd )
				)
				( attribute "RELATIVE_PROPAGATION_DELAY_SCOPE" "G"
					( Parent
						( matchGroupRef "@baseboard_fab2_lib.baseboard_fab2(sch_1):\MG_DQ_NEAR_DIMM_NG_M_J_BYTE4\" )
					)
					( Status sCSetFlattened )
					( Origin gBackEnd )
				)
				( attribute "RELATIVE_PROPAGATION_DELAY" "-50.00 MIL,50.00 MIL"
					( Parent
						( matchGroupRef "@baseboard_fab2_lib.baseboard_fab2(sch_1):\MG_DQ_NEAR_DIMM_NG_M_J_BYTE4\" )
					)
					( Units "uMatchProp" "ns" 1.000000)
					( Status sCSetFlattened )
					( Origin gBackEnd )
				)
			)
			( pinPair "@baseboard_fab2_lib.baseboard_fab2(sch_1):\PP2398\"
				( pinRef "@baseboard_fab2_lib.baseboard_fab2(sch_1):page59_i172:DDR2_DQ(33)" )
				( pinRef "@baseboard_fab2_lib.baseboard_fab2(sch_1):page81_i186:DQ(32)" )
				( attribute "RELATIVE_PROPAGATION_DELAY_SCOPE" "G"
					( Parent
						( matchGroupRef "@baseboard_fab2_lib.baseboard_fab2(sch_1):\MG_DQ-DQS_FAR_DIMM_NG_M_J_BYTE4\" )
					)
					( Status sCSetFlattened )
					( Origin gBackEnd )
				)
				( attribute "RELATIVE_PROPAGATION_DELAY" "0.00 MIL,195.00 MIL"
					( Parent
						( matchGroupRef "@baseboard_fab2_lib.baseboard_fab2(sch_1):\MG_DQ-DQS_FAR_DIMM_NG_M_J_BYTE4\" )
					)
					( Units "uMatchProp" "ns" 1.000000)
					( Status sCSetFlattened )
					( Origin gBackEnd )
				)
				( attribute "RELATIVE_PROPAGATION_DELAY_SCOPE" "G"
					( Parent
						( matchGroupRef "@baseboard_fab2_lib.baseboard_fab2(sch_1):\MG_DQ_FAR_DIMM_NG_M_J_BYTE4\" )
					)
					( Status sCSetFlattened )
					( Origin gBackEnd )
				)
				( attribute "RELATIVE_PROPAGATION_DELAY" "-50.00 MIL,50.00 MIL"
					( Parent
						( matchGroupRef "@baseboard_fab2_lib.baseboard_fab2(sch_1):\MG_DQ_FAR_DIMM_NG_M_J_BYTE4\" )
					)
					( Units "uMatchProp" "ns" 1.000000)
					( Status sCSetFlattened )
					( Origin gBackEnd )
				)
			)
			( pinPair "@baseboard_fab2_lib.baseboard_fab2(sch_1):\PP2400\"
				( pinRef "@baseboard_fab2_lib.baseboard_fab2(sch_1):page59_i172:DDR2_DQ(33)" )
				( pinRef "@baseboard_fab2_lib.baseboard_fab2(sch_1):page82_i187:DQ(33)" )
				( attribute "RELATIVE_PROPAGATION_DELAY_SCOPE" "G"
					( Parent
						( matchGroupRef "@baseboard_fab2_lib.baseboard_fab2(sch_1):\MG_DQ-DQS_NEAR_DIMM_NG_M_J_BYTE4\" )
					)
					( Status sCSetFlattened )
					( Origin gBackEnd )
				)
				( attribute "RELATIVE_PROPAGATION_DELAY" "0.00 MIL,195.00 MIL"
					( Parent
						( matchGroupRef "@baseboard_fab2_lib.baseboard_fab2(sch_1):\MG_DQ-DQS_NEAR_DIMM_NG_M_J_BYTE4\" )
					)
					( Units "uMatchProp" "ns" 1.000000)
					( Status sCSetFlattened )
					( Origin gBackEnd )
				)
				( attribute "RELATIVE_PROPAGATION_DELAY_SCOPE" "G"
					( Parent
						( matchGroupRef "@baseboard_fab2_lib.baseboard_fab2(sch_1):\MG_DQ_NEAR_DIMM_NG_M_J_BYTE4\" )
					)
					( Status sCSetFlattened )
					( Origin gBackEnd )
				)
				( attribute "RELATIVE_PROPAGATION_DELAY" "-50.00 MIL,50.00 MIL"
					( Parent
						( matchGroupRef "@baseboard_fab2_lib.baseboard_fab2(sch_1):\MG_DQ_NEAR_DIMM_NG_M_J_BYTE4\" )
					)
					( Units "uMatchProp" "ns" 1.000000)
					( Status sCSetFlattened )
					( Origin gBackEnd )
				)
			)
			( pinPair "@baseboard_fab2_lib.baseboard_fab2(sch_1):\PP2401\"
				( pinRef "@baseboard_fab2_lib.baseboard_fab2(sch_1):page59_i172:DDR2_DQ(34)" )
				( pinRef "@baseboard_fab2_lib.baseboard_fab2(sch_1):page81_i186:DQ(35)" )
				( attribute "RELATIVE_PROPAGATION_DELAY_SCOPE" "G"
					( Parent
						( matchGroupRef "@baseboard_fab2_lib.baseboard_fab2(sch_1):\MG_DQ-DQS_FAR_DIMM_NG_M_J_BYTE4\" )
					)
					( Status sCSetFlattened )
					( Origin gBackEnd )
				)
				( attribute "RELATIVE_PROPAGATION_DELAY" "0.00 MIL,195.00 MIL"
					( Parent
						( matchGroupRef "@baseboard_fab2_lib.baseboard_fab2(sch_1):\MG_DQ-DQS_FAR_DIMM_NG_M_J_BYTE4\" )
					)
					( Units "uMatchProp" "ns" 1.000000)
					( Status sCSetFlattened )
					( Origin gBackEnd )
				)
				( attribute "RELATIVE_PROPAGATION_DELAY_SCOPE" "G"
					( Parent
						( matchGroupRef "@baseboard_fab2_lib.baseboard_fab2(sch_1):\MG_DQ_FAR_DIMM_NG_M_J_BYTE4\" )
					)
					( Status sCSetFlattened )
					( Origin gBackEnd )
				)
				( attribute "RELATIVE_PROPAGATION_DELAY" "-50.00 MIL,50.00 MIL"
					( Parent
						( matchGroupRef "@baseboard_fab2_lib.baseboard_fab2(sch_1):\MG_DQ_FAR_DIMM_NG_M_J_BYTE4\" )
					)
					( Units "uMatchProp" "ns" 1.000000)
					( Status sCSetFlattened )
					( Origin gBackEnd )
				)
			)
			( pinPair "@baseboard_fab2_lib.baseboard_fab2(sch_1):\PP2403\"
				( pinRef "@baseboard_fab2_lib.baseboard_fab2(sch_1):page59_i172:DDR2_DQ(34)" )
				( pinRef "@baseboard_fab2_lib.baseboard_fab2(sch_1):page82_i187:DQ(34)" )
				( attribute "RELATIVE_PROPAGATION_DELAY_SCOPE" "G"
					( Parent
						( matchGroupRef "@baseboard_fab2_lib.baseboard_fab2(sch_1):\MG_DQ-DQS_NEAR_DIMM_NG_M_J_BYTE4\" )
					)
					( Status sCSetFlattened )
					( Origin gBackEnd )
				)
				( attribute "RELATIVE_PROPAGATION_DELAY" "0.00 MIL,195.00 MIL"
					( Parent
						( matchGroupRef "@baseboard_fab2_lib.baseboard_fab2(sch_1):\MG_DQ-DQS_NEAR_DIMM_NG_M_J_BYTE4\" )
					)
					( Units "uMatchProp" "ns" 1.000000)
					( Status sCSetFlattened )
					( Origin gBackEnd )
				)
				( attribute "RELATIVE_PROPAGATION_DELAY_SCOPE" "G"
					( Parent
						( matchGroupRef "@baseboard_fab2_lib.baseboard_fab2(sch_1):\MG_DQ_NEAR_DIMM_NG_M_J_BYTE4\" )
					)
					( Status sCSetFlattened )
					( Origin gBackEnd )
				)
				( attribute "RELATIVE_PROPAGATION_DELAY" "-50.00 MIL,50.00 MIL"
					( Parent
						( matchGroupRef "@baseboard_fab2_lib.baseboard_fab2(sch_1):\MG_DQ_NEAR_DIMM_NG_M_J_BYTE4\" )
					)
					( Units "uMatchProp" "ns" 1.000000)
					( Status sCSetFlattened )
					( Origin gBackEnd )
				)
			)
			( pinPair "@baseboard_fab2_lib.baseboard_fab2(sch_1):\PP2404\"
				( pinRef "@baseboard_fab2_lib.baseboard_fab2(sch_1):page59_i172:DDR2_DQ(35)" )
				( pinRef "@baseboard_fab2_lib.baseboard_fab2(sch_1):page81_i186:DQ(34)" )
				( attribute "RELATIVE_PROPAGATION_DELAY_SCOPE" "G"
					( Parent
						( matchGroupRef "@baseboard_fab2_lib.baseboard_fab2(sch_1):\MG_DQ-DQS_FAR_DIMM_NG_M_J_BYTE4\" )
					)
					( Status sCSetFlattened )
					( Origin gBackEnd )
				)
				( attribute "RELATIVE_PROPAGATION_DELAY" "0.00 MIL,195.00 MIL"
					( Parent
						( matchGroupRef "@baseboard_fab2_lib.baseboard_fab2(sch_1):\MG_DQ-DQS_FAR_DIMM_NG_M_J_BYTE4\" )
					)
					( Units "uMatchProp" "ns" 1.000000)
					( Status sCSetFlattened )
					( Origin gBackEnd )
				)
				( attribute "RELATIVE_PROPAGATION_DELAY_SCOPE" "G"
					( Parent
						( matchGroupRef "@baseboard_fab2_lib.baseboard_fab2(sch_1):\MG_DQ_FAR_DIMM_NG_M_J_BYTE4\" )
					)
					( Status sCSetFlattened )
					( Origin gBackEnd )
				)
				( attribute "RELATIVE_PROPAGATION_DELAY" "-50.00 MIL,50.00 MIL"
					( Parent
						( matchGroupRef "@baseboard_fab2_lib.baseboard_fab2(sch_1):\MG_DQ_FAR_DIMM_NG_M_J_BYTE4\" )
					)
					( Units "uMatchProp" "ns" 1.000000)
					( Status sCSetFlattened )
					( Origin gBackEnd )
				)
			)
			( pinPair "@baseboard_fab2_lib.baseboard_fab2(sch_1):\PP2406\"
				( pinRef "@baseboard_fab2_lib.baseboard_fab2(sch_1):page59_i172:DDR2_DQ(35)" )
				( pinRef "@baseboard_fab2_lib.baseboard_fab2(sch_1):page82_i187:DQ(35)" )
				( attribute "RELATIVE_PROPAGATION_DELAY_SCOPE" "G"
					( Parent
						( matchGroupRef "@baseboard_fab2_lib.baseboard_fab2(sch_1):\MG_DQ-DQS_NEAR_DIMM_NG_M_J_BYTE4\" )
					)
					( Status sCSetFlattened )
					( Origin gBackEnd )
				)
				( attribute "RELATIVE_PROPAGATION_DELAY" "0.00 MIL,195.00 MIL"
					( Parent
						( matchGroupRef "@baseboard_fab2_lib.baseboard_fab2(sch_1):\MG_DQ-DQS_NEAR_DIMM_NG_M_J_BYTE4\" )
					)
					( Units "uMatchProp" "ns" 1.000000)
					( Status sCSetFlattened )
					( Origin gBackEnd )
				)
				( attribute "RELATIVE_PROPAGATION_DELAY_SCOPE" "G"
					( Parent
						( matchGroupRef "@baseboard_fab2_lib.baseboard_fab2(sch_1):\MG_DQ_NEAR_DIMM_NG_M_J_BYTE4\" )
					)
					( Status sCSetFlattened )
					( Origin gBackEnd )
				)
				( attribute "RELATIVE_PROPAGATION_DELAY" "-50.00 MIL,50.00 MIL"
					( Parent
						( matchGroupRef "@baseboard_fab2_lib.baseboard_fab2(sch_1):\MG_DQ_NEAR_DIMM_NG_M_J_BYTE4\" )
					)
					( Units "uMatchProp" "ns" 1.000000)
					( Status sCSetFlattened )
					( Origin gBackEnd )
				)
			)
			( pinPair "@baseboard_fab2_lib.baseboard_fab2(sch_1):\PP2407\"
				( pinRef "@baseboard_fab2_lib.baseboard_fab2(sch_1):page59_i172:DDR2_DQ(36)" )
				( pinRef "@baseboard_fab2_lib.baseboard_fab2(sch_1):page81_i186:DQ(37)" )
				( attribute "RELATIVE_PROPAGATION_DELAY_SCOPE" "G"
					( Parent
						( matchGroupRef "@baseboard_fab2_lib.baseboard_fab2(sch_1):\MG_DQ-DQS_FAR_DIMM_NG_M_J_BYTE4\" )
					)
					( Status sCSetFlattened )
					( Origin gBackEnd )
				)
				( attribute "RELATIVE_PROPAGATION_DELAY" "0.00 MIL,195.00 MIL"
					( Parent
						( matchGroupRef "@baseboard_fab2_lib.baseboard_fab2(sch_1):\MG_DQ-DQS_FAR_DIMM_NG_M_J_BYTE4\" )
					)
					( Units "uMatchProp" "ns" 1.000000)
					( Status sCSetFlattened )
					( Origin gBackEnd )
				)
				( attribute "RELATIVE_PROPAGATION_DELAY_SCOPE" "G"
					( Parent
						( matchGroupRef "@baseboard_fab2_lib.baseboard_fab2(sch_1):\MG_DQ_FAR_DIMM_NG_M_J_BYTE4\" )
					)
					( Status sCSetFlattened )
					( Origin gBackEnd )
				)
				( attribute "RELATIVE_PROPAGATION_DELAY" "-50.00 MIL,50.00 MIL"
					( Parent
						( matchGroupRef "@baseboard_fab2_lib.baseboard_fab2(sch_1):\MG_DQ_FAR_DIMM_NG_M_J_BYTE4\" )
					)
					( Units "uMatchProp" "ns" 1.000000)
					( Status sCSetFlattened )
					( Origin gBackEnd )
				)
			)
			( pinPair "@baseboard_fab2_lib.baseboard_fab2(sch_1):\PP2409\"
				( pinRef "@baseboard_fab2_lib.baseboard_fab2(sch_1):page59_i172:DDR2_DQ(36)" )
				( pinRef "@baseboard_fab2_lib.baseboard_fab2(sch_1):page82_i187:DQ(36)" )
				( attribute "RELATIVE_PROPAGATION_DELAY_SCOPE" "G"
					( Parent
						( matchGroupRef "@baseboard_fab2_lib.baseboard_fab2(sch_1):\MG_DQ-DQS_NEAR_DIMM_NG_M_J_BYTE4\" )
					)
					( Status sCSetFlattened )
					( Origin gBackEnd )
				)
				( attribute "RELATIVE_PROPAGATION_DELAY" "0.00 MIL,195.00 MIL"
					( Parent
						( matchGroupRef "@baseboard_fab2_lib.baseboard_fab2(sch_1):\MG_DQ-DQS_NEAR_DIMM_NG_M_J_BYTE4\" )
					)
					( Units "uMatchProp" "ns" 1.000000)
					( Status sCSetFlattened )
					( Origin gBackEnd )
				)
				( attribute "RELATIVE_PROPAGATION_DELAY_SCOPE" "G"
					( Parent
						( matchGroupRef "@baseboard_fab2_lib.baseboard_fab2(sch_1):\MG_DQ_NEAR_DIMM_NG_M_J_BYTE4\" )
					)
					( Status sCSetFlattened )
					( Origin gBackEnd )
				)
				( attribute "RELATIVE_PROPAGATION_DELAY" "-50.00 MIL,50.00 MIL"
					( Parent
						( matchGroupRef "@baseboard_fab2_lib.baseboard_fab2(sch_1):\MG_DQ_NEAR_DIMM_NG_M_J_BYTE4\" )
					)
					( Units "uMatchProp" "ns" 1.000000)
					( Status sCSetFlattened )
					( Origin gBackEnd )
				)
			)
			( pinPair "@baseboard_fab2_lib.baseboard_fab2(sch_1):\PP2410\"
				( pinRef "@baseboard_fab2_lib.baseboard_fab2(sch_1):page59_i172:DDR2_DQ(37)" )
				( pinRef "@baseboard_fab2_lib.baseboard_fab2(sch_1):page81_i186:DQ(36)" )
				( attribute "RELATIVE_PROPAGATION_DELAY_SCOPE" "G"
					( Parent
						( matchGroupRef "@baseboard_fab2_lib.baseboard_fab2(sch_1):\MG_DQ-DQS_FAR_DIMM_NG_M_J_BYTE4\" )
					)
					( Status sCSetFlattened )
					( Origin gBackEnd )
				)
				( attribute "RELATIVE_PROPAGATION_DELAY" "0.00 MIL,195.00 MIL"
					( Parent
						( matchGroupRef "@baseboard_fab2_lib.baseboard_fab2(sch_1):\MG_DQ-DQS_FAR_DIMM_NG_M_J_BYTE4\" )
					)
					( Units "uMatchProp" "ns" 1.000000)
					( Status sCSetFlattened )
					( Origin gBackEnd )
				)
				( attribute "RELATIVE_PROPAGATION_DELAY_SCOPE" "G"
					( Parent
						( matchGroupRef "@baseboard_fab2_lib.baseboard_fab2(sch_1):\MG_DQ_FAR_DIMM_NG_M_J_BYTE4\" )
					)
					( Status sCSetFlattened )
					( Origin gBackEnd )
				)
				( attribute "RELATIVE_PROPAGATION_DELAY" "-50.00 MIL,50.00 MIL"
					( Parent
						( matchGroupRef "@baseboard_fab2_lib.baseboard_fab2(sch_1):\MG_DQ_FAR_DIMM_NG_M_J_BYTE4\" )
					)
					( Units "uMatchProp" "ns" 1.000000)
					( Status sCSetFlattened )
					( Origin gBackEnd )
				)
			)
			( pinPair "@baseboard_fab2_lib.baseboard_fab2(sch_1):\PP2412\"
				( pinRef "@baseboard_fab2_lib.baseboard_fab2(sch_1):page59_i172:DDR2_DQ(37)" )
				( pinRef "@baseboard_fab2_lib.baseboard_fab2(sch_1):page82_i187:DQ(37)" )
				( attribute "RELATIVE_PROPAGATION_DELAY_SCOPE" "G"
					( Parent
						( matchGroupRef "@baseboard_fab2_lib.baseboard_fab2(sch_1):\MG_DQ-DQS_NEAR_DIMM_NG_M_J_BYTE4\" )
					)
					( Status sCSetFlattened )
					( Origin gBackEnd )
				)
				( attribute "RELATIVE_PROPAGATION_DELAY" "0.00 MIL,195.00 MIL"
					( Parent
						( matchGroupRef "@baseboard_fab2_lib.baseboard_fab2(sch_1):\MG_DQ-DQS_NEAR_DIMM_NG_M_J_BYTE4\" )
					)
					( Units "uMatchProp" "ns" 1.000000)
					( Status sCSetFlattened )
					( Origin gBackEnd )
				)
				( attribute "RELATIVE_PROPAGATION_DELAY_SCOPE" "G"
					( Parent
						( matchGroupRef "@baseboard_fab2_lib.baseboard_fab2(sch_1):\MG_DQ_NEAR_DIMM_NG_M_J_BYTE4\" )
					)
					( Status sCSetFlattened )
					( Origin gBackEnd )
				)
				( attribute "RELATIVE_PROPAGATION_DELAY" "-50.00 MIL,50.00 MIL"
					( Parent
						( matchGroupRef "@baseboard_fab2_lib.baseboard_fab2(sch_1):\MG_DQ_NEAR_DIMM_NG_M_J_BYTE4\" )
					)
					( Units "uMatchProp" "ns" 1.000000)
					( Status sCSetFlattened )
					( Origin gBackEnd )
				)
			)
			( pinPair "@baseboard_fab2_lib.baseboard_fab2(sch_1):\PP2413\"
				( pinRef "@baseboard_fab2_lib.baseboard_fab2(sch_1):page59_i172:DDR2_DQ(38)" )
				( pinRef "@baseboard_fab2_lib.baseboard_fab2(sch_1):page81_i186:DQ(39)" )
				( attribute "RELATIVE_PROPAGATION_DELAY_SCOPE" "G"
					( Parent
						( matchGroupRef "@baseboard_fab2_lib.baseboard_fab2(sch_1):\MG_DQ-DQS_FAR_DIMM_NG_M_J_BYTE4\" )
					)
					( Status sCSetFlattened )
					( Origin gBackEnd )
				)
				( attribute "RELATIVE_PROPAGATION_DELAY" "0.00 MIL,195.00 MIL"
					( Parent
						( matchGroupRef "@baseboard_fab2_lib.baseboard_fab2(sch_1):\MG_DQ-DQS_FAR_DIMM_NG_M_J_BYTE4\" )
					)
					( Units "uMatchProp" "ns" 1.000000)
					( Status sCSetFlattened )
					( Origin gBackEnd )
				)
				( attribute "RELATIVE_PROPAGATION_DELAY_SCOPE" "G"
					( Parent
						( matchGroupRef "@baseboard_fab2_lib.baseboard_fab2(sch_1):\MG_DQ_FAR_DIMM_NG_M_J_BYTE4\" )
					)
					( Status sCSetFlattened )
					( Origin gBackEnd )
				)
				( attribute "RELATIVE_PROPAGATION_DELAY" "-50.00 MIL,50.00 MIL"
					( Parent
						( matchGroupRef "@baseboard_fab2_lib.baseboard_fab2(sch_1):\MG_DQ_FAR_DIMM_NG_M_J_BYTE4\" )
					)
					( Units "uMatchProp" "ns" 1.000000)
					( Status sCSetFlattened )
					( Origin gBackEnd )
				)
			)
			( pinPair "@baseboard_fab2_lib.baseboard_fab2(sch_1):\PP2415\"
				( pinRef "@baseboard_fab2_lib.baseboard_fab2(sch_1):page59_i172:DDR2_DQ(38)" )
				( pinRef "@baseboard_fab2_lib.baseboard_fab2(sch_1):page82_i187:DQ(38)" )
				( attribute "RELATIVE_PROPAGATION_DELAY_SCOPE" "G"
					( Parent
						( matchGroupRef "@baseboard_fab2_lib.baseboard_fab2(sch_1):\MG_DQ-DQS_NEAR_DIMM_NG_M_J_BYTE4\" )
					)
					( Status sCSetFlattened )
					( Origin gBackEnd )
				)
				( attribute "RELATIVE_PROPAGATION_DELAY" "0.00 MIL,195.00 MIL"
					( Parent
						( matchGroupRef "@baseboard_fab2_lib.baseboard_fab2(sch_1):\MG_DQ-DQS_NEAR_DIMM_NG_M_J_BYTE4\" )
					)
					( Units "uMatchProp" "ns" 1.000000)
					( Status sCSetFlattened )
					( Origin gBackEnd )
				)
				( attribute "RELATIVE_PROPAGATION_DELAY_SCOPE" "G"
					( Parent
						( matchGroupRef "@baseboard_fab2_lib.baseboard_fab2(sch_1):\MG_DQ_NEAR_DIMM_NG_M_J_BYTE4\" )
					)
					( Status sCSetFlattened )
					( Origin gBackEnd )
				)
				( attribute "RELATIVE_PROPAGATION_DELAY" "-50.00 MIL,50.00 MIL"
					( Parent
						( matchGroupRef "@baseboard_fab2_lib.baseboard_fab2(sch_1):\MG_DQ_NEAR_DIMM_NG_M_J_BYTE4\" )
					)
					( Units "uMatchProp" "ns" 1.000000)
					( Status sCSetFlattened )
					( Origin gBackEnd )
				)
			)
			( pinPair "@baseboard_fab2_lib.baseboard_fab2(sch_1):\PP2416\"
				( pinRef "@baseboard_fab2_lib.baseboard_fab2(sch_1):page59_i172:DDR2_DQ(39)" )
				( pinRef "@baseboard_fab2_lib.baseboard_fab2(sch_1):page81_i186:DQ(38)" )
				( attribute "RELATIVE_PROPAGATION_DELAY_SCOPE" "G"
					( Parent
						( matchGroupRef "@baseboard_fab2_lib.baseboard_fab2(sch_1):\MG_DQ-DQS_FAR_DIMM_NG_M_J_BYTE4\" )
					)
					( Status sCSetFlattened )
					( Origin gBackEnd )
				)
				( attribute "RELATIVE_PROPAGATION_DELAY" "0.00 MIL,195.00 MIL"
					( Parent
						( matchGroupRef "@baseboard_fab2_lib.baseboard_fab2(sch_1):\MG_DQ-DQS_FAR_DIMM_NG_M_J_BYTE4\" )
					)
					( Units "uMatchProp" "ns" 1.000000)
					( Status sCSetFlattened )
					( Origin gBackEnd )
				)
				( attribute "RELATIVE_PROPAGATION_DELAY_SCOPE" "G"
					( Parent
						( matchGroupRef "@baseboard_fab2_lib.baseboard_fab2(sch_1):\MG_DQ_FAR_DIMM_NG_M_J_BYTE4\" )
					)
					( Status sCSetFlattened )
					( Origin gBackEnd )
				)
				( attribute "RELATIVE_PROPAGATION_DELAY" "-50.00 MIL,50.00 MIL"
					( Parent
						( matchGroupRef "@baseboard_fab2_lib.baseboard_fab2(sch_1):\MG_DQ_FAR_DIMM_NG_M_J_BYTE4\" )
					)
					( Units "uMatchProp" "ns" 1.000000)
					( Status sCSetFlattened )
					( Origin gBackEnd )
				)
			)
			( pinPair "@baseboard_fab2_lib.baseboard_fab2(sch_1):\PP2418\"
				( pinRef "@baseboard_fab2_lib.baseboard_fab2(sch_1):page59_i172:DDR2_DQ(39)" )
				( pinRef "@baseboard_fab2_lib.baseboard_fab2(sch_1):page82_i187:DQ(39)" )
				( attribute "RELATIVE_PROPAGATION_DELAY_SCOPE" "G"
					( Parent
						( matchGroupRef "@baseboard_fab2_lib.baseboard_fab2(sch_1):\MG_DQ-DQS_NEAR_DIMM_NG_M_J_BYTE4\" )
					)
					( Status sCSetFlattened )
					( Origin gBackEnd )
				)
				( attribute "RELATIVE_PROPAGATION_DELAY" "0.00 MIL,195.00 MIL"
					( Parent
						( matchGroupRef "@baseboard_fab2_lib.baseboard_fab2(sch_1):\MG_DQ-DQS_NEAR_DIMM_NG_M_J_BYTE4\" )
					)
					( Units "uMatchProp" "ns" 1.000000)
					( Status sCSetFlattened )
					( Origin gBackEnd )
				)
				( attribute "RELATIVE_PROPAGATION_DELAY_SCOPE" "G"
					( Parent
						( matchGroupRef "@baseboard_fab2_lib.baseboard_fab2(sch_1):\MG_DQ_NEAR_DIMM_NG_M_J_BYTE4\" )
					)
					( Status sCSetFlattened )
					( Origin gBackEnd )
				)
				( attribute "RELATIVE_PROPAGATION_DELAY" "-50.00 MIL,50.00 MIL"
					( Parent
						( matchGroupRef "@baseboard_fab2_lib.baseboard_fab2(sch_1):\MG_DQ_NEAR_DIMM_NG_M_J_BYTE4\" )
					)
					( Units "uMatchProp" "ns" 1.000000)
					( Status sCSetFlattened )
					( Origin gBackEnd )
				)
			)
			( pinPair "@baseboard_fab2_lib.baseboard_fab2(sch_1):\PP2371\"
				( pinRef "@baseboard_fab2_lib.baseboard_fab2(sch_1):page59_i172:DDR2_DQ(40)" )
				( pinRef "@baseboard_fab2_lib.baseboard_fab2(sch_1):page81_i186:DQ(41)" )
				( attribute "RELATIVE_PROPAGATION_DELAY_SCOPE" "G"
					( Parent
						( matchGroupRef "@baseboard_fab2_lib.baseboard_fab2(sch_1):\MG_DQ-DQS_FAR_DIMM_NG_M_J_BYTE5\" )
					)
					( Status sCSetFlattened )
					( Origin gBackEnd )
				)
				( attribute "RELATIVE_PROPAGATION_DELAY" "0.00 MIL,195.00 MIL"
					( Parent
						( matchGroupRef "@baseboard_fab2_lib.baseboard_fab2(sch_1):\MG_DQ-DQS_FAR_DIMM_NG_M_J_BYTE5\" )
					)
					( Units "uMatchProp" "ns" 1.000000)
					( Status sCSetFlattened )
					( Origin gBackEnd )
				)
				( attribute "RELATIVE_PROPAGATION_DELAY_SCOPE" "G"
					( Parent
						( matchGroupRef "@baseboard_fab2_lib.baseboard_fab2(sch_1):\MG_DQ_FAR_DIMM_NG_M_J_BYTE5\" )
					)
					( Status sCSetFlattened )
					( Origin gBackEnd )
				)
				( attribute "RELATIVE_PROPAGATION_DELAY" "-50.00 MIL,50.00 MIL"
					( Parent
						( matchGroupRef "@baseboard_fab2_lib.baseboard_fab2(sch_1):\MG_DQ_FAR_DIMM_NG_M_J_BYTE5\" )
					)
					( Units "uMatchProp" "ns" 1.000000)
					( Status sCSetFlattened )
					( Origin gBackEnd )
				)
			)
			( pinPair "@baseboard_fab2_lib.baseboard_fab2(sch_1):\PP2373\"
				( pinRef "@baseboard_fab2_lib.baseboard_fab2(sch_1):page59_i172:DDR2_DQ(40)" )
				( pinRef "@baseboard_fab2_lib.baseboard_fab2(sch_1):page82_i187:DQ(40)" )
				( attribute "RELATIVE_PROPAGATION_DELAY_SCOPE" "G"
					( Parent
						( matchGroupRef "@baseboard_fab2_lib.baseboard_fab2(sch_1):\MG_DQ-DQS_NEAR_DIMM_NG_M_J_BYTE5\" )
					)
					( Status sCSetFlattened )
					( Origin gBackEnd )
				)
				( attribute "RELATIVE_PROPAGATION_DELAY" "0.00 MIL,195.00 MIL"
					( Parent
						( matchGroupRef "@baseboard_fab2_lib.baseboard_fab2(sch_1):\MG_DQ-DQS_NEAR_DIMM_NG_M_J_BYTE5\" )
					)
					( Units "uMatchProp" "ns" 1.000000)
					( Status sCSetFlattened )
					( Origin gBackEnd )
				)
				( attribute "RELATIVE_PROPAGATION_DELAY_SCOPE" "G"
					( Parent
						( matchGroupRef "@baseboard_fab2_lib.baseboard_fab2(sch_1):\MG_DQ_NEAR_DIMM_NG_M_J_BYTE5\" )
					)
					( Status sCSetFlattened )
					( Origin gBackEnd )
				)
				( attribute "RELATIVE_PROPAGATION_DELAY" "-50.00 MIL,50.00 MIL"
					( Parent
						( matchGroupRef "@baseboard_fab2_lib.baseboard_fab2(sch_1):\MG_DQ_NEAR_DIMM_NG_M_J_BYTE5\" )
					)
					( Units "uMatchProp" "ns" 1.000000)
					( Status sCSetFlattened )
					( Origin gBackEnd )
				)
			)
			( pinPair "@baseboard_fab2_lib.baseboard_fab2(sch_1):\PP2374\"
				( pinRef "@baseboard_fab2_lib.baseboard_fab2(sch_1):page59_i172:DDR2_DQ(41)" )
				( pinRef "@baseboard_fab2_lib.baseboard_fab2(sch_1):page81_i186:DQ(40)" )
				( attribute "RELATIVE_PROPAGATION_DELAY_SCOPE" "G"
					( Parent
						( matchGroupRef "@baseboard_fab2_lib.baseboard_fab2(sch_1):\MG_DQ-DQS_FAR_DIMM_NG_M_J_BYTE5\" )
					)
					( Status sCSetFlattened )
					( Origin gBackEnd )
				)
				( attribute "RELATIVE_PROPAGATION_DELAY" "0.00 MIL,195.00 MIL"
					( Parent
						( matchGroupRef "@baseboard_fab2_lib.baseboard_fab2(sch_1):\MG_DQ-DQS_FAR_DIMM_NG_M_J_BYTE5\" )
					)
					( Units "uMatchProp" "ns" 1.000000)
					( Status sCSetFlattened )
					( Origin gBackEnd )
				)
				( attribute "RELATIVE_PROPAGATION_DELAY_SCOPE" "G"
					( Parent
						( matchGroupRef "@baseboard_fab2_lib.baseboard_fab2(sch_1):\MG_DQ_FAR_DIMM_NG_M_J_BYTE5\" )
					)
					( Status sCSetFlattened )
					( Origin gBackEnd )
				)
				( attribute "RELATIVE_PROPAGATION_DELAY" "-50.00 MIL,50.00 MIL"
					( Parent
						( matchGroupRef "@baseboard_fab2_lib.baseboard_fab2(sch_1):\MG_DQ_FAR_DIMM_NG_M_J_BYTE5\" )
					)
					( Units "uMatchProp" "ns" 1.000000)
					( Status sCSetFlattened )
					( Origin gBackEnd )
				)
			)
			( pinPair "@baseboard_fab2_lib.baseboard_fab2(sch_1):\PP2376\"
				( pinRef "@baseboard_fab2_lib.baseboard_fab2(sch_1):page59_i172:DDR2_DQ(41)" )
				( pinRef "@baseboard_fab2_lib.baseboard_fab2(sch_1):page82_i187:DQ(41)" )
				( attribute "RELATIVE_PROPAGATION_DELAY_SCOPE" "G"
					( Parent
						( matchGroupRef "@baseboard_fab2_lib.baseboard_fab2(sch_1):\MG_DQ-DQS_NEAR_DIMM_NG_M_J_BYTE5\" )
					)
					( Status sCSetFlattened )
					( Origin gBackEnd )
				)
				( attribute "RELATIVE_PROPAGATION_DELAY" "0.00 MIL,195.00 MIL"
					( Parent
						( matchGroupRef "@baseboard_fab2_lib.baseboard_fab2(sch_1):\MG_DQ-DQS_NEAR_DIMM_NG_M_J_BYTE5\" )
					)
					( Units "uMatchProp" "ns" 1.000000)
					( Status sCSetFlattened )
					( Origin gBackEnd )
				)
				( attribute "RELATIVE_PROPAGATION_DELAY_SCOPE" "G"
					( Parent
						( matchGroupRef "@baseboard_fab2_lib.baseboard_fab2(sch_1):\MG_DQ_NEAR_DIMM_NG_M_J_BYTE5\" )
					)
					( Status sCSetFlattened )
					( Origin gBackEnd )
				)
				( attribute "RELATIVE_PROPAGATION_DELAY" "-50.00 MIL,50.00 MIL"
					( Parent
						( matchGroupRef "@baseboard_fab2_lib.baseboard_fab2(sch_1):\MG_DQ_NEAR_DIMM_NG_M_J_BYTE5\" )
					)
					( Units "uMatchProp" "ns" 1.000000)
					( Status sCSetFlattened )
					( Origin gBackEnd )
				)
			)
			( pinPair "@baseboard_fab2_lib.baseboard_fab2(sch_1):\PP2377\"
				( pinRef "@baseboard_fab2_lib.baseboard_fab2(sch_1):page59_i172:DDR2_DQ(42)" )
				( pinRef "@baseboard_fab2_lib.baseboard_fab2(sch_1):page81_i186:DQ(43)" )
				( attribute "RELATIVE_PROPAGATION_DELAY_SCOPE" "G"
					( Parent
						( matchGroupRef "@baseboard_fab2_lib.baseboard_fab2(sch_1):\MG_DQ-DQS_FAR_DIMM_NG_M_J_BYTE5\" )
					)
					( Status sCSetFlattened )
					( Origin gBackEnd )
				)
				( attribute "RELATIVE_PROPAGATION_DELAY" "0.00 MIL,195.00 MIL"
					( Parent
						( matchGroupRef "@baseboard_fab2_lib.baseboard_fab2(sch_1):\MG_DQ-DQS_FAR_DIMM_NG_M_J_BYTE5\" )
					)
					( Units "uMatchProp" "ns" 1.000000)
					( Status sCSetFlattened )
					( Origin gBackEnd )
				)
				( attribute "RELATIVE_PROPAGATION_DELAY_SCOPE" "G"
					( Parent
						( matchGroupRef "@baseboard_fab2_lib.baseboard_fab2(sch_1):\MG_DQ_FAR_DIMM_NG_M_J_BYTE5\" )
					)
					( Status sCSetFlattened )
					( Origin gBackEnd )
				)
				( attribute "RELATIVE_PROPAGATION_DELAY" "-50.00 MIL,50.00 MIL"
					( Parent
						( matchGroupRef "@baseboard_fab2_lib.baseboard_fab2(sch_1):\MG_DQ_FAR_DIMM_NG_M_J_BYTE5\" )
					)
					( Units "uMatchProp" "ns" 1.000000)
					( Status sCSetFlattened )
					( Origin gBackEnd )
				)
			)
			( pinPair "@baseboard_fab2_lib.baseboard_fab2(sch_1):\PP2379\"
				( pinRef "@baseboard_fab2_lib.baseboard_fab2(sch_1):page59_i172:DDR2_DQ(42)" )
				( pinRef "@baseboard_fab2_lib.baseboard_fab2(sch_1):page82_i187:DQ(42)" )
				( attribute "RELATIVE_PROPAGATION_DELAY_SCOPE" "G"
					( Parent
						( matchGroupRef "@baseboard_fab2_lib.baseboard_fab2(sch_1):\MG_DQ-DQS_NEAR_DIMM_NG_M_J_BYTE5\" )
					)
					( Status sCSetFlattened )
					( Origin gBackEnd )
				)
				( attribute "RELATIVE_PROPAGATION_DELAY" "0.00 MIL,195.00 MIL"
					( Parent
						( matchGroupRef "@baseboard_fab2_lib.baseboard_fab2(sch_1):\MG_DQ-DQS_NEAR_DIMM_NG_M_J_BYTE5\" )
					)
					( Units "uMatchProp" "ns" 1.000000)
					( Status sCSetFlattened )
					( Origin gBackEnd )
				)
				( attribute "RELATIVE_PROPAGATION_DELAY_SCOPE" "G"
					( Parent
						( matchGroupRef "@baseboard_fab2_lib.baseboard_fab2(sch_1):\MG_DQ_NEAR_DIMM_NG_M_J_BYTE5\" )
					)
					( Status sCSetFlattened )
					( Origin gBackEnd )
				)
				( attribute "RELATIVE_PROPAGATION_DELAY" "-50.00 MIL,50.00 MIL"
					( Parent
						( matchGroupRef "@baseboard_fab2_lib.baseboard_fab2(sch_1):\MG_DQ_NEAR_DIMM_NG_M_J_BYTE5\" )
					)
					( Units "uMatchProp" "ns" 1.000000)
					( Status sCSetFlattened )
					( Origin gBackEnd )
				)
			)
			( pinPair "@baseboard_fab2_lib.baseboard_fab2(sch_1):\PP2380\"
				( pinRef "@baseboard_fab2_lib.baseboard_fab2(sch_1):page59_i172:DDR2_DQ(43)" )
				( pinRef "@baseboard_fab2_lib.baseboard_fab2(sch_1):page81_i186:DQ(42)" )
				( attribute "RELATIVE_PROPAGATION_DELAY_SCOPE" "G"
					( Parent
						( matchGroupRef "@baseboard_fab2_lib.baseboard_fab2(sch_1):\MG_DQ-DQS_FAR_DIMM_NG_M_J_BYTE5\" )
					)
					( Status sCSetFlattened )
					( Origin gBackEnd )
				)
				( attribute "RELATIVE_PROPAGATION_DELAY" "0.00 MIL,195.00 MIL"
					( Parent
						( matchGroupRef "@baseboard_fab2_lib.baseboard_fab2(sch_1):\MG_DQ-DQS_FAR_DIMM_NG_M_J_BYTE5\" )
					)
					( Units "uMatchProp" "ns" 1.000000)
					( Status sCSetFlattened )
					( Origin gBackEnd )
				)
				( attribute "RELATIVE_PROPAGATION_DELAY_SCOPE" "G"
					( Parent
						( matchGroupRef "@baseboard_fab2_lib.baseboard_fab2(sch_1):\MG_DQ_FAR_DIMM_NG_M_J_BYTE5\" )
					)
					( Status sCSetFlattened )
					( Origin gBackEnd )
				)
				( attribute "RELATIVE_PROPAGATION_DELAY" "-50.00 MIL,50.00 MIL"
					( Parent
						( matchGroupRef "@baseboard_fab2_lib.baseboard_fab2(sch_1):\MG_DQ_FAR_DIMM_NG_M_J_BYTE5\" )
					)
					( Units "uMatchProp" "ns" 1.000000)
					( Status sCSetFlattened )
					( Origin gBackEnd )
				)
			)
			( pinPair "@baseboard_fab2_lib.baseboard_fab2(sch_1):\PP2382\"
				( pinRef "@baseboard_fab2_lib.baseboard_fab2(sch_1):page59_i172:DDR2_DQ(43)" )
				( pinRef "@baseboard_fab2_lib.baseboard_fab2(sch_1):page82_i187:DQ(43)" )
				( attribute "RELATIVE_PROPAGATION_DELAY_SCOPE" "G"
					( Parent
						( matchGroupRef "@baseboard_fab2_lib.baseboard_fab2(sch_1):\MG_DQ-DQS_NEAR_DIMM_NG_M_J_BYTE5\" )
					)
					( Status sCSetFlattened )
					( Origin gBackEnd )
				)
				( attribute "RELATIVE_PROPAGATION_DELAY" "0.00 MIL,195.00 MIL"
					( Parent
						( matchGroupRef "@baseboard_fab2_lib.baseboard_fab2(sch_1):\MG_DQ-DQS_NEAR_DIMM_NG_M_J_BYTE5\" )
					)
					( Units "uMatchProp" "ns" 1.000000)
					( Status sCSetFlattened )
					( Origin gBackEnd )
				)
				( attribute "RELATIVE_PROPAGATION_DELAY_SCOPE" "G"
					( Parent
						( matchGroupRef "@baseboard_fab2_lib.baseboard_fab2(sch_1):\MG_DQ_NEAR_DIMM_NG_M_J_BYTE5\" )
					)
					( Status sCSetFlattened )
					( Origin gBackEnd )
				)
				( attribute "RELATIVE_PROPAGATION_DELAY" "-50.00 MIL,50.00 MIL"
					( Parent
						( matchGroupRef "@baseboard_fab2_lib.baseboard_fab2(sch_1):\MG_DQ_NEAR_DIMM_NG_M_J_BYTE5\" )
					)
					( Units "uMatchProp" "ns" 1.000000)
					( Status sCSetFlattened )
					( Origin gBackEnd )
				)
			)
			( pinPair "@baseboard_fab2_lib.baseboard_fab2(sch_1):\PP2383\"
				( pinRef "@baseboard_fab2_lib.baseboard_fab2(sch_1):page59_i172:DDR2_DQ(44)" )
				( pinRef "@baseboard_fab2_lib.baseboard_fab2(sch_1):page81_i186:DQ(45)" )
				( attribute "RELATIVE_PROPAGATION_DELAY_SCOPE" "G"
					( Parent
						( matchGroupRef "@baseboard_fab2_lib.baseboard_fab2(sch_1):\MG_DQ-DQS_FAR_DIMM_NG_M_J_BYTE5\" )
					)
					( Status sCSetFlattened )
					( Origin gBackEnd )
				)
				( attribute "RELATIVE_PROPAGATION_DELAY" "0.00 MIL,195.00 MIL"
					( Parent
						( matchGroupRef "@baseboard_fab2_lib.baseboard_fab2(sch_1):\MG_DQ-DQS_FAR_DIMM_NG_M_J_BYTE5\" )
					)
					( Units "uMatchProp" "ns" 1.000000)
					( Status sCSetFlattened )
					( Origin gBackEnd )
				)
				( attribute "RELATIVE_PROPAGATION_DELAY_SCOPE" "G"
					( Parent
						( matchGroupRef "@baseboard_fab2_lib.baseboard_fab2(sch_1):\MG_DQ_FAR_DIMM_NG_M_J_BYTE5\" )
					)
					( Status sCSetFlattened )
					( Origin gBackEnd )
				)
				( attribute "RELATIVE_PROPAGATION_DELAY" "-50.00 MIL,50.00 MIL"
					( Parent
						( matchGroupRef "@baseboard_fab2_lib.baseboard_fab2(sch_1):\MG_DQ_FAR_DIMM_NG_M_J_BYTE5\" )
					)
					( Units "uMatchProp" "ns" 1.000000)
					( Status sCSetFlattened )
					( Origin gBackEnd )
				)
			)
			( pinPair "@baseboard_fab2_lib.baseboard_fab2(sch_1):\PP2385\"
				( pinRef "@baseboard_fab2_lib.baseboard_fab2(sch_1):page59_i172:DDR2_DQ(44)" )
				( pinRef "@baseboard_fab2_lib.baseboard_fab2(sch_1):page82_i187:DQ(44)" )
				( attribute "RELATIVE_PROPAGATION_DELAY_SCOPE" "G"
					( Parent
						( matchGroupRef "@baseboard_fab2_lib.baseboard_fab2(sch_1):\MG_DQ-DQS_NEAR_DIMM_NG_M_J_BYTE5\" )
					)
					( Status sCSetFlattened )
					( Origin gBackEnd )
				)
				( attribute "RELATIVE_PROPAGATION_DELAY" "0.00 MIL,195.00 MIL"
					( Parent
						( matchGroupRef "@baseboard_fab2_lib.baseboard_fab2(sch_1):\MG_DQ-DQS_NEAR_DIMM_NG_M_J_BYTE5\" )
					)
					( Units "uMatchProp" "ns" 1.000000)
					( Status sCSetFlattened )
					( Origin gBackEnd )
				)
				( attribute "RELATIVE_PROPAGATION_DELAY_SCOPE" "G"
					( Parent
						( matchGroupRef "@baseboard_fab2_lib.baseboard_fab2(sch_1):\MG_DQ_NEAR_DIMM_NG_M_J_BYTE5\" )
					)
					( Status sCSetFlattened )
					( Origin gBackEnd )
				)
				( attribute "RELATIVE_PROPAGATION_DELAY" "-50.00 MIL,50.00 MIL"
					( Parent
						( matchGroupRef "@baseboard_fab2_lib.baseboard_fab2(sch_1):\MG_DQ_NEAR_DIMM_NG_M_J_BYTE5\" )
					)
					( Units "uMatchProp" "ns" 1.000000)
					( Status sCSetFlattened )
					( Origin gBackEnd )
				)
			)
			( pinPair "@baseboard_fab2_lib.baseboard_fab2(sch_1):\PP2386\"
				( pinRef "@baseboard_fab2_lib.baseboard_fab2(sch_1):page59_i172:DDR2_DQ(45)" )
				( pinRef "@baseboard_fab2_lib.baseboard_fab2(sch_1):page81_i186:DQ(44)" )
				( attribute "RELATIVE_PROPAGATION_DELAY_SCOPE" "G"
					( Parent
						( matchGroupRef "@baseboard_fab2_lib.baseboard_fab2(sch_1):\MG_DQ-DQS_FAR_DIMM_NG_M_J_BYTE5\" )
					)
					( Status sCSetFlattened )
					( Origin gBackEnd )
				)
				( attribute "RELATIVE_PROPAGATION_DELAY" "0.00 MIL,195.00 MIL"
					( Parent
						( matchGroupRef "@baseboard_fab2_lib.baseboard_fab2(sch_1):\MG_DQ-DQS_FAR_DIMM_NG_M_J_BYTE5\" )
					)
					( Units "uMatchProp" "ns" 1.000000)
					( Status sCSetFlattened )
					( Origin gBackEnd )
				)
				( attribute "RELATIVE_PROPAGATION_DELAY_SCOPE" "G"
					( Parent
						( matchGroupRef "@baseboard_fab2_lib.baseboard_fab2(sch_1):\MG_DQ_FAR_DIMM_NG_M_J_BYTE5\" )
					)
					( Status sCSetFlattened )
					( Origin gBackEnd )
				)
				( attribute "RELATIVE_PROPAGATION_DELAY" "-50.00 MIL,50.00 MIL"
					( Parent
						( matchGroupRef "@baseboard_fab2_lib.baseboard_fab2(sch_1):\MG_DQ_FAR_DIMM_NG_M_J_BYTE5\" )
					)
					( Units "uMatchProp" "ns" 1.000000)
					( Status sCSetFlattened )
					( Origin gBackEnd )
				)
			)
			( pinPair "@baseboard_fab2_lib.baseboard_fab2(sch_1):\PP2388\"
				( pinRef "@baseboard_fab2_lib.baseboard_fab2(sch_1):page59_i172:DDR2_DQ(45)" )
				( pinRef "@baseboard_fab2_lib.baseboard_fab2(sch_1):page82_i187:DQ(45)" )
				( attribute "RELATIVE_PROPAGATION_DELAY_SCOPE" "G"
					( Parent
						( matchGroupRef "@baseboard_fab2_lib.baseboard_fab2(sch_1):\MG_DQ-DQS_NEAR_DIMM_NG_M_J_BYTE5\" )
					)
					( Status sCSetFlattened )
					( Origin gBackEnd )
				)
				( attribute "RELATIVE_PROPAGATION_DELAY" "0.00 MIL,195.00 MIL"
					( Parent
						( matchGroupRef "@baseboard_fab2_lib.baseboard_fab2(sch_1):\MG_DQ-DQS_NEAR_DIMM_NG_M_J_BYTE5\" )
					)
					( Units "uMatchProp" "ns" 1.000000)
					( Status sCSetFlattened )
					( Origin gBackEnd )
				)
				( attribute "RELATIVE_PROPAGATION_DELAY_SCOPE" "G"
					( Parent
						( matchGroupRef "@baseboard_fab2_lib.baseboard_fab2(sch_1):\MG_DQ_NEAR_DIMM_NG_M_J_BYTE5\" )
					)
					( Status sCSetFlattened )
					( Origin gBackEnd )
				)
				( attribute "RELATIVE_PROPAGATION_DELAY" "-50.00 MIL,50.00 MIL"
					( Parent
						( matchGroupRef "@baseboard_fab2_lib.baseboard_fab2(sch_1):\MG_DQ_NEAR_DIMM_NG_M_J_BYTE5\" )
					)
					( Units "uMatchProp" "ns" 1.000000)
					( Status sCSetFlattened )
					( Origin gBackEnd )
				)
			)
			( pinPair "@baseboard_fab2_lib.baseboard_fab2(sch_1):\PP2389\"
				( pinRef "@baseboard_fab2_lib.baseboard_fab2(sch_1):page59_i172:DDR2_DQ(46)" )
				( pinRef "@baseboard_fab2_lib.baseboard_fab2(sch_1):page81_i186:DQ(47)" )
				( attribute "RELATIVE_PROPAGATION_DELAY_SCOPE" "G"
					( Parent
						( matchGroupRef "@baseboard_fab2_lib.baseboard_fab2(sch_1):\MG_DQ-DQS_FAR_DIMM_NG_M_J_BYTE5\" )
					)
					( Status sCSetFlattened )
					( Origin gBackEnd )
				)
				( attribute "RELATIVE_PROPAGATION_DELAY" "0.00 MIL,195.00 MIL"
					( Parent
						( matchGroupRef "@baseboard_fab2_lib.baseboard_fab2(sch_1):\MG_DQ-DQS_FAR_DIMM_NG_M_J_BYTE5\" )
					)
					( Units "uMatchProp" "ns" 1.000000)
					( Status sCSetFlattened )
					( Origin gBackEnd )
				)
				( attribute "RELATIVE_PROPAGATION_DELAY_SCOPE" "G"
					( Parent
						( matchGroupRef "@baseboard_fab2_lib.baseboard_fab2(sch_1):\MG_DQ_FAR_DIMM_NG_M_J_BYTE5\" )
					)
					( Status sCSetFlattened )
					( Origin gBackEnd )
				)
				( attribute "RELATIVE_PROPAGATION_DELAY" "-50.00 MIL,50.00 MIL"
					( Parent
						( matchGroupRef "@baseboard_fab2_lib.baseboard_fab2(sch_1):\MG_DQ_FAR_DIMM_NG_M_J_BYTE5\" )
					)
					( Units "uMatchProp" "ns" 1.000000)
					( Status sCSetFlattened )
					( Origin gBackEnd )
				)
			)
			( pinPair "@baseboard_fab2_lib.baseboard_fab2(sch_1):\PP2391\"
				( pinRef "@baseboard_fab2_lib.baseboard_fab2(sch_1):page59_i172:DDR2_DQ(46)" )
				( pinRef "@baseboard_fab2_lib.baseboard_fab2(sch_1):page82_i187:DQ(46)" )
				( attribute "RELATIVE_PROPAGATION_DELAY_SCOPE" "G"
					( Parent
						( matchGroupRef "@baseboard_fab2_lib.baseboard_fab2(sch_1):\MG_DQ-DQS_NEAR_DIMM_NG_M_J_BYTE5\" )
					)
					( Status sCSetFlattened )
					( Origin gBackEnd )
				)
				( attribute "RELATIVE_PROPAGATION_DELAY" "0.00 MIL,195.00 MIL"
					( Parent
						( matchGroupRef "@baseboard_fab2_lib.baseboard_fab2(sch_1):\MG_DQ-DQS_NEAR_DIMM_NG_M_J_BYTE5\" )
					)
					( Units "uMatchProp" "ns" 1.000000)
					( Status sCSetFlattened )
					( Origin gBackEnd )
				)
				( attribute "RELATIVE_PROPAGATION_DELAY_SCOPE" "G"
					( Parent
						( matchGroupRef "@baseboard_fab2_lib.baseboard_fab2(sch_1):\MG_DQ_NEAR_DIMM_NG_M_J_BYTE5\" )
					)
					( Status sCSetFlattened )
					( Origin gBackEnd )
				)
				( attribute "RELATIVE_PROPAGATION_DELAY" "-50.00 MIL,50.00 MIL"
					( Parent
						( matchGroupRef "@baseboard_fab2_lib.baseboard_fab2(sch_1):\MG_DQ_NEAR_DIMM_NG_M_J_BYTE5\" )
					)
					( Units "uMatchProp" "ns" 1.000000)
					( Status sCSetFlattened )
					( Origin gBackEnd )
				)
			)
			( pinPair "@baseboard_fab2_lib.baseboard_fab2(sch_1):\PP2392\"
				( pinRef "@baseboard_fab2_lib.baseboard_fab2(sch_1):page59_i172:DDR2_DQ(47)" )
				( pinRef "@baseboard_fab2_lib.baseboard_fab2(sch_1):page81_i186:DQ(46)" )
				( attribute "RELATIVE_PROPAGATION_DELAY_SCOPE" "G"
					( Parent
						( matchGroupRef "@baseboard_fab2_lib.baseboard_fab2(sch_1):\MG_DQ-DQS_FAR_DIMM_NG_M_J_BYTE5\" )
					)
					( Status sCSetFlattened )
					( Origin gBackEnd )
				)
				( attribute "RELATIVE_PROPAGATION_DELAY" "0.00 MIL,195.00 MIL"
					( Parent
						( matchGroupRef "@baseboard_fab2_lib.baseboard_fab2(sch_1):\MG_DQ-DQS_FAR_DIMM_NG_M_J_BYTE5\" )
					)
					( Units "uMatchProp" "ns" 1.000000)
					( Status sCSetFlattened )
					( Origin gBackEnd )
				)
				( attribute "RELATIVE_PROPAGATION_DELAY_SCOPE" "G"
					( Parent
						( matchGroupRef "@baseboard_fab2_lib.baseboard_fab2(sch_1):\MG_DQ_FAR_DIMM_NG_M_J_BYTE5\" )
					)
					( Status sCSetFlattened )
					( Origin gBackEnd )
				)
				( attribute "RELATIVE_PROPAGATION_DELAY" "-50.00 MIL,50.00 MIL"
					( Parent
						( matchGroupRef "@baseboard_fab2_lib.baseboard_fab2(sch_1):\MG_DQ_FAR_DIMM_NG_M_J_BYTE5\" )
					)
					( Units "uMatchProp" "ns" 1.000000)
					( Status sCSetFlattened )
					( Origin gBackEnd )
				)
			)
			( pinPair "@baseboard_fab2_lib.baseboard_fab2(sch_1):\PP2394\"
				( pinRef "@baseboard_fab2_lib.baseboard_fab2(sch_1):page59_i172:DDR2_DQ(47)" )
				( pinRef "@baseboard_fab2_lib.baseboard_fab2(sch_1):page82_i187:DQ(47)" )
				( attribute "RELATIVE_PROPAGATION_DELAY_SCOPE" "G"
					( Parent
						( matchGroupRef "@baseboard_fab2_lib.baseboard_fab2(sch_1):\MG_DQ-DQS_NEAR_DIMM_NG_M_J_BYTE5\" )
					)
					( Status sCSetFlattened )
					( Origin gBackEnd )
				)
				( attribute "RELATIVE_PROPAGATION_DELAY" "0.00 MIL,195.00 MIL"
					( Parent
						( matchGroupRef "@baseboard_fab2_lib.baseboard_fab2(sch_1):\MG_DQ-DQS_NEAR_DIMM_NG_M_J_BYTE5\" )
					)
					( Units "uMatchProp" "ns" 1.000000)
					( Status sCSetFlattened )
					( Origin gBackEnd )
				)
				( attribute "RELATIVE_PROPAGATION_DELAY_SCOPE" "G"
					( Parent
						( matchGroupRef "@baseboard_fab2_lib.baseboard_fab2(sch_1):\MG_DQ_NEAR_DIMM_NG_M_J_BYTE5\" )
					)
					( Status sCSetFlattened )
					( Origin gBackEnd )
				)
				( attribute "RELATIVE_PROPAGATION_DELAY" "-50.00 MIL,50.00 MIL"
					( Parent
						( matchGroupRef "@baseboard_fab2_lib.baseboard_fab2(sch_1):\MG_DQ_NEAR_DIMM_NG_M_J_BYTE5\" )
					)
					( Units "uMatchProp" "ns" 1.000000)
					( Status sCSetFlattened )
					( Origin gBackEnd )
				)
			)
			( pinPair "@baseboard_fab2_lib.baseboard_fab2(sch_1):\PP2347\"
				( pinRef "@baseboard_fab2_lib.baseboard_fab2(sch_1):page59_i172:DDR2_DQ(48)" )
				( pinRef "@baseboard_fab2_lib.baseboard_fab2(sch_1):page81_i186:DQ(49)" )
				( attribute "RELATIVE_PROPAGATION_DELAY_SCOPE" "G"
					( Parent
						( matchGroupRef "@baseboard_fab2_lib.baseboard_fab2(sch_1):\MG_DQ-DQS_FAR_DIMM_NG_M_J_BYTE6\" )
					)
					( Status sCSetFlattened )
					( Origin gBackEnd )
				)
				( attribute "RELATIVE_PROPAGATION_DELAY" "0.00 MIL,195.00 MIL"
					( Parent
						( matchGroupRef "@baseboard_fab2_lib.baseboard_fab2(sch_1):\MG_DQ-DQS_FAR_DIMM_NG_M_J_BYTE6\" )
					)
					( Units "uMatchProp" "ns" 1.000000)
					( Status sCSetFlattened )
					( Origin gBackEnd )
				)
				( attribute "RELATIVE_PROPAGATION_DELAY_SCOPE" "G"
					( Parent
						( matchGroupRef "@crescent_city_bb_fab1_lib.crescent_city_bb_fab1(sch_1):\MG_DQ_FAR_DIMM_NG_M_J_BYTE6\" )
					)
					( Status sCSetFlattened )
					( Origin gBackEnd )
				)
				( attribute "RELATIVE_PROPAGATION_DELAY" "-50.00 MIL,50.00 MIL"
					( Parent
						( matchGroupRef "@crescent_city_bb_fab1_lib.crescent_city_bb_fab1(sch_1):\MG_DQ_FAR_DIMM_NG_M_J_BYTE6\" )
					)
					( Units "uMatchProp" "ns" 1.000000)
					( Status sCSetFlattened )
					( Origin gBackEnd )
				)
			)
			( pinPair "@baseboard_fab2_lib.baseboard_fab2(sch_1):\PP2349\"
				( pinRef "@baseboard_fab2_lib.baseboard_fab2(sch_1):page59_i172:DDR2_DQ(48)" )
				( pinRef "@baseboard_fab2_lib.baseboard_fab2(sch_1):page82_i187:DQ(48)" )
				( attribute "RELATIVE_PROPAGATION_DELAY_SCOPE" "G"
					( Parent
						( matchGroupRef "@baseboard_fab2_lib.baseboard_fab2(sch_1):\MG_DQ-DQS_NEAR_DIMM_NG_M_J_BYTE6\" )
					)
					( Status sCSetFlattened )
					( Origin gBackEnd )
				)
				( attribute "RELATIVE_PROPAGATION_DELAY" "0.00 MIL,195.00 MIL"
					( Parent
						( matchGroupRef "@baseboard_fab2_lib.baseboard_fab2(sch_1):\MG_DQ-DQS_NEAR_DIMM_NG_M_J_BYTE6\" )
					)
					( Units "uMatchProp" "ns" 1.000000)
					( Status sCSetFlattened )
					( Origin gBackEnd )
				)
				( attribute "RELATIVE_PROPAGATION_DELAY_SCOPE" "G"
					( Parent
						( matchGroupRef "@crescent_city_bb_fab1_lib.crescent_city_bb_fab1(sch_1):\MG_DQ_NEAR_DIMM_NG_M_J_BYTE6\" )
					)
					( Status sCSetFlattened )
					( Origin gBackEnd )
				)
				( attribute "RELATIVE_PROPAGATION_DELAY" "-50.00 MIL,50.00 MIL"
					( Parent
						( matchGroupRef "@crescent_city_bb_fab1_lib.crescent_city_bb_fab1(sch_1):\MG_DQ_NEAR_DIMM_NG_M_J_BYTE6\" )
					)
					( Units "uMatchProp" "ns" 1.000000)
					( Status sCSetFlattened )
					( Origin gBackEnd )
				)
			)
			( pinPair "@baseboard_fab2_lib.baseboard_fab2(sch_1):\PP2350\"
				( pinRef "@baseboard_fab2_lib.baseboard_fab2(sch_1):page59_i172:DDR2_DQ(49)" )
				( pinRef "@baseboard_fab2_lib.baseboard_fab2(sch_1):page81_i186:DQ(48)" )
				( attribute "RELATIVE_PROPAGATION_DELAY_SCOPE" "G"
					( Parent
						( matchGroupRef "@baseboard_fab2_lib.baseboard_fab2(sch_1):\MG_DQ-DQS_FAR_DIMM_NG_M_J_BYTE6\" )
					)
					( Status sCSetFlattened )
					( Origin gBackEnd )
				)
				( attribute "RELATIVE_PROPAGATION_DELAY" "0.00 MIL,195.00 MIL"
					( Parent
						( matchGroupRef "@baseboard_fab2_lib.baseboard_fab2(sch_1):\MG_DQ-DQS_FAR_DIMM_NG_M_J_BYTE6\" )
					)
					( Units "uMatchProp" "ns" 1.000000)
					( Status sCSetFlattened )
					( Origin gBackEnd )
				)
				( attribute "RELATIVE_PROPAGATION_DELAY_SCOPE" "G"
					( Parent
						( matchGroupRef "@crescent_city_bb_fab1_lib.crescent_city_bb_fab1(sch_1):\MG_DQ_FAR_DIMM_NG_M_J_BYTE6\" )
					)
					( Status sCSetFlattened )
					( Origin gBackEnd )
				)
				( attribute "RELATIVE_PROPAGATION_DELAY" "-50.00 MIL,50.00 MIL"
					( Parent
						( matchGroupRef "@crescent_city_bb_fab1_lib.crescent_city_bb_fab1(sch_1):\MG_DQ_FAR_DIMM_NG_M_J_BYTE6\" )
					)
					( Units "uMatchProp" "ns" 1.000000)
					( Status sCSetFlattened )
					( Origin gBackEnd )
				)
			)
			( pinPair "@baseboard_fab2_lib.baseboard_fab2(sch_1):\PP2352\"
				( pinRef "@baseboard_fab2_lib.baseboard_fab2(sch_1):page59_i172:DDR2_DQ(49)" )
				( pinRef "@baseboard_fab2_lib.baseboard_fab2(sch_1):page82_i187:DQ(49)" )
				( attribute "RELATIVE_PROPAGATION_DELAY_SCOPE" "G"
					( Parent
						( matchGroupRef "@baseboard_fab2_lib.baseboard_fab2(sch_1):\MG_DQ-DQS_NEAR_DIMM_NG_M_J_BYTE6\" )
					)
					( Status sCSetFlattened )
					( Origin gBackEnd )
				)
				( attribute "RELATIVE_PROPAGATION_DELAY" "0.00 MIL,195.00 MIL"
					( Parent
						( matchGroupRef "@baseboard_fab2_lib.baseboard_fab2(sch_1):\MG_DQ-DQS_NEAR_DIMM_NG_M_J_BYTE6\" )
					)
					( Units "uMatchProp" "ns" 1.000000)
					( Status sCSetFlattened )
					( Origin gBackEnd )
				)
				( attribute "RELATIVE_PROPAGATION_DELAY_SCOPE" "G"
					( Parent
						( matchGroupRef "@crescent_city_bb_fab1_lib.crescent_city_bb_fab1(sch_1):\MG_DQ_NEAR_DIMM_NG_M_J_BYTE6\" )
					)
					( Status sCSetFlattened )
					( Origin gBackEnd )
				)
				( attribute "RELATIVE_PROPAGATION_DELAY" "-50.00 MIL,50.00 MIL"
					( Parent
						( matchGroupRef "@crescent_city_bb_fab1_lib.crescent_city_bb_fab1(sch_1):\MG_DQ_NEAR_DIMM_NG_M_J_BYTE6\" )
					)
					( Units "uMatchProp" "ns" 1.000000)
					( Status sCSetFlattened )
					( Origin gBackEnd )
				)
			)
			( pinPair "@baseboard_fab2_lib.baseboard_fab2(sch_1):\PP2353\"
				( pinRef "@baseboard_fab2_lib.baseboard_fab2(sch_1):page59_i172:DDR2_DQ(50)" )
				( pinRef "@baseboard_fab2_lib.baseboard_fab2(sch_1):page81_i186:DQ(51)" )
				( attribute "RELATIVE_PROPAGATION_DELAY_SCOPE" "G"
					( Parent
						( matchGroupRef "@baseboard_fab2_lib.baseboard_fab2(sch_1):\MG_DQ-DQS_FAR_DIMM_NG_M_J_BYTE6\" )
					)
					( Status sCSetFlattened )
					( Origin gBackEnd )
				)
				( attribute "RELATIVE_PROPAGATION_DELAY" "0.00 MIL,195.00 MIL"
					( Parent
						( matchGroupRef "@baseboard_fab2_lib.baseboard_fab2(sch_1):\MG_DQ-DQS_FAR_DIMM_NG_M_J_BYTE6\" )
					)
					( Units "uMatchProp" "ns" 1.000000)
					( Status sCSetFlattened )
					( Origin gBackEnd )
				)
				( attribute "RELATIVE_PROPAGATION_DELAY_SCOPE" "G"
					( Parent
						( matchGroupRef "@crescent_city_bb_fab1_lib.crescent_city_bb_fab1(sch_1):\MG_DQ_FAR_DIMM_NG_M_J_BYTE6\" )
					)
					( Status sCSetFlattened )
					( Origin gBackEnd )
				)
				( attribute "RELATIVE_PROPAGATION_DELAY" "-50.00 MIL,50.00 MIL"
					( Parent
						( matchGroupRef "@crescent_city_bb_fab1_lib.crescent_city_bb_fab1(sch_1):\MG_DQ_FAR_DIMM_NG_M_J_BYTE6\" )
					)
					( Units "uMatchProp" "ns" 1.000000)
					( Status sCSetFlattened )
					( Origin gBackEnd )
				)
			)
			( pinPair "@baseboard_fab2_lib.baseboard_fab2(sch_1):\PP2355\"
				( pinRef "@baseboard_fab2_lib.baseboard_fab2(sch_1):page59_i172:DDR2_DQ(50)" )
				( pinRef "@baseboard_fab2_lib.baseboard_fab2(sch_1):page82_i187:DQ(50)" )
				( attribute "RELATIVE_PROPAGATION_DELAY_SCOPE" "G"
					( Parent
						( matchGroupRef "@baseboard_fab2_lib.baseboard_fab2(sch_1):\MG_DQ-DQS_NEAR_DIMM_NG_M_J_BYTE6\" )
					)
					( Status sCSetFlattened )
					( Origin gBackEnd )
				)
				( attribute "RELATIVE_PROPAGATION_DELAY" "0.00 MIL,195.00 MIL"
					( Parent
						( matchGroupRef "@baseboard_fab2_lib.baseboard_fab2(sch_1):\MG_DQ-DQS_NEAR_DIMM_NG_M_J_BYTE6\" )
					)
					( Units "uMatchProp" "ns" 1.000000)
					( Status sCSetFlattened )
					( Origin gBackEnd )
				)
				( attribute "RELATIVE_PROPAGATION_DELAY_SCOPE" "G"
					( Parent
						( matchGroupRef "@crescent_city_bb_fab1_lib.crescent_city_bb_fab1(sch_1):\MG_DQ_NEAR_DIMM_NG_M_J_BYTE6\" )
					)
					( Status sCSetFlattened )
					( Origin gBackEnd )
				)
				( attribute "RELATIVE_PROPAGATION_DELAY" "-50.00 MIL,50.00 MIL"
					( Parent
						( matchGroupRef "@crescent_city_bb_fab1_lib.crescent_city_bb_fab1(sch_1):\MG_DQ_NEAR_DIMM_NG_M_J_BYTE6\" )
					)
					( Units "uMatchProp" "ns" 1.000000)
					( Status sCSetFlattened )
					( Origin gBackEnd )
				)
			)
			( pinPair "@baseboard_fab2_lib.baseboard_fab2(sch_1):\PP2356\"
				( pinRef "@baseboard_fab2_lib.baseboard_fab2(sch_1):page59_i172:DDR2_DQ(51)" )
				( pinRef "@baseboard_fab2_lib.baseboard_fab2(sch_1):page81_i186:DQ(50)" )
				( attribute "RELATIVE_PROPAGATION_DELAY_SCOPE" "G"
					( Parent
						( matchGroupRef "@baseboard_fab2_lib.baseboard_fab2(sch_1):\MG_DQ-DQS_FAR_DIMM_NG_M_J_BYTE6\" )
					)
					( Status sCSetFlattened )
					( Origin gBackEnd )
				)
				( attribute "RELATIVE_PROPAGATION_DELAY" "0.00 MIL,195.00 MIL"
					( Parent
						( matchGroupRef "@baseboard_fab2_lib.baseboard_fab2(sch_1):\MG_DQ-DQS_FAR_DIMM_NG_M_J_BYTE6\" )
					)
					( Units "uMatchProp" "ns" 1.000000)
					( Status sCSetFlattened )
					( Origin gBackEnd )
				)
				( attribute "RELATIVE_PROPAGATION_DELAY_SCOPE" "G"
					( Parent
						( matchGroupRef "@crescent_city_bb_fab1_lib.crescent_city_bb_fab1(sch_1):\MG_DQ_FAR_DIMM_NG_M_J_BYTE6\" )
					)
					( Status sCSetFlattened )
					( Origin gBackEnd )
				)
				( attribute "RELATIVE_PROPAGATION_DELAY" "-50.00 MIL,50.00 MIL"
					( Parent
						( matchGroupRef "@crescent_city_bb_fab1_lib.crescent_city_bb_fab1(sch_1):\MG_DQ_FAR_DIMM_NG_M_J_BYTE6\" )
					)
					( Units "uMatchProp" "ns" 1.000000)
					( Status sCSetFlattened )
					( Origin gBackEnd )
				)
			)
			( pinPair "@baseboard_fab2_lib.baseboard_fab2(sch_1):\PP2358\"
				( pinRef "@baseboard_fab2_lib.baseboard_fab2(sch_1):page59_i172:DDR2_DQ(51)" )
				( pinRef "@baseboard_fab2_lib.baseboard_fab2(sch_1):page82_i187:DQ(51)" )
				( attribute "RELATIVE_PROPAGATION_DELAY_SCOPE" "G"
					( Parent
						( matchGroupRef "@baseboard_fab2_lib.baseboard_fab2(sch_1):\MG_DQ-DQS_NEAR_DIMM_NG_M_J_BYTE6\" )
					)
					( Status sCSetFlattened )
					( Origin gBackEnd )
				)
				( attribute "RELATIVE_PROPAGATION_DELAY" "0.00 MIL,195.00 MIL"
					( Parent
						( matchGroupRef "@baseboard_fab2_lib.baseboard_fab2(sch_1):\MG_DQ-DQS_NEAR_DIMM_NG_M_J_BYTE6\" )
					)
					( Units "uMatchProp" "ns" 1.000000)
					( Status sCSetFlattened )
					( Origin gBackEnd )
				)
				( attribute "RELATIVE_PROPAGATION_DELAY_SCOPE" "G"
					( Parent
						( matchGroupRef "@crescent_city_bb_fab1_lib.crescent_city_bb_fab1(sch_1):\MG_DQ_NEAR_DIMM_NG_M_J_BYTE6\" )
					)
					( Status sCSetFlattened )
					( Origin gBackEnd )
				)
				( attribute "RELATIVE_PROPAGATION_DELAY" "-50.00 MIL,50.00 MIL"
					( Parent
						( matchGroupRef "@crescent_city_bb_fab1_lib.crescent_city_bb_fab1(sch_1):\MG_DQ_NEAR_DIMM_NG_M_J_BYTE6\" )
					)
					( Units "uMatchProp" "ns" 1.000000)
					( Status sCSetFlattened )
					( Origin gBackEnd )
				)
			)
			( pinPair "@baseboard_fab2_lib.baseboard_fab2(sch_1):\PP2359\"
				( pinRef "@baseboard_fab2_lib.baseboard_fab2(sch_1):page59_i172:DDR2_DQ(52)" )
				( pinRef "@baseboard_fab2_lib.baseboard_fab2(sch_1):page81_i186:DQ(53)" )
				( attribute "RELATIVE_PROPAGATION_DELAY_SCOPE" "G"
					( Parent
						( matchGroupRef "@baseboard_fab2_lib.baseboard_fab2(sch_1):\MG_DQ-DQS_FAR_DIMM_NG_M_J_BYTE6\" )
					)
					( Status sCSetFlattened )
					( Origin gBackEnd )
				)
				( attribute "RELATIVE_PROPAGATION_DELAY" "0.00 MIL,195.00 MIL"
					( Parent
						( matchGroupRef "@baseboard_fab2_lib.baseboard_fab2(sch_1):\MG_DQ-DQS_FAR_DIMM_NG_M_J_BYTE6\" )
					)
					( Units "uMatchProp" "ns" 1.000000)
					( Status sCSetFlattened )
					( Origin gBackEnd )
				)
				( attribute "RELATIVE_PROPAGATION_DELAY_SCOPE" "G"
					( Parent
						( matchGroupRef "@crescent_city_bb_fab1_lib.crescent_city_bb_fab1(sch_1):\MG_DQ_FAR_DIMM_NG_M_J_BYTE6\" )
					)
					( Status sCSetFlattened )
					( Origin gBackEnd )
				)
				( attribute "RELATIVE_PROPAGATION_DELAY" "-50.00 MIL,50.00 MIL"
					( Parent
						( matchGroupRef "@crescent_city_bb_fab1_lib.crescent_city_bb_fab1(sch_1):\MG_DQ_FAR_DIMM_NG_M_J_BYTE6\" )
					)
					( Units "uMatchProp" "ns" 1.000000)
					( Status sCSetFlattened )
					( Origin gBackEnd )
				)
			)
			( pinPair "@baseboard_fab2_lib.baseboard_fab2(sch_1):\PP2361\"
				( pinRef "@baseboard_fab2_lib.baseboard_fab2(sch_1):page59_i172:DDR2_DQ(52)" )
				( pinRef "@baseboard_fab2_lib.baseboard_fab2(sch_1):page82_i187:DQ(52)" )
				( attribute "RELATIVE_PROPAGATION_DELAY_SCOPE" "G"
					( Parent
						( matchGroupRef "@baseboard_fab2_lib.baseboard_fab2(sch_1):\MG_DQ-DQS_NEAR_DIMM_NG_M_J_BYTE6\" )
					)
					( Status sCSetFlattened )
					( Origin gBackEnd )
				)
				( attribute "RELATIVE_PROPAGATION_DELAY" "0.00 MIL,195.00 MIL"
					( Parent
						( matchGroupRef "@baseboard_fab2_lib.baseboard_fab2(sch_1):\MG_DQ-DQS_NEAR_DIMM_NG_M_J_BYTE6\" )
					)
					( Units "uMatchProp" "ns" 1.000000)
					( Status sCSetFlattened )
					( Origin gBackEnd )
				)
				( attribute "RELATIVE_PROPAGATION_DELAY_SCOPE" "G"
					( Parent
						( matchGroupRef "@crescent_city_bb_fab1_lib.crescent_city_bb_fab1(sch_1):\MG_DQ_NEAR_DIMM_NG_M_J_BYTE6\" )
					)
					( Status sCSetFlattened )
					( Origin gBackEnd )
				)
				( attribute "RELATIVE_PROPAGATION_DELAY" "-50.00 MIL,50.00 MIL"
					( Parent
						( matchGroupRef "@crescent_city_bb_fab1_lib.crescent_city_bb_fab1(sch_1):\MG_DQ_NEAR_DIMM_NG_M_J_BYTE6\" )
					)
					( Units "uMatchProp" "ns" 1.000000)
					( Status sCSetFlattened )
					( Origin gBackEnd )
				)
			)
			( pinPair "@baseboard_fab2_lib.baseboard_fab2(sch_1):\PP2362\"
				( pinRef "@baseboard_fab2_lib.baseboard_fab2(sch_1):page59_i172:DDR2_DQ(53)" )
				( pinRef "@baseboard_fab2_lib.baseboard_fab2(sch_1):page81_i186:DQ(52)" )
				( attribute "RELATIVE_PROPAGATION_DELAY_SCOPE" "G"
					( Parent
						( matchGroupRef "@baseboard_fab2_lib.baseboard_fab2(sch_1):\MG_DQ-DQS_FAR_DIMM_NG_M_J_BYTE6\" )
					)
					( Status sCSetFlattened )
					( Origin gBackEnd )
				)
				( attribute "RELATIVE_PROPAGATION_DELAY" "0.00 MIL,195.00 MIL"
					( Parent
						( matchGroupRef "@baseboard_fab2_lib.baseboard_fab2(sch_1):\MG_DQ-DQS_FAR_DIMM_NG_M_J_BYTE6\" )
					)
					( Units "uMatchProp" "ns" 1.000000)
					( Status sCSetFlattened )
					( Origin gBackEnd )
				)
				( attribute "RELATIVE_PROPAGATION_DELAY_SCOPE" "G"
					( Parent
						( matchGroupRef "@crescent_city_bb_fab1_lib.crescent_city_bb_fab1(sch_1):\MG_DQ_FAR_DIMM_NG_M_J_BYTE6\" )
					)
					( Status sCSetFlattened )
					( Origin gBackEnd )
				)
				( attribute "RELATIVE_PROPAGATION_DELAY" "-50.00 MIL,50.00 MIL"
					( Parent
						( matchGroupRef "@crescent_city_bb_fab1_lib.crescent_city_bb_fab1(sch_1):\MG_DQ_FAR_DIMM_NG_M_J_BYTE6\" )
					)
					( Units "uMatchProp" "ns" 1.000000)
					( Status sCSetFlattened )
					( Origin gBackEnd )
				)
			)
			( pinPair "@baseboard_fab2_lib.baseboard_fab2(sch_1):\PP2364\"
				( pinRef "@baseboard_fab2_lib.baseboard_fab2(sch_1):page59_i172:DDR2_DQ(53)" )
				( pinRef "@baseboard_fab2_lib.baseboard_fab2(sch_1):page82_i187:DQ(53)" )
				( attribute "RELATIVE_PROPAGATION_DELAY_SCOPE" "G"
					( Parent
						( matchGroupRef "@baseboard_fab2_lib.baseboard_fab2(sch_1):\MG_DQ-DQS_NEAR_DIMM_NG_M_J_BYTE6\" )
					)
					( Status sCSetFlattened )
					( Origin gBackEnd )
				)
				( attribute "RELATIVE_PROPAGATION_DELAY" "0.00 MIL,195.00 MIL"
					( Parent
						( matchGroupRef "@baseboard_fab2_lib.baseboard_fab2(sch_1):\MG_DQ-DQS_NEAR_DIMM_NG_M_J_BYTE6\" )
					)
					( Units "uMatchProp" "ns" 1.000000)
					( Status sCSetFlattened )
					( Origin gBackEnd )
				)
				( attribute "RELATIVE_PROPAGATION_DELAY_SCOPE" "G"
					( Parent
						( matchGroupRef "@crescent_city_bb_fab1_lib.crescent_city_bb_fab1(sch_1):\MG_DQ_NEAR_DIMM_NG_M_J_BYTE6\" )
					)
					( Status sCSetFlattened )
					( Origin gBackEnd )
				)
				( attribute "RELATIVE_PROPAGATION_DELAY" "-50.00 MIL,50.00 MIL"
					( Parent
						( matchGroupRef "@crescent_city_bb_fab1_lib.crescent_city_bb_fab1(sch_1):\MG_DQ_NEAR_DIMM_NG_M_J_BYTE6\" )
					)
					( Units "uMatchProp" "ns" 1.000000)
					( Status sCSetFlattened )
					( Origin gBackEnd )
				)
			)
			( pinPair "@baseboard_fab2_lib.baseboard_fab2(sch_1):\PP2365\"
				( pinRef "@baseboard_fab2_lib.baseboard_fab2(sch_1):page59_i172:DDR2_DQ(54)" )
				( pinRef "@baseboard_fab2_lib.baseboard_fab2(sch_1):page81_i186:DQ(55)" )
				( attribute "RELATIVE_PROPAGATION_DELAY_SCOPE" "G"
					( Parent
						( matchGroupRef "@baseboard_fab2_lib.baseboard_fab2(sch_1):\MG_DQ-DQS_FAR_DIMM_NG_M_J_BYTE6\" )
					)
					( Status sCSetFlattened )
					( Origin gBackEnd )
				)
				( attribute "RELATIVE_PROPAGATION_DELAY" "0.00 MIL,195.00 MIL"
					( Parent
						( matchGroupRef "@baseboard_fab2_lib.baseboard_fab2(sch_1):\MG_DQ-DQS_FAR_DIMM_NG_M_J_BYTE6\" )
					)
					( Units "uMatchProp" "ns" 1.000000)
					( Status sCSetFlattened )
					( Origin gBackEnd )
				)
				( attribute "RELATIVE_PROPAGATION_DELAY_SCOPE" "G"
					( Parent
						( matchGroupRef "@crescent_city_bb_fab1_lib.crescent_city_bb_fab1(sch_1):\MG_DQ_FAR_DIMM_NG_M_J_BYTE6\" )
					)
					( Status sCSetFlattened )
					( Origin gBackEnd )
				)
				( attribute "RELATIVE_PROPAGATION_DELAY" "-50.00 MIL,50.00 MIL"
					( Parent
						( matchGroupRef "@crescent_city_bb_fab1_lib.crescent_city_bb_fab1(sch_1):\MG_DQ_FAR_DIMM_NG_M_J_BYTE6\" )
					)
					( Units "uMatchProp" "ns" 1.000000)
					( Status sCSetFlattened )
					( Origin gBackEnd )
				)
			)
			( pinPair "@baseboard_fab2_lib.baseboard_fab2(sch_1):\PP2367\"
				( pinRef "@baseboard_fab2_lib.baseboard_fab2(sch_1):page59_i172:DDR2_DQ(54)" )
				( pinRef "@baseboard_fab2_lib.baseboard_fab2(sch_1):page82_i187:DQ(54)" )
				( attribute "RELATIVE_PROPAGATION_DELAY_SCOPE" "G"
					( Parent
						( matchGroupRef "@baseboard_fab2_lib.baseboard_fab2(sch_1):\MG_DQ-DQS_NEAR_DIMM_NG_M_J_BYTE6\" )
					)
					( Status sCSetFlattened )
					( Origin gBackEnd )
				)
				( attribute "RELATIVE_PROPAGATION_DELAY" "0.00 MIL,195.00 MIL"
					( Parent
						( matchGroupRef "@baseboard_fab2_lib.baseboard_fab2(sch_1):\MG_DQ-DQS_NEAR_DIMM_NG_M_J_BYTE6\" )
					)
					( Units "uMatchProp" "ns" 1.000000)
					( Status sCSetFlattened )
					( Origin gBackEnd )
				)
				( attribute "RELATIVE_PROPAGATION_DELAY_SCOPE" "G"
					( Parent
						( matchGroupRef "@crescent_city_bb_fab1_lib.crescent_city_bb_fab1(sch_1):\MG_DQ_NEAR_DIMM_NG_M_J_BYTE6\" )
					)
					( Status sCSetFlattened )
					( Origin gBackEnd )
				)
				( attribute "RELATIVE_PROPAGATION_DELAY" "-50.00 MIL,50.00 MIL"
					( Parent
						( matchGroupRef "@crescent_city_bb_fab1_lib.crescent_city_bb_fab1(sch_1):\MG_DQ_NEAR_DIMM_NG_M_J_BYTE6\" )
					)
					( Units "uMatchProp" "ns" 1.000000)
					( Status sCSetFlattened )
					( Origin gBackEnd )
				)
			)
			( pinPair "@baseboard_fab2_lib.baseboard_fab2(sch_1):\PP2368\"
				( pinRef "@baseboard_fab2_lib.baseboard_fab2(sch_1):page59_i172:DDR2_DQ(55)" )
				( pinRef "@baseboard_fab2_lib.baseboard_fab2(sch_1):page81_i186:DQ(54)" )
				( attribute "RELATIVE_PROPAGATION_DELAY_SCOPE" "G"
					( Parent
						( matchGroupRef "@baseboard_fab2_lib.baseboard_fab2(sch_1):\MG_DQ-DQS_FAR_DIMM_NG_M_J_BYTE6\" )
					)
					( Status sCSetFlattened )
					( Origin gBackEnd )
				)
				( attribute "RELATIVE_PROPAGATION_DELAY" "0.00 MIL,195.00 MIL"
					( Parent
						( matchGroupRef "@baseboard_fab2_lib.baseboard_fab2(sch_1):\MG_DQ-DQS_FAR_DIMM_NG_M_J_BYTE6\" )
					)
					( Units "uMatchProp" "ns" 1.000000)
					( Status sCSetFlattened )
					( Origin gBackEnd )
				)
				( attribute "RELATIVE_PROPAGATION_DELAY_SCOPE" "G"
					( Parent
						( matchGroupRef "@crescent_city_bb_fab1_lib.crescent_city_bb_fab1(sch_1):\MG_DQ_FAR_DIMM_NG_M_J_BYTE6\" )
					)
					( Origin gBackEnd )
				)
				( attribute "RELATIVE_PROPAGATION_DELAY" "TARGET,TARGET"
					( Parent
						( matchGroupRef "@crescent_city_bb_fab1_lib.crescent_city_bb_fab1(sch_1):\MG_DQ_FAR_DIMM_NG_M_J_BYTE6\" )
					)
					( Units "uMatchProp" "ns" 1.000000)
					( Origin gBackEnd )
				)
			)
			( pinPair "@baseboard_fab2_lib.baseboard_fab2(sch_1):\PP2370\"
				( pinRef "@baseboard_fab2_lib.baseboard_fab2(sch_1):page59_i172:DDR2_DQ(55)" )
				( pinRef "@baseboard_fab2_lib.baseboard_fab2(sch_1):page82_i187:DQ(55)" )
				( attribute "RELATIVE_PROPAGATION_DELAY_SCOPE" "G"
					( Parent
						( matchGroupRef "@baseboard_fab2_lib.baseboard_fab2(sch_1):\MG_DQ-DQS_NEAR_DIMM_NG_M_J_BYTE6\" )
					)
					( Status sCSetFlattened )
					( Origin gBackEnd )
				)
				( attribute "RELATIVE_PROPAGATION_DELAY" "0.00 MIL,195.00 MIL"
					( Parent
						( matchGroupRef "@baseboard_fab2_lib.baseboard_fab2(sch_1):\MG_DQ-DQS_NEAR_DIMM_NG_M_J_BYTE6\" )
					)
					( Units "uMatchProp" "ns" 1.000000)
					( Status sCSetFlattened )
					( Origin gBackEnd )
				)
				( attribute "RELATIVE_PROPAGATION_DELAY_SCOPE" "G"
					( Parent
						( matchGroupRef "@crescent_city_bb_fab1_lib.crescent_city_bb_fab1(sch_1):\MG_DQ_NEAR_DIMM_NG_M_J_BYTE6\" )
					)
					( Origin gBackEnd )
				)
				( attribute "RELATIVE_PROPAGATION_DELAY" "TARGET,TARGET"
					( Parent
						( matchGroupRef "@crescent_city_bb_fab1_lib.crescent_city_bb_fab1(sch_1):\MG_DQ_NEAR_DIMM_NG_M_J_BYTE6\" )
					)
					( Units "uMatchProp" "ns" 1.000000)
					( Origin gBackEnd )
				)
			)
			( pinPair "@baseboard_fab2_lib.baseboard_fab2(sch_1):\PP2323\"
				( pinRef "@baseboard_fab2_lib.baseboard_fab2(sch_1):page59_i172:DDR2_DQ(56)" )
				( pinRef "@baseboard_fab2_lib.baseboard_fab2(sch_1):page81_i186:DQ(57)" )
				( attribute "RELATIVE_PROPAGATION_DELAY_SCOPE" "G"
					( Parent
						( matchGroupRef "@baseboard_fab2_lib.baseboard_fab2(sch_1):\MG_DQ-DQS_FAR_DIMM_NG_M_J_BYTE7\" )
					)
					( Status sCSetFlattened )
					( Origin gBackEnd )
				)
				( attribute "RELATIVE_PROPAGATION_DELAY" "0.00 MIL,195.00 MIL"
					( Parent
						( matchGroupRef "@baseboard_fab2_lib.baseboard_fab2(sch_1):\MG_DQ-DQS_FAR_DIMM_NG_M_J_BYTE7\" )
					)
					( Units "uMatchProp" "ns" 1.000000)
					( Status sCSetFlattened )
					( Origin gBackEnd )
				)
				( attribute "RELATIVE_PROPAGATION_DELAY_SCOPE" "G"
					( Parent
						( matchGroupRef "@baseboard_fab2_lib.baseboard_fab2(sch_1):\MG_DQ_FAR_DIMM_NG_M_J_BYTE7\" )
					)
					( Status sCSetFlattened )
					( Origin gBackEnd )
				)
				( attribute "RELATIVE_PROPAGATION_DELAY" "-50.00 MIL,50.00 MIL"
					( Parent
						( matchGroupRef "@baseboard_fab2_lib.baseboard_fab2(sch_1):\MG_DQ_FAR_DIMM_NG_M_J_BYTE7\" )
					)
					( Units "uMatchProp" "ns" 1.000000)
					( Status sCSetFlattened )
					( Origin gBackEnd )
				)
			)
			( pinPair "@baseboard_fab2_lib.baseboard_fab2(sch_1):\PP2325\"
				( pinRef "@baseboard_fab2_lib.baseboard_fab2(sch_1):page59_i172:DDR2_DQ(56)" )
				( pinRef "@baseboard_fab2_lib.baseboard_fab2(sch_1):page82_i187:DQ(56)" )
				( attribute "RELATIVE_PROPAGATION_DELAY_SCOPE" "G"
					( Parent
						( matchGroupRef "@baseboard_fab2_lib.baseboard_fab2(sch_1):\MG_DQ-DQS_NEAR_DIMM_NG_M_J_BYTE7\" )
					)
					( Status sCSetFlattened )
					( Origin gBackEnd )
				)
				( attribute "RELATIVE_PROPAGATION_DELAY" "0.00 MIL,195.00 MIL"
					( Parent
						( matchGroupRef "@baseboard_fab2_lib.baseboard_fab2(sch_1):\MG_DQ-DQS_NEAR_DIMM_NG_M_J_BYTE7\" )
					)
					( Units "uMatchProp" "ns" 1.000000)
					( Status sCSetFlattened )
					( Origin gBackEnd )
				)
				( attribute "RELATIVE_PROPAGATION_DELAY_SCOPE" "G"
					( Parent
						( matchGroupRef "@baseboard_fab2_lib.baseboard_fab2(sch_1):\MG_DQ_NEAR_DIMM_NG_M_J_BYTE7\" )
					)
					( Status sCSetFlattened )
					( Origin gBackEnd )
				)
				( attribute "RELATIVE_PROPAGATION_DELAY" "-50.00 MIL,50.00 MIL"
					( Parent
						( matchGroupRef "@baseboard_fab2_lib.baseboard_fab2(sch_1):\MG_DQ_NEAR_DIMM_NG_M_J_BYTE7\" )
					)
					( Units "uMatchProp" "ns" 1.000000)
					( Status sCSetFlattened )
					( Origin gBackEnd )
				)
			)
			( pinPair "@baseboard_fab2_lib.baseboard_fab2(sch_1):\PP2326\"
				( pinRef "@baseboard_fab2_lib.baseboard_fab2(sch_1):page59_i172:DDR2_DQ(57)" )
				( pinRef "@baseboard_fab2_lib.baseboard_fab2(sch_1):page81_i186:DQ(56)" )
				( attribute "RELATIVE_PROPAGATION_DELAY_SCOPE" "G"
					( Parent
						( matchGroupRef "@baseboard_fab2_lib.baseboard_fab2(sch_1):\MG_DQ-DQS_FAR_DIMM_NG_M_J_BYTE7\" )
					)
					( Status sCSetFlattened )
					( Origin gBackEnd )
				)
				( attribute "RELATIVE_PROPAGATION_DELAY" "0.00 MIL,195.00 MIL"
					( Parent
						( matchGroupRef "@baseboard_fab2_lib.baseboard_fab2(sch_1):\MG_DQ-DQS_FAR_DIMM_NG_M_J_BYTE7\" )
					)
					( Units "uMatchProp" "ns" 1.000000)
					( Status sCSetFlattened )
					( Origin gBackEnd )
				)
				( attribute "RELATIVE_PROPAGATION_DELAY_SCOPE" "G"
					( Parent
						( matchGroupRef "@baseboard_fab2_lib.baseboard_fab2(sch_1):\MG_DQ_FAR_DIMM_NG_M_J_BYTE7\" )
					)
					( Status sCSetFlattened )
					( Origin gBackEnd )
				)
				( attribute "RELATIVE_PROPAGATION_DELAY" "-50.00 MIL,50.00 MIL"
					( Parent
						( matchGroupRef "@baseboard_fab2_lib.baseboard_fab2(sch_1):\MG_DQ_FAR_DIMM_NG_M_J_BYTE7\" )
					)
					( Units "uMatchProp" "ns" 1.000000)
					( Status sCSetFlattened )
					( Origin gBackEnd )
				)
			)
			( pinPair "@baseboard_fab2_lib.baseboard_fab2(sch_1):\PP2328\"
				( pinRef "@baseboard_fab2_lib.baseboard_fab2(sch_1):page59_i172:DDR2_DQ(57)" )
				( pinRef "@baseboard_fab2_lib.baseboard_fab2(sch_1):page82_i187:DQ(57)" )
				( attribute "RELATIVE_PROPAGATION_DELAY_SCOPE" "G"
					( Parent
						( matchGroupRef "@baseboard_fab2_lib.baseboard_fab2(sch_1):\MG_DQ-DQS_NEAR_DIMM_NG_M_J_BYTE7\" )
					)
					( Status sCSetFlattened )
					( Origin gBackEnd )
				)
				( attribute "RELATIVE_PROPAGATION_DELAY" "0.00 MIL,195.00 MIL"
					( Parent
						( matchGroupRef "@baseboard_fab2_lib.baseboard_fab2(sch_1):\MG_DQ-DQS_NEAR_DIMM_NG_M_J_BYTE7\" )
					)
					( Units "uMatchProp" "ns" 1.000000)
					( Status sCSetFlattened )
					( Origin gBackEnd )
				)
				( attribute "RELATIVE_PROPAGATION_DELAY_SCOPE" "G"
					( Parent
						( matchGroupRef "@baseboard_fab2_lib.baseboard_fab2(sch_1):\MG_DQ_NEAR_DIMM_NG_M_J_BYTE7\" )
					)
					( Status sCSetFlattened )
					( Origin gBackEnd )
				)
				( attribute "RELATIVE_PROPAGATION_DELAY" "-50.00 MIL,50.00 MIL"
					( Parent
						( matchGroupRef "@baseboard_fab2_lib.baseboard_fab2(sch_1):\MG_DQ_NEAR_DIMM_NG_M_J_BYTE7\" )
					)
					( Units "uMatchProp" "ns" 1.000000)
					( Status sCSetFlattened )
					( Origin gBackEnd )
				)
			)
			( pinPair "@baseboard_fab2_lib.baseboard_fab2(sch_1):\PP2329\"
				( pinRef "@baseboard_fab2_lib.baseboard_fab2(sch_1):page59_i172:DDR2_DQ(58)" )
				( pinRef "@baseboard_fab2_lib.baseboard_fab2(sch_1):page81_i186:DQ(59)" )
				( attribute "RELATIVE_PROPAGATION_DELAY_SCOPE" "G"
					( Parent
						( matchGroupRef "@baseboard_fab2_lib.baseboard_fab2(sch_1):\MG_DQ-DQS_FAR_DIMM_NG_M_J_BYTE7\" )
					)
					( Status sCSetFlattened )
					( Origin gBackEnd )
				)
				( attribute "RELATIVE_PROPAGATION_DELAY" "0.00 MIL,195.00 MIL"
					( Parent
						( matchGroupRef "@baseboard_fab2_lib.baseboard_fab2(sch_1):\MG_DQ-DQS_FAR_DIMM_NG_M_J_BYTE7\" )
					)
					( Units "uMatchProp" "ns" 1.000000)
					( Status sCSetFlattened )
					( Origin gBackEnd )
				)
				( attribute "RELATIVE_PROPAGATION_DELAY_SCOPE" "G"
					( Parent
						( matchGroupRef "@baseboard_fab2_lib.baseboard_fab2(sch_1):\MG_DQ_FAR_DIMM_NG_M_J_BYTE7\" )
					)
					( Status sCSetFlattened )
					( Origin gBackEnd )
				)
				( attribute "RELATIVE_PROPAGATION_DELAY" "-50.00 MIL,50.00 MIL"
					( Parent
						( matchGroupRef "@baseboard_fab2_lib.baseboard_fab2(sch_1):\MG_DQ_FAR_DIMM_NG_M_J_BYTE7\" )
					)
					( Units "uMatchProp" "ns" 1.000000)
					( Status sCSetFlattened )
					( Origin gBackEnd )
				)
			)
			( pinPair "@baseboard_fab2_lib.baseboard_fab2(sch_1):\PP2331\"
				( pinRef "@baseboard_fab2_lib.baseboard_fab2(sch_1):page59_i172:DDR2_DQ(58)" )
				( pinRef "@baseboard_fab2_lib.baseboard_fab2(sch_1):page82_i187:DQ(58)" )
				( attribute "RELATIVE_PROPAGATION_DELAY_SCOPE" "G"
					( Parent
						( matchGroupRef "@baseboard_fab2_lib.baseboard_fab2(sch_1):\MG_DQ-DQS_NEAR_DIMM_NG_M_J_BYTE7\" )
					)
					( Status sCSetFlattened )
					( Origin gBackEnd )
				)
				( attribute "RELATIVE_PROPAGATION_DELAY" "0.00 MIL,195.00 MIL"
					( Parent
						( matchGroupRef "@baseboard_fab2_lib.baseboard_fab2(sch_1):\MG_DQ-DQS_NEAR_DIMM_NG_M_J_BYTE7\" )
					)
					( Units "uMatchProp" "ns" 1.000000)
					( Status sCSetFlattened )
					( Origin gBackEnd )
				)
				( attribute "RELATIVE_PROPAGATION_DELAY_SCOPE" "G"
					( Parent
						( matchGroupRef "@baseboard_fab2_lib.baseboard_fab2(sch_1):\MG_DQ_NEAR_DIMM_NG_M_J_BYTE7\" )
					)
					( Status sCSetFlattened )
					( Origin gBackEnd )
				)
				( attribute "RELATIVE_PROPAGATION_DELAY" "-50.00 MIL,50.00 MIL"
					( Parent
						( matchGroupRef "@baseboard_fab2_lib.baseboard_fab2(sch_1):\MG_DQ_NEAR_DIMM_NG_M_J_BYTE7\" )
					)
					( Units "uMatchProp" "ns" 1.000000)
					( Status sCSetFlattened )
					( Origin gBackEnd )
				)
			)
			( pinPair "@baseboard_fab2_lib.baseboard_fab2(sch_1):\PP2332\"
				( pinRef "@baseboard_fab2_lib.baseboard_fab2(sch_1):page59_i172:DDR2_DQ(59)" )
				( pinRef "@baseboard_fab2_lib.baseboard_fab2(sch_1):page81_i186:DQ(58)" )
				( attribute "RELATIVE_PROPAGATION_DELAY_SCOPE" "G"
					( Parent
						( matchGroupRef "@baseboard_fab2_lib.baseboard_fab2(sch_1):\MG_DQ-DQS_FAR_DIMM_NG_M_J_BYTE7\" )
					)
					( Status sCSetFlattened )
					( Origin gBackEnd )
				)
				( attribute "RELATIVE_PROPAGATION_DELAY" "0.00 MIL,195.00 MIL"
					( Parent
						( matchGroupRef "@baseboard_fab2_lib.baseboard_fab2(sch_1):\MG_DQ-DQS_FAR_DIMM_NG_M_J_BYTE7\" )
					)
					( Units "uMatchProp" "ns" 1.000000)
					( Status sCSetFlattened )
					( Origin gBackEnd )
				)
				( attribute "RELATIVE_PROPAGATION_DELAY_SCOPE" "G"
					( Parent
						( matchGroupRef "@baseboard_fab2_lib.baseboard_fab2(sch_1):\MG_DQ_FAR_DIMM_NG_M_J_BYTE7\" )
					)
					( Status sCSetFlattened )
					( Origin gBackEnd )
				)
				( attribute "RELATIVE_PROPAGATION_DELAY" "-50.00 MIL,50.00 MIL"
					( Parent
						( matchGroupRef "@baseboard_fab2_lib.baseboard_fab2(sch_1):\MG_DQ_FAR_DIMM_NG_M_J_BYTE7\" )
					)
					( Units "uMatchProp" "ns" 1.000000)
					( Status sCSetFlattened )
					( Origin gBackEnd )
				)
			)
			( pinPair "@baseboard_fab2_lib.baseboard_fab2(sch_1):\PP2334\"
				( pinRef "@baseboard_fab2_lib.baseboard_fab2(sch_1):page59_i172:DDR2_DQ(59)" )
				( pinRef "@baseboard_fab2_lib.baseboard_fab2(sch_1):page82_i187:DQ(59)" )
				( attribute "RELATIVE_PROPAGATION_DELAY_SCOPE" "G"
					( Parent
						( matchGroupRef "@baseboard_fab2_lib.baseboard_fab2(sch_1):\MG_DQ-DQS_NEAR_DIMM_NG_M_J_BYTE7\" )
					)
					( Status sCSetFlattened )
					( Origin gBackEnd )
				)
				( attribute "RELATIVE_PROPAGATION_DELAY" "0.00 MIL,195.00 MIL"
					( Parent
						( matchGroupRef "@baseboard_fab2_lib.baseboard_fab2(sch_1):\MG_DQ-DQS_NEAR_DIMM_NG_M_J_BYTE7\" )
					)
					( Units "uMatchProp" "ns" 1.000000)
					( Status sCSetFlattened )
					( Origin gBackEnd )
				)
				( attribute "RELATIVE_PROPAGATION_DELAY_SCOPE" "G"
					( Parent
						( matchGroupRef "@baseboard_fab2_lib.baseboard_fab2(sch_1):\MG_DQ_NEAR_DIMM_NG_M_J_BYTE7\" )
					)
					( Status sCSetFlattened )
					( Origin gBackEnd )
				)
				( attribute "RELATIVE_PROPAGATION_DELAY" "-50.00 MIL,50.00 MIL"
					( Parent
						( matchGroupRef "@baseboard_fab2_lib.baseboard_fab2(sch_1):\MG_DQ_NEAR_DIMM_NG_M_J_BYTE7\" )
					)
					( Units "uMatchProp" "ns" 1.000000)
					( Status sCSetFlattened )
					( Origin gBackEnd )
				)
			)
			( pinPair "@baseboard_fab2_lib.baseboard_fab2(sch_1):\PP2335\"
				( pinRef "@baseboard_fab2_lib.baseboard_fab2(sch_1):page59_i172:DDR2_DQ(60)" )
				( pinRef "@baseboard_fab2_lib.baseboard_fab2(sch_1):page81_i186:DQ(61)" )
				( attribute "RELATIVE_PROPAGATION_DELAY_SCOPE" "G"
					( Parent
						( matchGroupRef "@baseboard_fab2_lib.baseboard_fab2(sch_1):\MG_DQ-DQS_FAR_DIMM_NG_M_J_BYTE7\" )
					)
					( Status sCSetFlattened )
					( Origin gBackEnd )
				)
				( attribute "RELATIVE_PROPAGATION_DELAY" "0.00 MIL,195.00 MIL"
					( Parent
						( matchGroupRef "@baseboard_fab2_lib.baseboard_fab2(sch_1):\MG_DQ-DQS_FAR_DIMM_NG_M_J_BYTE7\" )
					)
					( Units "uMatchProp" "ns" 1.000000)
					( Status sCSetFlattened )
					( Origin gBackEnd )
				)
				( attribute "RELATIVE_PROPAGATION_DELAY_SCOPE" "G"
					( Parent
						( matchGroupRef "@baseboard_fab2_lib.baseboard_fab2(sch_1):\MG_DQ_FAR_DIMM_NG_M_J_BYTE7\" )
					)
					( Status sCSetFlattened )
					( Origin gBackEnd )
				)
				( attribute "RELATIVE_PROPAGATION_DELAY" "-50.00 MIL,50.00 MIL"
					( Parent
						( matchGroupRef "@baseboard_fab2_lib.baseboard_fab2(sch_1):\MG_DQ_FAR_DIMM_NG_M_J_BYTE7\" )
					)
					( Units "uMatchProp" "ns" 1.000000)
					( Status sCSetFlattened )
					( Origin gBackEnd )
				)
			)
			( pinPair "@baseboard_fab2_lib.baseboard_fab2(sch_1):\PP2337\"
				( pinRef "@baseboard_fab2_lib.baseboard_fab2(sch_1):page59_i172:DDR2_DQ(60)" )
				( pinRef "@baseboard_fab2_lib.baseboard_fab2(sch_1):page82_i187:DQ(60)" )
				( attribute "RELATIVE_PROPAGATION_DELAY_SCOPE" "G"
					( Parent
						( matchGroupRef "@baseboard_fab2_lib.baseboard_fab2(sch_1):\MG_DQ-DQS_NEAR_DIMM_NG_M_J_BYTE7\" )
					)
					( Status sCSetFlattened )
					( Origin gBackEnd )
				)
				( attribute "RELATIVE_PROPAGATION_DELAY" "0.00 MIL,195.00 MIL"
					( Parent
						( matchGroupRef "@baseboard_fab2_lib.baseboard_fab2(sch_1):\MG_DQ-DQS_NEAR_DIMM_NG_M_J_BYTE7\" )
					)
					( Units "uMatchProp" "ns" 1.000000)
					( Status sCSetFlattened )
					( Origin gBackEnd )
				)
				( attribute "RELATIVE_PROPAGATION_DELAY_SCOPE" "G"
					( Parent
						( matchGroupRef "@baseboard_fab2_lib.baseboard_fab2(sch_1):\MG_DQ_NEAR_DIMM_NG_M_J_BYTE7\" )
					)
					( Status sCSetFlattened )
					( Origin gBackEnd )
				)
				( attribute "RELATIVE_PROPAGATION_DELAY" "-50.00 MIL,50.00 MIL"
					( Parent
						( matchGroupRef "@baseboard_fab2_lib.baseboard_fab2(sch_1):\MG_DQ_NEAR_DIMM_NG_M_J_BYTE7\" )
					)
					( Units "uMatchProp" "ns" 1.000000)
					( Status sCSetFlattened )
					( Origin gBackEnd )
				)
			)
			( pinPair "@baseboard_fab2_lib.baseboard_fab2(sch_1):\PP2338\"
				( pinRef "@baseboard_fab2_lib.baseboard_fab2(sch_1):page59_i172:DDR2_DQ(61)" )
				( pinRef "@baseboard_fab2_lib.baseboard_fab2(sch_1):page81_i186:DQ(60)" )
				( attribute "RELATIVE_PROPAGATION_DELAY_SCOPE" "G"
					( Parent
						( matchGroupRef "@baseboard_fab2_lib.baseboard_fab2(sch_1):\MG_DQ-DQS_FAR_DIMM_NG_M_J_BYTE7\" )
					)
					( Status sCSetFlattened )
					( Origin gBackEnd )
				)
				( attribute "RELATIVE_PROPAGATION_DELAY" "0.00 MIL,195.00 MIL"
					( Parent
						( matchGroupRef "@baseboard_fab2_lib.baseboard_fab2(sch_1):\MG_DQ-DQS_FAR_DIMM_NG_M_J_BYTE7\" )
					)
					( Units "uMatchProp" "ns" 1.000000)
					( Status sCSetFlattened )
					( Origin gBackEnd )
				)
				( attribute "RELATIVE_PROPAGATION_DELAY_SCOPE" "G"
					( Parent
						( matchGroupRef "@baseboard_fab2_lib.baseboard_fab2(sch_1):\MG_DQ_FAR_DIMM_NG_M_J_BYTE7\" )
					)
					( Status sCSetFlattened )
					( Origin gBackEnd )
				)
				( attribute "RELATIVE_PROPAGATION_DELAY" "-50.00 MIL,50.00 MIL"
					( Parent
						( matchGroupRef "@baseboard_fab2_lib.baseboard_fab2(sch_1):\MG_DQ_FAR_DIMM_NG_M_J_BYTE7\" )
					)
					( Units "uMatchProp" "ns" 1.000000)
					( Status sCSetFlattened )
					( Origin gBackEnd )
				)
			)
			( pinPair "@baseboard_fab2_lib.baseboard_fab2(sch_1):\PP2340\"
				( pinRef "@baseboard_fab2_lib.baseboard_fab2(sch_1):page59_i172:DDR2_DQ(61)" )
				( pinRef "@baseboard_fab2_lib.baseboard_fab2(sch_1):page82_i187:DQ(61)" )
				( attribute "RELATIVE_PROPAGATION_DELAY_SCOPE" "G"
					( Parent
						( matchGroupRef "@baseboard_fab2_lib.baseboard_fab2(sch_1):\MG_DQ-DQS_NEAR_DIMM_NG_M_J_BYTE7\" )
					)
					( Status sCSetFlattened )
					( Origin gBackEnd )
				)
				( attribute "RELATIVE_PROPAGATION_DELAY" "0.00 MIL,195.00 MIL"
					( Parent
						( matchGroupRef "@baseboard_fab2_lib.baseboard_fab2(sch_1):\MG_DQ-DQS_NEAR_DIMM_NG_M_J_BYTE7\" )
					)
					( Units "uMatchProp" "ns" 1.000000)
					( Status sCSetFlattened )
					( Origin gBackEnd )
				)
				( attribute "RELATIVE_PROPAGATION_DELAY_SCOPE" "G"
					( Parent
						( matchGroupRef "@baseboard_fab2_lib.baseboard_fab2(sch_1):\MG_DQ_NEAR_DIMM_NG_M_J_BYTE7\" )
					)
					( Status sCSetFlattened )
					( Origin gBackEnd )
				)
				( attribute "RELATIVE_PROPAGATION_DELAY" "-50.00 MIL,50.00 MIL"
					( Parent
						( matchGroupRef "@baseboard_fab2_lib.baseboard_fab2(sch_1):\MG_DQ_NEAR_DIMM_NG_M_J_BYTE7\" )
					)
					( Units "uMatchProp" "ns" 1.000000)
					( Status sCSetFlattened )
					( Origin gBackEnd )
				)
			)
			( pinPair "@baseboard_fab2_lib.baseboard_fab2(sch_1):\PP2341\"
				( pinRef "@baseboard_fab2_lib.baseboard_fab2(sch_1):page59_i172:DDR2_DQ(62)" )
				( pinRef "@baseboard_fab2_lib.baseboard_fab2(sch_1):page81_i186:DQ(63)" )
				( attribute "RELATIVE_PROPAGATION_DELAY_SCOPE" "G"
					( Parent
						( matchGroupRef "@baseboard_fab2_lib.baseboard_fab2(sch_1):\MG_DQ-DQS_FAR_DIMM_NG_M_J_BYTE7\" )
					)
					( Status sCSetFlattened )
					( Origin gBackEnd )
				)
				( attribute "RELATIVE_PROPAGATION_DELAY" "0.00 MIL,195.00 MIL"
					( Parent
						( matchGroupRef "@baseboard_fab2_lib.baseboard_fab2(sch_1):\MG_DQ-DQS_FAR_DIMM_NG_M_J_BYTE7\" )
					)
					( Units "uMatchProp" "ns" 1.000000)
					( Status sCSetFlattened )
					( Origin gBackEnd )
				)
				( attribute "RELATIVE_PROPAGATION_DELAY_SCOPE" "G"
					( Parent
						( matchGroupRef "@baseboard_fab2_lib.baseboard_fab2(sch_1):\MG_DQ_FAR_DIMM_NG_M_J_BYTE7\" )
					)
					( Status sCSetFlattened )
					( Origin gBackEnd )
				)
				( attribute "RELATIVE_PROPAGATION_DELAY" "-50.00 MIL,50.00 MIL"
					( Parent
						( matchGroupRef "@baseboard_fab2_lib.baseboard_fab2(sch_1):\MG_DQ_FAR_DIMM_NG_M_J_BYTE7\" )
					)
					( Units "uMatchProp" "ns" 1.000000)
					( Status sCSetFlattened )
					( Origin gBackEnd )
				)
			)
			( pinPair "@baseboard_fab2_lib.baseboard_fab2(sch_1):\PP2343\"
				( pinRef "@baseboard_fab2_lib.baseboard_fab2(sch_1):page59_i172:DDR2_DQ(62)" )
				( pinRef "@baseboard_fab2_lib.baseboard_fab2(sch_1):page82_i187:DQ(62)" )
				( attribute "RELATIVE_PROPAGATION_DELAY_SCOPE" "G"
					( Parent
						( matchGroupRef "@baseboard_fab2_lib.baseboard_fab2(sch_1):\MG_DQ-DQS_NEAR_DIMM_NG_M_J_BYTE7\" )
					)
					( Status sCSetFlattened )
					( Origin gBackEnd )
				)
				( attribute "RELATIVE_PROPAGATION_DELAY" "0.00 MIL,195.00 MIL"
					( Parent
						( matchGroupRef "@baseboard_fab2_lib.baseboard_fab2(sch_1):\MG_DQ-DQS_NEAR_DIMM_NG_M_J_BYTE7\" )
					)
					( Units "uMatchProp" "ns" 1.000000)
					( Status sCSetFlattened )
					( Origin gBackEnd )
				)
				( attribute "RELATIVE_PROPAGATION_DELAY_SCOPE" "G"
					( Parent
						( matchGroupRef "@baseboard_fab2_lib.baseboard_fab2(sch_1):\MG_DQ_NEAR_DIMM_NG_M_J_BYTE7\" )
					)
					( Status sCSetFlattened )
					( Origin gBackEnd )
				)
				( attribute "RELATIVE_PROPAGATION_DELAY" "-50.00 MIL,50.00 MIL"
					( Parent
						( matchGroupRef "@baseboard_fab2_lib.baseboard_fab2(sch_1):\MG_DQ_NEAR_DIMM_NG_M_J_BYTE7\" )
					)
					( Units "uMatchProp" "ns" 1.000000)
					( Status sCSetFlattened )
					( Origin gBackEnd )
				)
			)
			( pinPair "@baseboard_fab2_lib.baseboard_fab2(sch_1):\PP2344\"
				( pinRef "@baseboard_fab2_lib.baseboard_fab2(sch_1):page59_i172:DDR2_DQ(63)" )
				( pinRef "@baseboard_fab2_lib.baseboard_fab2(sch_1):page81_i186:DQ(62)" )
				( attribute "RELATIVE_PROPAGATION_DELAY_SCOPE" "G"
					( Parent
						( matchGroupRef "@baseboard_fab2_lib.baseboard_fab2(sch_1):\MG_DQ-DQS_FAR_DIMM_NG_M_J_BYTE7\" )
					)
					( Status sCSetFlattened )
					( Origin gBackEnd )
				)
				( attribute "RELATIVE_PROPAGATION_DELAY" "0.00 MIL,195.00 MIL"
					( Parent
						( matchGroupRef "@baseboard_fab2_lib.baseboard_fab2(sch_1):\MG_DQ-DQS_FAR_DIMM_NG_M_J_BYTE7\" )
					)
					( Units "uMatchProp" "ns" 1.000000)
					( Status sCSetFlattened )
					( Origin gBackEnd )
				)
				( attribute "RELATIVE_PROPAGATION_DELAY_SCOPE" "G"
					( Parent
						( matchGroupRef "@baseboard_fab2_lib.baseboard_fab2(sch_1):\MG_DQ_FAR_DIMM_NG_M_J_BYTE7\" )
					)
					( Status sCSetFlattened )
					( Origin gBackEnd )
				)
				( attribute "RELATIVE_PROPAGATION_DELAY" "-50.00 MIL,50.00 MIL"
					( Parent
						( matchGroupRef "@baseboard_fab2_lib.baseboard_fab2(sch_1):\MG_DQ_FAR_DIMM_NG_M_J_BYTE7\" )
					)
					( Units "uMatchProp" "ns" 1.000000)
					( Status sCSetFlattened )
					( Origin gBackEnd )
				)
			)
			( pinPair "@baseboard_fab2_lib.baseboard_fab2(sch_1):\PP2346\"
				( pinRef "@baseboard_fab2_lib.baseboard_fab2(sch_1):page59_i172:DDR2_DQ(63)" )
				( pinRef "@baseboard_fab2_lib.baseboard_fab2(sch_1):page82_i187:DQ(63)" )
				( attribute "RELATIVE_PROPAGATION_DELAY_SCOPE" "G"
					( Parent
						( matchGroupRef "@baseboard_fab2_lib.baseboard_fab2(sch_1):\MG_DQ-DQS_NEAR_DIMM_NG_M_J_BYTE7\" )
					)
					( Status sCSetFlattened )
					( Origin gBackEnd )
				)
				( attribute "RELATIVE_PROPAGATION_DELAY" "0.00 MIL,195.00 MIL"
					( Parent
						( matchGroupRef "@baseboard_fab2_lib.baseboard_fab2(sch_1):\MG_DQ-DQS_NEAR_DIMM_NG_M_J_BYTE7\" )
					)
					( Units "uMatchProp" "ns" 1.000000)
					( Status sCSetFlattened )
					( Origin gBackEnd )
				)
				( attribute "RELATIVE_PROPAGATION_DELAY_SCOPE" "G"
					( Parent
						( matchGroupRef "@baseboard_fab2_lib.baseboard_fab2(sch_1):\MG_DQ_NEAR_DIMM_NG_M_J_BYTE7\" )
					)
					( Status sCSetFlattened )
					( Origin gBackEnd )
				)
				( attribute "RELATIVE_PROPAGATION_DELAY" "-50.00 MIL,50.00 MIL"
					( Parent
						( matchGroupRef "@baseboard_fab2_lib.baseboard_fab2(sch_1):\MG_DQ_NEAR_DIMM_NG_M_J_BYTE7\" )
					)
					( Units "uMatchProp" "ns" 1.000000)
					( Status sCSetFlattened )
					( Origin gBackEnd )
				)
			)
			( pinPair "@baseboard_fab2_lib.baseboard_fab2(sch_1):\PP2275\"
				( pinRef "@baseboard_fab2_lib.baseboard_fab2(sch_1):page60_i172:DDR3_DQ(0)" )
				( pinRef "@baseboard_fab2_lib.baseboard_fab2(sch_1):page83_i111:DQ(1)" )
				( attribute "RELATIVE_PROPAGATION_DELAY_SCOPE" "G"
					( Parent
						( matchGroupRef "@baseboard_fab2_lib.baseboard_fab2(sch_1):\MG_DQ-DQS_FAR_DIMM_NG_M_K_BYTE0\" )
					)
					( Status sCSetFlattened )
					( Origin gBackEnd )
				)
				( attribute "RELATIVE_PROPAGATION_DELAY" "0.00 MIL,195.00 MIL"
					( Parent
						( matchGroupRef "@baseboard_fab2_lib.baseboard_fab2(sch_1):\MG_DQ-DQS_FAR_DIMM_NG_M_K_BYTE0\" )
					)
					( Units "uMatchProp" "ns" 1.000000)
					( Status sCSetFlattened )
					( Origin gBackEnd )
				)
				( attribute "RELATIVE_PROPAGATION_DELAY_SCOPE" "G"
					( Parent
						( matchGroupRef "@baseboard_fab2_lib.baseboard_fab2(sch_1):\MG_DQ_FAR_DIMM_NG_M_K_BYTE0\" )
					)
					( Status sCSetFlattened )
					( Origin gBackEnd )
				)
				( attribute "RELATIVE_PROPAGATION_DELAY" "-50.00 MIL,50.00 MIL"
					( Parent
						( matchGroupRef "@baseboard_fab2_lib.baseboard_fab2(sch_1):\MG_DQ_FAR_DIMM_NG_M_K_BYTE0\" )
					)
					( Units "uMatchProp" "ns" 1.000000)
					( Status sCSetFlattened )
					( Origin gBackEnd )
				)
			)
			( pinPair "@baseboard_fab2_lib.baseboard_fab2(sch_1):\PP2276\"
				( pinRef "@baseboard_fab2_lib.baseboard_fab2(sch_1):page60_i172:DDR3_DQ(0)" )
				( pinRef "@baseboard_fab2_lib.baseboard_fab2(sch_1):page84_i14:DQ(0)" )
				( attribute "RELATIVE_PROPAGATION_DELAY_SCOPE" "G"
					( Parent
						( matchGroupRef "@baseboard_fab2_lib.baseboard_fab2(sch_1):\MG_DQ-DQS_NEAR_DIMM_NG_M_K_BYTE0\" )
					)
					( Status sCSetFlattened )
					( Origin gBackEnd )
				)
				( attribute "RELATIVE_PROPAGATION_DELAY" "0.00 MIL,195.00 MIL"
					( Parent
						( matchGroupRef "@baseboard_fab2_lib.baseboard_fab2(sch_1):\MG_DQ-DQS_NEAR_DIMM_NG_M_K_BYTE0\" )
					)
					( Units "uMatchProp" "ns" 1.000000)
					( Status sCSetFlattened )
					( Origin gBackEnd )
				)
				( attribute "RELATIVE_PROPAGATION_DELAY_SCOPE" "G"
					( Parent
						( matchGroupRef "@baseboard_fab2_lib.baseboard_fab2(sch_1):\MG_DQ_NEAR_DIMM_NG_M_K_BYTE0\" )
					)
					( Status sCSetFlattened )
					( Origin gBackEnd )
				)
				( attribute "RELATIVE_PROPAGATION_DELAY" "-50.00 MIL,50.00 MIL"
					( Parent
						( matchGroupRef "@baseboard_fab2_lib.baseboard_fab2(sch_1):\MG_DQ_NEAR_DIMM_NG_M_K_BYTE0\" )
					)
					( Units "uMatchProp" "ns" 1.000000)
					( Status sCSetFlattened )
					( Origin gBackEnd )
				)
			)
			( pinPair "@baseboard_fab2_lib.baseboard_fab2(sch_1):\PP2278\"
				( pinRef "@baseboard_fab2_lib.baseboard_fab2(sch_1):page60_i172:DDR3_DQ(1)" )
				( pinRef "@baseboard_fab2_lib.baseboard_fab2(sch_1):page83_i111:DQ(0)" )
				( attribute "RELATIVE_PROPAGATION_DELAY_SCOPE" "G"
					( Parent
						( matchGroupRef "@baseboard_fab2_lib.baseboard_fab2(sch_1):\MG_DQ-DQS_FAR_DIMM_NG_M_K_BYTE0\" )
					)
					( Status sCSetFlattened )
					( Origin gBackEnd )
				)
				( attribute "RELATIVE_PROPAGATION_DELAY" "0.00 MIL,195.00 MIL"
					( Parent
						( matchGroupRef "@baseboard_fab2_lib.baseboard_fab2(sch_1):\MG_DQ-DQS_FAR_DIMM_NG_M_K_BYTE0\" )
					)
					( Units "uMatchProp" "ns" 1.000000)
					( Status sCSetFlattened )
					( Origin gBackEnd )
				)
				( attribute "RELATIVE_PROPAGATION_DELAY_SCOPE" "G"
					( Parent
						( matchGroupRef "@baseboard_fab2_lib.baseboard_fab2(sch_1):\MG_DQ_FAR_DIMM_NG_M_K_BYTE0\" )
					)
					( Status sCSetFlattened )
					( Origin gBackEnd )
				)
				( attribute "RELATIVE_PROPAGATION_DELAY" "-50.00 MIL,50.00 MIL"
					( Parent
						( matchGroupRef "@baseboard_fab2_lib.baseboard_fab2(sch_1):\MG_DQ_FAR_DIMM_NG_M_K_BYTE0\" )
					)
					( Units "uMatchProp" "ns" 1.000000)
					( Status sCSetFlattened )
					( Origin gBackEnd )
				)
			)
			( pinPair "@baseboard_fab2_lib.baseboard_fab2(sch_1):\PP2279\"
				( pinRef "@baseboard_fab2_lib.baseboard_fab2(sch_1):page60_i172:DDR3_DQ(1)" )
				( pinRef "@baseboard_fab2_lib.baseboard_fab2(sch_1):page84_i14:DQ(1)" )
				( attribute "RELATIVE_PROPAGATION_DELAY_SCOPE" "G"
					( Parent
						( matchGroupRef "@baseboard_fab2_lib.baseboard_fab2(sch_1):\MG_DQ-DQS_NEAR_DIMM_NG_M_K_BYTE0\" )
					)
					( Status sCSetFlattened )
					( Origin gBackEnd )
				)
				( attribute "RELATIVE_PROPAGATION_DELAY" "0.00 MIL,195.00 MIL"
					( Parent
						( matchGroupRef "@baseboard_fab2_lib.baseboard_fab2(sch_1):\MG_DQ-DQS_NEAR_DIMM_NG_M_K_BYTE0\" )
					)
					( Units "uMatchProp" "ns" 1.000000)
					( Status sCSetFlattened )
					( Origin gBackEnd )
				)
				( attribute "RELATIVE_PROPAGATION_DELAY_SCOPE" "G"
					( Parent
						( matchGroupRef "@baseboard_fab2_lib.baseboard_fab2(sch_1):\MG_DQ_NEAR_DIMM_NG_M_K_BYTE0\" )
					)
					( Status sCSetFlattened )
					( Origin gBackEnd )
				)
				( attribute "RELATIVE_PROPAGATION_DELAY" "-50.00 MIL,50.00 MIL"
					( Parent
						( matchGroupRef "@baseboard_fab2_lib.baseboard_fab2(sch_1):\MG_DQ_NEAR_DIMM_NG_M_K_BYTE0\" )
					)
					( Units "uMatchProp" "ns" 1.000000)
					( Status sCSetFlattened )
					( Origin gBackEnd )
				)
			)
			( pinPair "@baseboard_fab2_lib.baseboard_fab2(sch_1):\PP2281\"
				( pinRef "@baseboard_fab2_lib.baseboard_fab2(sch_1):page60_i172:DDR3_DQ(2)" )
				( pinRef "@baseboard_fab2_lib.baseboard_fab2(sch_1):page83_i111:DQ(3)" )
				( attribute "RELATIVE_PROPAGATION_DELAY_SCOPE" "G"
					( Parent
						( matchGroupRef "@baseboard_fab2_lib.baseboard_fab2(sch_1):\MG_DQ-DQS_FAR_DIMM_NG_M_K_BYTE0\" )
					)
					( Status sCSetFlattened )
					( Origin gBackEnd )
				)
				( attribute "RELATIVE_PROPAGATION_DELAY" "0.00 MIL,195.00 MIL"
					( Parent
						( matchGroupRef "@baseboard_fab2_lib.baseboard_fab2(sch_1):\MG_DQ-DQS_FAR_DIMM_NG_M_K_BYTE0\" )
					)
					( Units "uMatchProp" "ns" 1.000000)
					( Status sCSetFlattened )
					( Origin gBackEnd )
				)
				( attribute "RELATIVE_PROPAGATION_DELAY_SCOPE" "G"
					( Parent
						( matchGroupRef "@baseboard_fab2_lib.baseboard_fab2(sch_1):\MG_DQ_FAR_DIMM_NG_M_K_BYTE0\" )
					)
					( Status sCSetFlattened )
					( Origin gBackEnd )
				)
				( attribute "RELATIVE_PROPAGATION_DELAY" "-50.00 MIL,50.00 MIL"
					( Parent
						( matchGroupRef "@baseboard_fab2_lib.baseboard_fab2(sch_1):\MG_DQ_FAR_DIMM_NG_M_K_BYTE0\" )
					)
					( Units "uMatchProp" "ns" 1.000000)
					( Status sCSetFlattened )
					( Origin gBackEnd )
				)
			)
			( pinPair "@baseboard_fab2_lib.baseboard_fab2(sch_1):\PP2282\"
				( pinRef "@baseboard_fab2_lib.baseboard_fab2(sch_1):page60_i172:DDR3_DQ(2)" )
				( pinRef "@baseboard_fab2_lib.baseboard_fab2(sch_1):page84_i14:DQ(2)" )
				( attribute "RELATIVE_PROPAGATION_DELAY_SCOPE" "G"
					( Parent
						( matchGroupRef "@baseboard_fab2_lib.baseboard_fab2(sch_1):\MG_DQ-DQS_NEAR_DIMM_NG_M_K_BYTE0\" )
					)
					( Status sCSetFlattened )
					( Origin gBackEnd )
				)
				( attribute "RELATIVE_PROPAGATION_DELAY" "0.00 MIL,195.00 MIL"
					( Parent
						( matchGroupRef "@baseboard_fab2_lib.baseboard_fab2(sch_1):\MG_DQ-DQS_NEAR_DIMM_NG_M_K_BYTE0\" )
					)
					( Units "uMatchProp" "ns" 1.000000)
					( Status sCSetFlattened )
					( Origin gBackEnd )
				)
				( attribute "RELATIVE_PROPAGATION_DELAY_SCOPE" "G"
					( Parent
						( matchGroupRef "@baseboard_fab2_lib.baseboard_fab2(sch_1):\MG_DQ_NEAR_DIMM_NG_M_K_BYTE0\" )
					)
					( Status sCSetFlattened )
					( Origin gBackEnd )
				)
				( attribute "RELATIVE_PROPAGATION_DELAY" "-50.00 MIL,50.00 MIL"
					( Parent
						( matchGroupRef "@baseboard_fab2_lib.baseboard_fab2(sch_1):\MG_DQ_NEAR_DIMM_NG_M_K_BYTE0\" )
					)
					( Units "uMatchProp" "ns" 1.000000)
					( Status sCSetFlattened )
					( Origin gBackEnd )
				)
			)
			( pinPair "@baseboard_fab2_lib.baseboard_fab2(sch_1):\PP2284\"
				( pinRef "@baseboard_fab2_lib.baseboard_fab2(sch_1):page60_i172:DDR3_DQ(3)" )
				( pinRef "@baseboard_fab2_lib.baseboard_fab2(sch_1):page83_i111:DQ(2)" )
				( attribute "RELATIVE_PROPAGATION_DELAY_SCOPE" "G"
					( Parent
						( matchGroupRef "@baseboard_fab2_lib.baseboard_fab2(sch_1):\MG_DQ-DQS_FAR_DIMM_NG_M_K_BYTE0\" )
					)
					( Status sCSetFlattened )
					( Origin gBackEnd )
				)
				( attribute "RELATIVE_PROPAGATION_DELAY" "0.00 MIL,195.00 MIL"
					( Parent
						( matchGroupRef "@baseboard_fab2_lib.baseboard_fab2(sch_1):\MG_DQ-DQS_FAR_DIMM_NG_M_K_BYTE0\" )
					)
					( Units "uMatchProp" "ns" 1.000000)
					( Status sCSetFlattened )
					( Origin gBackEnd )
				)
				( attribute "RELATIVE_PROPAGATION_DELAY_SCOPE" "G"
					( Parent
						( matchGroupRef "@baseboard_fab2_lib.baseboard_fab2(sch_1):\MG_DQ_FAR_DIMM_NG_M_K_BYTE0\" )
					)
					( Status sCSetFlattened )
					( Origin gBackEnd )
				)
				( attribute "RELATIVE_PROPAGATION_DELAY" "-50.00 MIL,50.00 MIL"
					( Parent
						( matchGroupRef "@baseboard_fab2_lib.baseboard_fab2(sch_1):\MG_DQ_FAR_DIMM_NG_M_K_BYTE0\" )
					)
					( Units "uMatchProp" "ns" 1.000000)
					( Status sCSetFlattened )
					( Origin gBackEnd )
				)
			)
			( pinPair "@baseboard_fab2_lib.baseboard_fab2(sch_1):\PP2285\"
				( pinRef "@baseboard_fab2_lib.baseboard_fab2(sch_1):page60_i172:DDR3_DQ(3)" )
				( pinRef "@baseboard_fab2_lib.baseboard_fab2(sch_1):page84_i14:DQ(3)" )
				( attribute "RELATIVE_PROPAGATION_DELAY_SCOPE" "G"
					( Parent
						( matchGroupRef "@baseboard_fab2_lib.baseboard_fab2(sch_1):\MG_DQ-DQS_NEAR_DIMM_NG_M_K_BYTE0\" )
					)
					( Status sCSetFlattened )
					( Origin gBackEnd )
				)
				( attribute "RELATIVE_PROPAGATION_DELAY" "0.00 MIL,195.00 MIL"
					( Parent
						( matchGroupRef "@baseboard_fab2_lib.baseboard_fab2(sch_1):\MG_DQ-DQS_NEAR_DIMM_NG_M_K_BYTE0\" )
					)
					( Units "uMatchProp" "ns" 1.000000)
					( Status sCSetFlattened )
					( Origin gBackEnd )
				)
				( attribute "RELATIVE_PROPAGATION_DELAY_SCOPE" "G"
					( Parent
						( matchGroupRef "@baseboard_fab2_lib.baseboard_fab2(sch_1):\MG_DQ_NEAR_DIMM_NG_M_K_BYTE0\" )
					)
					( Status sCSetFlattened )
					( Origin gBackEnd )
				)
				( attribute "RELATIVE_PROPAGATION_DELAY" "-50.00 MIL,50.00 MIL"
					( Parent
						( matchGroupRef "@baseboard_fab2_lib.baseboard_fab2(sch_1):\MG_DQ_NEAR_DIMM_NG_M_K_BYTE0\" )
					)
					( Units "uMatchProp" "ns" 1.000000)
					( Status sCSetFlattened )
					( Origin gBackEnd )
				)
			)
			( pinPair "@baseboard_fab2_lib.baseboard_fab2(sch_1):\PP2287\"
				( pinRef "@baseboard_fab2_lib.baseboard_fab2(sch_1):page60_i172:DDR3_DQ(4)" )
				( pinRef "@baseboard_fab2_lib.baseboard_fab2(sch_1):page83_i111:DQ(5)" )
				( attribute "RELATIVE_PROPAGATION_DELAY_SCOPE" "G"
					( Parent
						( matchGroupRef "@baseboard_fab2_lib.baseboard_fab2(sch_1):\MG_DQ-DQS_FAR_DIMM_NG_M_K_BYTE0\" )
					)
					( Status sCSetFlattened )
					( Origin gBackEnd )
				)
				( attribute "RELATIVE_PROPAGATION_DELAY" "0.00 MIL,195.00 MIL"
					( Parent
						( matchGroupRef "@baseboard_fab2_lib.baseboard_fab2(sch_1):\MG_DQ-DQS_FAR_DIMM_NG_M_K_BYTE0\" )
					)
					( Units "uMatchProp" "ns" 1.000000)
					( Status sCSetFlattened )
					( Origin gBackEnd )
				)
				( attribute "RELATIVE_PROPAGATION_DELAY_SCOPE" "G"
					( Parent
						( matchGroupRef "@baseboard_fab2_lib.baseboard_fab2(sch_1):\MG_DQ_FAR_DIMM_NG_M_K_BYTE0\" )
					)
					( Status sCSetFlattened )
					( Origin gBackEnd )
				)
				( attribute "RELATIVE_PROPAGATION_DELAY" "-50.00 MIL,50.00 MIL"
					( Parent
						( matchGroupRef "@baseboard_fab2_lib.baseboard_fab2(sch_1):\MG_DQ_FAR_DIMM_NG_M_K_BYTE0\" )
					)
					( Units "uMatchProp" "ns" 1.000000)
					( Status sCSetFlattened )
					( Origin gBackEnd )
				)
			)
			( pinPair "@baseboard_fab2_lib.baseboard_fab2(sch_1):\PP2288\"
				( pinRef "@baseboard_fab2_lib.baseboard_fab2(sch_1):page60_i172:DDR3_DQ(4)" )
				( pinRef "@baseboard_fab2_lib.baseboard_fab2(sch_1):page84_i14:DQ(4)" )
				( attribute "RELATIVE_PROPAGATION_DELAY_SCOPE" "G"
					( Parent
						( matchGroupRef "@baseboard_fab2_lib.baseboard_fab2(sch_1):\MG_DQ-DQS_NEAR_DIMM_NG_M_K_BYTE0\" )
					)
					( Status sCSetFlattened )
					( Origin gBackEnd )
				)
				( attribute "RELATIVE_PROPAGATION_DELAY" "0.00 MIL,195.00 MIL"
					( Parent
						( matchGroupRef "@baseboard_fab2_lib.baseboard_fab2(sch_1):\MG_DQ-DQS_NEAR_DIMM_NG_M_K_BYTE0\" )
					)
					( Units "uMatchProp" "ns" 1.000000)
					( Status sCSetFlattened )
					( Origin gBackEnd )
				)
				( attribute "RELATIVE_PROPAGATION_DELAY_SCOPE" "G"
					( Parent
						( matchGroupRef "@baseboard_fab2_lib.baseboard_fab2(sch_1):\MG_DQ_NEAR_DIMM_NG_M_K_BYTE0\" )
					)
					( Status sCSetFlattened )
					( Origin gBackEnd )
				)
				( attribute "RELATIVE_PROPAGATION_DELAY" "-50.00 MIL,50.00 MIL"
					( Parent
						( matchGroupRef "@baseboard_fab2_lib.baseboard_fab2(sch_1):\MG_DQ_NEAR_DIMM_NG_M_K_BYTE0\" )
					)
					( Units "uMatchProp" "ns" 1.000000)
					( Status sCSetFlattened )
					( Origin gBackEnd )
				)
			)
			( pinPair "@baseboard_fab2_lib.baseboard_fab2(sch_1):\PP2290\"
				( pinRef "@baseboard_fab2_lib.baseboard_fab2(sch_1):page60_i172:DDR3_DQ(5)" )
				( pinRef "@baseboard_fab2_lib.baseboard_fab2(sch_1):page83_i111:DQ(4)" )
				( attribute "RELATIVE_PROPAGATION_DELAY_SCOPE" "G"
					( Parent
						( matchGroupRef "@baseboard_fab2_lib.baseboard_fab2(sch_1):\MG_DQ-DQS_FAR_DIMM_NG_M_K_BYTE0\" )
					)
					( Status sCSetFlattened )
					( Origin gBackEnd )
				)
				( attribute "RELATIVE_PROPAGATION_DELAY" "0.00 MIL,195.00 MIL"
					( Parent
						( matchGroupRef "@baseboard_fab2_lib.baseboard_fab2(sch_1):\MG_DQ-DQS_FAR_DIMM_NG_M_K_BYTE0\" )
					)
					( Units "uMatchProp" "ns" 1.000000)
					( Status sCSetFlattened )
					( Origin gBackEnd )
				)
				( attribute "RELATIVE_PROPAGATION_DELAY_SCOPE" "G"
					( Parent
						( matchGroupRef "@baseboard_fab2_lib.baseboard_fab2(sch_1):\MG_DQ_FAR_DIMM_NG_M_K_BYTE0\" )
					)
					( Status sCSetFlattened )
					( Origin gBackEnd )
				)
				( attribute "RELATIVE_PROPAGATION_DELAY" "-50.00 MIL,50.00 MIL"
					( Parent
						( matchGroupRef "@baseboard_fab2_lib.baseboard_fab2(sch_1):\MG_DQ_FAR_DIMM_NG_M_K_BYTE0\" )
					)
					( Units "uMatchProp" "ns" 1.000000)
					( Status sCSetFlattened )
					( Origin gBackEnd )
				)
			)
			( pinPair "@baseboard_fab2_lib.baseboard_fab2(sch_1):\PP2291\"
				( pinRef "@baseboard_fab2_lib.baseboard_fab2(sch_1):page60_i172:DDR3_DQ(5)" )
				( pinRef "@baseboard_fab2_lib.baseboard_fab2(sch_1):page84_i14:DQ(5)" )
				( attribute "RELATIVE_PROPAGATION_DELAY_SCOPE" "G"
					( Parent
						( matchGroupRef "@baseboard_fab2_lib.baseboard_fab2(sch_1):\MG_DQ-DQS_NEAR_DIMM_NG_M_K_BYTE0\" )
					)
					( Status sCSetFlattened )
					( Origin gBackEnd )
				)
				( attribute "RELATIVE_PROPAGATION_DELAY" "0.00 MIL,195.00 MIL"
					( Parent
						( matchGroupRef "@baseboard_fab2_lib.baseboard_fab2(sch_1):\MG_DQ-DQS_NEAR_DIMM_NG_M_K_BYTE0\" )
					)
					( Units "uMatchProp" "ns" 1.000000)
					( Status sCSetFlattened )
					( Origin gBackEnd )
				)
				( attribute "RELATIVE_PROPAGATION_DELAY_SCOPE" "G"
					( Parent
						( matchGroupRef "@baseboard_fab2_lib.baseboard_fab2(sch_1):\MG_DQ_NEAR_DIMM_NG_M_K_BYTE0\" )
					)
					( Status sCSetFlattened )
					( Origin gBackEnd )
				)
				( attribute "RELATIVE_PROPAGATION_DELAY" "-50.00 MIL,50.00 MIL"
					( Parent
						( matchGroupRef "@baseboard_fab2_lib.baseboard_fab2(sch_1):\MG_DQ_NEAR_DIMM_NG_M_K_BYTE0\" )
					)
					( Units "uMatchProp" "ns" 1.000000)
					( Status sCSetFlattened )
					( Origin gBackEnd )
				)
			)
			( pinPair "@baseboard_fab2_lib.baseboard_fab2(sch_1):\PP2293\"
				( pinRef "@baseboard_fab2_lib.baseboard_fab2(sch_1):page60_i172:DDR3_DQ(6)" )
				( pinRef "@baseboard_fab2_lib.baseboard_fab2(sch_1):page83_i111:DQ(7)" )
				( attribute "RELATIVE_PROPAGATION_DELAY_SCOPE" "G"
					( Parent
						( matchGroupRef "@baseboard_fab2_lib.baseboard_fab2(sch_1):\MG_DQ-DQS_FAR_DIMM_NG_M_K_BYTE0\" )
					)
					( Status sCSetFlattened )
					( Origin gBackEnd )
				)
				( attribute "RELATIVE_PROPAGATION_DELAY" "0.00 MIL,195.00 MIL"
					( Parent
						( matchGroupRef "@baseboard_fab2_lib.baseboard_fab2(sch_1):\MG_DQ-DQS_FAR_DIMM_NG_M_K_BYTE0\" )
					)
					( Units "uMatchProp" "ns" 1.000000)
					( Status sCSetFlattened )
					( Origin gBackEnd )
				)
				( attribute "RELATIVE_PROPAGATION_DELAY_SCOPE" "G"
					( Parent
						( matchGroupRef "@baseboard_fab2_lib.baseboard_fab2(sch_1):\MG_DQ_FAR_DIMM_NG_M_K_BYTE0\" )
					)
					( Status sCSetFlattened )
					( Origin gBackEnd )
				)
				( attribute "RELATIVE_PROPAGATION_DELAY" "-50.00 MIL,50.00 MIL"
					( Parent
						( matchGroupRef "@baseboard_fab2_lib.baseboard_fab2(sch_1):\MG_DQ_FAR_DIMM_NG_M_K_BYTE0\" )
					)
					( Units "uMatchProp" "ns" 1.000000)
					( Status sCSetFlattened )
					( Origin gBackEnd )
				)
			)
			( pinPair "@baseboard_fab2_lib.baseboard_fab2(sch_1):\PP2294\"
				( pinRef "@baseboard_fab2_lib.baseboard_fab2(sch_1):page60_i172:DDR3_DQ(6)" )
				( pinRef "@baseboard_fab2_lib.baseboard_fab2(sch_1):page84_i14:DQ(6)" )
				( attribute "RELATIVE_PROPAGATION_DELAY_SCOPE" "G"
					( Parent
						( matchGroupRef "@baseboard_fab2_lib.baseboard_fab2(sch_1):\MG_DQ-DQS_NEAR_DIMM_NG_M_K_BYTE0\" )
					)
					( Status sCSetFlattened )
					( Origin gBackEnd )
				)
				( attribute "RELATIVE_PROPAGATION_DELAY" "0.00 MIL,195.00 MIL"
					( Parent
						( matchGroupRef "@baseboard_fab2_lib.baseboard_fab2(sch_1):\MG_DQ-DQS_NEAR_DIMM_NG_M_K_BYTE0\" )
					)
					( Units "uMatchProp" "ns" 1.000000)
					( Status sCSetFlattened )
					( Origin gBackEnd )
				)
				( attribute "RELATIVE_PROPAGATION_DELAY_SCOPE" "G"
					( Parent
						( matchGroupRef "@baseboard_fab2_lib.baseboard_fab2(sch_1):\MG_DQ_NEAR_DIMM_NG_M_K_BYTE0\" )
					)
					( Status sCSetFlattened )
					( Origin gBackEnd )
				)
				( attribute "RELATIVE_PROPAGATION_DELAY" "-50.00 MIL,50.00 MIL"
					( Parent
						( matchGroupRef "@baseboard_fab2_lib.baseboard_fab2(sch_1):\MG_DQ_NEAR_DIMM_NG_M_K_BYTE0\" )
					)
					( Units "uMatchProp" "ns" 1.000000)
					( Status sCSetFlattened )
					( Origin gBackEnd )
				)
			)
			( pinPair "@baseboard_fab2_lib.baseboard_fab2(sch_1):\PP2296\"
				( pinRef "@baseboard_fab2_lib.baseboard_fab2(sch_1):page60_i172:DDR3_DQ(7)" )
				( pinRef "@baseboard_fab2_lib.baseboard_fab2(sch_1):page83_i111:DQ(6)" )
				( attribute "RELATIVE_PROPAGATION_DELAY_SCOPE" "G"
					( Parent
						( matchGroupRef "@baseboard_fab2_lib.baseboard_fab2(sch_1):\MG_DQ-DQS_FAR_DIMM_NG_M_K_BYTE0\" )
					)
					( Status sCSetFlattened )
					( Origin gBackEnd )
				)
				( attribute "RELATIVE_PROPAGATION_DELAY" "0.00 MIL,195.00 MIL"
					( Parent
						( matchGroupRef "@baseboard_fab2_lib.baseboard_fab2(sch_1):\MG_DQ-DQS_FAR_DIMM_NG_M_K_BYTE0\" )
					)
					( Units "uMatchProp" "ns" 1.000000)
					( Status sCSetFlattened )
					( Origin gBackEnd )
				)
				( attribute "RELATIVE_PROPAGATION_DELAY_SCOPE" "G"
					( Parent
						( matchGroupRef "@baseboard_fab2_lib.baseboard_fab2(sch_1):\MG_DQ_FAR_DIMM_NG_M_K_BYTE0\" )
					)
					( Status sCSetFlattened )
					( Origin gBackEnd )
				)
				( attribute "RELATIVE_PROPAGATION_DELAY" "-50.00 MIL,50.00 MIL"
					( Parent
						( matchGroupRef "@baseboard_fab2_lib.baseboard_fab2(sch_1):\MG_DQ_FAR_DIMM_NG_M_K_BYTE0\" )
					)
					( Units "uMatchProp" "ns" 1.000000)
					( Status sCSetFlattened )
					( Origin gBackEnd )
				)
			)
			( pinPair "@baseboard_fab2_lib.baseboard_fab2(sch_1):\PP2297\"
				( pinRef "@baseboard_fab2_lib.baseboard_fab2(sch_1):page60_i172:DDR3_DQ(7)" )
				( pinRef "@baseboard_fab2_lib.baseboard_fab2(sch_1):page84_i14:DQ(7)" )
				( attribute "RELATIVE_PROPAGATION_DELAY_SCOPE" "G"
					( Parent
						( matchGroupRef "@baseboard_fab2_lib.baseboard_fab2(sch_1):\MG_DQ-DQS_NEAR_DIMM_NG_M_K_BYTE0\" )
					)
					( Status sCSetFlattened )
					( Origin gBackEnd )
				)
				( attribute "RELATIVE_PROPAGATION_DELAY" "0.00 MIL,195.00 MIL"
					( Parent
						( matchGroupRef "@baseboard_fab2_lib.baseboard_fab2(sch_1):\MG_DQ-DQS_NEAR_DIMM_NG_M_K_BYTE0\" )
					)
					( Units "uMatchProp" "ns" 1.000000)
					( Status sCSetFlattened )
					( Origin gBackEnd )
				)
				( attribute "RELATIVE_PROPAGATION_DELAY_SCOPE" "G"
					( Parent
						( matchGroupRef "@baseboard_fab2_lib.baseboard_fab2(sch_1):\MG_DQ_NEAR_DIMM_NG_M_K_BYTE0\" )
					)
					( Status sCSetFlattened )
					( Origin gBackEnd )
				)
				( attribute "RELATIVE_PROPAGATION_DELAY" "-50.00 MIL,50.00 MIL"
					( Parent
						( matchGroupRef "@baseboard_fab2_lib.baseboard_fab2(sch_1):\MG_DQ_NEAR_DIMM_NG_M_K_BYTE0\" )
					)
					( Units "uMatchProp" "ns" 1.000000)
					( Status sCSetFlattened )
					( Origin gBackEnd )
				)
			)
			( pinPair "@baseboard_fab2_lib.baseboard_fab2(sch_1):\PP2251\"
				( pinRef "@baseboard_fab2_lib.baseboard_fab2(sch_1):page60_i172:DDR3_DQ(8)" )
				( pinRef "@baseboard_fab2_lib.baseboard_fab2(sch_1):page83_i111:DQ(9)" )
				( attribute "RELATIVE_PROPAGATION_DELAY_SCOPE" "G"
					( Parent
						( matchGroupRef "@baseboard_fab2_lib.baseboard_fab2(sch_1):\MG_DQ-DQS_FAR_DIMM_NG_M_K_BYTE1\" )
					)
					( Status sCSetFlattened )
					( Origin gBackEnd )
				)
				( attribute "RELATIVE_PROPAGATION_DELAY" "0.00 MIL,195.00 MIL"
					( Parent
						( matchGroupRef "@baseboard_fab2_lib.baseboard_fab2(sch_1):\MG_DQ-DQS_FAR_DIMM_NG_M_K_BYTE1\" )
					)
					( Units "uMatchProp" "ns" 1.000000)
					( Status sCSetFlattened )
					( Origin gBackEnd )
				)
				( attribute "RELATIVE_PROPAGATION_DELAY_SCOPE" "G"
					( Parent
						( matchGroupRef "@baseboard_fab2_lib.baseboard_fab2(sch_1):\MG_DQ_FAR_DIMM_NG_M_K_BYTE1\" )
					)
					( Status sCSetFlattened )
					( Origin gBackEnd )
				)
				( attribute "RELATIVE_PROPAGATION_DELAY" "-50.00 MIL,50.00 MIL"
					( Parent
						( matchGroupRef "@baseboard_fab2_lib.baseboard_fab2(sch_1):\MG_DQ_FAR_DIMM_NG_M_K_BYTE1\" )
					)
					( Units "uMatchProp" "ns" 1.000000)
					( Status sCSetFlattened )
					( Origin gBackEnd )
				)
			)
			( pinPair "@baseboard_fab2_lib.baseboard_fab2(sch_1):\PP2252\"
				( pinRef "@baseboard_fab2_lib.baseboard_fab2(sch_1):page84_i14:DQ(8)" )
				( pinRef "@baseboard_fab2_lib.baseboard_fab2(sch_1):page60_i172:DDR3_DQ(8)" )
				( attribute "RELATIVE_PROPAGATION_DELAY_SCOPE" "G"
					( Parent
						( matchGroupRef "@baseboard_fab2_lib.baseboard_fab2(sch_1):\MG_DQ-DQS_NEAR_DIMM_NG_M_K_BYTE1\" )
					)
					( Status sCSetFlattened )
					( Origin gBackEnd )
				)
				( attribute "RELATIVE_PROPAGATION_DELAY" "0.00 MIL,195.00 MIL"
					( Parent
						( matchGroupRef "@baseboard_fab2_lib.baseboard_fab2(sch_1):\MG_DQ-DQS_NEAR_DIMM_NG_M_K_BYTE1\" )
					)
					( Units "uMatchProp" "ns" 1.000000)
					( Status sCSetFlattened )
					( Origin gBackEnd )
				)
				( attribute "RELATIVE_PROPAGATION_DELAY_SCOPE" "G"
					( Parent
						( matchGroupRef "@baseboard_fab2_lib.baseboard_fab2(sch_1):\MG_DQ_NEAR_DIMM_NG_M_K_BYTE1\" )
					)
					( Status sCSetFlattened )
					( Origin gBackEnd )
				)
				( attribute "RELATIVE_PROPAGATION_DELAY" "-50.00 MIL,50.00 MIL"
					( Parent
						( matchGroupRef "@baseboard_fab2_lib.baseboard_fab2(sch_1):\MG_DQ_NEAR_DIMM_NG_M_K_BYTE1\" )
					)
					( Units "uMatchProp" "ns" 1.000000)
					( Status sCSetFlattened )
					( Origin gBackEnd )
				)
			)
			( pinPair "@baseboard_fab2_lib.baseboard_fab2(sch_1):\PP2254\"
				( pinRef "@baseboard_fab2_lib.baseboard_fab2(sch_1):page60_i172:DDR3_DQ(9)" )
				( pinRef "@baseboard_fab2_lib.baseboard_fab2(sch_1):page83_i111:DQ(8)" )
				( attribute "RELATIVE_PROPAGATION_DELAY_SCOPE" "G"
					( Parent
						( matchGroupRef "@baseboard_fab2_lib.baseboard_fab2(sch_1):\MG_DQ-DQS_FAR_DIMM_NG_M_K_BYTE1\" )
					)
					( Status sCSetFlattened )
					( Origin gBackEnd )
				)
				( attribute "RELATIVE_PROPAGATION_DELAY" "0.00 MIL,195.00 MIL"
					( Parent
						( matchGroupRef "@baseboard_fab2_lib.baseboard_fab2(sch_1):\MG_DQ-DQS_FAR_DIMM_NG_M_K_BYTE1\" )
					)
					( Units "uMatchProp" "ns" 1.000000)
					( Status sCSetFlattened )
					( Origin gBackEnd )
				)
				( attribute "RELATIVE_PROPAGATION_DELAY_SCOPE" "G"
					( Parent
						( matchGroupRef "@baseboard_fab2_lib.baseboard_fab2(sch_1):\MG_DQ_FAR_DIMM_NG_M_K_BYTE1\" )
					)
					( Status sCSetFlattened )
					( Origin gBackEnd )
				)
				( attribute "RELATIVE_PROPAGATION_DELAY" "-50.00 MIL,50.00 MIL"
					( Parent
						( matchGroupRef "@baseboard_fab2_lib.baseboard_fab2(sch_1):\MG_DQ_FAR_DIMM_NG_M_K_BYTE1\" )
					)
					( Units "uMatchProp" "ns" 1.000000)
					( Status sCSetFlattened )
					( Origin gBackEnd )
				)
			)
			( pinPair "@baseboard_fab2_lib.baseboard_fab2(sch_1):\PP2255\"
				( pinRef "@baseboard_fab2_lib.baseboard_fab2(sch_1):page84_i14:DQ(9)" )
				( pinRef "@baseboard_fab2_lib.baseboard_fab2(sch_1):page60_i172:DDR3_DQ(9)" )
				( attribute "RELATIVE_PROPAGATION_DELAY_SCOPE" "G"
					( Parent
						( matchGroupRef "@baseboard_fab2_lib.baseboard_fab2(sch_1):\MG_DQ-DQS_NEAR_DIMM_NG_M_K_BYTE1\" )
					)
					( Status sCSetFlattened )
					( Origin gBackEnd )
				)
				( attribute "RELATIVE_PROPAGATION_DELAY" "0.00 MIL,195.00 MIL"
					( Parent
						( matchGroupRef "@baseboard_fab2_lib.baseboard_fab2(sch_1):\MG_DQ-DQS_NEAR_DIMM_NG_M_K_BYTE1\" )
					)
					( Units "uMatchProp" "ns" 1.000000)
					( Status sCSetFlattened )
					( Origin gBackEnd )
				)
				( attribute "RELATIVE_PROPAGATION_DELAY_SCOPE" "G"
					( Parent
						( matchGroupRef "@baseboard_fab2_lib.baseboard_fab2(sch_1):\MG_DQ_NEAR_DIMM_NG_M_K_BYTE1\" )
					)
					( Status sCSetFlattened )
					( Origin gBackEnd )
				)
				( attribute "RELATIVE_PROPAGATION_DELAY" "-50.00 MIL,50.00 MIL"
					( Parent
						( matchGroupRef "@baseboard_fab2_lib.baseboard_fab2(sch_1):\MG_DQ_NEAR_DIMM_NG_M_K_BYTE1\" )
					)
					( Units "uMatchProp" "ns" 1.000000)
					( Status sCSetFlattened )
					( Origin gBackEnd )
				)
			)
			( pinPair "@baseboard_fab2_lib.baseboard_fab2(sch_1):\PP2257\"
				( pinRef "@baseboard_fab2_lib.baseboard_fab2(sch_1):page60_i172:DDR3_DQ(10)" )
				( pinRef "@baseboard_fab2_lib.baseboard_fab2(sch_1):page83_i111:DQ(11)" )
				( attribute "RELATIVE_PROPAGATION_DELAY_SCOPE" "G"
					( Parent
						( matchGroupRef "@baseboard_fab2_lib.baseboard_fab2(sch_1):\MG_DQ-DQS_FAR_DIMM_NG_M_K_BYTE1\" )
					)
					( Status sCSetFlattened )
					( Origin gBackEnd )
				)
				( attribute "RELATIVE_PROPAGATION_DELAY" "0.00 MIL,195.00 MIL"
					( Parent
						( matchGroupRef "@baseboard_fab2_lib.baseboard_fab2(sch_1):\MG_DQ-DQS_FAR_DIMM_NG_M_K_BYTE1\" )
					)
					( Units "uMatchProp" "ns" 1.000000)
					( Status sCSetFlattened )
					( Origin gBackEnd )
				)
				( attribute "RELATIVE_PROPAGATION_DELAY_SCOPE" "G"
					( Parent
						( matchGroupRef "@baseboard_fab2_lib.baseboard_fab2(sch_1):\MG_DQ_FAR_DIMM_NG_M_K_BYTE1\" )
					)
					( Status sCSetFlattened )
					( Origin gBackEnd )
				)
				( attribute "RELATIVE_PROPAGATION_DELAY" "-50.00 MIL,50.00 MIL"
					( Parent
						( matchGroupRef "@baseboard_fab2_lib.baseboard_fab2(sch_1):\MG_DQ_FAR_DIMM_NG_M_K_BYTE1\" )
					)
					( Units "uMatchProp" "ns" 1.000000)
					( Status sCSetFlattened )
					( Origin gBackEnd )
				)
			)
			( pinPair "@baseboard_fab2_lib.baseboard_fab2(sch_1):\PP2258\"
				( pinRef "@baseboard_fab2_lib.baseboard_fab2(sch_1):page84_i14:DQ(10)" )
				( pinRef "@baseboard_fab2_lib.baseboard_fab2(sch_1):page60_i172:DDR3_DQ(10)" )
				( attribute "RELATIVE_PROPAGATION_DELAY_SCOPE" "G"
					( Parent
						( matchGroupRef "@baseboard_fab2_lib.baseboard_fab2(sch_1):\MG_DQ-DQS_NEAR_DIMM_NG_M_K_BYTE1\" )
					)
					( Status sCSetFlattened )
					( Origin gBackEnd )
				)
				( attribute "RELATIVE_PROPAGATION_DELAY" "0.00 MIL,195.00 MIL"
					( Parent
						( matchGroupRef "@baseboard_fab2_lib.baseboard_fab2(sch_1):\MG_DQ-DQS_NEAR_DIMM_NG_M_K_BYTE1\" )
					)
					( Units "uMatchProp" "ns" 1.000000)
					( Status sCSetFlattened )
					( Origin gBackEnd )
				)
				( attribute "RELATIVE_PROPAGATION_DELAY_SCOPE" "G"
					( Parent
						( matchGroupRef "@baseboard_fab2_lib.baseboard_fab2(sch_1):\MG_DQ_NEAR_DIMM_NG_M_K_BYTE1\" )
					)
					( Status sCSetFlattened )
					( Origin gBackEnd )
				)
				( attribute "RELATIVE_PROPAGATION_DELAY" "-50.00 MIL,50.00 MIL"
					( Parent
						( matchGroupRef "@baseboard_fab2_lib.baseboard_fab2(sch_1):\MG_DQ_NEAR_DIMM_NG_M_K_BYTE1\" )
					)
					( Units "uMatchProp" "ns" 1.000000)
					( Status sCSetFlattened )
					( Origin gBackEnd )
				)
			)
			( pinPair "@baseboard_fab2_lib.baseboard_fab2(sch_1):\PP2260\"
				( pinRef "@baseboard_fab2_lib.baseboard_fab2(sch_1):page60_i172:DDR3_DQ(11)" )
				( pinRef "@baseboard_fab2_lib.baseboard_fab2(sch_1):page83_i111:DQ(10)" )
				( attribute "RELATIVE_PROPAGATION_DELAY_SCOPE" "G"
					( Parent
						( matchGroupRef "@baseboard_fab2_lib.baseboard_fab2(sch_1):\MG_DQ-DQS_FAR_DIMM_NG_M_K_BYTE1\" )
					)
					( Status sCSetFlattened )
					( Origin gBackEnd )
				)
				( attribute "RELATIVE_PROPAGATION_DELAY" "0.00 MIL,195.00 MIL"
					( Parent
						( matchGroupRef "@baseboard_fab2_lib.baseboard_fab2(sch_1):\MG_DQ-DQS_FAR_DIMM_NG_M_K_BYTE1\" )
					)
					( Units "uMatchProp" "ns" 1.000000)
					( Status sCSetFlattened )
					( Origin gBackEnd )
				)
				( attribute "RELATIVE_PROPAGATION_DELAY_SCOPE" "G"
					( Parent
						( matchGroupRef "@baseboard_fab2_lib.baseboard_fab2(sch_1):\MG_DQ_FAR_DIMM_NG_M_K_BYTE1\" )
					)
					( Status sCSetFlattened )
					( Origin gBackEnd )
				)
				( attribute "RELATIVE_PROPAGATION_DELAY" "-50.00 MIL,50.00 MIL"
					( Parent
						( matchGroupRef "@baseboard_fab2_lib.baseboard_fab2(sch_1):\MG_DQ_FAR_DIMM_NG_M_K_BYTE1\" )
					)
					( Units "uMatchProp" "ns" 1.000000)
					( Status sCSetFlattened )
					( Origin gBackEnd )
				)
			)
			( pinPair "@baseboard_fab2_lib.baseboard_fab2(sch_1):\PP2261\"
				( pinRef "@baseboard_fab2_lib.baseboard_fab2(sch_1):page84_i14:DQ(11)" )
				( pinRef "@baseboard_fab2_lib.baseboard_fab2(sch_1):page60_i172:DDR3_DQ(11)" )
				( attribute "RELATIVE_PROPAGATION_DELAY_SCOPE" "G"
					( Parent
						( matchGroupRef "@baseboard_fab2_lib.baseboard_fab2(sch_1):\MG_DQ-DQS_NEAR_DIMM_NG_M_K_BYTE1\" )
					)
					( Status sCSetFlattened )
					( Origin gBackEnd )
				)
				( attribute "RELATIVE_PROPAGATION_DELAY" "0.00 MIL,195.00 MIL"
					( Parent
						( matchGroupRef "@baseboard_fab2_lib.baseboard_fab2(sch_1):\MG_DQ-DQS_NEAR_DIMM_NG_M_K_BYTE1\" )
					)
					( Units "uMatchProp" "ns" 1.000000)
					( Status sCSetFlattened )
					( Origin gBackEnd )
				)
				( attribute "RELATIVE_PROPAGATION_DELAY_SCOPE" "G"
					( Parent
						( matchGroupRef "@baseboard_fab2_lib.baseboard_fab2(sch_1):\MG_DQ_NEAR_DIMM_NG_M_K_BYTE1\" )
					)
					( Status sCSetFlattened )
					( Origin gBackEnd )
				)
				( attribute "RELATIVE_PROPAGATION_DELAY" "-50.00 MIL,50.00 MIL"
					( Parent
						( matchGroupRef "@baseboard_fab2_lib.baseboard_fab2(sch_1):\MG_DQ_NEAR_DIMM_NG_M_K_BYTE1\" )
					)
					( Units "uMatchProp" "ns" 1.000000)
					( Status sCSetFlattened )
					( Origin gBackEnd )
				)
			)
			( pinPair "@baseboard_fab2_lib.baseboard_fab2(sch_1):\PP2263\"
				( pinRef "@baseboard_fab2_lib.baseboard_fab2(sch_1):page60_i172:DDR3_DQ(12)" )
				( pinRef "@baseboard_fab2_lib.baseboard_fab2(sch_1):page83_i111:DQ(13)" )
				( attribute "RELATIVE_PROPAGATION_DELAY_SCOPE" "G"
					( Parent
						( matchGroupRef "@baseboard_fab2_lib.baseboard_fab2(sch_1):\MG_DQ-DQS_FAR_DIMM_NG_M_K_BYTE1\" )
					)
					( Status sCSetFlattened )
					( Origin gBackEnd )
				)
				( attribute "RELATIVE_PROPAGATION_DELAY" "0.00 MIL,195.00 MIL"
					( Parent
						( matchGroupRef "@baseboard_fab2_lib.baseboard_fab2(sch_1):\MG_DQ-DQS_FAR_DIMM_NG_M_K_BYTE1\" )
					)
					( Units "uMatchProp" "ns" 1.000000)
					( Status sCSetFlattened )
					( Origin gBackEnd )
				)
				( attribute "RELATIVE_PROPAGATION_DELAY_SCOPE" "G"
					( Parent
						( matchGroupRef "@baseboard_fab2_lib.baseboard_fab2(sch_1):\MG_DQ_FAR_DIMM_NG_M_K_BYTE1\" )
					)
					( Status sCSetFlattened )
					( Origin gBackEnd )
				)
				( attribute "RELATIVE_PROPAGATION_DELAY" "-50.00 MIL,50.00 MIL"
					( Parent
						( matchGroupRef "@baseboard_fab2_lib.baseboard_fab2(sch_1):\MG_DQ_FAR_DIMM_NG_M_K_BYTE1\" )
					)
					( Units "uMatchProp" "ns" 1.000000)
					( Status sCSetFlattened )
					( Origin gBackEnd )
				)
			)
			( pinPair "@baseboard_fab2_lib.baseboard_fab2(sch_1):\PP2264\"
				( pinRef "@baseboard_fab2_lib.baseboard_fab2(sch_1):page84_i14:DQ(12)" )
				( pinRef "@baseboard_fab2_lib.baseboard_fab2(sch_1):page60_i172:DDR3_DQ(12)" )
				( attribute "RELATIVE_PROPAGATION_DELAY_SCOPE" "G"
					( Parent
						( matchGroupRef "@baseboard_fab2_lib.baseboard_fab2(sch_1):\MG_DQ-DQS_NEAR_DIMM_NG_M_K_BYTE1\" )
					)
					( Status sCSetFlattened )
					( Origin gBackEnd )
				)
				( attribute "RELATIVE_PROPAGATION_DELAY" "0.00 MIL,195.00 MIL"
					( Parent
						( matchGroupRef "@baseboard_fab2_lib.baseboard_fab2(sch_1):\MG_DQ-DQS_NEAR_DIMM_NG_M_K_BYTE1\" )
					)
					( Units "uMatchProp" "ns" 1.000000)
					( Status sCSetFlattened )
					( Origin gBackEnd )
				)
				( attribute "RELATIVE_PROPAGATION_DELAY_SCOPE" "G"
					( Parent
						( matchGroupRef "@baseboard_fab2_lib.baseboard_fab2(sch_1):\MG_DQ_NEAR_DIMM_NG_M_K_BYTE1\" )
					)
					( Status sCSetFlattened )
					( Origin gBackEnd )
				)
				( attribute "RELATIVE_PROPAGATION_DELAY" "-50.00 MIL,50.00 MIL"
					( Parent
						( matchGroupRef "@baseboard_fab2_lib.baseboard_fab2(sch_1):\MG_DQ_NEAR_DIMM_NG_M_K_BYTE1\" )
					)
					( Units "uMatchProp" "ns" 1.000000)
					( Status sCSetFlattened )
					( Origin gBackEnd )
				)
			)
			( pinPair "@baseboard_fab2_lib.baseboard_fab2(sch_1):\PP2266\"
				( pinRef "@baseboard_fab2_lib.baseboard_fab2(sch_1):page60_i172:DDR3_DQ(13)" )
				( pinRef "@baseboard_fab2_lib.baseboard_fab2(sch_1):page83_i111:DQ(12)" )
				( attribute "RELATIVE_PROPAGATION_DELAY_SCOPE" "G"
					( Parent
						( matchGroupRef "@baseboard_fab2_lib.baseboard_fab2(sch_1):\MG_DQ-DQS_FAR_DIMM_NG_M_K_BYTE1\" )
					)
					( Status sCSetFlattened )
					( Origin gBackEnd )
				)
				( attribute "RELATIVE_PROPAGATION_DELAY" "0.00 MIL,195.00 MIL"
					( Parent
						( matchGroupRef "@baseboard_fab2_lib.baseboard_fab2(sch_1):\MG_DQ-DQS_FAR_DIMM_NG_M_K_BYTE1\" )
					)
					( Units "uMatchProp" "ns" 1.000000)
					( Status sCSetFlattened )
					( Origin gBackEnd )
				)
				( attribute "RELATIVE_PROPAGATION_DELAY_SCOPE" "G"
					( Parent
						( matchGroupRef "@baseboard_fab2_lib.baseboard_fab2(sch_1):\MG_DQ_FAR_DIMM_NG_M_K_BYTE1\" )
					)
					( Status sCSetFlattened )
					( Origin gBackEnd )
				)
				( attribute "RELATIVE_PROPAGATION_DELAY" "-50.00 MIL,50.00 MIL"
					( Parent
						( matchGroupRef "@baseboard_fab2_lib.baseboard_fab2(sch_1):\MG_DQ_FAR_DIMM_NG_M_K_BYTE1\" )
					)
					( Units "uMatchProp" "ns" 1.000000)
					( Status sCSetFlattened )
					( Origin gBackEnd )
				)
			)
			( pinPair "@baseboard_fab2_lib.baseboard_fab2(sch_1):\PP2267\"
				( pinRef "@baseboard_fab2_lib.baseboard_fab2(sch_1):page84_i14:DQ(13)" )
				( pinRef "@baseboard_fab2_lib.baseboard_fab2(sch_1):page60_i172:DDR3_DQ(13)" )
				( attribute "RELATIVE_PROPAGATION_DELAY_SCOPE" "G"
					( Parent
						( matchGroupRef "@baseboard_fab2_lib.baseboard_fab2(sch_1):\MG_DQ-DQS_NEAR_DIMM_NG_M_K_BYTE1\" )
					)
					( Status sCSetFlattened )
					( Origin gBackEnd )
				)
				( attribute "RELATIVE_PROPAGATION_DELAY" "0.00 MIL,195.00 MIL"
					( Parent
						( matchGroupRef "@baseboard_fab2_lib.baseboard_fab2(sch_1):\MG_DQ-DQS_NEAR_DIMM_NG_M_K_BYTE1\" )
					)
					( Units "uMatchProp" "ns" 1.000000)
					( Status sCSetFlattened )
					( Origin gBackEnd )
				)
				( attribute "RELATIVE_PROPAGATION_DELAY_SCOPE" "G"
					( Parent
						( matchGroupRef "@baseboard_fab2_lib.baseboard_fab2(sch_1):\MG_DQ_NEAR_DIMM_NG_M_K_BYTE1\" )
					)
					( Status sCSetFlattened )
					( Origin gBackEnd )
				)
				( attribute "RELATIVE_PROPAGATION_DELAY" "-50.00 MIL,50.00 MIL"
					( Parent
						( matchGroupRef "@baseboard_fab2_lib.baseboard_fab2(sch_1):\MG_DQ_NEAR_DIMM_NG_M_K_BYTE1\" )
					)
					( Units "uMatchProp" "ns" 1.000000)
					( Status sCSetFlattened )
					( Origin gBackEnd )
				)
			)
			( pinPair "@baseboard_fab2_lib.baseboard_fab2(sch_1):\PP2269\"
				( pinRef "@baseboard_fab2_lib.baseboard_fab2(sch_1):page60_i172:DDR3_DQ(14)" )
				( pinRef "@baseboard_fab2_lib.baseboard_fab2(sch_1):page83_i111:DQ(15)" )
				( attribute "RELATIVE_PROPAGATION_DELAY_SCOPE" "G"
					( Parent
						( matchGroupRef "@baseboard_fab2_lib.baseboard_fab2(sch_1):\MG_DQ-DQS_FAR_DIMM_NG_M_K_BYTE1\" )
					)
					( Status sCSetFlattened )
					( Origin gBackEnd )
				)
				( attribute "RELATIVE_PROPAGATION_DELAY" "0.00 MIL,195.00 MIL"
					( Parent
						( matchGroupRef "@baseboard_fab2_lib.baseboard_fab2(sch_1):\MG_DQ-DQS_FAR_DIMM_NG_M_K_BYTE1\" )
					)
					( Units "uMatchProp" "ns" 1.000000)
					( Status sCSetFlattened )
					( Origin gBackEnd )
				)
				( attribute "RELATIVE_PROPAGATION_DELAY_SCOPE" "G"
					( Parent
						( matchGroupRef "@baseboard_fab2_lib.baseboard_fab2(sch_1):\MG_DQ_FAR_DIMM_NG_M_K_BYTE1\" )
					)
					( Status sCSetFlattened )
					( Origin gBackEnd )
				)
				( attribute "RELATIVE_PROPAGATION_DELAY" "-50.00 MIL,50.00 MIL"
					( Parent
						( matchGroupRef "@baseboard_fab2_lib.baseboard_fab2(sch_1):\MG_DQ_FAR_DIMM_NG_M_K_BYTE1\" )
					)
					( Units "uMatchProp" "ns" 1.000000)
					( Status sCSetFlattened )
					( Origin gBackEnd )
				)
			)
			( pinPair "@baseboard_fab2_lib.baseboard_fab2(sch_1):\PP2270\"
				( pinRef "@baseboard_fab2_lib.baseboard_fab2(sch_1):page84_i14:DQ(14)" )
				( pinRef "@baseboard_fab2_lib.baseboard_fab2(sch_1):page60_i172:DDR3_DQ(14)" )
				( attribute "RELATIVE_PROPAGATION_DELAY_SCOPE" "G"
					( Parent
						( matchGroupRef "@baseboard_fab2_lib.baseboard_fab2(sch_1):\MG_DQ-DQS_NEAR_DIMM_NG_M_K_BYTE1\" )
					)
					( Status sCSetFlattened )
					( Origin gBackEnd )
				)
				( attribute "RELATIVE_PROPAGATION_DELAY" "0.00 MIL,195.00 MIL"
					( Parent
						( matchGroupRef "@baseboard_fab2_lib.baseboard_fab2(sch_1):\MG_DQ-DQS_NEAR_DIMM_NG_M_K_BYTE1\" )
					)
					( Units "uMatchProp" "ns" 1.000000)
					( Status sCSetFlattened )
					( Origin gBackEnd )
				)
				( attribute "RELATIVE_PROPAGATION_DELAY_SCOPE" "G"
					( Parent
						( matchGroupRef "@baseboard_fab2_lib.baseboard_fab2(sch_1):\MG_DQ_NEAR_DIMM_NG_M_K_BYTE1\" )
					)
					( Status sCSetFlattened )
					( Origin gBackEnd )
				)
				( attribute "RELATIVE_PROPAGATION_DELAY" "-50.00 MIL,50.00 MIL"
					( Parent
						( matchGroupRef "@baseboard_fab2_lib.baseboard_fab2(sch_1):\MG_DQ_NEAR_DIMM_NG_M_K_BYTE1\" )
					)
					( Units "uMatchProp" "ns" 1.000000)
					( Status sCSetFlattened )
					( Origin gBackEnd )
				)
			)
			( pinPair "@baseboard_fab2_lib.baseboard_fab2(sch_1):\PP2272\"
				( pinRef "@baseboard_fab2_lib.baseboard_fab2(sch_1):page60_i172:DDR3_DQ(15)" )
				( pinRef "@baseboard_fab2_lib.baseboard_fab2(sch_1):page83_i111:DQ(14)" )
				( attribute "RELATIVE_PROPAGATION_DELAY_SCOPE" "G"
					( Parent
						( matchGroupRef "@baseboard_fab2_lib.baseboard_fab2(sch_1):\MG_DQ-DQS_FAR_DIMM_NG_M_K_BYTE1\" )
					)
					( Status sCSetFlattened )
					( Origin gBackEnd )
				)
				( attribute "RELATIVE_PROPAGATION_DELAY" "0.00 MIL,195.00 MIL"
					( Parent
						( matchGroupRef "@baseboard_fab2_lib.baseboard_fab2(sch_1):\MG_DQ-DQS_FAR_DIMM_NG_M_K_BYTE1\" )
					)
					( Units "uMatchProp" "ns" 1.000000)
					( Status sCSetFlattened )
					( Origin gBackEnd )
				)
				( attribute "RELATIVE_PROPAGATION_DELAY_SCOPE" "G"
					( Parent
						( matchGroupRef "@baseboard_fab2_lib.baseboard_fab2(sch_1):\MG_DQ_FAR_DIMM_NG_M_K_BYTE1\" )
					)
					( Status sCSetFlattened )
					( Origin gBackEnd )
				)
				( attribute "RELATIVE_PROPAGATION_DELAY" "-50.00 MIL,50.00 MIL"
					( Parent
						( matchGroupRef "@baseboard_fab2_lib.baseboard_fab2(sch_1):\MG_DQ_FAR_DIMM_NG_M_K_BYTE1\" )
					)
					( Units "uMatchProp" "ns" 1.000000)
					( Status sCSetFlattened )
					( Origin gBackEnd )
				)
			)
			( pinPair "@baseboard_fab2_lib.baseboard_fab2(sch_1):\PP2273\"
				( pinRef "@baseboard_fab2_lib.baseboard_fab2(sch_1):page84_i14:DQ(15)" )
				( pinRef "@baseboard_fab2_lib.baseboard_fab2(sch_1):page60_i172:DDR3_DQ(15)" )
				( attribute "RELATIVE_PROPAGATION_DELAY_SCOPE" "G"
					( Parent
						( matchGroupRef "@baseboard_fab2_lib.baseboard_fab2(sch_1):\MG_DQ-DQS_NEAR_DIMM_NG_M_K_BYTE1\" )
					)
					( Status sCSetFlattened )
					( Origin gBackEnd )
				)
				( attribute "RELATIVE_PROPAGATION_DELAY" "0.00 MIL,195.00 MIL"
					( Parent
						( matchGroupRef "@baseboard_fab2_lib.baseboard_fab2(sch_1):\MG_DQ-DQS_NEAR_DIMM_NG_M_K_BYTE1\" )
					)
					( Units "uMatchProp" "ns" 1.000000)
					( Status sCSetFlattened )
					( Origin gBackEnd )
				)
				( attribute "RELATIVE_PROPAGATION_DELAY_SCOPE" "G"
					( Parent
						( matchGroupRef "@baseboard_fab2_lib.baseboard_fab2(sch_1):\MG_DQ_NEAR_DIMM_NG_M_K_BYTE1\" )
					)
					( Status sCSetFlattened )
					( Origin gBackEnd )
				)
				( attribute "RELATIVE_PROPAGATION_DELAY" "-50.00 MIL,50.00 MIL"
					( Parent
						( matchGroupRef "@baseboard_fab2_lib.baseboard_fab2(sch_1):\MG_DQ_NEAR_DIMM_NG_M_K_BYTE1\" )
					)
					( Units "uMatchProp" "ns" 1.000000)
					( Status sCSetFlattened )
					( Origin gBackEnd )
				)
			)
			( pinPair "@baseboard_fab2_lib.baseboard_fab2(sch_1):\PP2227\"
				( pinRef "@baseboard_fab2_lib.baseboard_fab2(sch_1):page60_i172:DDR3_DQ(16)" )
				( pinRef "@baseboard_fab2_lib.baseboard_fab2(sch_1):page83_i111:DQ(17)" )
				( attribute "RELATIVE_PROPAGATION_DELAY_SCOPE" "G"
					( Parent
						( matchGroupRef "@baseboard_fab2_lib.baseboard_fab2(sch_1):\MG_DQ-DQS_FAR_DIMM_NG_M_K_BYTE2\" )
					)
					( Status sCSetFlattened )
					( Origin gBackEnd )
				)
				( attribute "RELATIVE_PROPAGATION_DELAY" "0.00 MIL,195.00 MIL"
					( Parent
						( matchGroupRef "@baseboard_fab2_lib.baseboard_fab2(sch_1):\MG_DQ-DQS_FAR_DIMM_NG_M_K_BYTE2\" )
					)
					( Units "uMatchProp" "ns" 1.000000)
					( Status sCSetFlattened )
					( Origin gBackEnd )
				)
				( attribute "RELATIVE_PROPAGATION_DELAY_SCOPE" "G"
					( Parent
						( matchGroupRef "@baseboard_fab2_lib.baseboard_fab2(sch_1):\MG_DQ_FAR_DIMM_NG_M_K_BYTE2\" )
					)
					( Status sCSetFlattened )
					( Origin gBackEnd )
				)
				( attribute "RELATIVE_PROPAGATION_DELAY" "-50.00 MIL,50.00 MIL"
					( Parent
						( matchGroupRef "@baseboard_fab2_lib.baseboard_fab2(sch_1):\MG_DQ_FAR_DIMM_NG_M_K_BYTE2\" )
					)
					( Units "uMatchProp" "ns" 1.000000)
					( Status sCSetFlattened )
					( Origin gBackEnd )
				)
			)
			( pinPair "@baseboard_fab2_lib.baseboard_fab2(sch_1):\PP2228\"
				( pinRef "@baseboard_fab2_lib.baseboard_fab2(sch_1):page60_i172:DDR3_DQ(16)" )
				( pinRef "@baseboard_fab2_lib.baseboard_fab2(sch_1):page84_i14:DQ(16)" )
				( attribute "RELATIVE_PROPAGATION_DELAY_SCOPE" "G"
					( Parent
						( matchGroupRef "@baseboard_fab2_lib.baseboard_fab2(sch_1):\MG_DQ-DQS_NEAR_DIMM_NG_M_K_BYTE2\" )
					)
					( Status sCSetFlattened )
					( Origin gBackEnd )
				)
				( attribute "RELATIVE_PROPAGATION_DELAY" "0.00 MIL,195.00 MIL"
					( Parent
						( matchGroupRef "@baseboard_fab2_lib.baseboard_fab2(sch_1):\MG_DQ-DQS_NEAR_DIMM_NG_M_K_BYTE2\" )
					)
					( Units "uMatchProp" "ns" 1.000000)
					( Status sCSetFlattened )
					( Origin gBackEnd )
				)
				( attribute "RELATIVE_PROPAGATION_DELAY_SCOPE" "G"
					( Parent
						( matchGroupRef "@baseboard_fab2_lib.baseboard_fab2(sch_1):\MG_DQ_NEAR_DIMM_NG_M_K_BYTE2\" )
					)
					( Status sCSetFlattened )
					( Origin gBackEnd )
				)
				( attribute "RELATIVE_PROPAGATION_DELAY" "-50.00 MIL,50.00 MIL"
					( Parent
						( matchGroupRef "@baseboard_fab2_lib.baseboard_fab2(sch_1):\MG_DQ_NEAR_DIMM_NG_M_K_BYTE2\" )
					)
					( Units "uMatchProp" "ns" 1.000000)
					( Status sCSetFlattened )
					( Origin gBackEnd )
				)
			)
			( pinPair "@baseboard_fab2_lib.baseboard_fab2(sch_1):\PP2230\"
				( pinRef "@baseboard_fab2_lib.baseboard_fab2(sch_1):page60_i172:DDR3_DQ(17)" )
				( pinRef "@baseboard_fab2_lib.baseboard_fab2(sch_1):page83_i111:DQ(16)" )
				( attribute "RELATIVE_PROPAGATION_DELAY_SCOPE" "G"
					( Parent
						( matchGroupRef "@baseboard_fab2_lib.baseboard_fab2(sch_1):\MG_DQ-DQS_FAR_DIMM_NG_M_K_BYTE2\" )
					)
					( Status sCSetFlattened )
					( Origin gBackEnd )
				)
				( attribute "RELATIVE_PROPAGATION_DELAY" "0.00 MIL,195.00 MIL"
					( Parent
						( matchGroupRef "@baseboard_fab2_lib.baseboard_fab2(sch_1):\MG_DQ-DQS_FAR_DIMM_NG_M_K_BYTE2\" )
					)
					( Units "uMatchProp" "ns" 1.000000)
					( Status sCSetFlattened )
					( Origin gBackEnd )
				)
				( attribute "RELATIVE_PROPAGATION_DELAY_SCOPE" "G"
					( Parent
						( matchGroupRef "@baseboard_fab2_lib.baseboard_fab2(sch_1):\MG_DQ_FAR_DIMM_NG_M_K_BYTE2\" )
					)
					( Status sCSetFlattened )
					( Origin gBackEnd )
				)
				( attribute "RELATIVE_PROPAGATION_DELAY" "-50.00 MIL,50.00 MIL"
					( Parent
						( matchGroupRef "@baseboard_fab2_lib.baseboard_fab2(sch_1):\MG_DQ_FAR_DIMM_NG_M_K_BYTE2\" )
					)
					( Units "uMatchProp" "ns" 1.000000)
					( Status sCSetFlattened )
					( Origin gBackEnd )
				)
			)
			( pinPair "@baseboard_fab2_lib.baseboard_fab2(sch_1):\PP2231\"
				( pinRef "@baseboard_fab2_lib.baseboard_fab2(sch_1):page60_i172:DDR3_DQ(17)" )
				( pinRef "@baseboard_fab2_lib.baseboard_fab2(sch_1):page84_i14:DQ(17)" )
				( attribute "RELATIVE_PROPAGATION_DELAY_SCOPE" "G"
					( Parent
						( matchGroupRef "@baseboard_fab2_lib.baseboard_fab2(sch_1):\MG_DQ-DQS_NEAR_DIMM_NG_M_K_BYTE2\" )
					)
					( Status sCSetFlattened )
					( Origin gBackEnd )
				)
				( attribute "RELATIVE_PROPAGATION_DELAY" "0.00 MIL,195.00 MIL"
					( Parent
						( matchGroupRef "@baseboard_fab2_lib.baseboard_fab2(sch_1):\MG_DQ-DQS_NEAR_DIMM_NG_M_K_BYTE2\" )
					)
					( Units "uMatchProp" "ns" 1.000000)
					( Status sCSetFlattened )
					( Origin gBackEnd )
				)
				( attribute "RELATIVE_PROPAGATION_DELAY_SCOPE" "G"
					( Parent
						( matchGroupRef "@baseboard_fab2_lib.baseboard_fab2(sch_1):\MG_DQ_NEAR_DIMM_NG_M_K_BYTE2\" )
					)
					( Status sCSetFlattened )
					( Origin gBackEnd )
				)
				( attribute "RELATIVE_PROPAGATION_DELAY" "-50.00 MIL,50.00 MIL"
					( Parent
						( matchGroupRef "@baseboard_fab2_lib.baseboard_fab2(sch_1):\MG_DQ_NEAR_DIMM_NG_M_K_BYTE2\" )
					)
					( Units "uMatchProp" "ns" 1.000000)
					( Status sCSetFlattened )
					( Origin gBackEnd )
				)
			)
			( pinPair "@baseboard_fab2_lib.baseboard_fab2(sch_1):\PP2233\"
				( pinRef "@baseboard_fab2_lib.baseboard_fab2(sch_1):page60_i172:DDR3_DQ(18)" )
				( pinRef "@baseboard_fab2_lib.baseboard_fab2(sch_1):page83_i111:DQ(19)" )
				( attribute "RELATIVE_PROPAGATION_DELAY_SCOPE" "G"
					( Parent
						( matchGroupRef "@baseboard_fab2_lib.baseboard_fab2(sch_1):\MG_DQ-DQS_FAR_DIMM_NG_M_K_BYTE2\" )
					)
					( Status sCSetFlattened )
					( Origin gBackEnd )
				)
				( attribute "RELATIVE_PROPAGATION_DELAY" "0.00 MIL,195.00 MIL"
					( Parent
						( matchGroupRef "@baseboard_fab2_lib.baseboard_fab2(sch_1):\MG_DQ-DQS_FAR_DIMM_NG_M_K_BYTE2\" )
					)
					( Units "uMatchProp" "ns" 1.000000)
					( Status sCSetFlattened )
					( Origin gBackEnd )
				)
				( attribute "RELATIVE_PROPAGATION_DELAY_SCOPE" "G"
					( Parent
						( matchGroupRef "@baseboard_fab2_lib.baseboard_fab2(sch_1):\MG_DQ_FAR_DIMM_NG_M_K_BYTE2\" )
					)
					( Status sCSetFlattened )
					( Origin gBackEnd )
				)
				( attribute "RELATIVE_PROPAGATION_DELAY" "-50.00 MIL,50.00 MIL"
					( Parent
						( matchGroupRef "@baseboard_fab2_lib.baseboard_fab2(sch_1):\MG_DQ_FAR_DIMM_NG_M_K_BYTE2\" )
					)
					( Units "uMatchProp" "ns" 1.000000)
					( Status sCSetFlattened )
					( Origin gBackEnd )
				)
			)
			( pinPair "@baseboard_fab2_lib.baseboard_fab2(sch_1):\PP2234\"
				( pinRef "@baseboard_fab2_lib.baseboard_fab2(sch_1):page60_i172:DDR3_DQ(18)" )
				( pinRef "@baseboard_fab2_lib.baseboard_fab2(sch_1):page84_i14:DQ(18)" )
				( attribute "RELATIVE_PROPAGATION_DELAY_SCOPE" "G"
					( Parent
						( matchGroupRef "@baseboard_fab2_lib.baseboard_fab2(sch_1):\MG_DQ-DQS_NEAR_DIMM_NG_M_K_BYTE2\" )
					)
					( Status sCSetFlattened )
					( Origin gBackEnd )
				)
				( attribute "RELATIVE_PROPAGATION_DELAY" "0.00 MIL,195.00 MIL"
					( Parent
						( matchGroupRef "@baseboard_fab2_lib.baseboard_fab2(sch_1):\MG_DQ-DQS_NEAR_DIMM_NG_M_K_BYTE2\" )
					)
					( Units "uMatchProp" "ns" 1.000000)
					( Status sCSetFlattened )
					( Origin gBackEnd )
				)
				( attribute "RELATIVE_PROPAGATION_DELAY_SCOPE" "G"
					( Parent
						( matchGroupRef "@baseboard_fab2_lib.baseboard_fab2(sch_1):\MG_DQ_NEAR_DIMM_NG_M_K_BYTE2\" )
					)
					( Status sCSetFlattened )
					( Origin gBackEnd )
				)
				( attribute "RELATIVE_PROPAGATION_DELAY" "-50.00 MIL,50.00 MIL"
					( Parent
						( matchGroupRef "@baseboard_fab2_lib.baseboard_fab2(sch_1):\MG_DQ_NEAR_DIMM_NG_M_K_BYTE2\" )
					)
					( Units "uMatchProp" "ns" 1.000000)
					( Status sCSetFlattened )
					( Origin gBackEnd )
				)
			)
			( pinPair "@baseboard_fab2_lib.baseboard_fab2(sch_1):\PP2236\"
				( pinRef "@baseboard_fab2_lib.baseboard_fab2(sch_1):page60_i172:DDR3_DQ(19)" )
				( pinRef "@baseboard_fab2_lib.baseboard_fab2(sch_1):page83_i111:DQ(18)" )
				( attribute "RELATIVE_PROPAGATION_DELAY_SCOPE" "G"
					( Parent
						( matchGroupRef "@baseboard_fab2_lib.baseboard_fab2(sch_1):\MG_DQ-DQS_FAR_DIMM_NG_M_K_BYTE2\" )
					)
					( Status sCSetFlattened )
					( Origin gBackEnd )
				)
				( attribute "RELATIVE_PROPAGATION_DELAY" "0.00 MIL,195.00 MIL"
					( Parent
						( matchGroupRef "@baseboard_fab2_lib.baseboard_fab2(sch_1):\MG_DQ-DQS_FAR_DIMM_NG_M_K_BYTE2\" )
					)
					( Units "uMatchProp" "ns" 1.000000)
					( Status sCSetFlattened )
					( Origin gBackEnd )
				)
				( attribute "RELATIVE_PROPAGATION_DELAY_SCOPE" "G"
					( Parent
						( matchGroupRef "@baseboard_fab2_lib.baseboard_fab2(sch_1):\MG_DQ_FAR_DIMM_NG_M_K_BYTE2\" )
					)
					( Status sCSetFlattened )
					( Origin gBackEnd )
				)
				( attribute "RELATIVE_PROPAGATION_DELAY" "-50.00 MIL,50.00 MIL"
					( Parent
						( matchGroupRef "@baseboard_fab2_lib.baseboard_fab2(sch_1):\MG_DQ_FAR_DIMM_NG_M_K_BYTE2\" )
					)
					( Units "uMatchProp" "ns" 1.000000)
					( Status sCSetFlattened )
					( Origin gBackEnd )
				)
			)
			( pinPair "@baseboard_fab2_lib.baseboard_fab2(sch_1):\PP2237\"
				( pinRef "@baseboard_fab2_lib.baseboard_fab2(sch_1):page60_i172:DDR3_DQ(19)" )
				( pinRef "@baseboard_fab2_lib.baseboard_fab2(sch_1):page84_i14:DQ(19)" )
				( attribute "RELATIVE_PROPAGATION_DELAY_SCOPE" "G"
					( Parent
						( matchGroupRef "@baseboard_fab2_lib.baseboard_fab2(sch_1):\MG_DQ-DQS_NEAR_DIMM_NG_M_K_BYTE2\" )
					)
					( Status sCSetFlattened )
					( Origin gBackEnd )
				)
				( attribute "RELATIVE_PROPAGATION_DELAY" "0.00 MIL,195.00 MIL"
					( Parent
						( matchGroupRef "@baseboard_fab2_lib.baseboard_fab2(sch_1):\MG_DQ-DQS_NEAR_DIMM_NG_M_K_BYTE2\" )
					)
					( Units "uMatchProp" "ns" 1.000000)
					( Status sCSetFlattened )
					( Origin gBackEnd )
				)
				( attribute "RELATIVE_PROPAGATION_DELAY_SCOPE" "G"
					( Parent
						( matchGroupRef "@baseboard_fab2_lib.baseboard_fab2(sch_1):\MG_DQ_NEAR_DIMM_NG_M_K_BYTE2\" )
					)
					( Status sCSetFlattened )
					( Origin gBackEnd )
				)
				( attribute "RELATIVE_PROPAGATION_DELAY" "-50.00 MIL,50.00 MIL"
					( Parent
						( matchGroupRef "@baseboard_fab2_lib.baseboard_fab2(sch_1):\MG_DQ_NEAR_DIMM_NG_M_K_BYTE2\" )
					)
					( Units "uMatchProp" "ns" 1.000000)
					( Status sCSetFlattened )
					( Origin gBackEnd )
				)
			)
			( pinPair "@baseboard_fab2_lib.baseboard_fab2(sch_1):\PP2239\"
				( pinRef "@baseboard_fab2_lib.baseboard_fab2(sch_1):page60_i172:DDR3_DQ(20)" )
				( pinRef "@baseboard_fab2_lib.baseboard_fab2(sch_1):page83_i111:DQ(21)" )
				( attribute "RELATIVE_PROPAGATION_DELAY_SCOPE" "G"
					( Parent
						( matchGroupRef "@baseboard_fab2_lib.baseboard_fab2(sch_1):\MG_DQ-DQS_FAR_DIMM_NG_M_K_BYTE2\" )
					)
					( Status sCSetFlattened )
					( Origin gBackEnd )
				)
				( attribute "RELATIVE_PROPAGATION_DELAY" "0.00 MIL,195.00 MIL"
					( Parent
						( matchGroupRef "@baseboard_fab2_lib.baseboard_fab2(sch_1):\MG_DQ-DQS_FAR_DIMM_NG_M_K_BYTE2\" )
					)
					( Units "uMatchProp" "ns" 1.000000)
					( Status sCSetFlattened )
					( Origin gBackEnd )
				)
				( attribute "RELATIVE_PROPAGATION_DELAY_SCOPE" "G"
					( Parent
						( matchGroupRef "@baseboard_fab2_lib.baseboard_fab2(sch_1):\MG_DQ_FAR_DIMM_NG_M_K_BYTE2\" )
					)
					( Status sCSetFlattened )
					( Origin gBackEnd )
				)
				( attribute "RELATIVE_PROPAGATION_DELAY" "-50.00 MIL,50.00 MIL"
					( Parent
						( matchGroupRef "@baseboard_fab2_lib.baseboard_fab2(sch_1):\MG_DQ_FAR_DIMM_NG_M_K_BYTE2\" )
					)
					( Units "uMatchProp" "ns" 1.000000)
					( Status sCSetFlattened )
					( Origin gBackEnd )
				)
			)
			( pinPair "@baseboard_fab2_lib.baseboard_fab2(sch_1):\PP2240\"
				( pinRef "@baseboard_fab2_lib.baseboard_fab2(sch_1):page60_i172:DDR3_DQ(20)" )
				( pinRef "@baseboard_fab2_lib.baseboard_fab2(sch_1):page84_i14:DQ(20)" )
				( attribute "RELATIVE_PROPAGATION_DELAY_SCOPE" "G"
					( Parent
						( matchGroupRef "@baseboard_fab2_lib.baseboard_fab2(sch_1):\MG_DQ-DQS_NEAR_DIMM_NG_M_K_BYTE2\" )
					)
					( Status sCSetFlattened )
					( Origin gBackEnd )
				)
				( attribute "RELATIVE_PROPAGATION_DELAY" "0.00 MIL,195.00 MIL"
					( Parent
						( matchGroupRef "@baseboard_fab2_lib.baseboard_fab2(sch_1):\MG_DQ-DQS_NEAR_DIMM_NG_M_K_BYTE2\" )
					)
					( Units "uMatchProp" "ns" 1.000000)
					( Status sCSetFlattened )
					( Origin gBackEnd )
				)
				( attribute "RELATIVE_PROPAGATION_DELAY_SCOPE" "G"
					( Parent
						( matchGroupRef "@baseboard_fab2_lib.baseboard_fab2(sch_1):\MG_DQ_NEAR_DIMM_NG_M_K_BYTE2\" )
					)
					( Status sCSetFlattened )
					( Origin gBackEnd )
				)
				( attribute "RELATIVE_PROPAGATION_DELAY" "-50.00 MIL,50.00 MIL"
					( Parent
						( matchGroupRef "@baseboard_fab2_lib.baseboard_fab2(sch_1):\MG_DQ_NEAR_DIMM_NG_M_K_BYTE2\" )
					)
					( Units "uMatchProp" "ns" 1.000000)
					( Status sCSetFlattened )
					( Origin gBackEnd )
				)
			)
			( pinPair "@baseboard_fab2_lib.baseboard_fab2(sch_1):\PP2242\"
				( pinRef "@baseboard_fab2_lib.baseboard_fab2(sch_1):page60_i172:DDR3_DQ(21)" )
				( pinRef "@baseboard_fab2_lib.baseboard_fab2(sch_1):page83_i111:DQ(20)" )
				( attribute "RELATIVE_PROPAGATION_DELAY_SCOPE" "G"
					( Parent
						( matchGroupRef "@baseboard_fab2_lib.baseboard_fab2(sch_1):\MG_DQ-DQS_FAR_DIMM_NG_M_K_BYTE2\" )
					)
					( Status sCSetFlattened )
					( Origin gBackEnd )
				)
				( attribute "RELATIVE_PROPAGATION_DELAY" "0.00 MIL,195.00 MIL"
					( Parent
						( matchGroupRef "@baseboard_fab2_lib.baseboard_fab2(sch_1):\MG_DQ-DQS_FAR_DIMM_NG_M_K_BYTE2\" )
					)
					( Units "uMatchProp" "ns" 1.000000)
					( Status sCSetFlattened )
					( Origin gBackEnd )
				)
				( attribute "RELATIVE_PROPAGATION_DELAY_SCOPE" "G"
					( Parent
						( matchGroupRef "@baseboard_fab2_lib.baseboard_fab2(sch_1):\MG_DQ_FAR_DIMM_NG_M_K_BYTE2\" )
					)
					( Status sCSetFlattened )
					( Origin gBackEnd )
				)
				( attribute "RELATIVE_PROPAGATION_DELAY" "-50.00 MIL,50.00 MIL"
					( Parent
						( matchGroupRef "@baseboard_fab2_lib.baseboard_fab2(sch_1):\MG_DQ_FAR_DIMM_NG_M_K_BYTE2\" )
					)
					( Units "uMatchProp" "ns" 1.000000)
					( Status sCSetFlattened )
					( Origin gBackEnd )
				)
			)
			( pinPair "@baseboard_fab2_lib.baseboard_fab2(sch_1):\PP2243\"
				( pinRef "@baseboard_fab2_lib.baseboard_fab2(sch_1):page60_i172:DDR3_DQ(21)" )
				( pinRef "@baseboard_fab2_lib.baseboard_fab2(sch_1):page84_i14:DQ(21)" )
				( attribute "RELATIVE_PROPAGATION_DELAY_SCOPE" "G"
					( Parent
						( matchGroupRef "@baseboard_fab2_lib.baseboard_fab2(sch_1):\MG_DQ-DQS_NEAR_DIMM_NG_M_K_BYTE2\" )
					)
					( Status sCSetFlattened )
					( Origin gBackEnd )
				)
				( attribute "RELATIVE_PROPAGATION_DELAY" "0.00 MIL,195.00 MIL"
					( Parent
						( matchGroupRef "@baseboard_fab2_lib.baseboard_fab2(sch_1):\MG_DQ-DQS_NEAR_DIMM_NG_M_K_BYTE2\" )
					)
					( Units "uMatchProp" "ns" 1.000000)
					( Status sCSetFlattened )
					( Origin gBackEnd )
				)
				( attribute "RELATIVE_PROPAGATION_DELAY_SCOPE" "G"
					( Parent
						( matchGroupRef "@baseboard_fab2_lib.baseboard_fab2(sch_1):\MG_DQ_NEAR_DIMM_NG_M_K_BYTE2\" )
					)
					( Status sCSetFlattened )
					( Origin gBackEnd )
				)
				( attribute "RELATIVE_PROPAGATION_DELAY" "-50.00 MIL,50.00 MIL"
					( Parent
						( matchGroupRef "@baseboard_fab2_lib.baseboard_fab2(sch_1):\MG_DQ_NEAR_DIMM_NG_M_K_BYTE2\" )
					)
					( Units "uMatchProp" "ns" 1.000000)
					( Status sCSetFlattened )
					( Origin gBackEnd )
				)
			)
			( pinPair "@baseboard_fab2_lib.baseboard_fab2(sch_1):\PP2245\"
				( pinRef "@baseboard_fab2_lib.baseboard_fab2(sch_1):page60_i172:DDR3_DQ(22)" )
				( pinRef "@baseboard_fab2_lib.baseboard_fab2(sch_1):page83_i111:DQ(23)" )
				( attribute "RELATIVE_PROPAGATION_DELAY_SCOPE" "G"
					( Parent
						( matchGroupRef "@baseboard_fab2_lib.baseboard_fab2(sch_1):\MG_DQ-DQS_FAR_DIMM_NG_M_K_BYTE2\" )
					)
					( Status sCSetFlattened )
					( Origin gBackEnd )
				)
				( attribute "RELATIVE_PROPAGATION_DELAY" "0.00 MIL,195.00 MIL"
					( Parent
						( matchGroupRef "@baseboard_fab2_lib.baseboard_fab2(sch_1):\MG_DQ-DQS_FAR_DIMM_NG_M_K_BYTE2\" )
					)
					( Units "uMatchProp" "ns" 1.000000)
					( Status sCSetFlattened )
					( Origin gBackEnd )
				)
				( attribute "RELATIVE_PROPAGATION_DELAY_SCOPE" "G"
					( Parent
						( matchGroupRef "@baseboard_fab2_lib.baseboard_fab2(sch_1):\MG_DQ_FAR_DIMM_NG_M_K_BYTE2\" )
					)
					( Status sCSetFlattened )
					( Origin gBackEnd )
				)
				( attribute "RELATIVE_PROPAGATION_DELAY" "-50.00 MIL,50.00 MIL"
					( Parent
						( matchGroupRef "@baseboard_fab2_lib.baseboard_fab2(sch_1):\MG_DQ_FAR_DIMM_NG_M_K_BYTE2\" )
					)
					( Units "uMatchProp" "ns" 1.000000)
					( Status sCSetFlattened )
					( Origin gBackEnd )
				)
			)
			( pinPair "@baseboard_fab2_lib.baseboard_fab2(sch_1):\PP2246\"
				( pinRef "@baseboard_fab2_lib.baseboard_fab2(sch_1):page84_i14:DQ(22)" )
				( pinRef "@baseboard_fab2_lib.baseboard_fab2(sch_1):page60_i172:DDR3_DQ(22)" )
				( attribute "RELATIVE_PROPAGATION_DELAY_SCOPE" "G"
					( Parent
						( matchGroupRef "@baseboard_fab2_lib.baseboard_fab2(sch_1):\MG_DQ-DQS_NEAR_DIMM_NG_M_K_BYTE2\" )
					)
					( Status sCSetFlattened )
					( Origin gBackEnd )
				)
				( attribute "RELATIVE_PROPAGATION_DELAY" "0.00 MIL,195.00 MIL"
					( Parent
						( matchGroupRef "@baseboard_fab2_lib.baseboard_fab2(sch_1):\MG_DQ-DQS_NEAR_DIMM_NG_M_K_BYTE2\" )
					)
					( Units "uMatchProp" "ns" 1.000000)
					( Status sCSetFlattened )
					( Origin gBackEnd )
				)
				( attribute "RELATIVE_PROPAGATION_DELAY_SCOPE" "G"
					( Parent
						( matchGroupRef "@baseboard_fab2_lib.baseboard_fab2(sch_1):\MG_DQ_NEAR_DIMM_NG_M_K_BYTE2\" )
					)
					( Status sCSetFlattened )
					( Origin gBackEnd )
				)
				( attribute "RELATIVE_PROPAGATION_DELAY" "-50.00 MIL,50.00 MIL"
					( Parent
						( matchGroupRef "@baseboard_fab2_lib.baseboard_fab2(sch_1):\MG_DQ_NEAR_DIMM_NG_M_K_BYTE2\" )
					)
					( Units "uMatchProp" "ns" 1.000000)
					( Status sCSetFlattened )
					( Origin gBackEnd )
				)
			)
			( pinPair "@baseboard_fab2_lib.baseboard_fab2(sch_1):\PP2248\"
				( pinRef "@baseboard_fab2_lib.baseboard_fab2(sch_1):page60_i172:DDR3_DQ(23)" )
				( pinRef "@baseboard_fab2_lib.baseboard_fab2(sch_1):page83_i111:DQ(22)" )
				( attribute "RELATIVE_PROPAGATION_DELAY_SCOPE" "G"
					( Parent
						( matchGroupRef "@baseboard_fab2_lib.baseboard_fab2(sch_1):\MG_DQ-DQS_FAR_DIMM_NG_M_K_BYTE2\" )
					)
					( Status sCSetFlattened )
					( Origin gBackEnd )
				)
				( attribute "RELATIVE_PROPAGATION_DELAY" "0.00 MIL,195.00 MIL"
					( Parent
						( matchGroupRef "@baseboard_fab2_lib.baseboard_fab2(sch_1):\MG_DQ-DQS_FAR_DIMM_NG_M_K_BYTE2\" )
					)
					( Units "uMatchProp" "ns" 1.000000)
					( Status sCSetFlattened )
					( Origin gBackEnd )
				)
				( attribute "RELATIVE_PROPAGATION_DELAY_SCOPE" "G"
					( Parent
						( matchGroupRef "@baseboard_fab2_lib.baseboard_fab2(sch_1):\MG_DQ_FAR_DIMM_NG_M_K_BYTE2\" )
					)
					( Status sCSetFlattened )
					( Origin gBackEnd )
				)
				( attribute "RELATIVE_PROPAGATION_DELAY" "-50.00 MIL,50.00 MIL"
					( Parent
						( matchGroupRef "@baseboard_fab2_lib.baseboard_fab2(sch_1):\MG_DQ_FAR_DIMM_NG_M_K_BYTE2\" )
					)
					( Units "uMatchProp" "ns" 1.000000)
					( Status sCSetFlattened )
					( Origin gBackEnd )
				)
			)
			( pinPair "@baseboard_fab2_lib.baseboard_fab2(sch_1):\PP2249\"
				( pinRef "@baseboard_fab2_lib.baseboard_fab2(sch_1):page60_i172:DDR3_DQ(23)" )
				( pinRef "@baseboard_fab2_lib.baseboard_fab2(sch_1):page84_i14:DQ(23)" )
				( attribute "RELATIVE_PROPAGATION_DELAY_SCOPE" "G"
					( Parent
						( matchGroupRef "@baseboard_fab2_lib.baseboard_fab2(sch_1):\MG_DQ-DQS_NEAR_DIMM_NG_M_K_BYTE2\" )
					)
					( Status sCSetFlattened )
					( Origin gBackEnd )
				)
				( attribute "RELATIVE_PROPAGATION_DELAY" "0.00 MIL,195.00 MIL"
					( Parent
						( matchGroupRef "@baseboard_fab2_lib.baseboard_fab2(sch_1):\MG_DQ-DQS_NEAR_DIMM_NG_M_K_BYTE2\" )
					)
					( Units "uMatchProp" "ns" 1.000000)
					( Status sCSetFlattened )
					( Origin gBackEnd )
				)
				( attribute "RELATIVE_PROPAGATION_DELAY_SCOPE" "G"
					( Parent
						( matchGroupRef "@baseboard_fab2_lib.baseboard_fab2(sch_1):\MG_DQ_NEAR_DIMM_NG_M_K_BYTE2\" )
					)
					( Status sCSetFlattened )
					( Origin gBackEnd )
				)
				( attribute "RELATIVE_PROPAGATION_DELAY" "-50.00 MIL,50.00 MIL"
					( Parent
						( matchGroupRef "@baseboard_fab2_lib.baseboard_fab2(sch_1):\MG_DQ_NEAR_DIMM_NG_M_K_BYTE2\" )
					)
					( Units "uMatchProp" "ns" 1.000000)
					( Status sCSetFlattened )
					( Origin gBackEnd )
				)
			)
			( pinPair "@baseboard_fab2_lib.baseboard_fab2(sch_1):\PP2203\"
				( pinRef "@baseboard_fab2_lib.baseboard_fab2(sch_1):page60_i172:DDR3_DQ(24)" )
				( pinRef "@baseboard_fab2_lib.baseboard_fab2(sch_1):page83_i111:DQ(25)" )
				( attribute "RELATIVE_PROPAGATION_DELAY_SCOPE" "G"
					( Parent
						( matchGroupRef "@baseboard_fab2_lib.baseboard_fab2(sch_1):\MG_DQ-DQS_FAR_DIMM_NG_M_K_BYTE3\" )
					)
					( Status sCSetFlattened )
					( Origin gBackEnd )
				)
				( attribute "RELATIVE_PROPAGATION_DELAY" "0.00 MIL,195.00 MIL"
					( Parent
						( matchGroupRef "@baseboard_fab2_lib.baseboard_fab2(sch_1):\MG_DQ-DQS_FAR_DIMM_NG_M_K_BYTE3\" )
					)
					( Units "uMatchProp" "ns" 1.000000)
					( Status sCSetFlattened )
					( Origin gBackEnd )
				)
				( attribute "RELATIVE_PROPAGATION_DELAY_SCOPE" "G"
					( Parent
						( matchGroupRef "@crescent_city_bb_fab1_lib.crescent_city_bb_fab1(sch_1):\MG_DQ_FAR_DIMM_NG_M_K_BYTE3\" )
					)
					( Origin gBackEnd )
				)
				( attribute "RELATIVE_PROPAGATION_DELAY" "TARGET,TARGET"
					( Parent
						( matchGroupRef "@crescent_city_bb_fab1_lib.crescent_city_bb_fab1(sch_1):\MG_DQ_FAR_DIMM_NG_M_K_BYTE3\" )
					)
					( Units "uMatchProp" "ns" 1.000000)
					( Origin gBackEnd )
				)
			)
			( pinPair "@baseboard_fab2_lib.baseboard_fab2(sch_1):\PP2204\"
				( pinRef "@baseboard_fab2_lib.baseboard_fab2(sch_1):page60_i172:DDR3_DQ(24)" )
				( pinRef "@baseboard_fab2_lib.baseboard_fab2(sch_1):page84_i14:DQ(24)" )
				( attribute "RELATIVE_PROPAGATION_DELAY_SCOPE" "G"
					( Parent
						( matchGroupRef "@baseboard_fab2_lib.baseboard_fab2(sch_1):\MG_DQ-DQS_NEAR_DIMM_NG_M_K_BYTE3\" )
					)
					( Status sCSetFlattened )
					( Origin gBackEnd )
				)
				( attribute "RELATIVE_PROPAGATION_DELAY" "0.00 MIL,195.00 MIL"
					( Parent
						( matchGroupRef "@baseboard_fab2_lib.baseboard_fab2(sch_1):\MG_DQ-DQS_NEAR_DIMM_NG_M_K_BYTE3\" )
					)
					( Units "uMatchProp" "ns" 1.000000)
					( Status sCSetFlattened )
					( Origin gBackEnd )
				)
				( attribute "RELATIVE_PROPAGATION_DELAY_SCOPE" "G"
					( Parent
						( matchGroupRef "@crescent_city_bb_fab1_lib.crescent_city_bb_fab1(sch_1):\MG_DQ_NEAR_DIMM_NG_M_K_BYTE3\" )
					)
					( Status sCSetFlattened )
					( Origin gBackEnd )
				)
				( attribute "RELATIVE_PROPAGATION_DELAY" "-50.00 MIL,50.00 MIL"
					( Parent
						( matchGroupRef "@crescent_city_bb_fab1_lib.crescent_city_bb_fab1(sch_1):\MG_DQ_NEAR_DIMM_NG_M_K_BYTE3\" )
					)
					( Units "uMatchProp" "ns" 1.000000)
					( Status sCSetFlattened )
					( Origin gBackEnd )
				)
			)
			( pinPair "@baseboard_fab2_lib.baseboard_fab2(sch_1):\PP2206\"
				( pinRef "@baseboard_fab2_lib.baseboard_fab2(sch_1):page60_i172:DDR3_DQ(25)" )
				( pinRef "@baseboard_fab2_lib.baseboard_fab2(sch_1):page83_i111:DQ(24)" )
				( attribute "RELATIVE_PROPAGATION_DELAY_SCOPE" "G"
					( Parent
						( matchGroupRef "@baseboard_fab2_lib.baseboard_fab2(sch_1):\MG_DQ-DQS_FAR_DIMM_NG_M_K_BYTE3\" )
					)
					( Status sCSetFlattened )
					( Origin gBackEnd )
				)
				( attribute "RELATIVE_PROPAGATION_DELAY" "0.00 MIL,195.00 MIL"
					( Parent
						( matchGroupRef "@baseboard_fab2_lib.baseboard_fab2(sch_1):\MG_DQ-DQS_FAR_DIMM_NG_M_K_BYTE3\" )
					)
					( Units "uMatchProp" "ns" 1.000000)
					( Status sCSetFlattened )
					( Origin gBackEnd )
				)
				( attribute "RELATIVE_PROPAGATION_DELAY_SCOPE" "G"
					( Parent
						( matchGroupRef "@crescent_city_bb_fab1_lib.crescent_city_bb_fab1(sch_1):\MG_DQ_FAR_DIMM_NG_M_K_BYTE3\" )
					)
					( Status sCSetFlattened )
					( Origin gBackEnd )
				)
				( attribute "RELATIVE_PROPAGATION_DELAY" "-50.00 MIL,50.00 MIL"
					( Parent
						( matchGroupRef "@crescent_city_bb_fab1_lib.crescent_city_bb_fab1(sch_1):\MG_DQ_FAR_DIMM_NG_M_K_BYTE3\" )
					)
					( Units "uMatchProp" "ns" 1.000000)
					( Status sCSetFlattened )
					( Origin gBackEnd )
				)
			)
			( pinPair "@baseboard_fab2_lib.baseboard_fab2(sch_1):\PP2207\"
				( pinRef "@baseboard_fab2_lib.baseboard_fab2(sch_1):page60_i172:DDR3_DQ(25)" )
				( pinRef "@baseboard_fab2_lib.baseboard_fab2(sch_1):page84_i14:DQ(25)" )
				( attribute "RELATIVE_PROPAGATION_DELAY_SCOPE" "G"
					( Parent
						( matchGroupRef "@baseboard_fab2_lib.baseboard_fab2(sch_1):\MG_DQ-DQS_NEAR_DIMM_NG_M_K_BYTE3\" )
					)
					( Status sCSetFlattened )
					( Origin gBackEnd )
				)
				( attribute "RELATIVE_PROPAGATION_DELAY" "0.00 MIL,195.00 MIL"
					( Parent
						( matchGroupRef "@baseboard_fab2_lib.baseboard_fab2(sch_1):\MG_DQ-DQS_NEAR_DIMM_NG_M_K_BYTE3\" )
					)
					( Units "uMatchProp" "ns" 1.000000)
					( Status sCSetFlattened )
					( Origin gBackEnd )
				)
				( attribute "RELATIVE_PROPAGATION_DELAY_SCOPE" "G"
					( Parent
						( matchGroupRef "@crescent_city_bb_fab1_lib.crescent_city_bb_fab1(sch_1):\MG_DQ_NEAR_DIMM_NG_M_K_BYTE3\" )
					)
					( Status sCSetFlattened )
					( Origin gBackEnd )
				)
				( attribute "RELATIVE_PROPAGATION_DELAY" "-50.00 MIL,50.00 MIL"
					( Parent
						( matchGroupRef "@crescent_city_bb_fab1_lib.crescent_city_bb_fab1(sch_1):\MG_DQ_NEAR_DIMM_NG_M_K_BYTE3\" )
					)
					( Units "uMatchProp" "ns" 1.000000)
					( Status sCSetFlattened )
					( Origin gBackEnd )
				)
			)
			( pinPair "@baseboard_fab2_lib.baseboard_fab2(sch_1):\PP2209\"
				( pinRef "@baseboard_fab2_lib.baseboard_fab2(sch_1):page60_i172:DDR3_DQ(26)" )
				( pinRef "@baseboard_fab2_lib.baseboard_fab2(sch_1):page83_i111:DQ(27)" )
				( attribute "RELATIVE_PROPAGATION_DELAY_SCOPE" "G"
					( Parent
						( matchGroupRef "@baseboard_fab2_lib.baseboard_fab2(sch_1):\MG_DQ-DQS_FAR_DIMM_NG_M_K_BYTE3\" )
					)
					( Status sCSetFlattened )
					( Origin gBackEnd )
				)
				( attribute "RELATIVE_PROPAGATION_DELAY" "0.00 MIL,195.00 MIL"
					( Parent
						( matchGroupRef "@baseboard_fab2_lib.baseboard_fab2(sch_1):\MG_DQ-DQS_FAR_DIMM_NG_M_K_BYTE3\" )
					)
					( Units "uMatchProp" "ns" 1.000000)
					( Status sCSetFlattened )
					( Origin gBackEnd )
				)
				( attribute "RELATIVE_PROPAGATION_DELAY_SCOPE" "G"
					( Parent
						( matchGroupRef "@crescent_city_bb_fab1_lib.crescent_city_bb_fab1(sch_1):\MG_DQ_FAR_DIMM_NG_M_K_BYTE3\" )
					)
					( Status sCSetFlattened )
					( Origin gBackEnd )
				)
				( attribute "RELATIVE_PROPAGATION_DELAY" "-50.00 MIL,50.00 MIL"
					( Parent
						( matchGroupRef "@crescent_city_bb_fab1_lib.crescent_city_bb_fab1(sch_1):\MG_DQ_FAR_DIMM_NG_M_K_BYTE3\" )
					)
					( Units "uMatchProp" "ns" 1.000000)
					( Status sCSetFlattened )
					( Origin gBackEnd )
				)
			)
			( pinPair "@baseboard_fab2_lib.baseboard_fab2(sch_1):\PP2210\"
				( pinRef "@baseboard_fab2_lib.baseboard_fab2(sch_1):page60_i172:DDR3_DQ(26)" )
				( pinRef "@baseboard_fab2_lib.baseboard_fab2(sch_1):page84_i14:DQ(26)" )
				( attribute "RELATIVE_PROPAGATION_DELAY_SCOPE" "G"
					( Parent
						( matchGroupRef "@baseboard_fab2_lib.baseboard_fab2(sch_1):\MG_DQ-DQS_NEAR_DIMM_NG_M_K_BYTE3\" )
					)
					( Status sCSetFlattened )
					( Origin gBackEnd )
				)
				( attribute "RELATIVE_PROPAGATION_DELAY" "0.00 MIL,195.00 MIL"
					( Parent
						( matchGroupRef "@baseboard_fab2_lib.baseboard_fab2(sch_1):\MG_DQ-DQS_NEAR_DIMM_NG_M_K_BYTE3\" )
					)
					( Units "uMatchProp" "ns" 1.000000)
					( Status sCSetFlattened )
					( Origin gBackEnd )
				)
				( attribute "RELATIVE_PROPAGATION_DELAY_SCOPE" "G"
					( Parent
						( matchGroupRef "@crescent_city_bb_fab1_lib.crescent_city_bb_fab1(sch_1):\MG_DQ_NEAR_DIMM_NG_M_K_BYTE3\" )
					)
					( Status sCSetFlattened )
					( Origin gBackEnd )
				)
				( attribute "RELATIVE_PROPAGATION_DELAY" "-50.00 MIL,50.00 MIL"
					( Parent
						( matchGroupRef "@crescent_city_bb_fab1_lib.crescent_city_bb_fab1(sch_1):\MG_DQ_NEAR_DIMM_NG_M_K_BYTE3\" )
					)
					( Units "uMatchProp" "ns" 1.000000)
					( Status sCSetFlattened )
					( Origin gBackEnd )
				)
			)
			( pinPair "@baseboard_fab2_lib.baseboard_fab2(sch_1):\PP2212\"
				( pinRef "@baseboard_fab2_lib.baseboard_fab2(sch_1):page60_i172:DDR3_DQ(27)" )
				( pinRef "@baseboard_fab2_lib.baseboard_fab2(sch_1):page83_i111:DQ(26)" )
				( attribute "RELATIVE_PROPAGATION_DELAY_SCOPE" "G"
					( Parent
						( matchGroupRef "@baseboard_fab2_lib.baseboard_fab2(sch_1):\MG_DQ-DQS_FAR_DIMM_NG_M_K_BYTE3\" )
					)
					( Status sCSetFlattened )
					( Origin gBackEnd )
				)
				( attribute "RELATIVE_PROPAGATION_DELAY" "0.00 MIL,195.00 MIL"
					( Parent
						( matchGroupRef "@baseboard_fab2_lib.baseboard_fab2(sch_1):\MG_DQ-DQS_FAR_DIMM_NG_M_K_BYTE3\" )
					)
					( Units "uMatchProp" "ns" 1.000000)
					( Status sCSetFlattened )
					( Origin gBackEnd )
				)
				( attribute "RELATIVE_PROPAGATION_DELAY_SCOPE" "G"
					( Parent
						( matchGroupRef "@crescent_city_bb_fab1_lib.crescent_city_bb_fab1(sch_1):\MG_DQ_FAR_DIMM_NG_M_K_BYTE3\" )
					)
					( Status sCSetFlattened )
					( Origin gBackEnd )
				)
				( attribute "RELATIVE_PROPAGATION_DELAY" "-50.00 MIL,50.00 MIL"
					( Parent
						( matchGroupRef "@crescent_city_bb_fab1_lib.crescent_city_bb_fab1(sch_1):\MG_DQ_FAR_DIMM_NG_M_K_BYTE3\" )
					)
					( Units "uMatchProp" "ns" 1.000000)
					( Status sCSetFlattened )
					( Origin gBackEnd )
				)
			)
			( pinPair "@baseboard_fab2_lib.baseboard_fab2(sch_1):\PP2213\"
				( pinRef "@baseboard_fab2_lib.baseboard_fab2(sch_1):page60_i172:DDR3_DQ(27)" )
				( pinRef "@baseboard_fab2_lib.baseboard_fab2(sch_1):page84_i14:DQ(27)" )
				( attribute "RELATIVE_PROPAGATION_DELAY_SCOPE" "G"
					( Parent
						( matchGroupRef "@baseboard_fab2_lib.baseboard_fab2(sch_1):\MG_DQ-DQS_NEAR_DIMM_NG_M_K_BYTE3\" )
					)
					( Status sCSetFlattened )
					( Origin gBackEnd )
				)
				( attribute "RELATIVE_PROPAGATION_DELAY" "0.00 MIL,195.00 MIL"
					( Parent
						( matchGroupRef "@baseboard_fab2_lib.baseboard_fab2(sch_1):\MG_DQ-DQS_NEAR_DIMM_NG_M_K_BYTE3\" )
					)
					( Units "uMatchProp" "ns" 1.000000)
					( Status sCSetFlattened )
					( Origin gBackEnd )
				)
				( attribute "RELATIVE_PROPAGATION_DELAY_SCOPE" "G"
					( Parent
						( matchGroupRef "@crescent_city_bb_fab1_lib.crescent_city_bb_fab1(sch_1):\MG_DQ_NEAR_DIMM_NG_M_K_BYTE3\" )
					)
					( Origin gBackEnd )
				)
				( attribute "RELATIVE_PROPAGATION_DELAY" "TARGET,TARGET"
					( Parent
						( matchGroupRef "@crescent_city_bb_fab1_lib.crescent_city_bb_fab1(sch_1):\MG_DQ_NEAR_DIMM_NG_M_K_BYTE3\" )
					)
					( Units "uMatchProp" "ns" 1.000000)
					( Origin gBackEnd )
				)
			)
			( pinPair "@baseboard_fab2_lib.baseboard_fab2(sch_1):\PP2215\"
				( pinRef "@baseboard_fab2_lib.baseboard_fab2(sch_1):page60_i172:DDR3_DQ(28)" )
				( pinRef "@baseboard_fab2_lib.baseboard_fab2(sch_1):page83_i111:DQ(29)" )
				( attribute "RELATIVE_PROPAGATION_DELAY_SCOPE" "G"
					( Parent
						( matchGroupRef "@baseboard_fab2_lib.baseboard_fab2(sch_1):\MG_DQ-DQS_FAR_DIMM_NG_M_K_BYTE3\" )
					)
					( Status sCSetFlattened )
					( Origin gBackEnd )
				)
				( attribute "RELATIVE_PROPAGATION_DELAY" "0.00 MIL,195.00 MIL"
					( Parent
						( matchGroupRef "@baseboard_fab2_lib.baseboard_fab2(sch_1):\MG_DQ-DQS_FAR_DIMM_NG_M_K_BYTE3\" )
					)
					( Units "uMatchProp" "ns" 1.000000)
					( Status sCSetFlattened )
					( Origin gBackEnd )
				)
				( attribute "RELATIVE_PROPAGATION_DELAY_SCOPE" "G"
					( Parent
						( matchGroupRef "@crescent_city_bb_fab1_lib.crescent_city_bb_fab1(sch_1):\MG_DQ_FAR_DIMM_NG_M_K_BYTE3\" )
					)
					( Status sCSetFlattened )
					( Origin gBackEnd )
				)
				( attribute "RELATIVE_PROPAGATION_DELAY" "-50.00 MIL,50.00 MIL"
					( Parent
						( matchGroupRef "@crescent_city_bb_fab1_lib.crescent_city_bb_fab1(sch_1):\MG_DQ_FAR_DIMM_NG_M_K_BYTE3\" )
					)
					( Units "uMatchProp" "ns" 1.000000)
					( Status sCSetFlattened )
					( Origin gBackEnd )
				)
			)
			( pinPair "@baseboard_fab2_lib.baseboard_fab2(sch_1):\PP2216\"
				( pinRef "@baseboard_fab2_lib.baseboard_fab2(sch_1):page60_i172:DDR3_DQ(28)" )
				( pinRef "@baseboard_fab2_lib.baseboard_fab2(sch_1):page84_i14:DQ(28)" )
				( attribute "RELATIVE_PROPAGATION_DELAY_SCOPE" "G"
					( Parent
						( matchGroupRef "@baseboard_fab2_lib.baseboard_fab2(sch_1):\MG_DQ-DQS_NEAR_DIMM_NG_M_K_BYTE3\" )
					)
					( Status sCSetFlattened )
					( Origin gBackEnd )
				)
				( attribute "RELATIVE_PROPAGATION_DELAY" "0.00 MIL,195.00 MIL"
					( Parent
						( matchGroupRef "@baseboard_fab2_lib.baseboard_fab2(sch_1):\MG_DQ-DQS_NEAR_DIMM_NG_M_K_BYTE3\" )
					)
					( Units "uMatchProp" "ns" 1.000000)
					( Status sCSetFlattened )
					( Origin gBackEnd )
				)
				( attribute "RELATIVE_PROPAGATION_DELAY_SCOPE" "G"
					( Parent
						( matchGroupRef "@crescent_city_bb_fab1_lib.crescent_city_bb_fab1(sch_1):\MG_DQ_NEAR_DIMM_NG_M_K_BYTE3\" )
					)
					( Status sCSetFlattened )
					( Origin gBackEnd )
				)
				( attribute "RELATIVE_PROPAGATION_DELAY" "-50.00 MIL,50.00 MIL"
					( Parent
						( matchGroupRef "@crescent_city_bb_fab1_lib.crescent_city_bb_fab1(sch_1):\MG_DQ_NEAR_DIMM_NG_M_K_BYTE3\" )
					)
					( Units "uMatchProp" "ns" 1.000000)
					( Status sCSetFlattened )
					( Origin gBackEnd )
				)
			)
			( pinPair "@baseboard_fab2_lib.baseboard_fab2(sch_1):\PP2218\"
				( pinRef "@baseboard_fab2_lib.baseboard_fab2(sch_1):page60_i172:DDR3_DQ(29)" )
				( pinRef "@baseboard_fab2_lib.baseboard_fab2(sch_1):page83_i111:DQ(28)" )
				( attribute "RELATIVE_PROPAGATION_DELAY_SCOPE" "G"
					( Parent
						( matchGroupRef "@baseboard_fab2_lib.baseboard_fab2(sch_1):\MG_DQ-DQS_FAR_DIMM_NG_M_K_BYTE3\" )
					)
					( Status sCSetFlattened )
					( Origin gBackEnd )
				)
				( attribute "RELATIVE_PROPAGATION_DELAY" "0.00 MIL,195.00 MIL"
					( Parent
						( matchGroupRef "@baseboard_fab2_lib.baseboard_fab2(sch_1):\MG_DQ-DQS_FAR_DIMM_NG_M_K_BYTE3\" )
					)
					( Units "uMatchProp" "ns" 1.000000)
					( Status sCSetFlattened )
					( Origin gBackEnd )
				)
				( attribute "RELATIVE_PROPAGATION_DELAY_SCOPE" "G"
					( Parent
						( matchGroupRef "@crescent_city_bb_fab1_lib.crescent_city_bb_fab1(sch_1):\MG_DQ_FAR_DIMM_NG_M_K_BYTE3\" )
					)
					( Status sCSetFlattened )
					( Origin gBackEnd )
				)
				( attribute "RELATIVE_PROPAGATION_DELAY" "-50.00 MIL,50.00 MIL"
					( Parent
						( matchGroupRef "@crescent_city_bb_fab1_lib.crescent_city_bb_fab1(sch_1):\MG_DQ_FAR_DIMM_NG_M_K_BYTE3\" )
					)
					( Units "uMatchProp" "ns" 1.000000)
					( Status sCSetFlattened )
					( Origin gBackEnd )
				)
			)
			( pinPair "@baseboard_fab2_lib.baseboard_fab2(sch_1):\PP2219\"
				( pinRef "@baseboard_fab2_lib.baseboard_fab2(sch_1):page60_i172:DDR3_DQ(29)" )
				( pinRef "@baseboard_fab2_lib.baseboard_fab2(sch_1):page84_i14:DQ(29)" )
				( attribute "RELATIVE_PROPAGATION_DELAY_SCOPE" "G"
					( Parent
						( matchGroupRef "@baseboard_fab2_lib.baseboard_fab2(sch_1):\MG_DQ-DQS_NEAR_DIMM_NG_M_K_BYTE3\" )
					)
					( Status sCSetFlattened )
					( Origin gBackEnd )
				)
				( attribute "RELATIVE_PROPAGATION_DELAY" "0.00 MIL,195.00 MIL"
					( Parent
						( matchGroupRef "@baseboard_fab2_lib.baseboard_fab2(sch_1):\MG_DQ-DQS_NEAR_DIMM_NG_M_K_BYTE3\" )
					)
					( Units "uMatchProp" "ns" 1.000000)
					( Status sCSetFlattened )
					( Origin gBackEnd )
				)
				( attribute "RELATIVE_PROPAGATION_DELAY_SCOPE" "G"
					( Parent
						( matchGroupRef "@crescent_city_bb_fab1_lib.crescent_city_bb_fab1(sch_1):\MG_DQ_NEAR_DIMM_NG_M_K_BYTE3\" )
					)
					( Status sCSetFlattened )
					( Origin gBackEnd )
				)
				( attribute "RELATIVE_PROPAGATION_DELAY" "-50.00 MIL,50.00 MIL"
					( Parent
						( matchGroupRef "@crescent_city_bb_fab1_lib.crescent_city_bb_fab1(sch_1):\MG_DQ_NEAR_DIMM_NG_M_K_BYTE3\" )
					)
					( Units "uMatchProp" "ns" 1.000000)
					( Status sCSetFlattened )
					( Origin gBackEnd )
				)
			)
			( pinPair "@baseboard_fab2_lib.baseboard_fab2(sch_1):\PP2221\"
				( pinRef "@baseboard_fab2_lib.baseboard_fab2(sch_1):page60_i172:DDR3_DQ(30)" )
				( pinRef "@baseboard_fab2_lib.baseboard_fab2(sch_1):page83_i111:DQ(31)" )
				( attribute "RELATIVE_PROPAGATION_DELAY_SCOPE" "G"
					( Parent
						( matchGroupRef "@baseboard_fab2_lib.baseboard_fab2(sch_1):\MG_DQ-DQS_FAR_DIMM_NG_M_K_BYTE3\" )
					)
					( Status sCSetFlattened )
					( Origin gBackEnd )
				)
				( attribute "RELATIVE_PROPAGATION_DELAY" "0.00 MIL,195.00 MIL"
					( Parent
						( matchGroupRef "@baseboard_fab2_lib.baseboard_fab2(sch_1):\MG_DQ-DQS_FAR_DIMM_NG_M_K_BYTE3\" )
					)
					( Units "uMatchProp" "ns" 1.000000)
					( Status sCSetFlattened )
					( Origin gBackEnd )
				)
				( attribute "RELATIVE_PROPAGATION_DELAY_SCOPE" "G"
					( Parent
						( matchGroupRef "@crescent_city_bb_fab1_lib.crescent_city_bb_fab1(sch_1):\MG_DQ_FAR_DIMM_NG_M_K_BYTE3\" )
					)
					( Status sCSetFlattened )
					( Origin gBackEnd )
				)
				( attribute "RELATIVE_PROPAGATION_DELAY" "-50.00 MIL,50.00 MIL"
					( Parent
						( matchGroupRef "@crescent_city_bb_fab1_lib.crescent_city_bb_fab1(sch_1):\MG_DQ_FAR_DIMM_NG_M_K_BYTE3\" )
					)
					( Units "uMatchProp" "ns" 1.000000)
					( Status sCSetFlattened )
					( Origin gBackEnd )
				)
			)
			( pinPair "@baseboard_fab2_lib.baseboard_fab2(sch_1):\PP2222\"
				( pinRef "@baseboard_fab2_lib.baseboard_fab2(sch_1):page60_i172:DDR3_DQ(30)" )
				( pinRef "@baseboard_fab2_lib.baseboard_fab2(sch_1):page84_i14:DQ(30)" )
				( attribute "RELATIVE_PROPAGATION_DELAY_SCOPE" "G"
					( Parent
						( matchGroupRef "@baseboard_fab2_lib.baseboard_fab2(sch_1):\MG_DQ-DQS_NEAR_DIMM_NG_M_K_BYTE3\" )
					)
					( Status sCSetFlattened )
					( Origin gBackEnd )
				)
				( attribute "RELATIVE_PROPAGATION_DELAY" "0.00 MIL,195.00 MIL"
					( Parent
						( matchGroupRef "@baseboard_fab2_lib.baseboard_fab2(sch_1):\MG_DQ-DQS_NEAR_DIMM_NG_M_K_BYTE3\" )
					)
					( Units "uMatchProp" "ns" 1.000000)
					( Status sCSetFlattened )
					( Origin gBackEnd )
				)
				( attribute "RELATIVE_PROPAGATION_DELAY_SCOPE" "G"
					( Parent
						( matchGroupRef "@crescent_city_bb_fab1_lib.crescent_city_bb_fab1(sch_1):\MG_DQ_NEAR_DIMM_NG_M_K_BYTE3\" )
					)
					( Status sCSetFlattened )
					( Origin gBackEnd )
				)
				( attribute "RELATIVE_PROPAGATION_DELAY" "-50.00 MIL,50.00 MIL"
					( Parent
						( matchGroupRef "@crescent_city_bb_fab1_lib.crescent_city_bb_fab1(sch_1):\MG_DQ_NEAR_DIMM_NG_M_K_BYTE3\" )
					)
					( Units "uMatchProp" "ns" 1.000000)
					( Status sCSetFlattened )
					( Origin gBackEnd )
				)
			)
			( pinPair "@baseboard_fab2_lib.baseboard_fab2(sch_1):\PP2224\"
				( pinRef "@baseboard_fab2_lib.baseboard_fab2(sch_1):page60_i172:DDR3_DQ(31)" )
				( pinRef "@baseboard_fab2_lib.baseboard_fab2(sch_1):page83_i111:DQ(30)" )
				( attribute "RELATIVE_PROPAGATION_DELAY_SCOPE" "G"
					( Parent
						( matchGroupRef "@baseboard_fab2_lib.baseboard_fab2(sch_1):\MG_DQ-DQS_FAR_DIMM_NG_M_K_BYTE3\" )
					)
					( Status sCSetFlattened )
					( Origin gBackEnd )
				)
				( attribute "RELATIVE_PROPAGATION_DELAY" "0.00 MIL,195.00 MIL"
					( Parent
						( matchGroupRef "@baseboard_fab2_lib.baseboard_fab2(sch_1):\MG_DQ-DQS_FAR_DIMM_NG_M_K_BYTE3\" )
					)
					( Units "uMatchProp" "ns" 1.000000)
					( Status sCSetFlattened )
					( Origin gBackEnd )
				)
				( attribute "RELATIVE_PROPAGATION_DELAY_SCOPE" "G"
					( Parent
						( matchGroupRef "@crescent_city_bb_fab1_lib.crescent_city_bb_fab1(sch_1):\MG_DQ_FAR_DIMM_NG_M_K_BYTE3\" )
					)
					( Status sCSetFlattened )
					( Origin gBackEnd )
				)
				( attribute "RELATIVE_PROPAGATION_DELAY" "-50.00 MIL,50.00 MIL"
					( Parent
						( matchGroupRef "@crescent_city_bb_fab1_lib.crescent_city_bb_fab1(sch_1):\MG_DQ_FAR_DIMM_NG_M_K_BYTE3\" )
					)
					( Units "uMatchProp" "ns" 1.000000)
					( Status sCSetFlattened )
					( Origin gBackEnd )
				)
			)
			( pinPair "@baseboard_fab2_lib.baseboard_fab2(sch_1):\PP2225\"
				( pinRef "@baseboard_fab2_lib.baseboard_fab2(sch_1):page60_i172:DDR3_DQ(31)" )
				( pinRef "@baseboard_fab2_lib.baseboard_fab2(sch_1):page84_i14:DQ(31)" )
				( attribute "RELATIVE_PROPAGATION_DELAY_SCOPE" "G"
					( Parent
						( matchGroupRef "@baseboard_fab2_lib.baseboard_fab2(sch_1):\MG_DQ-DQS_NEAR_DIMM_NG_M_K_BYTE3\" )
					)
					( Status sCSetFlattened )
					( Origin gBackEnd )
				)
				( attribute "RELATIVE_PROPAGATION_DELAY" "0.00 MIL,195.00 MIL"
					( Parent
						( matchGroupRef "@baseboard_fab2_lib.baseboard_fab2(sch_1):\MG_DQ-DQS_NEAR_DIMM_NG_M_K_BYTE3\" )
					)
					( Units "uMatchProp" "ns" 1.000000)
					( Status sCSetFlattened )
					( Origin gBackEnd )
				)
				( attribute "RELATIVE_PROPAGATION_DELAY_SCOPE" "G"
					( Parent
						( matchGroupRef "@crescent_city_bb_fab1_lib.crescent_city_bb_fab1(sch_1):\MG_DQ_NEAR_DIMM_NG_M_K_BYTE3\" )
					)
					( Status sCSetFlattened )
					( Origin gBackEnd )
				)
				( attribute "RELATIVE_PROPAGATION_DELAY" "-50.00 MIL,50.00 MIL"
					( Parent
						( matchGroupRef "@crescent_city_bb_fab1_lib.crescent_city_bb_fab1(sch_1):\MG_DQ_NEAR_DIMM_NG_M_K_BYTE3\" )
					)
					( Units "uMatchProp" "ns" 1.000000)
					( Status sCSetFlattened )
					( Origin gBackEnd )
				)
			)
			( pinPair "@baseboard_fab2_lib.baseboard_fab2(sch_1):\PP2179\"
				( pinRef "@baseboard_fab2_lib.baseboard_fab2(sch_1):page60_i172:DDR3_DQ(32)" )
				( pinRef "@baseboard_fab2_lib.baseboard_fab2(sch_1):page83_i111:DQ(33)" )
				( attribute "RELATIVE_PROPAGATION_DELAY_SCOPE" "G"
					( Parent
						( matchGroupRef "@baseboard_fab2_lib.baseboard_fab2(sch_1):\MG_DQ-DQS_FAR_DIMM_NG_M_K_BYTE4\" )
					)
					( Status sCSetFlattened )
					( Origin gBackEnd )
				)
				( attribute "RELATIVE_PROPAGATION_DELAY" "0.00 MIL,195.00 MIL"
					( Parent
						( matchGroupRef "@baseboard_fab2_lib.baseboard_fab2(sch_1):\MG_DQ-DQS_FAR_DIMM_NG_M_K_BYTE4\" )
					)
					( Units "uMatchProp" "ns" 1.000000)
					( Status sCSetFlattened )
					( Origin gBackEnd )
				)
				( attribute "RELATIVE_PROPAGATION_DELAY_SCOPE" "G"
					( Parent
						( matchGroupRef "@baseboard_fab2_lib.baseboard_fab2(sch_1):\MG_DQ_FAR_DIMM_NG_M_K_BYTE4\" )
					)
					( Status sCSetFlattened )
					( Origin gBackEnd )
				)
				( attribute "RELATIVE_PROPAGATION_DELAY" "-50.00 MIL,50.00 MIL"
					( Parent
						( matchGroupRef "@baseboard_fab2_lib.baseboard_fab2(sch_1):\MG_DQ_FAR_DIMM_NG_M_K_BYTE4\" )
					)
					( Units "uMatchProp" "ns" 1.000000)
					( Status sCSetFlattened )
					( Origin gBackEnd )
				)
			)
			( pinPair "@baseboard_fab2_lib.baseboard_fab2(sch_1):\PP2181\"
				( pinRef "@baseboard_fab2_lib.baseboard_fab2(sch_1):page84_i14:DQ(32)" )
				( pinRef "@baseboard_fab2_lib.baseboard_fab2(sch_1):page60_i172:DDR3_DQ(32)" )
				( attribute "RELATIVE_PROPAGATION_DELAY_SCOPE" "G"
					( Parent
						( matchGroupRef "@baseboard_fab2_lib.baseboard_fab2(sch_1):\MG_DQ-DQS_NEAR_DIMM_NG_M_K_BYTE4\" )
					)
					( Status sCSetFlattened )
					( Origin gBackEnd )
				)
				( attribute "RELATIVE_PROPAGATION_DELAY" "0.00 MIL,195.00 MIL"
					( Parent
						( matchGroupRef "@baseboard_fab2_lib.baseboard_fab2(sch_1):\MG_DQ-DQS_NEAR_DIMM_NG_M_K_BYTE4\" )
					)
					( Units "uMatchProp" "ns" 1.000000)
					( Status sCSetFlattened )
					( Origin gBackEnd )
				)
				( attribute "RELATIVE_PROPAGATION_DELAY_SCOPE" "G"
					( Parent
						( matchGroupRef "@crescent_city_bb_fab1_lib.crescent_city_bb_fab1(sch_1):\MG_DQ_NEAR_DIMM_NG_M_K_BYTE4\" )
					)
					( Status sCSetFlattened )
					( Origin gBackEnd )
				)
				( attribute "RELATIVE_PROPAGATION_DELAY" "-50.00 MIL,50.00 MIL"
					( Parent
						( matchGroupRef "@crescent_city_bb_fab1_lib.crescent_city_bb_fab1(sch_1):\MG_DQ_NEAR_DIMM_NG_M_K_BYTE4\" )
					)
					( Units "uMatchProp" "ns" 1.000000)
					( Status sCSetFlattened )
					( Origin gBackEnd )
				)
			)
			( pinPair "@baseboard_fab2_lib.baseboard_fab2(sch_1):\PP2182\"
				( pinRef "@baseboard_fab2_lib.baseboard_fab2(sch_1):page60_i172:DDR3_DQ(33)" )
				( pinRef "@baseboard_fab2_lib.baseboard_fab2(sch_1):page83_i111:DQ(32)" )
				( attribute "RELATIVE_PROPAGATION_DELAY_SCOPE" "G"
					( Parent
						( matchGroupRef "@baseboard_fab2_lib.baseboard_fab2(sch_1):\MG_DQ-DQS_FAR_DIMM_NG_M_K_BYTE4\" )
					)
					( Status sCSetFlattened )
					( Origin gBackEnd )
				)
				( attribute "RELATIVE_PROPAGATION_DELAY" "0.00 MIL,195.00 MIL"
					( Parent
						( matchGroupRef "@baseboard_fab2_lib.baseboard_fab2(sch_1):\MG_DQ-DQS_FAR_DIMM_NG_M_K_BYTE4\" )
					)
					( Units "uMatchProp" "ns" 1.000000)
					( Status sCSetFlattened )
					( Origin gBackEnd )
				)
				( attribute "RELATIVE_PROPAGATION_DELAY_SCOPE" "G"
					( Parent
						( matchGroupRef "@baseboard_fab2_lib.baseboard_fab2(sch_1):\MG_DQ_FAR_DIMM_NG_M_K_BYTE4\" )
					)
					( Status sCSetFlattened )
					( Origin gBackEnd )
				)
				( attribute "RELATIVE_PROPAGATION_DELAY" "-50.00 MIL,50.00 MIL"
					( Parent
						( matchGroupRef "@baseboard_fab2_lib.baseboard_fab2(sch_1):\MG_DQ_FAR_DIMM_NG_M_K_BYTE4\" )
					)
					( Units "uMatchProp" "ns" 1.000000)
					( Status sCSetFlattened )
					( Origin gBackEnd )
				)
			)
			( pinPair "@baseboard_fab2_lib.baseboard_fab2(sch_1):\PP2184\"
				( pinRef "@baseboard_fab2_lib.baseboard_fab2(sch_1):page84_i14:DQ(33)" )
				( pinRef "@baseboard_fab2_lib.baseboard_fab2(sch_1):page60_i172:DDR3_DQ(33)" )
				( attribute "RELATIVE_PROPAGATION_DELAY_SCOPE" "G"
					( Parent
						( matchGroupRef "@baseboard_fab2_lib.baseboard_fab2(sch_1):\MG_DQ-DQS_NEAR_DIMM_NG_M_K_BYTE4\" )
					)
					( Status sCSetFlattened )
					( Origin gBackEnd )
				)
				( attribute "RELATIVE_PROPAGATION_DELAY" "0.00 MIL,195.00 MIL"
					( Parent
						( matchGroupRef "@baseboard_fab2_lib.baseboard_fab2(sch_1):\MG_DQ-DQS_NEAR_DIMM_NG_M_K_BYTE4\" )
					)
					( Units "uMatchProp" "ns" 1.000000)
					( Status sCSetFlattened )
					( Origin gBackEnd )
				)
				( attribute "RELATIVE_PROPAGATION_DELAY_SCOPE" "G"
					( Parent
						( matchGroupRef "@crescent_city_bb_fab1_lib.crescent_city_bb_fab1(sch_1):\MG_DQ_NEAR_DIMM_NG_M_K_BYTE4\" )
					)
					( Status sCSetFlattened )
					( Origin gBackEnd )
				)
				( attribute "RELATIVE_PROPAGATION_DELAY" "-50.00 MIL,50.00 MIL"
					( Parent
						( matchGroupRef "@crescent_city_bb_fab1_lib.crescent_city_bb_fab1(sch_1):\MG_DQ_NEAR_DIMM_NG_M_K_BYTE4\" )
					)
					( Units "uMatchProp" "ns" 1.000000)
					( Status sCSetFlattened )
					( Origin gBackEnd )
				)
			)
			( pinPair "@baseboard_fab2_lib.baseboard_fab2(sch_1):\PP2185\"
				( pinRef "@baseboard_fab2_lib.baseboard_fab2(sch_1):page60_i172:DDR3_DQ(34)" )
				( pinRef "@baseboard_fab2_lib.baseboard_fab2(sch_1):page83_i111:DQ(35)" )
				( attribute "RELATIVE_PROPAGATION_DELAY_SCOPE" "G"
					( Parent
						( matchGroupRef "@baseboard_fab2_lib.baseboard_fab2(sch_1):\MG_DQ-DQS_FAR_DIMM_NG_M_K_BYTE4\" )
					)
					( Status sCSetFlattened )
					( Origin gBackEnd )
				)
				( attribute "RELATIVE_PROPAGATION_DELAY" "0.00 MIL,195.00 MIL"
					( Parent
						( matchGroupRef "@baseboard_fab2_lib.baseboard_fab2(sch_1):\MG_DQ-DQS_FAR_DIMM_NG_M_K_BYTE4\" )
					)
					( Units "uMatchProp" "ns" 1.000000)
					( Status sCSetFlattened )
					( Origin gBackEnd )
				)
				( attribute "RELATIVE_PROPAGATION_DELAY_SCOPE" "G"
					( Parent
						( matchGroupRef "@baseboard_fab2_lib.baseboard_fab2(sch_1):\MG_DQ_FAR_DIMM_NG_M_K_BYTE4\" )
					)
					( Status sCSetFlattened )
					( Origin gBackEnd )
				)
				( attribute "RELATIVE_PROPAGATION_DELAY" "-50.00 MIL,50.00 MIL"
					( Parent
						( matchGroupRef "@baseboard_fab2_lib.baseboard_fab2(sch_1):\MG_DQ_FAR_DIMM_NG_M_K_BYTE4\" )
					)
					( Units "uMatchProp" "ns" 1.000000)
					( Status sCSetFlattened )
					( Origin gBackEnd )
				)
			)
			( pinPair "@baseboard_fab2_lib.baseboard_fab2(sch_1):\PP2187\"
				( pinRef "@baseboard_fab2_lib.baseboard_fab2(sch_1):page84_i14:DQ(34)" )
				( pinRef "@baseboard_fab2_lib.baseboard_fab2(sch_1):page60_i172:DDR3_DQ(34)" )
				( attribute "RELATIVE_PROPAGATION_DELAY_SCOPE" "G"
					( Parent
						( matchGroupRef "@baseboard_fab2_lib.baseboard_fab2(sch_1):\MG_DQ-DQS_NEAR_DIMM_NG_M_K_BYTE4\" )
					)
					( Status sCSetFlattened )
					( Origin gBackEnd )
				)
				( attribute "RELATIVE_PROPAGATION_DELAY" "0.00 MIL,195.00 MIL"
					( Parent
						( matchGroupRef "@baseboard_fab2_lib.baseboard_fab2(sch_1):\MG_DQ-DQS_NEAR_DIMM_NG_M_K_BYTE4\" )
					)
					( Units "uMatchProp" "ns" 1.000000)
					( Status sCSetFlattened )
					( Origin gBackEnd )
				)
				( attribute "RELATIVE_PROPAGATION_DELAY_SCOPE" "G"
					( Parent
						( matchGroupRef "@crescent_city_bb_fab1_lib.crescent_city_bb_fab1(sch_1):\MG_DQ_NEAR_DIMM_NG_M_K_BYTE4\" )
					)
					( Status sCSetFlattened )
					( Origin gBackEnd )
				)
				( attribute "RELATIVE_PROPAGATION_DELAY" "-50.00 MIL,50.00 MIL"
					( Parent
						( matchGroupRef "@crescent_city_bb_fab1_lib.crescent_city_bb_fab1(sch_1):\MG_DQ_NEAR_DIMM_NG_M_K_BYTE4\" )
					)
					( Units "uMatchProp" "ns" 1.000000)
					( Status sCSetFlattened )
					( Origin gBackEnd )
				)
			)
			( pinPair "@baseboard_fab2_lib.baseboard_fab2(sch_1):\PP2188\"
				( pinRef "@baseboard_fab2_lib.baseboard_fab2(sch_1):page60_i172:DDR3_DQ(35)" )
				( pinRef "@baseboard_fab2_lib.baseboard_fab2(sch_1):page83_i111:DQ(34)" )
				( attribute "RELATIVE_PROPAGATION_DELAY_SCOPE" "G"
					( Parent
						( matchGroupRef "@baseboard_fab2_lib.baseboard_fab2(sch_1):\MG_DQ-DQS_FAR_DIMM_NG_M_K_BYTE4\" )
					)
					( Status sCSetFlattened )
					( Origin gBackEnd )
				)
				( attribute "RELATIVE_PROPAGATION_DELAY" "0.00 MIL,195.00 MIL"
					( Parent
						( matchGroupRef "@baseboard_fab2_lib.baseboard_fab2(sch_1):\MG_DQ-DQS_FAR_DIMM_NG_M_K_BYTE4\" )
					)
					( Units "uMatchProp" "ns" 1.000000)
					( Status sCSetFlattened )
					( Origin gBackEnd )
				)
				( attribute "RELATIVE_PROPAGATION_DELAY_SCOPE" "G"
					( Parent
						( matchGroupRef "@baseboard_fab2_lib.baseboard_fab2(sch_1):\MG_DQ_FAR_DIMM_NG_M_K_BYTE4\" )
					)
					( Status sCSetFlattened )
					( Origin gBackEnd )
				)
				( attribute "RELATIVE_PROPAGATION_DELAY" "-50.00 MIL,50.00 MIL"
					( Parent
						( matchGroupRef "@baseboard_fab2_lib.baseboard_fab2(sch_1):\MG_DQ_FAR_DIMM_NG_M_K_BYTE4\" )
					)
					( Units "uMatchProp" "ns" 1.000000)
					( Status sCSetFlattened )
					( Origin gBackEnd )
				)
			)
			( pinPair "@baseboard_fab2_lib.baseboard_fab2(sch_1):\PP2190\"
				( pinRef "@baseboard_fab2_lib.baseboard_fab2(sch_1):page84_i14:DQ(35)" )
				( pinRef "@baseboard_fab2_lib.baseboard_fab2(sch_1):page60_i172:DDR3_DQ(35)" )
				( attribute "RELATIVE_PROPAGATION_DELAY_SCOPE" "G"
					( Parent
						( matchGroupRef "@baseboard_fab2_lib.baseboard_fab2(sch_1):\MG_DQ-DQS_NEAR_DIMM_NG_M_K_BYTE4\" )
					)
					( Status sCSetFlattened )
					( Origin gBackEnd )
				)
				( attribute "RELATIVE_PROPAGATION_DELAY" "0.00 MIL,195.00 MIL"
					( Parent
						( matchGroupRef "@baseboard_fab2_lib.baseboard_fab2(sch_1):\MG_DQ-DQS_NEAR_DIMM_NG_M_K_BYTE4\" )
					)
					( Units "uMatchProp" "ns" 1.000000)
					( Status sCSetFlattened )
					( Origin gBackEnd )
				)
				( attribute "RELATIVE_PROPAGATION_DELAY_SCOPE" "G"
					( Parent
						( matchGroupRef "@crescent_city_bb_fab1_lib.crescent_city_bb_fab1(sch_1):\MG_DQ_NEAR_DIMM_NG_M_K_BYTE4\" )
					)
					( Origin gBackEnd )
				)
				( attribute "RELATIVE_PROPAGATION_DELAY" "TARGET,TARGET"
					( Parent
						( matchGroupRef "@crescent_city_bb_fab1_lib.crescent_city_bb_fab1(sch_1):\MG_DQ_NEAR_DIMM_NG_M_K_BYTE4\" )
					)
					( Units "uMatchProp" "ns" 1.000000)
					( Origin gBackEnd )
				)
			)
			( pinPair "@baseboard_fab2_lib.baseboard_fab2(sch_1):\PP2191\"
				( pinRef "@baseboard_fab2_lib.baseboard_fab2(sch_1):page60_i172:DDR3_DQ(36)" )
				( pinRef "@baseboard_fab2_lib.baseboard_fab2(sch_1):page83_i111:DQ(37)" )
				( attribute "RELATIVE_PROPAGATION_DELAY_SCOPE" "G"
					( Parent
						( matchGroupRef "@baseboard_fab2_lib.baseboard_fab2(sch_1):\MG_DQ-DQS_FAR_DIMM_NG_M_K_BYTE4\" )
					)
					( Status sCSetFlattened )
					( Origin gBackEnd )
				)
				( attribute "RELATIVE_PROPAGATION_DELAY" "0.00 MIL,195.00 MIL"
					( Parent
						( matchGroupRef "@baseboard_fab2_lib.baseboard_fab2(sch_1):\MG_DQ-DQS_FAR_DIMM_NG_M_K_BYTE4\" )
					)
					( Units "uMatchProp" "ns" 1.000000)
					( Status sCSetFlattened )
					( Origin gBackEnd )
				)
				( attribute "RELATIVE_PROPAGATION_DELAY_SCOPE" "G"
					( Parent
						( matchGroupRef "@baseboard_fab2_lib.baseboard_fab2(sch_1):\MG_DQ_FAR_DIMM_NG_M_K_BYTE4\" )
					)
					( Status sCSetFlattened )
					( Origin gBackEnd )
				)
				( attribute "RELATIVE_PROPAGATION_DELAY" "-50.00 MIL,50.00 MIL"
					( Parent
						( matchGroupRef "@baseboard_fab2_lib.baseboard_fab2(sch_1):\MG_DQ_FAR_DIMM_NG_M_K_BYTE4\" )
					)
					( Units "uMatchProp" "ns" 1.000000)
					( Status sCSetFlattened )
					( Origin gBackEnd )
				)
			)
			( pinPair "@baseboard_fab2_lib.baseboard_fab2(sch_1):\PP2193\"
				( pinRef "@baseboard_fab2_lib.baseboard_fab2(sch_1):page84_i14:DQ(36)" )
				( pinRef "@baseboard_fab2_lib.baseboard_fab2(sch_1):page60_i172:DDR3_DQ(36)" )
				( attribute "RELATIVE_PROPAGATION_DELAY_SCOPE" "G"
					( Parent
						( matchGroupRef "@baseboard_fab2_lib.baseboard_fab2(sch_1):\MG_DQ-DQS_NEAR_DIMM_NG_M_K_BYTE4\" )
					)
					( Status sCSetFlattened )
					( Origin gBackEnd )
				)
				( attribute "RELATIVE_PROPAGATION_DELAY" "0.00 MIL,195.00 MIL"
					( Parent
						( matchGroupRef "@baseboard_fab2_lib.baseboard_fab2(sch_1):\MG_DQ-DQS_NEAR_DIMM_NG_M_K_BYTE4\" )
					)
					( Units "uMatchProp" "ns" 1.000000)
					( Status sCSetFlattened )
					( Origin gBackEnd )
				)
				( attribute "RELATIVE_PROPAGATION_DELAY_SCOPE" "G"
					( Parent
						( matchGroupRef "@crescent_city_bb_fab1_lib.crescent_city_bb_fab1(sch_1):\MG_DQ_NEAR_DIMM_NG_M_K_BYTE4\" )
					)
					( Status sCSetFlattened )
					( Origin gBackEnd )
				)
				( attribute "RELATIVE_PROPAGATION_DELAY" "-50.00 MIL,50.00 MIL"
					( Parent
						( matchGroupRef "@crescent_city_bb_fab1_lib.crescent_city_bb_fab1(sch_1):\MG_DQ_NEAR_DIMM_NG_M_K_BYTE4\" )
					)
					( Units "uMatchProp" "ns" 1.000000)
					( Status sCSetFlattened )
					( Origin gBackEnd )
				)
			)
			( pinPair "@baseboard_fab2_lib.baseboard_fab2(sch_1):\PP2194\"
				( pinRef "@baseboard_fab2_lib.baseboard_fab2(sch_1):page60_i172:DDR3_DQ(37)" )
				( pinRef "@baseboard_fab2_lib.baseboard_fab2(sch_1):page83_i111:DQ(36)" )
				( attribute "RELATIVE_PROPAGATION_DELAY_SCOPE" "G"
					( Parent
						( matchGroupRef "@baseboard_fab2_lib.baseboard_fab2(sch_1):\MG_DQ-DQS_FAR_DIMM_NG_M_K_BYTE4\" )
					)
					( Status sCSetFlattened )
					( Origin gBackEnd )
				)
				( attribute "RELATIVE_PROPAGATION_DELAY" "0.00 MIL,195.00 MIL"
					( Parent
						( matchGroupRef "@baseboard_fab2_lib.baseboard_fab2(sch_1):\MG_DQ-DQS_FAR_DIMM_NG_M_K_BYTE4\" )
					)
					( Units "uMatchProp" "ns" 1.000000)
					( Status sCSetFlattened )
					( Origin gBackEnd )
				)
				( attribute "RELATIVE_PROPAGATION_DELAY_SCOPE" "G"
					( Parent
						( matchGroupRef "@baseboard_fab2_lib.baseboard_fab2(sch_1):\MG_DQ_FAR_DIMM_NG_M_K_BYTE4\" )
					)
					( Status sCSetFlattened )
					( Origin gBackEnd )
				)
				( attribute "RELATIVE_PROPAGATION_DELAY" "-50.00 MIL,50.00 MIL"
					( Parent
						( matchGroupRef "@baseboard_fab2_lib.baseboard_fab2(sch_1):\MG_DQ_FAR_DIMM_NG_M_K_BYTE4\" )
					)
					( Units "uMatchProp" "ns" 1.000000)
					( Status sCSetFlattened )
					( Origin gBackEnd )
				)
			)
			( pinPair "@baseboard_fab2_lib.baseboard_fab2(sch_1):\PP2196\"
				( pinRef "@baseboard_fab2_lib.baseboard_fab2(sch_1):page84_i14:DQ(37)" )
				( pinRef "@baseboard_fab2_lib.baseboard_fab2(sch_1):page60_i172:DDR3_DQ(37)" )
				( attribute "RELATIVE_PROPAGATION_DELAY_SCOPE" "G"
					( Parent
						( matchGroupRef "@baseboard_fab2_lib.baseboard_fab2(sch_1):\MG_DQ-DQS_NEAR_DIMM_NG_M_K_BYTE4\" )
					)
					( Status sCSetFlattened )
					( Origin gBackEnd )
				)
				( attribute "RELATIVE_PROPAGATION_DELAY" "0.00 MIL,195.00 MIL"
					( Parent
						( matchGroupRef "@baseboard_fab2_lib.baseboard_fab2(sch_1):\MG_DQ-DQS_NEAR_DIMM_NG_M_K_BYTE4\" )
					)
					( Units "uMatchProp" "ns" 1.000000)
					( Status sCSetFlattened )
					( Origin gBackEnd )
				)
				( attribute "RELATIVE_PROPAGATION_DELAY_SCOPE" "G"
					( Parent
						( matchGroupRef "@crescent_city_bb_fab1_lib.crescent_city_bb_fab1(sch_1):\MG_DQ_NEAR_DIMM_NG_M_K_BYTE4\" )
					)
					( Status sCSetFlattened )
					( Origin gBackEnd )
				)
				( attribute "RELATIVE_PROPAGATION_DELAY" "-50.00 MIL,50.00 MIL"
					( Parent
						( matchGroupRef "@crescent_city_bb_fab1_lib.crescent_city_bb_fab1(sch_1):\MG_DQ_NEAR_DIMM_NG_M_K_BYTE4\" )
					)
					( Units "uMatchProp" "ns" 1.000000)
					( Status sCSetFlattened )
					( Origin gBackEnd )
				)
			)
			( pinPair "@baseboard_fab2_lib.baseboard_fab2(sch_1):\PP2197\"
				( pinRef "@baseboard_fab2_lib.baseboard_fab2(sch_1):page60_i172:DDR3_DQ(38)" )
				( pinRef "@baseboard_fab2_lib.baseboard_fab2(sch_1):page83_i111:DQ(39)" )
				( attribute "RELATIVE_PROPAGATION_DELAY_SCOPE" "G"
					( Parent
						( matchGroupRef "@baseboard_fab2_lib.baseboard_fab2(sch_1):\MG_DQ-DQS_FAR_DIMM_NG_M_K_BYTE4\" )
					)
					( Status sCSetFlattened )
					( Origin gBackEnd )
				)
				( attribute "RELATIVE_PROPAGATION_DELAY" "0.00 MIL,195.00 MIL"
					( Parent
						( matchGroupRef "@baseboard_fab2_lib.baseboard_fab2(sch_1):\MG_DQ-DQS_FAR_DIMM_NG_M_K_BYTE4\" )
					)
					( Units "uMatchProp" "ns" 1.000000)
					( Status sCSetFlattened )
					( Origin gBackEnd )
				)
				( attribute "RELATIVE_PROPAGATION_DELAY_SCOPE" "G"
					( Parent
						( matchGroupRef "@baseboard_fab2_lib.baseboard_fab2(sch_1):\MG_DQ_FAR_DIMM_NG_M_K_BYTE4\" )
					)
					( Status sCSetFlattened )
					( Origin gBackEnd )
				)
				( attribute "RELATIVE_PROPAGATION_DELAY" "-50.00 MIL,50.00 MIL"
					( Parent
						( matchGroupRef "@baseboard_fab2_lib.baseboard_fab2(sch_1):\MG_DQ_FAR_DIMM_NG_M_K_BYTE4\" )
					)
					( Units "uMatchProp" "ns" 1.000000)
					( Status sCSetFlattened )
					( Origin gBackEnd )
				)
			)
			( pinPair "@baseboard_fab2_lib.baseboard_fab2(sch_1):\PP2199\"
				( pinRef "@baseboard_fab2_lib.baseboard_fab2(sch_1):page84_i14:DQ(38)" )
				( pinRef "@baseboard_fab2_lib.baseboard_fab2(sch_1):page60_i172:DDR3_DQ(38)" )
				( attribute "RELATIVE_PROPAGATION_DELAY_SCOPE" "G"
					( Parent
						( matchGroupRef "@baseboard_fab2_lib.baseboard_fab2(sch_1):\MG_DQ-DQS_NEAR_DIMM_NG_M_K_BYTE4\" )
					)
					( Status sCSetFlattened )
					( Origin gBackEnd )
				)
				( attribute "RELATIVE_PROPAGATION_DELAY" "0.00 MIL,195.00 MIL"
					( Parent
						( matchGroupRef "@baseboard_fab2_lib.baseboard_fab2(sch_1):\MG_DQ-DQS_NEAR_DIMM_NG_M_K_BYTE4\" )
					)
					( Units "uMatchProp" "ns" 1.000000)
					( Status sCSetFlattened )
					( Origin gBackEnd )
				)
				( attribute "RELATIVE_PROPAGATION_DELAY_SCOPE" "G"
					( Parent
						( matchGroupRef "@crescent_city_bb_fab1_lib.crescent_city_bb_fab1(sch_1):\MG_DQ_NEAR_DIMM_NG_M_K_BYTE4\" )
					)
					( Status sCSetFlattened )
					( Origin gBackEnd )
				)
				( attribute "RELATIVE_PROPAGATION_DELAY" "-50.00 MIL,50.00 MIL"
					( Parent
						( matchGroupRef "@crescent_city_bb_fab1_lib.crescent_city_bb_fab1(sch_1):\MG_DQ_NEAR_DIMM_NG_M_K_BYTE4\" )
					)
					( Units "uMatchProp" "ns" 1.000000)
					( Status sCSetFlattened )
					( Origin gBackEnd )
				)
			)
			( pinPair "@baseboard_fab2_lib.baseboard_fab2(sch_1):\PP2200\"
				( pinRef "@baseboard_fab2_lib.baseboard_fab2(sch_1):page60_i172:DDR3_DQ(39)" )
				( pinRef "@baseboard_fab2_lib.baseboard_fab2(sch_1):page83_i111:DQ(38)" )
				( attribute "RELATIVE_PROPAGATION_DELAY_SCOPE" "G"
					( Parent
						( matchGroupRef "@baseboard_fab2_lib.baseboard_fab2(sch_1):\MG_DQ-DQS_FAR_DIMM_NG_M_K_BYTE4\" )
					)
					( Status sCSetFlattened )
					( Origin gBackEnd )
				)
				( attribute "RELATIVE_PROPAGATION_DELAY" "0.00 MIL,195.00 MIL"
					( Parent
						( matchGroupRef "@baseboard_fab2_lib.baseboard_fab2(sch_1):\MG_DQ-DQS_FAR_DIMM_NG_M_K_BYTE4\" )
					)
					( Units "uMatchProp" "ns" 1.000000)
					( Status sCSetFlattened )
					( Origin gBackEnd )
				)
				( attribute "RELATIVE_PROPAGATION_DELAY_SCOPE" "G"
					( Parent
						( matchGroupRef "@baseboard_fab2_lib.baseboard_fab2(sch_1):\MG_DQ_FAR_DIMM_NG_M_K_BYTE4\" )
					)
					( Status sCSetFlattened )
					( Origin gBackEnd )
				)
				( attribute "RELATIVE_PROPAGATION_DELAY" "-50.00 MIL,50.00 MIL"
					( Parent
						( matchGroupRef "@baseboard_fab2_lib.baseboard_fab2(sch_1):\MG_DQ_FAR_DIMM_NG_M_K_BYTE4\" )
					)
					( Units "uMatchProp" "ns" 1.000000)
					( Status sCSetFlattened )
					( Origin gBackEnd )
				)
			)
			( pinPair "@baseboard_fab2_lib.baseboard_fab2(sch_1):\PP2202\"
				( pinRef "@baseboard_fab2_lib.baseboard_fab2(sch_1):page84_i14:DQ(39)" )
				( pinRef "@baseboard_fab2_lib.baseboard_fab2(sch_1):page60_i172:DDR3_DQ(39)" )
				( attribute "RELATIVE_PROPAGATION_DELAY_SCOPE" "G"
					( Parent
						( matchGroupRef "@baseboard_fab2_lib.baseboard_fab2(sch_1):\MG_DQ-DQS_NEAR_DIMM_NG_M_K_BYTE4\" )
					)
					( Status sCSetFlattened )
					( Origin gBackEnd )
				)
				( attribute "RELATIVE_PROPAGATION_DELAY" "0.00 MIL,195.00 MIL"
					( Parent
						( matchGroupRef "@baseboard_fab2_lib.baseboard_fab2(sch_1):\MG_DQ-DQS_NEAR_DIMM_NG_M_K_BYTE4\" )
					)
					( Units "uMatchProp" "ns" 1.000000)
					( Status sCSetFlattened )
					( Origin gBackEnd )
				)
				( attribute "RELATIVE_PROPAGATION_DELAY_SCOPE" "G"
					( Parent
						( matchGroupRef "@crescent_city_bb_fab1_lib.crescent_city_bb_fab1(sch_1):\MG_DQ_NEAR_DIMM_NG_M_K_BYTE4\" )
					)
					( Status sCSetFlattened )
					( Origin gBackEnd )
				)
				( attribute "RELATIVE_PROPAGATION_DELAY" "-50.00 MIL,50.00 MIL"
					( Parent
						( matchGroupRef "@crescent_city_bb_fab1_lib.crescent_city_bb_fab1(sch_1):\MG_DQ_NEAR_DIMM_NG_M_K_BYTE4\" )
					)
					( Units "uMatchProp" "ns" 1.000000)
					( Status sCSetFlattened )
					( Origin gBackEnd )
				)
			)
			( pinPair "@baseboard_fab2_lib.baseboard_fab2(sch_1):\PP2155\"
				( pinRef "@baseboard_fab2_lib.baseboard_fab2(sch_1):page60_i172:DDR3_DQ(40)" )
				( pinRef "@baseboard_fab2_lib.baseboard_fab2(sch_1):page83_i111:DQ(41)" )
				( attribute "RELATIVE_PROPAGATION_DELAY_SCOPE" "G"
					( Parent
						( matchGroupRef "@baseboard_fab2_lib.baseboard_fab2(sch_1):\MG_DQ-DQS_FAR_DIMM_NG_M_K_BYTE5\" )
					)
					( Status sCSetFlattened )
					( Origin gBackEnd )
				)
				( attribute "RELATIVE_PROPAGATION_DELAY" "0.00 MIL,195.00 MIL"
					( Parent
						( matchGroupRef "@baseboard_fab2_lib.baseboard_fab2(sch_1):\MG_DQ-DQS_FAR_DIMM_NG_M_K_BYTE5\" )
					)
					( Units "uMatchProp" "ns" 1.000000)
					( Status sCSetFlattened )
					( Origin gBackEnd )
				)
				( attribute "RELATIVE_PROPAGATION_DELAY_SCOPE" "G"
					( Parent
						( matchGroupRef "@crescent_city_bb_fab1_lib.crescent_city_bb_fab1(sch_1):\MG_DQ_FAR_DIMM_NG_M_K_BYTE5\" )
					)
					( Status sCSetFlattened )
					( Origin gBackEnd )
				)
				( attribute "RELATIVE_PROPAGATION_DELAY" "-50.00 MIL,50.00 MIL"
					( Parent
						( matchGroupRef "@crescent_city_bb_fab1_lib.crescent_city_bb_fab1(sch_1):\MG_DQ_FAR_DIMM_NG_M_K_BYTE5\" )
					)
					( Units "uMatchProp" "ns" 1.000000)
					( Status sCSetFlattened )
					( Origin gBackEnd )
				)
			)
			( pinPair "@baseboard_fab2_lib.baseboard_fab2(sch_1):\PP2157\"
				( pinRef "@baseboard_fab2_lib.baseboard_fab2(sch_1):page60_i172:DDR3_DQ(40)" )
				( pinRef "@baseboard_fab2_lib.baseboard_fab2(sch_1):page84_i14:DQ(40)" )
				( attribute "RELATIVE_PROPAGATION_DELAY_SCOPE" "G"
					( Parent
						( matchGroupRef "@baseboard_fab2_lib.baseboard_fab2(sch_1):\MG_DQ-DQS_NEAR_DIMM_NG_M_K_BYTE5\" )
					)
					( Status sCSetFlattened )
					( Origin gBackEnd )
				)
				( attribute "RELATIVE_PROPAGATION_DELAY" "0.00 MIL,195.00 MIL"
					( Parent
						( matchGroupRef "@baseboard_fab2_lib.baseboard_fab2(sch_1):\MG_DQ-DQS_NEAR_DIMM_NG_M_K_BYTE5\" )
					)
					( Units "uMatchProp" "ns" 1.000000)
					( Status sCSetFlattened )
					( Origin gBackEnd )
				)
				( attribute "RELATIVE_PROPAGATION_DELAY_SCOPE" "G"
					( Parent
						( matchGroupRef "@crescent_city_bb_fab1_lib.crescent_city_bb_fab1(sch_1):\MG_DQ_NEAR_DIMM_NG_M_K_BYTE5\" )
					)
					( Status sCSetFlattened )
					( Origin gBackEnd )
				)
				( attribute "RELATIVE_PROPAGATION_DELAY" "-50.00 MIL,50.00 MIL"
					( Parent
						( matchGroupRef "@crescent_city_bb_fab1_lib.crescent_city_bb_fab1(sch_1):\MG_DQ_NEAR_DIMM_NG_M_K_BYTE5\" )
					)
					( Units "uMatchProp" "ns" 1.000000)
					( Status sCSetFlattened )
					( Origin gBackEnd )
				)
			)
			( pinPair "@baseboard_fab2_lib.baseboard_fab2(sch_1):\PP2158\"
				( pinRef "@baseboard_fab2_lib.baseboard_fab2(sch_1):page60_i172:DDR3_DQ(41)" )
				( pinRef "@baseboard_fab2_lib.baseboard_fab2(sch_1):page83_i111:DQ(40)" )
				( attribute "RELATIVE_PROPAGATION_DELAY_SCOPE" "G"
					( Parent
						( matchGroupRef "@baseboard_fab2_lib.baseboard_fab2(sch_1):\MG_DQ-DQS_FAR_DIMM_NG_M_K_BYTE5\" )
					)
					( Status sCSetFlattened )
					( Origin gBackEnd )
				)
				( attribute "RELATIVE_PROPAGATION_DELAY" "0.00 MIL,195.00 MIL"
					( Parent
						( matchGroupRef "@baseboard_fab2_lib.baseboard_fab2(sch_1):\MG_DQ-DQS_FAR_DIMM_NG_M_K_BYTE5\" )
					)
					( Units "uMatchProp" "ns" 1.000000)
					( Status sCSetFlattened )
					( Origin gBackEnd )
				)
				( attribute "RELATIVE_PROPAGATION_DELAY_SCOPE" "G"
					( Parent
						( matchGroupRef "@crescent_city_bb_fab1_lib.crescent_city_bb_fab1(sch_1):\MG_DQ_FAR_DIMM_NG_M_K_BYTE5\" )
					)
					( Status sCSetFlattened )
					( Origin gBackEnd )
				)
				( attribute "RELATIVE_PROPAGATION_DELAY" "-50.00 MIL,50.00 MIL"
					( Parent
						( matchGroupRef "@crescent_city_bb_fab1_lib.crescent_city_bb_fab1(sch_1):\MG_DQ_FAR_DIMM_NG_M_K_BYTE5\" )
					)
					( Units "uMatchProp" "ns" 1.000000)
					( Status sCSetFlattened )
					( Origin gBackEnd )
				)
			)
			( pinPair "@baseboard_fab2_lib.baseboard_fab2(sch_1):\PP2160\"
				( pinRef "@baseboard_fab2_lib.baseboard_fab2(sch_1):page60_i172:DDR3_DQ(41)" )
				( pinRef "@baseboard_fab2_lib.baseboard_fab2(sch_1):page84_i14:DQ(41)" )
				( attribute "RELATIVE_PROPAGATION_DELAY_SCOPE" "G"
					( Parent
						( matchGroupRef "@baseboard_fab2_lib.baseboard_fab2(sch_1):\MG_DQ-DQS_NEAR_DIMM_NG_M_K_BYTE5\" )
					)
					( Status sCSetFlattened )
					( Origin gBackEnd )
				)
				( attribute "RELATIVE_PROPAGATION_DELAY" "0.00 MIL,195.00 MIL"
					( Parent
						( matchGroupRef "@baseboard_fab2_lib.baseboard_fab2(sch_1):\MG_DQ-DQS_NEAR_DIMM_NG_M_K_BYTE5\" )
					)
					( Units "uMatchProp" "ns" 1.000000)
					( Status sCSetFlattened )
					( Origin gBackEnd )
				)
				( attribute "RELATIVE_PROPAGATION_DELAY_SCOPE" "G"
					( Parent
						( matchGroupRef "@crescent_city_bb_fab1_lib.crescent_city_bb_fab1(sch_1):\MG_DQ_NEAR_DIMM_NG_M_K_BYTE5\" )
					)
					( Origin gBackEnd )
				)
				( attribute "RELATIVE_PROPAGATION_DELAY" "TARGET,TARGET"
					( Parent
						( matchGroupRef "@crescent_city_bb_fab1_lib.crescent_city_bb_fab1(sch_1):\MG_DQ_NEAR_DIMM_NG_M_K_BYTE5\" )
					)
					( Units "uMatchProp" "ns" 1.000000)
					( Origin gBackEnd )
				)
			)
			( pinPair "@baseboard_fab2_lib.baseboard_fab2(sch_1):\PP2161\"
				( pinRef "@baseboard_fab2_lib.baseboard_fab2(sch_1):page60_i172:DDR3_DQ(42)" )
				( pinRef "@baseboard_fab2_lib.baseboard_fab2(sch_1):page83_i111:DQ(43)" )
				( attribute "RELATIVE_PROPAGATION_DELAY_SCOPE" "G"
					( Parent
						( matchGroupRef "@baseboard_fab2_lib.baseboard_fab2(sch_1):\MG_DQ-DQS_FAR_DIMM_NG_M_K_BYTE5\" )
					)
					( Status sCSetFlattened )
					( Origin gBackEnd )
				)
				( attribute "RELATIVE_PROPAGATION_DELAY" "0.00 MIL,195.00 MIL"
					( Parent
						( matchGroupRef "@baseboard_fab2_lib.baseboard_fab2(sch_1):\MG_DQ-DQS_FAR_DIMM_NG_M_K_BYTE5\" )
					)
					( Units "uMatchProp" "ns" 1.000000)
					( Status sCSetFlattened )
					( Origin gBackEnd )
				)
				( attribute "RELATIVE_PROPAGATION_DELAY_SCOPE" "G"
					( Parent
						( matchGroupRef "@crescent_city_bb_fab1_lib.crescent_city_bb_fab1(sch_1):\MG_DQ_FAR_DIMM_NG_M_K_BYTE5\" )
					)
					( Status sCSetFlattened )
					( Origin gBackEnd )
				)
				( attribute "RELATIVE_PROPAGATION_DELAY" "-50.00 MIL,50.00 MIL"
					( Parent
						( matchGroupRef "@crescent_city_bb_fab1_lib.crescent_city_bb_fab1(sch_1):\MG_DQ_FAR_DIMM_NG_M_K_BYTE5\" )
					)
					( Units "uMatchProp" "ns" 1.000000)
					( Status sCSetFlattened )
					( Origin gBackEnd )
				)
			)
			( pinPair "@baseboard_fab2_lib.baseboard_fab2(sch_1):\PP2163\"
				( pinRef "@baseboard_fab2_lib.baseboard_fab2(sch_1):page60_i172:DDR3_DQ(42)" )
				( pinRef "@baseboard_fab2_lib.baseboard_fab2(sch_1):page84_i14:DQ(42)" )
				( attribute "RELATIVE_PROPAGATION_DELAY_SCOPE" "G"
					( Parent
						( matchGroupRef "@baseboard_fab2_lib.baseboard_fab2(sch_1):\MG_DQ-DQS_NEAR_DIMM_NG_M_K_BYTE5\" )
					)
					( Status sCSetFlattened )
					( Origin gBackEnd )
				)
				( attribute "RELATIVE_PROPAGATION_DELAY" "0.00 MIL,195.00 MIL"
					( Parent
						( matchGroupRef "@baseboard_fab2_lib.baseboard_fab2(sch_1):\MG_DQ-DQS_NEAR_DIMM_NG_M_K_BYTE5\" )
					)
					( Units "uMatchProp" "ns" 1.000000)
					( Status sCSetFlattened )
					( Origin gBackEnd )
				)
				( attribute "RELATIVE_PROPAGATION_DELAY_SCOPE" "G"
					( Parent
						( matchGroupRef "@crescent_city_bb_fab1_lib.crescent_city_bb_fab1(sch_1):\MG_DQ_NEAR_DIMM_NG_M_K_BYTE5\" )
					)
					( Status sCSetFlattened )
					( Origin gBackEnd )
				)
				( attribute "RELATIVE_PROPAGATION_DELAY" "-50.00 MIL,50.00 MIL"
					( Parent
						( matchGroupRef "@crescent_city_bb_fab1_lib.crescent_city_bb_fab1(sch_1):\MG_DQ_NEAR_DIMM_NG_M_K_BYTE5\" )
					)
					( Units "uMatchProp" "ns" 1.000000)
					( Status sCSetFlattened )
					( Origin gBackEnd )
				)
			)
			( pinPair "@baseboard_fab2_lib.baseboard_fab2(sch_1):\PP2164\"
				( pinRef "@baseboard_fab2_lib.baseboard_fab2(sch_1):page60_i172:DDR3_DQ(43)" )
				( pinRef "@baseboard_fab2_lib.baseboard_fab2(sch_1):page83_i111:DQ(42)" )
				( attribute "RELATIVE_PROPAGATION_DELAY_SCOPE" "G"
					( Parent
						( matchGroupRef "@baseboard_fab2_lib.baseboard_fab2(sch_1):\MG_DQ-DQS_FAR_DIMM_NG_M_K_BYTE5\" )
					)
					( Status sCSetFlattened )
					( Origin gBackEnd )
				)
				( attribute "RELATIVE_PROPAGATION_DELAY" "0.00 MIL,195.00 MIL"
					( Parent
						( matchGroupRef "@baseboard_fab2_lib.baseboard_fab2(sch_1):\MG_DQ-DQS_FAR_DIMM_NG_M_K_BYTE5\" )
					)
					( Units "uMatchProp" "ns" 1.000000)
					( Status sCSetFlattened )
					( Origin gBackEnd )
				)
				( attribute "RELATIVE_PROPAGATION_DELAY_SCOPE" "G"
					( Parent
						( matchGroupRef "@crescent_city_bb_fab1_lib.crescent_city_bb_fab1(sch_1):\MG_DQ_FAR_DIMM_NG_M_K_BYTE5\" )
					)
					( Status sCSetFlattened )
					( Origin gBackEnd )
				)
				( attribute "RELATIVE_PROPAGATION_DELAY" "-50.00 MIL,50.00 MIL"
					( Parent
						( matchGroupRef "@crescent_city_bb_fab1_lib.crescent_city_bb_fab1(sch_1):\MG_DQ_FAR_DIMM_NG_M_K_BYTE5\" )
					)
					( Units "uMatchProp" "ns" 1.000000)
					( Status sCSetFlattened )
					( Origin gBackEnd )
				)
			)
			( pinPair "@baseboard_fab2_lib.baseboard_fab2(sch_1):\PP2166\"
				( pinRef "@baseboard_fab2_lib.baseboard_fab2(sch_1):page60_i172:DDR3_DQ(43)" )
				( pinRef "@baseboard_fab2_lib.baseboard_fab2(sch_1):page84_i14:DQ(43)" )
				( attribute "RELATIVE_PROPAGATION_DELAY_SCOPE" "G"
					( Parent
						( matchGroupRef "@baseboard_fab2_lib.baseboard_fab2(sch_1):\MG_DQ-DQS_NEAR_DIMM_NG_M_K_BYTE5\" )
					)
					( Status sCSetFlattened )
					( Origin gBackEnd )
				)
				( attribute "RELATIVE_PROPAGATION_DELAY" "0.00 MIL,195.00 MIL"
					( Parent
						( matchGroupRef "@baseboard_fab2_lib.baseboard_fab2(sch_1):\MG_DQ-DQS_NEAR_DIMM_NG_M_K_BYTE5\" )
					)
					( Units "uMatchProp" "ns" 1.000000)
					( Status sCSetFlattened )
					( Origin gBackEnd )
				)
				( attribute "RELATIVE_PROPAGATION_DELAY_SCOPE" "G"
					( Parent
						( matchGroupRef "@crescent_city_bb_fab1_lib.crescent_city_bb_fab1(sch_1):\MG_DQ_NEAR_DIMM_NG_M_K_BYTE5\" )
					)
					( Status sCSetFlattened )
					( Origin gBackEnd )
				)
				( attribute "RELATIVE_PROPAGATION_DELAY" "-50.00 MIL,50.00 MIL"
					( Parent
						( matchGroupRef "@crescent_city_bb_fab1_lib.crescent_city_bb_fab1(sch_1):\MG_DQ_NEAR_DIMM_NG_M_K_BYTE5\" )
					)
					( Units "uMatchProp" "ns" 1.000000)
					( Status sCSetFlattened )
					( Origin gBackEnd )
				)
			)
			( pinPair "@baseboard_fab2_lib.baseboard_fab2(sch_1):\PP2167\"
				( pinRef "@baseboard_fab2_lib.baseboard_fab2(sch_1):page60_i172:DDR3_DQ(44)" )
				( pinRef "@baseboard_fab2_lib.baseboard_fab2(sch_1):page83_i111:DQ(45)" )
				( attribute "RELATIVE_PROPAGATION_DELAY_SCOPE" "G"
					( Parent
						( matchGroupRef "@baseboard_fab2_lib.baseboard_fab2(sch_1):\MG_DQ-DQS_FAR_DIMM_NG_M_K_BYTE5\" )
					)
					( Status sCSetFlattened )
					( Origin gBackEnd )
				)
				( attribute "RELATIVE_PROPAGATION_DELAY" "0.00 MIL,195.00 MIL"
					( Parent
						( matchGroupRef "@baseboard_fab2_lib.baseboard_fab2(sch_1):\MG_DQ-DQS_FAR_DIMM_NG_M_K_BYTE5\" )
					)
					( Units "uMatchProp" "ns" 1.000000)
					( Status sCSetFlattened )
					( Origin gBackEnd )
				)
				( attribute "RELATIVE_PROPAGATION_DELAY_SCOPE" "G"
					( Parent
						( matchGroupRef "@crescent_city_bb_fab1_lib.crescent_city_bb_fab1(sch_1):\MG_DQ_FAR_DIMM_NG_M_K_BYTE5\" )
					)
					( Status sCSetFlattened )
					( Origin gBackEnd )
				)
				( attribute "RELATIVE_PROPAGATION_DELAY" "-50.00 MIL,50.00 MIL"
					( Parent
						( matchGroupRef "@crescent_city_bb_fab1_lib.crescent_city_bb_fab1(sch_1):\MG_DQ_FAR_DIMM_NG_M_K_BYTE5\" )
					)
					( Units "uMatchProp" "ns" 1.000000)
					( Status sCSetFlattened )
					( Origin gBackEnd )
				)
			)
			( pinPair "@baseboard_fab2_lib.baseboard_fab2(sch_1):\PP2169\"
				( pinRef "@baseboard_fab2_lib.baseboard_fab2(sch_1):page60_i172:DDR3_DQ(44)" )
				( pinRef "@baseboard_fab2_lib.baseboard_fab2(sch_1):page84_i14:DQ(44)" )
				( attribute "RELATIVE_PROPAGATION_DELAY_SCOPE" "G"
					( Parent
						( matchGroupRef "@baseboard_fab2_lib.baseboard_fab2(sch_1):\MG_DQ-DQS_NEAR_DIMM_NG_M_K_BYTE5\" )
					)
					( Status sCSetFlattened )
					( Origin gBackEnd )
				)
				( attribute "RELATIVE_PROPAGATION_DELAY" "0.00 MIL,195.00 MIL"
					( Parent
						( matchGroupRef "@baseboard_fab2_lib.baseboard_fab2(sch_1):\MG_DQ-DQS_NEAR_DIMM_NG_M_K_BYTE5\" )
					)
					( Units "uMatchProp" "ns" 1.000000)
					( Status sCSetFlattened )
					( Origin gBackEnd )
				)
				( attribute "RELATIVE_PROPAGATION_DELAY_SCOPE" "G"
					( Parent
						( matchGroupRef "@crescent_city_bb_fab1_lib.crescent_city_bb_fab1(sch_1):\MG_DQ_NEAR_DIMM_NG_M_K_BYTE5\" )
					)
					( Status sCSetFlattened )
					( Origin gBackEnd )
				)
				( attribute "RELATIVE_PROPAGATION_DELAY" "-50.00 MIL,50.00 MIL"
					( Parent
						( matchGroupRef "@crescent_city_bb_fab1_lib.crescent_city_bb_fab1(sch_1):\MG_DQ_NEAR_DIMM_NG_M_K_BYTE5\" )
					)
					( Units "uMatchProp" "ns" 1.000000)
					( Status sCSetFlattened )
					( Origin gBackEnd )
				)
			)
			( pinPair "@baseboard_fab2_lib.baseboard_fab2(sch_1):\PP2170\"
				( pinRef "@baseboard_fab2_lib.baseboard_fab2(sch_1):page60_i172:DDR3_DQ(45)" )
				( pinRef "@baseboard_fab2_lib.baseboard_fab2(sch_1):page83_i111:DQ(44)" )
				( attribute "RELATIVE_PROPAGATION_DELAY_SCOPE" "G"
					( Parent
						( matchGroupRef "@baseboard_fab2_lib.baseboard_fab2(sch_1):\MG_DQ-DQS_FAR_DIMM_NG_M_K_BYTE5\" )
					)
					( Status sCSetFlattened )
					( Origin gBackEnd )
				)
				( attribute "RELATIVE_PROPAGATION_DELAY" "0.00 MIL,195.00 MIL"
					( Parent
						( matchGroupRef "@baseboard_fab2_lib.baseboard_fab2(sch_1):\MG_DQ-DQS_FAR_DIMM_NG_M_K_BYTE5\" )
					)
					( Units "uMatchProp" "ns" 1.000000)
					( Status sCSetFlattened )
					( Origin gBackEnd )
				)
				( attribute "RELATIVE_PROPAGATION_DELAY_SCOPE" "G"
					( Parent
						( matchGroupRef "@crescent_city_bb_fab1_lib.crescent_city_bb_fab1(sch_1):\MG_DQ_FAR_DIMM_NG_M_K_BYTE5\" )
					)
					( Status sCSetFlattened )
					( Origin gBackEnd )
				)
				( attribute "RELATIVE_PROPAGATION_DELAY" "-50.00 MIL,50.00 MIL"
					( Parent
						( matchGroupRef "@crescent_city_bb_fab1_lib.crescent_city_bb_fab1(sch_1):\MG_DQ_FAR_DIMM_NG_M_K_BYTE5\" )
					)
					( Units "uMatchProp" "ns" 1.000000)
					( Status sCSetFlattened )
					( Origin gBackEnd )
				)
			)
			( pinPair "@baseboard_fab2_lib.baseboard_fab2(sch_1):\PP2172\"
				( pinRef "@baseboard_fab2_lib.baseboard_fab2(sch_1):page60_i172:DDR3_DQ(45)" )
				( pinRef "@baseboard_fab2_lib.baseboard_fab2(sch_1):page84_i14:DQ(45)" )
				( attribute "RELATIVE_PROPAGATION_DELAY_SCOPE" "G"
					( Parent
						( matchGroupRef "@baseboard_fab2_lib.baseboard_fab2(sch_1):\MG_DQ-DQS_NEAR_DIMM_NG_M_K_BYTE5\" )
					)
					( Status sCSetFlattened )
					( Origin gBackEnd )
				)
				( attribute "RELATIVE_PROPAGATION_DELAY" "0.00 MIL,195.00 MIL"
					( Parent
						( matchGroupRef "@baseboard_fab2_lib.baseboard_fab2(sch_1):\MG_DQ-DQS_NEAR_DIMM_NG_M_K_BYTE5\" )
					)
					( Units "uMatchProp" "ns" 1.000000)
					( Status sCSetFlattened )
					( Origin gBackEnd )
				)
				( attribute "RELATIVE_PROPAGATION_DELAY_SCOPE" "G"
					( Parent
						( matchGroupRef "@crescent_city_bb_fab1_lib.crescent_city_bb_fab1(sch_1):\MG_DQ_NEAR_DIMM_NG_M_K_BYTE5\" )
					)
					( Status sCSetFlattened )
					( Origin gBackEnd )
				)
				( attribute "RELATIVE_PROPAGATION_DELAY" "-50.00 MIL,50.00 MIL"
					( Parent
						( matchGroupRef "@crescent_city_bb_fab1_lib.crescent_city_bb_fab1(sch_1):\MG_DQ_NEAR_DIMM_NG_M_K_BYTE5\" )
					)
					( Units "uMatchProp" "ns" 1.000000)
					( Status sCSetFlattened )
					( Origin gBackEnd )
				)
			)
			( pinPair "@baseboard_fab2_lib.baseboard_fab2(sch_1):\PP2173\"
				( pinRef "@baseboard_fab2_lib.baseboard_fab2(sch_1):page60_i172:DDR3_DQ(46)" )
				( pinRef "@baseboard_fab2_lib.baseboard_fab2(sch_1):page83_i111:DQ(47)" )
				( attribute "RELATIVE_PROPAGATION_DELAY_SCOPE" "G"
					( Parent
						( matchGroupRef "@baseboard_fab2_lib.baseboard_fab2(sch_1):\MG_DQ-DQS_FAR_DIMM_NG_M_K_BYTE5\" )
					)
					( Status sCSetFlattened )
					( Origin gBackEnd )
				)
				( attribute "RELATIVE_PROPAGATION_DELAY" "0.00 MIL,195.00 MIL"
					( Parent
						( matchGroupRef "@baseboard_fab2_lib.baseboard_fab2(sch_1):\MG_DQ-DQS_FAR_DIMM_NG_M_K_BYTE5\" )
					)
					( Units "uMatchProp" "ns" 1.000000)
					( Status sCSetFlattened )
					( Origin gBackEnd )
				)
				( attribute "RELATIVE_PROPAGATION_DELAY_SCOPE" "G"
					( Parent
						( matchGroupRef "@crescent_city_bb_fab1_lib.crescent_city_bb_fab1(sch_1):\MG_DQ_FAR_DIMM_NG_M_K_BYTE5\" )
					)
					( Origin gBackEnd )
				)
				( attribute "RELATIVE_PROPAGATION_DELAY" "TARGET,TARGET"
					( Parent
						( matchGroupRef "@crescent_city_bb_fab1_lib.crescent_city_bb_fab1(sch_1):\MG_DQ_FAR_DIMM_NG_M_K_BYTE5\" )
					)
					( Units "uMatchProp" "ns" 1.000000)
					( Origin gBackEnd )
				)
			)
			( pinPair "@baseboard_fab2_lib.baseboard_fab2(sch_1):\PP2175\"
				( pinRef "@baseboard_fab2_lib.baseboard_fab2(sch_1):page60_i172:DDR3_DQ(46)" )
				( pinRef "@baseboard_fab2_lib.baseboard_fab2(sch_1):page84_i14:DQ(46)" )
				( attribute "RELATIVE_PROPAGATION_DELAY_SCOPE" "G"
					( Parent
						( matchGroupRef "@baseboard_fab2_lib.baseboard_fab2(sch_1):\MG_DQ-DQS_NEAR_DIMM_NG_M_K_BYTE5\" )
					)
					( Status sCSetFlattened )
					( Origin gBackEnd )
				)
				( attribute "RELATIVE_PROPAGATION_DELAY" "0.00 MIL,195.00 MIL"
					( Parent
						( matchGroupRef "@baseboard_fab2_lib.baseboard_fab2(sch_1):\MG_DQ-DQS_NEAR_DIMM_NG_M_K_BYTE5\" )
					)
					( Units "uMatchProp" "ns" 1.000000)
					( Status sCSetFlattened )
					( Origin gBackEnd )
				)
				( attribute "RELATIVE_PROPAGATION_DELAY_SCOPE" "G"
					( Parent
						( matchGroupRef "@crescent_city_bb_fab1_lib.crescent_city_bb_fab1(sch_1):\MG_DQ_NEAR_DIMM_NG_M_K_BYTE5\" )
					)
					( Status sCSetFlattened )
					( Origin gBackEnd )
				)
				( attribute "RELATIVE_PROPAGATION_DELAY" "-50.00 MIL,50.00 MIL"
					( Parent
						( matchGroupRef "@crescent_city_bb_fab1_lib.crescent_city_bb_fab1(sch_1):\MG_DQ_NEAR_DIMM_NG_M_K_BYTE5\" )
					)
					( Units "uMatchProp" "ns" 1.000000)
					( Status sCSetFlattened )
					( Origin gBackEnd )
				)
			)
			( pinPair "@baseboard_fab2_lib.baseboard_fab2(sch_1):\PP2176\"
				( pinRef "@baseboard_fab2_lib.baseboard_fab2(sch_1):page60_i172:DDR3_DQ(47)" )
				( pinRef "@baseboard_fab2_lib.baseboard_fab2(sch_1):page83_i111:DQ(46)" )
				( attribute "RELATIVE_PROPAGATION_DELAY_SCOPE" "G"
					( Parent
						( matchGroupRef "@baseboard_fab2_lib.baseboard_fab2(sch_1):\MG_DQ-DQS_FAR_DIMM_NG_M_K_BYTE5\" )
					)
					( Status sCSetFlattened )
					( Origin gBackEnd )
				)
				( attribute "RELATIVE_PROPAGATION_DELAY" "0.00 MIL,195.00 MIL"
					( Parent
						( matchGroupRef "@baseboard_fab2_lib.baseboard_fab2(sch_1):\MG_DQ-DQS_FAR_DIMM_NG_M_K_BYTE5\" )
					)
					( Units "uMatchProp" "ns" 1.000000)
					( Status sCSetFlattened )
					( Origin gBackEnd )
				)
				( attribute "RELATIVE_PROPAGATION_DELAY_SCOPE" "G"
					( Parent
						( matchGroupRef "@crescent_city_bb_fab1_lib.crescent_city_bb_fab1(sch_1):\MG_DQ_FAR_DIMM_NG_M_K_BYTE5\" )
					)
					( Status sCSetFlattened )
					( Origin gBackEnd )
				)
				( attribute "RELATIVE_PROPAGATION_DELAY" "-50.00 MIL,50.00 MIL"
					( Parent
						( matchGroupRef "@crescent_city_bb_fab1_lib.crescent_city_bb_fab1(sch_1):\MG_DQ_FAR_DIMM_NG_M_K_BYTE5\" )
					)
					( Units "uMatchProp" "ns" 1.000000)
					( Status sCSetFlattened )
					( Origin gBackEnd )
				)
			)
			( pinPair "@baseboard_fab2_lib.baseboard_fab2(sch_1):\PP2178\"
				( pinRef "@baseboard_fab2_lib.baseboard_fab2(sch_1):page60_i172:DDR3_DQ(47)" )
				( pinRef "@baseboard_fab2_lib.baseboard_fab2(sch_1):page84_i14:DQ(47)" )
				( attribute "RELATIVE_PROPAGATION_DELAY_SCOPE" "G"
					( Parent
						( matchGroupRef "@baseboard_fab2_lib.baseboard_fab2(sch_1):\MG_DQ-DQS_NEAR_DIMM_NG_M_K_BYTE5\" )
					)
					( Status sCSetFlattened )
					( Origin gBackEnd )
				)
				( attribute "RELATIVE_PROPAGATION_DELAY" "0.00 MIL,195.00 MIL"
					( Parent
						( matchGroupRef "@baseboard_fab2_lib.baseboard_fab2(sch_1):\MG_DQ-DQS_NEAR_DIMM_NG_M_K_BYTE5\" )
					)
					( Units "uMatchProp" "ns" 1.000000)
					( Status sCSetFlattened )
					( Origin gBackEnd )
				)
				( attribute "RELATIVE_PROPAGATION_DELAY_SCOPE" "G"
					( Parent
						( matchGroupRef "@crescent_city_bb_fab1_lib.crescent_city_bb_fab1(sch_1):\MG_DQ_NEAR_DIMM_NG_M_K_BYTE5\" )
					)
					( Status sCSetFlattened )
					( Origin gBackEnd )
				)
				( attribute "RELATIVE_PROPAGATION_DELAY" "-50.00 MIL,50.00 MIL"
					( Parent
						( matchGroupRef "@crescent_city_bb_fab1_lib.crescent_city_bb_fab1(sch_1):\MG_DQ_NEAR_DIMM_NG_M_K_BYTE5\" )
					)
					( Units "uMatchProp" "ns" 1.000000)
					( Status sCSetFlattened )
					( Origin gBackEnd )
				)
			)
			( pinPair "@baseboard_fab2_lib.baseboard_fab2(sch_1):\PP2131\"
				( pinRef "@baseboard_fab2_lib.baseboard_fab2(sch_1):page60_i172:DDR3_DQ(48)" )
				( pinRef "@baseboard_fab2_lib.baseboard_fab2(sch_1):page83_i111:DQ(49)" )
				( attribute "RELATIVE_PROPAGATION_DELAY_SCOPE" "G"
					( Parent
						( matchGroupRef "@baseboard_fab2_lib.baseboard_fab2(sch_1):\MG_DQ-DQS_FAR_DIMM_NG_M_K_BYTE6\" )
					)
					( Status sCSetFlattened )
					( Origin gBackEnd )
				)
				( attribute "RELATIVE_PROPAGATION_DELAY" "0.00 MIL,195.00 MIL"
					( Parent
						( matchGroupRef "@baseboard_fab2_lib.baseboard_fab2(sch_1):\MG_DQ-DQS_FAR_DIMM_NG_M_K_BYTE6\" )
					)
					( Units "uMatchProp" "ns" 1.000000)
					( Status sCSetFlattened )
					( Origin gBackEnd )
				)
				( attribute "RELATIVE_PROPAGATION_DELAY_SCOPE" "G"
					( Parent
						( matchGroupRef "@baseboard_fab2_lib.baseboard_fab2(sch_1):\MG_DQ_FAR_DIMM_NG_M_K_BYTE6\" )
					)
					( Status sCSetFlattened )
					( Origin gBackEnd )
				)
				( attribute "RELATIVE_PROPAGATION_DELAY" "-50.00 MIL,50.00 MIL"
					( Parent
						( matchGroupRef "@baseboard_fab2_lib.baseboard_fab2(sch_1):\MG_DQ_FAR_DIMM_NG_M_K_BYTE6\" )
					)
					( Units "uMatchProp" "ns" 1.000000)
					( Status sCSetFlattened )
					( Origin gBackEnd )
				)
			)
			( pinPair "@baseboard_fab2_lib.baseboard_fab2(sch_1):\PP2133\"
				( pinRef "@baseboard_fab2_lib.baseboard_fab2(sch_1):page60_i172:DDR3_DQ(48)" )
				( pinRef "@baseboard_fab2_lib.baseboard_fab2(sch_1):page84_i14:DQ(48)" )
				( attribute "RELATIVE_PROPAGATION_DELAY_SCOPE" "G"
					( Parent
						( matchGroupRef "@baseboard_fab2_lib.baseboard_fab2(sch_1):\MG_DQ-DQS_NEAR_DIMM_NG_M_K_BYTE6\" )
					)
					( Status sCSetFlattened )
					( Origin gBackEnd )
				)
				( attribute "RELATIVE_PROPAGATION_DELAY" "0.00 MIL,195.00 MIL"
					( Parent
						( matchGroupRef "@baseboard_fab2_lib.baseboard_fab2(sch_1):\MG_DQ-DQS_NEAR_DIMM_NG_M_K_BYTE6\" )
					)
					( Units "uMatchProp" "ns" 1.000000)
					( Status sCSetFlattened )
					( Origin gBackEnd )
				)
				( attribute "RELATIVE_PROPAGATION_DELAY_SCOPE" "G"
					( Parent
						( matchGroupRef "@crescent_city_bb_fab1_lib.crescent_city_bb_fab1(sch_1):\MG_DQ_NEAR_DIMM_NG_M_K_BYTE6\" )
					)
					( Status sCSetFlattened )
					( Origin gBackEnd )
				)
				( attribute "RELATIVE_PROPAGATION_DELAY" "-50.00 MIL,50.00 MIL"
					( Parent
						( matchGroupRef "@crescent_city_bb_fab1_lib.crescent_city_bb_fab1(sch_1):\MG_DQ_NEAR_DIMM_NG_M_K_BYTE6\" )
					)
					( Units "uMatchProp" "ns" 1.000000)
					( Status sCSetFlattened )
					( Origin gBackEnd )
				)
			)
			( pinPair "@baseboard_fab2_lib.baseboard_fab2(sch_1):\PP2134\"
				( pinRef "@baseboard_fab2_lib.baseboard_fab2(sch_1):page60_i172:DDR3_DQ(49)" )
				( pinRef "@baseboard_fab2_lib.baseboard_fab2(sch_1):page83_i111:DQ(48)" )
				( attribute "RELATIVE_PROPAGATION_DELAY_SCOPE" "G"
					( Parent
						( matchGroupRef "@baseboard_fab2_lib.baseboard_fab2(sch_1):\MG_DQ-DQS_FAR_DIMM_NG_M_K_BYTE6\" )
					)
					( Status sCSetFlattened )
					( Origin gBackEnd )
				)
				( attribute "RELATIVE_PROPAGATION_DELAY" "0.00 MIL,195.00 MIL"
					( Parent
						( matchGroupRef "@baseboard_fab2_lib.baseboard_fab2(sch_1):\MG_DQ-DQS_FAR_DIMM_NG_M_K_BYTE6\" )
					)
					( Units "uMatchProp" "ns" 1.000000)
					( Status sCSetFlattened )
					( Origin gBackEnd )
				)
				( attribute "RELATIVE_PROPAGATION_DELAY_SCOPE" "G"
					( Parent
						( matchGroupRef "@baseboard_fab2_lib.baseboard_fab2(sch_1):\MG_DQ_FAR_DIMM_NG_M_K_BYTE6\" )
					)
					( Status sCSetFlattened )
					( Origin gBackEnd )
				)
				( attribute "RELATIVE_PROPAGATION_DELAY" "-50.00 MIL,50.00 MIL"
					( Parent
						( matchGroupRef "@baseboard_fab2_lib.baseboard_fab2(sch_1):\MG_DQ_FAR_DIMM_NG_M_K_BYTE6\" )
					)
					( Units "uMatchProp" "ns" 1.000000)
					( Status sCSetFlattened )
					( Origin gBackEnd )
				)
			)
			( pinPair "@baseboard_fab2_lib.baseboard_fab2(sch_1):\PP2136\"
				( pinRef "@baseboard_fab2_lib.baseboard_fab2(sch_1):page60_i172:DDR3_DQ(49)" )
				( pinRef "@baseboard_fab2_lib.baseboard_fab2(sch_1):page84_i14:DQ(49)" )
				( attribute "RELATIVE_PROPAGATION_DELAY_SCOPE" "G"
					( Parent
						( matchGroupRef "@baseboard_fab2_lib.baseboard_fab2(sch_1):\MG_DQ-DQS_NEAR_DIMM_NG_M_K_BYTE6\" )
					)
					( Status sCSetFlattened )
					( Origin gBackEnd )
				)
				( attribute "RELATIVE_PROPAGATION_DELAY" "0.00 MIL,195.00 MIL"
					( Parent
						( matchGroupRef "@baseboard_fab2_lib.baseboard_fab2(sch_1):\MG_DQ-DQS_NEAR_DIMM_NG_M_K_BYTE6\" )
					)
					( Units "uMatchProp" "ns" 1.000000)
					( Status sCSetFlattened )
					( Origin gBackEnd )
				)
				( attribute "RELATIVE_PROPAGATION_DELAY_SCOPE" "G"
					( Parent
						( matchGroupRef "@crescent_city_bb_fab1_lib.crescent_city_bb_fab1(sch_1):\MG_DQ_NEAR_DIMM_NG_M_K_BYTE6\" )
					)
					( Status sCSetFlattened )
					( Origin gBackEnd )
				)
				( attribute "RELATIVE_PROPAGATION_DELAY" "-50.00 MIL,50.00 MIL"
					( Parent
						( matchGroupRef "@crescent_city_bb_fab1_lib.crescent_city_bb_fab1(sch_1):\MG_DQ_NEAR_DIMM_NG_M_K_BYTE6\" )
					)
					( Units "uMatchProp" "ns" 1.000000)
					( Status sCSetFlattened )
					( Origin gBackEnd )
				)
			)
			( pinPair "@baseboard_fab2_lib.baseboard_fab2(sch_1):\PP2137\"
				( pinRef "@baseboard_fab2_lib.baseboard_fab2(sch_1):page60_i172:DDR3_DQ(50)" )
				( pinRef "@baseboard_fab2_lib.baseboard_fab2(sch_1):page83_i111:DQ(51)" )
				( attribute "RELATIVE_PROPAGATION_DELAY_SCOPE" "G"
					( Parent
						( matchGroupRef "@baseboard_fab2_lib.baseboard_fab2(sch_1):\MG_DQ-DQS_FAR_DIMM_NG_M_K_BYTE6\" )
					)
					( Status sCSetFlattened )
					( Origin gBackEnd )
				)
				( attribute "RELATIVE_PROPAGATION_DELAY" "0.00 MIL,195.00 MIL"
					( Parent
						( matchGroupRef "@baseboard_fab2_lib.baseboard_fab2(sch_1):\MG_DQ-DQS_FAR_DIMM_NG_M_K_BYTE6\" )
					)
					( Units "uMatchProp" "ns" 1.000000)
					( Status sCSetFlattened )
					( Origin gBackEnd )
				)
				( attribute "RELATIVE_PROPAGATION_DELAY_SCOPE" "G"
					( Parent
						( matchGroupRef "@baseboard_fab2_lib.baseboard_fab2(sch_1):\MG_DQ_FAR_DIMM_NG_M_K_BYTE6\" )
					)
					( Status sCSetFlattened )
					( Origin gBackEnd )
				)
				( attribute "RELATIVE_PROPAGATION_DELAY" "-50.00 MIL,50.00 MIL"
					( Parent
						( matchGroupRef "@baseboard_fab2_lib.baseboard_fab2(sch_1):\MG_DQ_FAR_DIMM_NG_M_K_BYTE6\" )
					)
					( Units "uMatchProp" "ns" 1.000000)
					( Status sCSetFlattened )
					( Origin gBackEnd )
				)
			)
			( pinPair "@baseboard_fab2_lib.baseboard_fab2(sch_1):\PP2139\"
				( pinRef "@baseboard_fab2_lib.baseboard_fab2(sch_1):page60_i172:DDR3_DQ(50)" )
				( pinRef "@baseboard_fab2_lib.baseboard_fab2(sch_1):page84_i14:DQ(50)" )
				( attribute "RELATIVE_PROPAGATION_DELAY_SCOPE" "G"
					( Parent
						( matchGroupRef "@baseboard_fab2_lib.baseboard_fab2(sch_1):\MG_DQ-DQS_NEAR_DIMM_NG_M_K_BYTE6\" )
					)
					( Status sCSetFlattened )
					( Origin gBackEnd )
				)
				( attribute "RELATIVE_PROPAGATION_DELAY" "0.00 MIL,195.00 MIL"
					( Parent
						( matchGroupRef "@baseboard_fab2_lib.baseboard_fab2(sch_1):\MG_DQ-DQS_NEAR_DIMM_NG_M_K_BYTE6\" )
					)
					( Units "uMatchProp" "ns" 1.000000)
					( Status sCSetFlattened )
					( Origin gBackEnd )
				)
				( attribute "RELATIVE_PROPAGATION_DELAY_SCOPE" "G"
					( Parent
						( matchGroupRef "@crescent_city_bb_fab1_lib.crescent_city_bb_fab1(sch_1):\MG_DQ_NEAR_DIMM_NG_M_K_BYTE6\" )
					)
					( Status sCSetFlattened )
					( Origin gBackEnd )
				)
				( attribute "RELATIVE_PROPAGATION_DELAY" "-50.00 MIL,50.00 MIL"
					( Parent
						( matchGroupRef "@crescent_city_bb_fab1_lib.crescent_city_bb_fab1(sch_1):\MG_DQ_NEAR_DIMM_NG_M_K_BYTE6\" )
					)
					( Units "uMatchProp" "ns" 1.000000)
					( Status sCSetFlattened )
					( Origin gBackEnd )
				)
			)
			( pinPair "@baseboard_fab2_lib.baseboard_fab2(sch_1):\PP2140\"
				( pinRef "@baseboard_fab2_lib.baseboard_fab2(sch_1):page60_i172:DDR3_DQ(51)" )
				( pinRef "@baseboard_fab2_lib.baseboard_fab2(sch_1):page83_i111:DQ(50)" )
				( attribute "RELATIVE_PROPAGATION_DELAY_SCOPE" "G"
					( Parent
						( matchGroupRef "@baseboard_fab2_lib.baseboard_fab2(sch_1):\MG_DQ-DQS_FAR_DIMM_NG_M_K_BYTE6\" )
					)
					( Status sCSetFlattened )
					( Origin gBackEnd )
				)
				( attribute "RELATIVE_PROPAGATION_DELAY" "0.00 MIL,195.00 MIL"
					( Parent
						( matchGroupRef "@baseboard_fab2_lib.baseboard_fab2(sch_1):\MG_DQ-DQS_FAR_DIMM_NG_M_K_BYTE6\" )
					)
					( Units "uMatchProp" "ns" 1.000000)
					( Status sCSetFlattened )
					( Origin gBackEnd )
				)
				( attribute "RELATIVE_PROPAGATION_DELAY_SCOPE" "G"
					( Parent
						( matchGroupRef "@baseboard_fab2_lib.baseboard_fab2(sch_1):\MG_DQ_FAR_DIMM_NG_M_K_BYTE6\" )
					)
					( Status sCSetFlattened )
					( Origin gBackEnd )
				)
				( attribute "RELATIVE_PROPAGATION_DELAY" "-50.00 MIL,50.00 MIL"
					( Parent
						( matchGroupRef "@baseboard_fab2_lib.baseboard_fab2(sch_1):\MG_DQ_FAR_DIMM_NG_M_K_BYTE6\" )
					)
					( Units "uMatchProp" "ns" 1.000000)
					( Status sCSetFlattened )
					( Origin gBackEnd )
				)
			)
			( pinPair "@baseboard_fab2_lib.baseboard_fab2(sch_1):\PP2142\"
				( pinRef "@baseboard_fab2_lib.baseboard_fab2(sch_1):page60_i172:DDR3_DQ(51)" )
				( pinRef "@baseboard_fab2_lib.baseboard_fab2(sch_1):page84_i14:DQ(51)" )
				( attribute "RELATIVE_PROPAGATION_DELAY_SCOPE" "G"
					( Parent
						( matchGroupRef "@baseboard_fab2_lib.baseboard_fab2(sch_1):\MG_DQ-DQS_NEAR_DIMM_NG_M_K_BYTE6\" )
					)
					( Status sCSetFlattened )
					( Origin gBackEnd )
				)
				( attribute "RELATIVE_PROPAGATION_DELAY" "0.00 MIL,195.00 MIL"
					( Parent
						( matchGroupRef "@baseboard_fab2_lib.baseboard_fab2(sch_1):\MG_DQ-DQS_NEAR_DIMM_NG_M_K_BYTE6\" )
					)
					( Units "uMatchProp" "ns" 1.000000)
					( Status sCSetFlattened )
					( Origin gBackEnd )
				)
				( attribute "RELATIVE_PROPAGATION_DELAY_SCOPE" "G"
					( Parent
						( matchGroupRef "@crescent_city_bb_fab1_lib.crescent_city_bb_fab1(sch_1):\MG_DQ_NEAR_DIMM_NG_M_K_BYTE6\" )
					)
					( Origin gBackEnd )
				)
				( attribute "RELATIVE_PROPAGATION_DELAY" "TARGET,TARGET"
					( Parent
						( matchGroupRef "@crescent_city_bb_fab1_lib.crescent_city_bb_fab1(sch_1):\MG_DQ_NEAR_DIMM_NG_M_K_BYTE6\" )
					)
					( Units "uMatchProp" "ns" 1.000000)
					( Origin gBackEnd )
				)
			)
			( pinPair "@baseboard_fab2_lib.baseboard_fab2(sch_1):\PP2143\"
				( pinRef "@baseboard_fab2_lib.baseboard_fab2(sch_1):page60_i172:DDR3_DQ(52)" )
				( pinRef "@baseboard_fab2_lib.baseboard_fab2(sch_1):page83_i111:DQ(53)" )
				( attribute "RELATIVE_PROPAGATION_DELAY_SCOPE" "G"
					( Parent
						( matchGroupRef "@baseboard_fab2_lib.baseboard_fab2(sch_1):\MG_DQ-DQS_FAR_DIMM_NG_M_K_BYTE6\" )
					)
					( Status sCSetFlattened )
					( Origin gBackEnd )
				)
				( attribute "RELATIVE_PROPAGATION_DELAY" "0.00 MIL,195.00 MIL"
					( Parent
						( matchGroupRef "@baseboard_fab2_lib.baseboard_fab2(sch_1):\MG_DQ-DQS_FAR_DIMM_NG_M_K_BYTE6\" )
					)
					( Units "uMatchProp" "ns" 1.000000)
					( Status sCSetFlattened )
					( Origin gBackEnd )
				)
				( attribute "RELATIVE_PROPAGATION_DELAY_SCOPE" "G"
					( Parent
						( matchGroupRef "@baseboard_fab2_lib.baseboard_fab2(sch_1):\MG_DQ_FAR_DIMM_NG_M_K_BYTE6\" )
					)
					( Status sCSetFlattened )
					( Origin gBackEnd )
				)
				( attribute "RELATIVE_PROPAGATION_DELAY" "-50.00 MIL,50.00 MIL"
					( Parent
						( matchGroupRef "@baseboard_fab2_lib.baseboard_fab2(sch_1):\MG_DQ_FAR_DIMM_NG_M_K_BYTE6\" )
					)
					( Units "uMatchProp" "ns" 1.000000)
					( Status sCSetFlattened )
					( Origin gBackEnd )
				)
			)
			( pinPair "@baseboard_fab2_lib.baseboard_fab2(sch_1):\PP2145\"
				( pinRef "@baseboard_fab2_lib.baseboard_fab2(sch_1):page60_i172:DDR3_DQ(52)" )
				( pinRef "@baseboard_fab2_lib.baseboard_fab2(sch_1):page84_i14:DQ(52)" )
				( attribute "RELATIVE_PROPAGATION_DELAY_SCOPE" "G"
					( Parent
						( matchGroupRef "@baseboard_fab2_lib.baseboard_fab2(sch_1):\MG_DQ-DQS_NEAR_DIMM_NG_M_K_BYTE6\" )
					)
					( Status sCSetFlattened )
					( Origin gBackEnd )
				)
				( attribute "RELATIVE_PROPAGATION_DELAY" "0.00 MIL,195.00 MIL"
					( Parent
						( matchGroupRef "@baseboard_fab2_lib.baseboard_fab2(sch_1):\MG_DQ-DQS_NEAR_DIMM_NG_M_K_BYTE6\" )
					)
					( Units "uMatchProp" "ns" 1.000000)
					( Status sCSetFlattened )
					( Origin gBackEnd )
				)
				( attribute "RELATIVE_PROPAGATION_DELAY_SCOPE" "G"
					( Parent
						( matchGroupRef "@crescent_city_bb_fab1_lib.crescent_city_bb_fab1(sch_1):\MG_DQ_NEAR_DIMM_NG_M_K_BYTE6\" )
					)
					( Status sCSetFlattened )
					( Origin gBackEnd )
				)
				( attribute "RELATIVE_PROPAGATION_DELAY" "-50.00 MIL,50.00 MIL"
					( Parent
						( matchGroupRef "@crescent_city_bb_fab1_lib.crescent_city_bb_fab1(sch_1):\MG_DQ_NEAR_DIMM_NG_M_K_BYTE6\" )
					)
					( Units "uMatchProp" "ns" 1.000000)
					( Status sCSetFlattened )
					( Origin gBackEnd )
				)
			)
			( pinPair "@baseboard_fab2_lib.baseboard_fab2(sch_1):\PP2146\"
				( pinRef "@baseboard_fab2_lib.baseboard_fab2(sch_1):page60_i172:DDR3_DQ(53)" )
				( pinRef "@baseboard_fab2_lib.baseboard_fab2(sch_1):page83_i111:DQ(52)" )
				( attribute "RELATIVE_PROPAGATION_DELAY_SCOPE" "G"
					( Parent
						( matchGroupRef "@baseboard_fab2_lib.baseboard_fab2(sch_1):\MG_DQ-DQS_FAR_DIMM_NG_M_K_BYTE6\" )
					)
					( Status sCSetFlattened )
					( Origin gBackEnd )
				)
				( attribute "RELATIVE_PROPAGATION_DELAY" "0.00 MIL,195.00 MIL"
					( Parent
						( matchGroupRef "@baseboard_fab2_lib.baseboard_fab2(sch_1):\MG_DQ-DQS_FAR_DIMM_NG_M_K_BYTE6\" )
					)
					( Units "uMatchProp" "ns" 1.000000)
					( Status sCSetFlattened )
					( Origin gBackEnd )
				)
				( attribute "RELATIVE_PROPAGATION_DELAY_SCOPE" "G"
					( Parent
						( matchGroupRef "@baseboard_fab2_lib.baseboard_fab2(sch_1):\MG_DQ_FAR_DIMM_NG_M_K_BYTE6\" )
					)
					( Status sCSetFlattened )
					( Origin gBackEnd )
				)
				( attribute "RELATIVE_PROPAGATION_DELAY" "-50.00 MIL,50.00 MIL"
					( Parent
						( matchGroupRef "@baseboard_fab2_lib.baseboard_fab2(sch_1):\MG_DQ_FAR_DIMM_NG_M_K_BYTE6\" )
					)
					( Units "uMatchProp" "ns" 1.000000)
					( Status sCSetFlattened )
					( Origin gBackEnd )
				)
			)
			( pinPair "@baseboard_fab2_lib.baseboard_fab2(sch_1):\PP2148\"
				( pinRef "@baseboard_fab2_lib.baseboard_fab2(sch_1):page60_i172:DDR3_DQ(53)" )
				( pinRef "@baseboard_fab2_lib.baseboard_fab2(sch_1):page84_i14:DQ(53)" )
				( attribute "RELATIVE_PROPAGATION_DELAY_SCOPE" "G"
					( Parent
						( matchGroupRef "@baseboard_fab2_lib.baseboard_fab2(sch_1):\MG_DQ-DQS_NEAR_DIMM_NG_M_K_BYTE6\" )
					)
					( Status sCSetFlattened )
					( Origin gBackEnd )
				)
				( attribute "RELATIVE_PROPAGATION_DELAY" "0.00 MIL,195.00 MIL"
					( Parent
						( matchGroupRef "@baseboard_fab2_lib.baseboard_fab2(sch_1):\MG_DQ-DQS_NEAR_DIMM_NG_M_K_BYTE6\" )
					)
					( Units "uMatchProp" "ns" 1.000000)
					( Status sCSetFlattened )
					( Origin gBackEnd )
				)
				( attribute "RELATIVE_PROPAGATION_DELAY_SCOPE" "G"
					( Parent
						( matchGroupRef "@crescent_city_bb_fab1_lib.crescent_city_bb_fab1(sch_1):\MG_DQ_NEAR_DIMM_NG_M_K_BYTE6\" )
					)
					( Status sCSetFlattened )
					( Origin gBackEnd )
				)
				( attribute "RELATIVE_PROPAGATION_DELAY" "-50.00 MIL,50.00 MIL"
					( Parent
						( matchGroupRef "@crescent_city_bb_fab1_lib.crescent_city_bb_fab1(sch_1):\MG_DQ_NEAR_DIMM_NG_M_K_BYTE6\" )
					)
					( Units "uMatchProp" "ns" 1.000000)
					( Status sCSetFlattened )
					( Origin gBackEnd )
				)
			)
			( pinPair "@baseboard_fab2_lib.baseboard_fab2(sch_1):\PP2149\"
				( pinRef "@baseboard_fab2_lib.baseboard_fab2(sch_1):page60_i172:DDR3_DQ(54)" )
				( pinRef "@baseboard_fab2_lib.baseboard_fab2(sch_1):page83_i111:DQ(55)" )
				( attribute "RELATIVE_PROPAGATION_DELAY_SCOPE" "G"
					( Parent
						( matchGroupRef "@baseboard_fab2_lib.baseboard_fab2(sch_1):\MG_DQ-DQS_FAR_DIMM_NG_M_K_BYTE6\" )
					)
					( Status sCSetFlattened )
					( Origin gBackEnd )
				)
				( attribute "RELATIVE_PROPAGATION_DELAY" "0.00 MIL,195.00 MIL"
					( Parent
						( matchGroupRef "@baseboard_fab2_lib.baseboard_fab2(sch_1):\MG_DQ-DQS_FAR_DIMM_NG_M_K_BYTE6\" )
					)
					( Units "uMatchProp" "ns" 1.000000)
					( Status sCSetFlattened )
					( Origin gBackEnd )
				)
				( attribute "RELATIVE_PROPAGATION_DELAY_SCOPE" "G"
					( Parent
						( matchGroupRef "@baseboard_fab2_lib.baseboard_fab2(sch_1):\MG_DQ_FAR_DIMM_NG_M_K_BYTE6\" )
					)
					( Status sCSetFlattened )
					( Origin gBackEnd )
				)
				( attribute "RELATIVE_PROPAGATION_DELAY" "-50.00 MIL,50.00 MIL"
					( Parent
						( matchGroupRef "@baseboard_fab2_lib.baseboard_fab2(sch_1):\MG_DQ_FAR_DIMM_NG_M_K_BYTE6\" )
					)
					( Units "uMatchProp" "ns" 1.000000)
					( Status sCSetFlattened )
					( Origin gBackEnd )
				)
			)
			( pinPair "@baseboard_fab2_lib.baseboard_fab2(sch_1):\PP2151\"
				( pinRef "@baseboard_fab2_lib.baseboard_fab2(sch_1):page60_i172:DDR3_DQ(54)" )
				( pinRef "@baseboard_fab2_lib.baseboard_fab2(sch_1):page84_i14:DQ(54)" )
				( attribute "RELATIVE_PROPAGATION_DELAY_SCOPE" "G"
					( Parent
						( matchGroupRef "@baseboard_fab2_lib.baseboard_fab2(sch_1):\MG_DQ-DQS_NEAR_DIMM_NG_M_K_BYTE6\" )
					)
					( Status sCSetFlattened )
					( Origin gBackEnd )
				)
				( attribute "RELATIVE_PROPAGATION_DELAY" "0.00 MIL,195.00 MIL"
					( Parent
						( matchGroupRef "@baseboard_fab2_lib.baseboard_fab2(sch_1):\MG_DQ-DQS_NEAR_DIMM_NG_M_K_BYTE6\" )
					)
					( Units "uMatchProp" "ns" 1.000000)
					( Status sCSetFlattened )
					( Origin gBackEnd )
				)
				( attribute "RELATIVE_PROPAGATION_DELAY_SCOPE" "G"
					( Parent
						( matchGroupRef "@crescent_city_bb_fab1_lib.crescent_city_bb_fab1(sch_1):\MG_DQ_NEAR_DIMM_NG_M_K_BYTE6\" )
					)
					( Status sCSetFlattened )
					( Origin gBackEnd )
				)
				( attribute "RELATIVE_PROPAGATION_DELAY" "-50.00 MIL,50.00 MIL"
					( Parent
						( matchGroupRef "@crescent_city_bb_fab1_lib.crescent_city_bb_fab1(sch_1):\MG_DQ_NEAR_DIMM_NG_M_K_BYTE6\" )
					)
					( Units "uMatchProp" "ns" 1.000000)
					( Status sCSetFlattened )
					( Origin gBackEnd )
				)
			)
			( pinPair "@baseboard_fab2_lib.baseboard_fab2(sch_1):\PP2152\"
				( pinRef "@baseboard_fab2_lib.baseboard_fab2(sch_1):page60_i172:DDR3_DQ(55)" )
				( pinRef "@baseboard_fab2_lib.baseboard_fab2(sch_1):page83_i111:DQ(54)" )
				( attribute "RELATIVE_PROPAGATION_DELAY_SCOPE" "G"
					( Parent
						( matchGroupRef "@baseboard_fab2_lib.baseboard_fab2(sch_1):\MG_DQ-DQS_FAR_DIMM_NG_M_K_BYTE6\" )
					)
					( Status sCSetFlattened )
					( Origin gBackEnd )
				)
				( attribute "RELATIVE_PROPAGATION_DELAY" "0.00 MIL,195.00 MIL"
					( Parent
						( matchGroupRef "@baseboard_fab2_lib.baseboard_fab2(sch_1):\MG_DQ-DQS_FAR_DIMM_NG_M_K_BYTE6\" )
					)
					( Units "uMatchProp" "ns" 1.000000)
					( Status sCSetFlattened )
					( Origin gBackEnd )
				)
				( attribute "RELATIVE_PROPAGATION_DELAY_SCOPE" "G"
					( Parent
						( matchGroupRef "@baseboard_fab2_lib.baseboard_fab2(sch_1):\MG_DQ_FAR_DIMM_NG_M_K_BYTE6\" )
					)
					( Status sCSetFlattened )
					( Origin gBackEnd )
				)
				( attribute "RELATIVE_PROPAGATION_DELAY" "-50.00 MIL,50.00 MIL"
					( Parent
						( matchGroupRef "@baseboard_fab2_lib.baseboard_fab2(sch_1):\MG_DQ_FAR_DIMM_NG_M_K_BYTE6\" )
					)
					( Units "uMatchProp" "ns" 1.000000)
					( Status sCSetFlattened )
					( Origin gBackEnd )
				)
			)
			( pinPair "@baseboard_fab2_lib.baseboard_fab2(sch_1):\PP2154\"
				( pinRef "@baseboard_fab2_lib.baseboard_fab2(sch_1):page60_i172:DDR3_DQ(55)" )
				( pinRef "@baseboard_fab2_lib.baseboard_fab2(sch_1):page84_i14:DQ(55)" )
				( attribute "RELATIVE_PROPAGATION_DELAY_SCOPE" "G"
					( Parent
						( matchGroupRef "@baseboard_fab2_lib.baseboard_fab2(sch_1):\MG_DQ-DQS_NEAR_DIMM_NG_M_K_BYTE6\" )
					)
					( Status sCSetFlattened )
					( Origin gBackEnd )
				)
				( attribute "RELATIVE_PROPAGATION_DELAY" "0.00 MIL,195.00 MIL"
					( Parent
						( matchGroupRef "@baseboard_fab2_lib.baseboard_fab2(sch_1):\MG_DQ-DQS_NEAR_DIMM_NG_M_K_BYTE6\" )
					)
					( Units "uMatchProp" "ns" 1.000000)
					( Status sCSetFlattened )
					( Origin gBackEnd )
				)
				( attribute "RELATIVE_PROPAGATION_DELAY_SCOPE" "G"
					( Parent
						( matchGroupRef "@crescent_city_bb_fab1_lib.crescent_city_bb_fab1(sch_1):\MG_DQ_NEAR_DIMM_NG_M_K_BYTE6\" )
					)
					( Status sCSetFlattened )
					( Origin gBackEnd )
				)
				( attribute "RELATIVE_PROPAGATION_DELAY" "-50.00 MIL,50.00 MIL"
					( Parent
						( matchGroupRef "@crescent_city_bb_fab1_lib.crescent_city_bb_fab1(sch_1):\MG_DQ_NEAR_DIMM_NG_M_K_BYTE6\" )
					)
					( Units "uMatchProp" "ns" 1.000000)
					( Status sCSetFlattened )
					( Origin gBackEnd )
				)
			)
			( pinPair "@baseboard_fab2_lib.baseboard_fab2(sch_1):\PP2107\"
				( pinRef "@baseboard_fab2_lib.baseboard_fab2(sch_1):page60_i172:DDR3_DQ(56)" )
				( pinRef "@baseboard_fab2_lib.baseboard_fab2(sch_1):page83_i111:DQ(57)" )
				( attribute "RELATIVE_PROPAGATION_DELAY_SCOPE" "G"
					( Parent
						( matchGroupRef "@baseboard_fab2_lib.baseboard_fab2(sch_1):\MG_DQ-DQS_FAR_DIMM_NG_M_K_BYTE7\" )
					)
					( Status sCSetFlattened )
					( Origin gBackEnd )
				)
				( attribute "RELATIVE_PROPAGATION_DELAY" "0.00 MIL,195.00 MIL"
					( Parent
						( matchGroupRef "@baseboard_fab2_lib.baseboard_fab2(sch_1):\MG_DQ-DQS_FAR_DIMM_NG_M_K_BYTE7\" )
					)
					( Units "uMatchProp" "ns" 1.000000)
					( Status sCSetFlattened )
					( Origin gBackEnd )
				)
				( attribute "RELATIVE_PROPAGATION_DELAY_SCOPE" "G"
					( Parent
						( matchGroupRef "@crescent_city_bb_fab1_lib.crescent_city_bb_fab1(sch_1):\MG_DQ_FAR_DIMM_NG_M_K_BYTE7\" )
					)
					( Status sCSetFlattened )
					( Origin gBackEnd )
				)
				( attribute "RELATIVE_PROPAGATION_DELAY" "-50.00 MIL,50.00 MIL"
					( Parent
						( matchGroupRef "@crescent_city_bb_fab1_lib.crescent_city_bb_fab1(sch_1):\MG_DQ_FAR_DIMM_NG_M_K_BYTE7\" )
					)
					( Units "uMatchProp" "ns" 1.000000)
					( Status sCSetFlattened )
					( Origin gBackEnd )
				)
			)
			( pinPair "@baseboard_fab2_lib.baseboard_fab2(sch_1):\PP2109\"
				( pinRef "@baseboard_fab2_lib.baseboard_fab2(sch_1):page60_i172:DDR3_DQ(56)" )
				( pinRef "@baseboard_fab2_lib.baseboard_fab2(sch_1):page84_i14:DQ(56)" )
				( attribute "RELATIVE_PROPAGATION_DELAY_SCOPE" "G"
					( Parent
						( matchGroupRef "@baseboard_fab2_lib.baseboard_fab2(sch_1):\MG_DQ-DQS_NEAR_DIMM_NG_M_K_BYTE7\" )
					)
					( Status sCSetFlattened )
					( Origin gBackEnd )
				)
				( attribute "RELATIVE_PROPAGATION_DELAY" "0.00 MIL,195.00 MIL"
					( Parent
						( matchGroupRef "@baseboard_fab2_lib.baseboard_fab2(sch_1):\MG_DQ-DQS_NEAR_DIMM_NG_M_K_BYTE7\" )
					)
					( Units "uMatchProp" "ns" 1.000000)
					( Status sCSetFlattened )
					( Origin gBackEnd )
				)
				( attribute "RELATIVE_PROPAGATION_DELAY_SCOPE" "G"
					( Parent
						( matchGroupRef "@crescent_city_bb_fab1_lib.crescent_city_bb_fab1(sch_1):\MG_DQ_NEAR_DIMM_NG_M_K_BYTE7\" )
					)
					( Status sCSetFlattened )
					( Origin gBackEnd )
				)
				( attribute "RELATIVE_PROPAGATION_DELAY" "-50.00 MIL,50.00 MIL"
					( Parent
						( matchGroupRef "@crescent_city_bb_fab1_lib.crescent_city_bb_fab1(sch_1):\MG_DQ_NEAR_DIMM_NG_M_K_BYTE7\" )
					)
					( Units "uMatchProp" "ns" 1.000000)
					( Status sCSetFlattened )
					( Origin gBackEnd )
				)
			)
			( pinPair "@baseboard_fab2_lib.baseboard_fab2(sch_1):\PP2818\"
				( pinRef "@baseboard_fab2_lib.baseboard_fab2(sch_1):page57_i172:DDR0_DQ(45)" )
				( pinRef "@baseboard_fab2_lib.baseboard_fab2(sch_1):page77_i111:DQ(44)" )
				( attribute "RELATIVE_PROPAGATION_DELAY_SCOPE" "G"
					( Parent
						( matchGroupRef "@baseboard_fab2_lib.baseboard_fab2(sch_1):\MG_DQ-DQS_FAR_DIMM_NG_M_G_BYTE5\" )
					)
					( Status sCSetFlattened )
					( Origin gBackEnd )
				)
				( attribute "RELATIVE_PROPAGATION_DELAY" "0.00 MIL,195.00 MIL"
					( Parent
						( matchGroupRef "@baseboard_fab2_lib.baseboard_fab2(sch_1):\MG_DQ-DQS_FAR_DIMM_NG_M_G_BYTE5\" )
					)
					( Units "uMatchProp" "ns" 1.000000)
					( Status sCSetFlattened )
					( Origin gBackEnd )
				)
				( attribute "RELATIVE_PROPAGATION_DELAY_SCOPE" "G"
					( Parent
						( matchGroupRef "@crescent_city_bb_fab1_lib.crescent_city_bb_fab1(sch_1):\MG_DQ_FAR_DIMM_NG_M_G_BYTE5\" )
					)
					( Status sCSetFlattened )
					( Origin gBackEnd )
				)
				( attribute "RELATIVE_PROPAGATION_DELAY" "-50.00 MIL,50.00 MIL"
					( Parent
						( matchGroupRef "@crescent_city_bb_fab1_lib.crescent_city_bb_fab1(sch_1):\MG_DQ_FAR_DIMM_NG_M_G_BYTE5\" )
					)
					( Units "uMatchProp" "ns" 1.000000)
					( Status sCSetFlattened )
					( Origin gBackEnd )
				)
			)
			( pinPair "@baseboard_fab2_lib.baseboard_fab2(sch_1):\PP2820\"
				( pinRef "@baseboard_fab2_lib.baseboard_fab2(sch_1):page57_i172:DDR0_DQ(45)" )
				( pinRef "@baseboard_fab2_lib.baseboard_fab2(sch_1):page78_i13:DQ(45)" )
				( attribute "RELATIVE_PROPAGATION_DELAY_SCOPE" "G"
					( Parent
						( matchGroupRef "@baseboard_fab2_lib.baseboard_fab2(sch_1):\MG_DQ-DQS_NEAR_DIMM_NG_M_G_BYTE5\" )
					)
					( Status sCSetFlattened )
					( Origin gBackEnd )
				)
				( attribute "RELATIVE_PROPAGATION_DELAY" "0.00 MIL,195.00 MIL"
					( Parent
						( matchGroupRef "@baseboard_fab2_lib.baseboard_fab2(sch_1):\MG_DQ-DQS_NEAR_DIMM_NG_M_G_BYTE5\" )
					)
					( Units "uMatchProp" "ns" 1.000000)
					( Status sCSetFlattened )
					( Origin gBackEnd )
				)
				( attribute "RELATIVE_PROPAGATION_DELAY_SCOPE" "G"
					( Parent
						( matchGroupRef "@crescent_city_bb_fab1_lib.crescent_city_bb_fab1(sch_1):\MG_DQ_NEAR_DIMM_NG_M_G_BYTE5\" )
					)
					( Status sCSetFlattened )
					( Origin gBackEnd )
				)
				( attribute "RELATIVE_PROPAGATION_DELAY" "-50.00 MIL,50.00 MIL"
					( Parent
						( matchGroupRef "@crescent_city_bb_fab1_lib.crescent_city_bb_fab1(sch_1):\MG_DQ_NEAR_DIMM_NG_M_G_BYTE5\" )
					)
					( Units "uMatchProp" "ns" 1.000000)
					( Status sCSetFlattened )
					( Origin gBackEnd )
				)
			)
			( pinPair "@baseboard_fab2_lib.baseboard_fab2(sch_1):\PP2821\"
				( pinRef "@baseboard_fab2_lib.baseboard_fab2(sch_1):page57_i172:DDR0_DQ(46)" )
				( pinRef "@baseboard_fab2_lib.baseboard_fab2(sch_1):page77_i111:DQ(47)" )
				( attribute "RELATIVE_PROPAGATION_DELAY_SCOPE" "G"
					( Parent
						( matchGroupRef "@baseboard_fab2_lib.baseboard_fab2(sch_1):\MG_DQ-DQS_FAR_DIMM_NG_M_G_BYTE5\" )
					)
					( Status sCSetFlattened )
					( Origin gBackEnd )
				)
				( attribute "RELATIVE_PROPAGATION_DELAY" "0.00 MIL,195.00 MIL"
					( Parent
						( matchGroupRef "@baseboard_fab2_lib.baseboard_fab2(sch_1):\MG_DQ-DQS_FAR_DIMM_NG_M_G_BYTE5\" )
					)
					( Units "uMatchProp" "ns" 1.000000)
					( Status sCSetFlattened )
					( Origin gBackEnd )
				)
				( attribute "RELATIVE_PROPAGATION_DELAY_SCOPE" "G"
					( Parent
						( matchGroupRef "@crescent_city_bb_fab1_lib.crescent_city_bb_fab1(sch_1):\MG_DQ_FAR_DIMM_NG_M_G_BYTE5\" )
					)
					( Status sCSetFlattened )
					( Origin gBackEnd )
				)
				( attribute "RELATIVE_PROPAGATION_DELAY" "-50.00 MIL,50.00 MIL"
					( Parent
						( matchGroupRef "@crescent_city_bb_fab1_lib.crescent_city_bb_fab1(sch_1):\MG_DQ_FAR_DIMM_NG_M_G_BYTE5\" )
					)
					( Units "uMatchProp" "ns" 1.000000)
					( Status sCSetFlattened )
					( Origin gBackEnd )
				)
			)
			( pinPair "@baseboard_fab2_lib.baseboard_fab2(sch_1):\PP2823\"
				( pinRef "@baseboard_fab2_lib.baseboard_fab2(sch_1):page78_i13:DQ(46)" )
				( pinRef "@baseboard_fab2_lib.baseboard_fab2(sch_1):page57_i172:DDR0_DQ(46)" )
				( attribute "RELATIVE_PROPAGATION_DELAY_SCOPE" "G"
					( Parent
						( matchGroupRef "@baseboard_fab2_lib.baseboard_fab2(sch_1):\MG_DQ-DQS_NEAR_DIMM_NG_M_G_BYTE5\" )
					)
					( Status sCSetFlattened )
					( Origin gBackEnd )
				)
				( attribute "RELATIVE_PROPAGATION_DELAY" "0.00 MIL,195.00 MIL"
					( Parent
						( matchGroupRef "@baseboard_fab2_lib.baseboard_fab2(sch_1):\MG_DQ-DQS_NEAR_DIMM_NG_M_G_BYTE5\" )
					)
					( Units "uMatchProp" "ns" 1.000000)
					( Status sCSetFlattened )
					( Origin gBackEnd )
				)
				( attribute "RELATIVE_PROPAGATION_DELAY_SCOPE" "G"
					( Parent
						( matchGroupRef "@crescent_city_bb_fab1_lib.crescent_city_bb_fab1(sch_1):\MG_DQ_NEAR_DIMM_NG_M_G_BYTE5\" )
					)
					( Status sCSetFlattened )
					( Origin gBackEnd )
				)
				( attribute "RELATIVE_PROPAGATION_DELAY" "-50.00 MIL,50.00 MIL"
					( Parent
						( matchGroupRef "@crescent_city_bb_fab1_lib.crescent_city_bb_fab1(sch_1):\MG_DQ_NEAR_DIMM_NG_M_G_BYTE5\" )
					)
					( Units "uMatchProp" "ns" 1.000000)
					( Status sCSetFlattened )
					( Origin gBackEnd )
				)
			)
			( pinPair "@baseboard_fab2_lib.baseboard_fab2(sch_1):\PP2824\"
				( pinRef "@baseboard_fab2_lib.baseboard_fab2(sch_1):page57_i172:DDR0_DQ(47)" )
				( pinRef "@baseboard_fab2_lib.baseboard_fab2(sch_1):page77_i111:DQ(46)" )
				( attribute "RELATIVE_PROPAGATION_DELAY_SCOPE" "G"
					( Parent
						( matchGroupRef "@baseboard_fab2_lib.baseboard_fab2(sch_1):\MG_DQ-DQS_FAR_DIMM_NG_M_G_BYTE5\" )
					)
					( Status sCSetFlattened )
					( Origin gBackEnd )
				)
				( attribute "RELATIVE_PROPAGATION_DELAY" "0.00 MIL,195.00 MIL"
					( Parent
						( matchGroupRef "@baseboard_fab2_lib.baseboard_fab2(sch_1):\MG_DQ-DQS_FAR_DIMM_NG_M_G_BYTE5\" )
					)
					( Units "uMatchProp" "ns" 1.000000)
					( Status sCSetFlattened )
					( Origin gBackEnd )
				)
				( attribute "RELATIVE_PROPAGATION_DELAY_SCOPE" "G"
					( Parent
						( matchGroupRef "@crescent_city_bb_fab1_lib.crescent_city_bb_fab1(sch_1):\MG_DQ_FAR_DIMM_NG_M_G_BYTE5\" )
					)
					( Origin gBackEnd )
				)
				( attribute "RELATIVE_PROPAGATION_DELAY" "TARGET,TARGET"
					( Parent
						( matchGroupRef "@crescent_city_bb_fab1_lib.crescent_city_bb_fab1(sch_1):\MG_DQ_FAR_DIMM_NG_M_G_BYTE5\" )
					)
					( Units "uMatchProp" "ns" 1.000000)
					( Origin gBackEnd )
				)
			)
			( pinPair "@baseboard_fab2_lib.baseboard_fab2(sch_1):\PP2826\"
				( pinRef "@baseboard_fab2_lib.baseboard_fab2(sch_1):page78_i13:DQ(47)" )
				( pinRef "@baseboard_fab2_lib.baseboard_fab2(sch_1):page57_i172:DDR0_DQ(47)" )
				( attribute "RELATIVE_PROPAGATION_DELAY_SCOPE" "G"
					( Parent
						( matchGroupRef "@baseboard_fab2_lib.baseboard_fab2(sch_1):\MG_DQ-DQS_NEAR_DIMM_NG_M_G_BYTE5\" )
					)
					( Status sCSetFlattened )
					( Origin gBackEnd )
				)
				( attribute "RELATIVE_PROPAGATION_DELAY" "0.00 MIL,195.00 MIL"
					( Parent
						( matchGroupRef "@baseboard_fab2_lib.baseboard_fab2(sch_1):\MG_DQ-DQS_NEAR_DIMM_NG_M_G_BYTE5\" )
					)
					( Units "uMatchProp" "ns" 1.000000)
					( Status sCSetFlattened )
					( Origin gBackEnd )
				)
				( attribute "RELATIVE_PROPAGATION_DELAY_SCOPE" "G"
					( Parent
						( matchGroupRef "@crescent_city_bb_fab1_lib.crescent_city_bb_fab1(sch_1):\MG_DQ_NEAR_DIMM_NG_M_G_BYTE5\" )
					)
					( Origin gBackEnd )
				)
				( attribute "RELATIVE_PROPAGATION_DELAY" "TARGET,TARGET"
					( Parent
						( matchGroupRef "@crescent_city_bb_fab1_lib.crescent_city_bb_fab1(sch_1):\MG_DQ_NEAR_DIMM_NG_M_G_BYTE5\" )
					)
					( Units "uMatchProp" "ns" 1.000000)
					( Origin gBackEnd )
				)
			)
			( pinPair "@baseboard_fab2_lib.baseboard_fab2(sch_1):\PP2779\"
				( pinRef "@baseboard_fab2_lib.baseboard_fab2(sch_1):page57_i172:DDR0_DQ(48)" )
				( pinRef "@baseboard_fab2_lib.baseboard_fab2(sch_1):page77_i111:DQ(49)" )
				( attribute "RELATIVE_PROPAGATION_DELAY_SCOPE" "G"
					( Parent
						( matchGroupRef "@baseboard_fab2_lib.baseboard_fab2(sch_1):\MG_DQ-DQS_FAR_DIMM_NG_M_G_BYTE6\" )
					)
					( Status sCSetFlattened )
					( Origin gBackEnd )
				)
				( attribute "RELATIVE_PROPAGATION_DELAY" "0.00 MIL,195.00 MIL"
					( Parent
						( matchGroupRef "@baseboard_fab2_lib.baseboard_fab2(sch_1):\MG_DQ-DQS_FAR_DIMM_NG_M_G_BYTE6\" )
					)
					( Units "uMatchProp" "ns" 1.000000)
					( Status sCSetFlattened )
					( Origin gBackEnd )
				)
				( attribute "RELATIVE_PROPAGATION_DELAY_SCOPE" "G"
					( Parent
						( matchGroupRef "@baseboard_fab2_lib.baseboard_fab2(sch_1):\MG_DQ_FAR_DIMM_NG_M_G_BYTE6\" )
					)
					( Status sCSetFlattened )
					( Origin gBackEnd )
				)
				( attribute "RELATIVE_PROPAGATION_DELAY" "-50.00 MIL,50.00 MIL"
					( Parent
						( matchGroupRef "@baseboard_fab2_lib.baseboard_fab2(sch_1):\MG_DQ_FAR_DIMM_NG_M_G_BYTE6\" )
					)
					( Units "uMatchProp" "ns" 1.000000)
					( Status sCSetFlattened )
					( Origin gBackEnd )
				)
			)
			( pinPair "@baseboard_fab2_lib.baseboard_fab2(sch_1):\PP2781\"
				( pinRef "@baseboard_fab2_lib.baseboard_fab2(sch_1):page78_i13:DQ(48)" )
				( pinRef "@baseboard_fab2_lib.baseboard_fab2(sch_1):page57_i172:DDR0_DQ(48)" )
				( attribute "RELATIVE_PROPAGATION_DELAY_SCOPE" "G"
					( Parent
						( matchGroupRef "@baseboard_fab2_lib.baseboard_fab2(sch_1):\MG_DQ-DQS_NEAR_DIMM_NG_M_G_BYTE6\" )
					)
					( Status sCSetFlattened )
					( Origin gBackEnd )
				)
				( attribute "RELATIVE_PROPAGATION_DELAY" "0.00 MIL,195.00 MIL"
					( Parent
						( matchGroupRef "@baseboard_fab2_lib.baseboard_fab2(sch_1):\MG_DQ-DQS_NEAR_DIMM_NG_M_G_BYTE6\" )
					)
					( Units "uMatchProp" "ns" 1.000000)
					( Status sCSetFlattened )
					( Origin gBackEnd )
				)
				( attribute "RELATIVE_PROPAGATION_DELAY_SCOPE" "G"
					( Parent
						( matchGroupRef "@baseboard_fab2_lib.baseboard_fab2(sch_1):\MG_DQ_NEAR_DIMM_NG_M_G_BYTE6\" )
					)
					( Status sCSetFlattened )
					( Origin gBackEnd )
				)
				( attribute "RELATIVE_PROPAGATION_DELAY" "-50.00 MIL,50.00 MIL"
					( Parent
						( matchGroupRef "@baseboard_fab2_lib.baseboard_fab2(sch_1):\MG_DQ_NEAR_DIMM_NG_M_G_BYTE6\" )
					)
					( Units "uMatchProp" "ns" 1.000000)
					( Status sCSetFlattened )
					( Origin gBackEnd )
				)
			)
			( pinPair "@baseboard_fab2_lib.baseboard_fab2(sch_1):\PP2782\"
				( pinRef "@baseboard_fab2_lib.baseboard_fab2(sch_1):page57_i172:DDR0_DQ(49)" )
				( pinRef "@baseboard_fab2_lib.baseboard_fab2(sch_1):page77_i111:DQ(48)" )
				( attribute "RELATIVE_PROPAGATION_DELAY_SCOPE" "G"
					( Parent
						( matchGroupRef "@baseboard_fab2_lib.baseboard_fab2(sch_1):\MG_DQ-DQS_FAR_DIMM_NG_M_G_BYTE6\" )
					)
					( Status sCSetFlattened )
					( Origin gBackEnd )
				)
				( attribute "RELATIVE_PROPAGATION_DELAY" "0.00 MIL,195.00 MIL"
					( Parent
						( matchGroupRef "@baseboard_fab2_lib.baseboard_fab2(sch_1):\MG_DQ-DQS_FAR_DIMM_NG_M_G_BYTE6\" )
					)
					( Units "uMatchProp" "ns" 1.000000)
					( Status sCSetFlattened )
					( Origin gBackEnd )
				)
				( attribute "RELATIVE_PROPAGATION_DELAY_SCOPE" "G"
					( Parent
						( matchGroupRef "@baseboard_fab2_lib.baseboard_fab2(sch_1):\MG_DQ_FAR_DIMM_NG_M_G_BYTE6\" )
					)
					( Status sCSetFlattened )
					( Origin gBackEnd )
				)
				( attribute "RELATIVE_PROPAGATION_DELAY" "-50.00 MIL,50.00 MIL"
					( Parent
						( matchGroupRef "@baseboard_fab2_lib.baseboard_fab2(sch_1):\MG_DQ_FAR_DIMM_NG_M_G_BYTE6\" )
					)
					( Units "uMatchProp" "ns" 1.000000)
					( Status sCSetFlattened )
					( Origin gBackEnd )
				)
			)
			( pinPair "@baseboard_fab2_lib.baseboard_fab2(sch_1):\PP2784\"
				( pinRef "@baseboard_fab2_lib.baseboard_fab2(sch_1):page78_i13:DQ(49)" )
				( pinRef "@baseboard_fab2_lib.baseboard_fab2(sch_1):page57_i172:DDR0_DQ(49)" )
				( attribute "RELATIVE_PROPAGATION_DELAY_SCOPE" "G"
					( Parent
						( matchGroupRef "@baseboard_fab2_lib.baseboard_fab2(sch_1):\MG_DQ-DQS_NEAR_DIMM_NG_M_G_BYTE6\" )
					)
					( Status sCSetFlattened )
					( Origin gBackEnd )
				)
				( attribute "RELATIVE_PROPAGATION_DELAY" "0.00 MIL,195.00 MIL"
					( Parent
						( matchGroupRef "@baseboard_fab2_lib.baseboard_fab2(sch_1):\MG_DQ-DQS_NEAR_DIMM_NG_M_G_BYTE6\" )
					)
					( Units "uMatchProp" "ns" 1.000000)
					( Status sCSetFlattened )
					( Origin gBackEnd )
				)
				( attribute "RELATIVE_PROPAGATION_DELAY_SCOPE" "G"
					( Parent
						( matchGroupRef "@baseboard_fab2_lib.baseboard_fab2(sch_1):\MG_DQ_NEAR_DIMM_NG_M_G_BYTE6\" )
					)
					( Status sCSetFlattened )
					( Origin gBackEnd )
				)
				( attribute "RELATIVE_PROPAGATION_DELAY" "-50.00 MIL,50.00 MIL"
					( Parent
						( matchGroupRef "@baseboard_fab2_lib.baseboard_fab2(sch_1):\MG_DQ_NEAR_DIMM_NG_M_G_BYTE6\" )
					)
					( Units "uMatchProp" "ns" 1.000000)
					( Status sCSetFlattened )
					( Origin gBackEnd )
				)
			)
			( pinPair "@baseboard_fab2_lib.baseboard_fab2(sch_1):\PP2785\"
				( pinRef "@baseboard_fab2_lib.baseboard_fab2(sch_1):page57_i172:DDR0_DQ(50)" )
				( pinRef "@baseboard_fab2_lib.baseboard_fab2(sch_1):page77_i111:DQ(51)" )
				( attribute "RELATIVE_PROPAGATION_DELAY_SCOPE" "G"
					( Parent
						( matchGroupRef "@baseboard_fab2_lib.baseboard_fab2(sch_1):\MG_DQ-DQS_FAR_DIMM_NG_M_G_BYTE6\" )
					)
					( Status sCSetFlattened )
					( Origin gBackEnd )
				)
				( attribute "RELATIVE_PROPAGATION_DELAY" "0.00 MIL,195.00 MIL"
					( Parent
						( matchGroupRef "@baseboard_fab2_lib.baseboard_fab2(sch_1):\MG_DQ-DQS_FAR_DIMM_NG_M_G_BYTE6\" )
					)
					( Units "uMatchProp" "ns" 1.000000)
					( Status sCSetFlattened )
					( Origin gBackEnd )
				)
				( attribute "RELATIVE_PROPAGATION_DELAY_SCOPE" "G"
					( Parent
						( matchGroupRef "@baseboard_fab2_lib.baseboard_fab2(sch_1):\MG_DQ_FAR_DIMM_NG_M_G_BYTE6\" )
					)
					( Status sCSetFlattened )
					( Origin gBackEnd )
				)
				( attribute "RELATIVE_PROPAGATION_DELAY" "-50.00 MIL,50.00 MIL"
					( Parent
						( matchGroupRef "@baseboard_fab2_lib.baseboard_fab2(sch_1):\MG_DQ_FAR_DIMM_NG_M_G_BYTE6\" )
					)
					( Units "uMatchProp" "ns" 1.000000)
					( Status sCSetFlattened )
					( Origin gBackEnd )
				)
			)
			( pinPair "@baseboard_fab2_lib.baseboard_fab2(sch_1):\PP2787\"
				( pinRef "@baseboard_fab2_lib.baseboard_fab2(sch_1):page57_i172:DDR0_DQ(50)" )
				( pinRef "@baseboard_fab2_lib.baseboard_fab2(sch_1):page78_i13:DQ(50)" )
				( attribute "RELATIVE_PROPAGATION_DELAY_SCOPE" "G"
					( Parent
						( matchGroupRef "@baseboard_fab2_lib.baseboard_fab2(sch_1):\MG_DQ-DQS_NEAR_DIMM_NG_M_G_BYTE6\" )
					)
					( Status sCSetFlattened )
					( Origin gBackEnd )
				)
				( attribute "RELATIVE_PROPAGATION_DELAY" "0.00 MIL,195.00 MIL"
					( Parent
						( matchGroupRef "@baseboard_fab2_lib.baseboard_fab2(sch_1):\MG_DQ-DQS_NEAR_DIMM_NG_M_G_BYTE6\" )
					)
					( Units "uMatchProp" "ns" 1.000000)
					( Status sCSetFlattened )
					( Origin gBackEnd )
				)
				( attribute "RELATIVE_PROPAGATION_DELAY_SCOPE" "G"
					( Parent
						( matchGroupRef "@baseboard_fab2_lib.baseboard_fab2(sch_1):\MG_DQ_NEAR_DIMM_NG_M_G_BYTE6\" )
					)
					( Status sCSetFlattened )
					( Origin gBackEnd )
				)
				( attribute "RELATIVE_PROPAGATION_DELAY" "-50.00 MIL,50.00 MIL"
					( Parent
						( matchGroupRef "@baseboard_fab2_lib.baseboard_fab2(sch_1):\MG_DQ_NEAR_DIMM_NG_M_G_BYTE6\" )
					)
					( Units "uMatchProp" "ns" 1.000000)
					( Status sCSetFlattened )
					( Origin gBackEnd )
				)
			)
			( pinPair "@baseboard_fab2_lib.baseboard_fab2(sch_1):\PP2788\"
				( pinRef "@baseboard_fab2_lib.baseboard_fab2(sch_1):page57_i172:DDR0_DQ(51)" )
				( pinRef "@baseboard_fab2_lib.baseboard_fab2(sch_1):page77_i111:DQ(50)" )
				( attribute "RELATIVE_PROPAGATION_DELAY_SCOPE" "G"
					( Parent
						( matchGroupRef "@baseboard_fab2_lib.baseboard_fab2(sch_1):\MG_DQ-DQS_FAR_DIMM_NG_M_G_BYTE6\" )
					)
					( Status sCSetFlattened )
					( Origin gBackEnd )
				)
				( attribute "RELATIVE_PROPAGATION_DELAY" "0.00 MIL,195.00 MIL"
					( Parent
						( matchGroupRef "@baseboard_fab2_lib.baseboard_fab2(sch_1):\MG_DQ-DQS_FAR_DIMM_NG_M_G_BYTE6\" )
					)
					( Units "uMatchProp" "ns" 1.000000)
					( Status sCSetFlattened )
					( Origin gBackEnd )
				)
				( attribute "RELATIVE_PROPAGATION_DELAY_SCOPE" "G"
					( Parent
						( matchGroupRef "@baseboard_fab2_lib.baseboard_fab2(sch_1):\MG_DQ_FAR_DIMM_NG_M_G_BYTE6\" )
					)
					( Status sCSetFlattened )
					( Origin gBackEnd )
				)
				( attribute "RELATIVE_PROPAGATION_DELAY" "-50.00 MIL,50.00 MIL"
					( Parent
						( matchGroupRef "@baseboard_fab2_lib.baseboard_fab2(sch_1):\MG_DQ_FAR_DIMM_NG_M_G_BYTE6\" )
					)
					( Units "uMatchProp" "ns" 1.000000)
					( Status sCSetFlattened )
					( Origin gBackEnd )
				)
			)
			( pinPair "@baseboard_fab2_lib.baseboard_fab2(sch_1):\PP2790\"
				( pinRef "@baseboard_fab2_lib.baseboard_fab2(sch_1):page78_i13:DQ(51)" )
				( pinRef "@baseboard_fab2_lib.baseboard_fab2(sch_1):page57_i172:DDR0_DQ(51)" )
				( attribute "RELATIVE_PROPAGATION_DELAY_SCOPE" "G"
					( Parent
						( matchGroupRef "@baseboard_fab2_lib.baseboard_fab2(sch_1):\MG_DQ-DQS_NEAR_DIMM_NG_M_G_BYTE6\" )
					)
					( Status sCSetFlattened )
					( Origin gBackEnd )
				)
				( attribute "RELATIVE_PROPAGATION_DELAY" "0.00 MIL,195.00 MIL"
					( Parent
						( matchGroupRef "@baseboard_fab2_lib.baseboard_fab2(sch_1):\MG_DQ-DQS_NEAR_DIMM_NG_M_G_BYTE6\" )
					)
					( Units "uMatchProp" "ns" 1.000000)
					( Status sCSetFlattened )
					( Origin gBackEnd )
				)
				( attribute "RELATIVE_PROPAGATION_DELAY_SCOPE" "G"
					( Parent
						( matchGroupRef "@baseboard_fab2_lib.baseboard_fab2(sch_1):\MG_DQ_NEAR_DIMM_NG_M_G_BYTE6\" )
					)
					( Status sCSetFlattened )
					( Origin gBackEnd )
				)
				( attribute "RELATIVE_PROPAGATION_DELAY" "-50.00 MIL,50.00 MIL"
					( Parent
						( matchGroupRef "@baseboard_fab2_lib.baseboard_fab2(sch_1):\MG_DQ_NEAR_DIMM_NG_M_G_BYTE6\" )
					)
					( Units "uMatchProp" "ns" 1.000000)
					( Status sCSetFlattened )
					( Origin gBackEnd )
				)
			)
			( pinPair "@baseboard_fab2_lib.baseboard_fab2(sch_1):\PP2791\"
				( pinRef "@baseboard_fab2_lib.baseboard_fab2(sch_1):page57_i172:DDR0_DQ(52)" )
				( pinRef "@baseboard_fab2_lib.baseboard_fab2(sch_1):page77_i111:DQ(53)" )
				( attribute "RELATIVE_PROPAGATION_DELAY_SCOPE" "G"
					( Parent
						( matchGroupRef "@baseboard_fab2_lib.baseboard_fab2(sch_1):\MG_DQ-DQS_FAR_DIMM_NG_M_G_BYTE6\" )
					)
					( Status sCSetFlattened )
					( Origin gBackEnd )
				)
				( attribute "RELATIVE_PROPAGATION_DELAY" "0.00 MIL,195.00 MIL"
					( Parent
						( matchGroupRef "@baseboard_fab2_lib.baseboard_fab2(sch_1):\MG_DQ-DQS_FAR_DIMM_NG_M_G_BYTE6\" )
					)
					( Units "uMatchProp" "ns" 1.000000)
					( Status sCSetFlattened )
					( Origin gBackEnd )
				)
				( attribute "RELATIVE_PROPAGATION_DELAY_SCOPE" "G"
					( Parent
						( matchGroupRef "@baseboard_fab2_lib.baseboard_fab2(sch_1):\MG_DQ_FAR_DIMM_NG_M_G_BYTE6\" )
					)
					( Status sCSetFlattened )
					( Origin gBackEnd )
				)
				( attribute "RELATIVE_PROPAGATION_DELAY" "-50.00 MIL,50.00 MIL"
					( Parent
						( matchGroupRef "@baseboard_fab2_lib.baseboard_fab2(sch_1):\MG_DQ_FAR_DIMM_NG_M_G_BYTE6\" )
					)
					( Units "uMatchProp" "ns" 1.000000)
					( Status sCSetFlattened )
					( Origin gBackEnd )
				)
			)
			( pinPair "@baseboard_fab2_lib.baseboard_fab2(sch_1):\PP2793\"
				( pinRef "@baseboard_fab2_lib.baseboard_fab2(sch_1):page78_i13:DQ(52)" )
				( pinRef "@baseboard_fab2_lib.baseboard_fab2(sch_1):page57_i172:DDR0_DQ(52)" )
				( attribute "RELATIVE_PROPAGATION_DELAY_SCOPE" "G"
					( Parent
						( matchGroupRef "@baseboard_fab2_lib.baseboard_fab2(sch_1):\MG_DQ-DQS_NEAR_DIMM_NG_M_G_BYTE6\" )
					)
					( Status sCSetFlattened )
					( Origin gBackEnd )
				)
				( attribute "RELATIVE_PROPAGATION_DELAY" "0.00 MIL,195.00 MIL"
					( Parent
						( matchGroupRef "@baseboard_fab2_lib.baseboard_fab2(sch_1):\MG_DQ-DQS_NEAR_DIMM_NG_M_G_BYTE6\" )
					)
					( Units "uMatchProp" "ns" 1.000000)
					( Status sCSetFlattened )
					( Origin gBackEnd )
				)
				( attribute "RELATIVE_PROPAGATION_DELAY_SCOPE" "G"
					( Parent
						( matchGroupRef "@baseboard_fab2_lib.baseboard_fab2(sch_1):\MG_DQ_NEAR_DIMM_NG_M_G_BYTE6\" )
					)
					( Status sCSetFlattened )
					( Origin gBackEnd )
				)
				( attribute "RELATIVE_PROPAGATION_DELAY" "-50.00 MIL,50.00 MIL"
					( Parent
						( matchGroupRef "@baseboard_fab2_lib.baseboard_fab2(sch_1):\MG_DQ_NEAR_DIMM_NG_M_G_BYTE6\" )
					)
					( Units "uMatchProp" "ns" 1.000000)
					( Status sCSetFlattened )
					( Origin gBackEnd )
				)
			)
			( pinPair "@baseboard_fab2_lib.baseboard_fab2(sch_1):\PP2794\"
				( pinRef "@baseboard_fab2_lib.baseboard_fab2(sch_1):page57_i172:DDR0_DQ(53)" )
				( pinRef "@baseboard_fab2_lib.baseboard_fab2(sch_1):page77_i111:DQ(52)" )
				( attribute "RELATIVE_PROPAGATION_DELAY_SCOPE" "G"
					( Parent
						( matchGroupRef "@baseboard_fab2_lib.baseboard_fab2(sch_1):\MG_DQ-DQS_FAR_DIMM_NG_M_G_BYTE6\" )
					)
					( Status sCSetFlattened )
					( Origin gBackEnd )
				)
				( attribute "RELATIVE_PROPAGATION_DELAY" "0.00 MIL,195.00 MIL"
					( Parent
						( matchGroupRef "@baseboard_fab2_lib.baseboard_fab2(sch_1):\MG_DQ-DQS_FAR_DIMM_NG_M_G_BYTE6\" )
					)
					( Units "uMatchProp" "ns" 1.000000)
					( Status sCSetFlattened )
					( Origin gBackEnd )
				)
				( attribute "RELATIVE_PROPAGATION_DELAY_SCOPE" "G"
					( Parent
						( matchGroupRef "@baseboard_fab2_lib.baseboard_fab2(sch_1):\MG_DQ_FAR_DIMM_NG_M_G_BYTE6\" )
					)
					( Status sCSetFlattened )
					( Origin gBackEnd )
				)
				( attribute "RELATIVE_PROPAGATION_DELAY" "-50.00 MIL,50.00 MIL"
					( Parent
						( matchGroupRef "@baseboard_fab2_lib.baseboard_fab2(sch_1):\MG_DQ_FAR_DIMM_NG_M_G_BYTE6\" )
					)
					( Units "uMatchProp" "ns" 1.000000)
					( Status sCSetFlattened )
					( Origin gBackEnd )
				)
			)
			( pinPair "@baseboard_fab2_lib.baseboard_fab2(sch_1):\PP2796\"
				( pinRef "@baseboard_fab2_lib.baseboard_fab2(sch_1):page78_i13:DQ(53)" )
				( pinRef "@baseboard_fab2_lib.baseboard_fab2(sch_1):page57_i172:DDR0_DQ(53)" )
				( attribute "RELATIVE_PROPAGATION_DELAY_SCOPE" "G"
					( Parent
						( matchGroupRef "@baseboard_fab2_lib.baseboard_fab2(sch_1):\MG_DQ-DQS_NEAR_DIMM_NG_M_G_BYTE6\" )
					)
					( Status sCSetFlattened )
					( Origin gBackEnd )
				)
				( attribute "RELATIVE_PROPAGATION_DELAY" "0.00 MIL,195.00 MIL"
					( Parent
						( matchGroupRef "@baseboard_fab2_lib.baseboard_fab2(sch_1):\MG_DQ-DQS_NEAR_DIMM_NG_M_G_BYTE6\" )
					)
					( Units "uMatchProp" "ns" 1.000000)
					( Status sCSetFlattened )
					( Origin gBackEnd )
				)
				( attribute "RELATIVE_PROPAGATION_DELAY_SCOPE" "G"
					( Parent
						( matchGroupRef "@baseboard_fab2_lib.baseboard_fab2(sch_1):\MG_DQ_NEAR_DIMM_NG_M_G_BYTE6\" )
					)
					( Status sCSetFlattened )
					( Origin gBackEnd )
				)
				( attribute "RELATIVE_PROPAGATION_DELAY" "-50.00 MIL,50.00 MIL"
					( Parent
						( matchGroupRef "@baseboard_fab2_lib.baseboard_fab2(sch_1):\MG_DQ_NEAR_DIMM_NG_M_G_BYTE6\" )
					)
					( Units "uMatchProp" "ns" 1.000000)
					( Status sCSetFlattened )
					( Origin gBackEnd )
				)
			)
			( pinPair "@baseboard_fab2_lib.baseboard_fab2(sch_1):\PP2797\"
				( pinRef "@baseboard_fab2_lib.baseboard_fab2(sch_1):page57_i172:DDR0_DQ(54)" )
				( pinRef "@baseboard_fab2_lib.baseboard_fab2(sch_1):page77_i111:DQ(55)" )
				( attribute "RELATIVE_PROPAGATION_DELAY_SCOPE" "G"
					( Parent
						( matchGroupRef "@baseboard_fab2_lib.baseboard_fab2(sch_1):\MG_DQ-DQS_FAR_DIMM_NG_M_G_BYTE6\" )
					)
					( Status sCSetFlattened )
					( Origin gBackEnd )
				)
				( attribute "RELATIVE_PROPAGATION_DELAY" "0.00 MIL,195.00 MIL"
					( Parent
						( matchGroupRef "@baseboard_fab2_lib.baseboard_fab2(sch_1):\MG_DQ-DQS_FAR_DIMM_NG_M_G_BYTE6\" )
					)
					( Units "uMatchProp" "ns" 1.000000)
					( Status sCSetFlattened )
					( Origin gBackEnd )
				)
				( attribute "RELATIVE_PROPAGATION_DELAY_SCOPE" "G"
					( Parent
						( matchGroupRef "@baseboard_fab2_lib.baseboard_fab2(sch_1):\MG_DQ_FAR_DIMM_NG_M_G_BYTE6\" )
					)
					( Status sCSetFlattened )
					( Origin gBackEnd )
				)
				( attribute "RELATIVE_PROPAGATION_DELAY" "-50.00 MIL,50.00 MIL"
					( Parent
						( matchGroupRef "@baseboard_fab2_lib.baseboard_fab2(sch_1):\MG_DQ_FAR_DIMM_NG_M_G_BYTE6\" )
					)
					( Units "uMatchProp" "ns" 1.000000)
					( Status sCSetFlattened )
					( Origin gBackEnd )
				)
			)
			( pinPair "@baseboard_fab2_lib.baseboard_fab2(sch_1):\PP2799\"
				( pinRef "@baseboard_fab2_lib.baseboard_fab2(sch_1):page57_i172:DDR0_DQ(54)" )
				( pinRef "@baseboard_fab2_lib.baseboard_fab2(sch_1):page78_i13:DQ(54)" )
				( attribute "RELATIVE_PROPAGATION_DELAY_SCOPE" "G"
					( Parent
						( matchGroupRef "@baseboard_fab2_lib.baseboard_fab2(sch_1):\MG_DQ-DQS_NEAR_DIMM_NG_M_G_BYTE6\" )
					)
					( Status sCSetFlattened )
					( Origin gBackEnd )
				)
				( attribute "RELATIVE_PROPAGATION_DELAY" "0.00 MIL,195.00 MIL"
					( Parent
						( matchGroupRef "@baseboard_fab2_lib.baseboard_fab2(sch_1):\MG_DQ-DQS_NEAR_DIMM_NG_M_G_BYTE6\" )
					)
					( Units "uMatchProp" "ns" 1.000000)
					( Status sCSetFlattened )
					( Origin gBackEnd )
				)
				( attribute "RELATIVE_PROPAGATION_DELAY_SCOPE" "G"
					( Parent
						( matchGroupRef "@baseboard_fab2_lib.baseboard_fab2(sch_1):\MG_DQ_NEAR_DIMM_NG_M_G_BYTE6\" )
					)
					( Status sCSetFlattened )
					( Origin gBackEnd )
				)
				( attribute "RELATIVE_PROPAGATION_DELAY" "-50.00 MIL,50.00 MIL"
					( Parent
						( matchGroupRef "@baseboard_fab2_lib.baseboard_fab2(sch_1):\MG_DQ_NEAR_DIMM_NG_M_G_BYTE6\" )
					)
					( Units "uMatchProp" "ns" 1.000000)
					( Status sCSetFlattened )
					( Origin gBackEnd )
				)
			)
			( pinPair "@baseboard_fab2_lib.baseboard_fab2(sch_1):\PP2800\"
				( pinRef "@baseboard_fab2_lib.baseboard_fab2(sch_1):page57_i172:DDR0_DQ(55)" )
				( pinRef "@baseboard_fab2_lib.baseboard_fab2(sch_1):page77_i111:DQ(54)" )
				( attribute "RELATIVE_PROPAGATION_DELAY_SCOPE" "G"
					( Parent
						( matchGroupRef "@baseboard_fab2_lib.baseboard_fab2(sch_1):\MG_DQ-DQS_FAR_DIMM_NG_M_G_BYTE6\" )
					)
					( Status sCSetFlattened )
					( Origin gBackEnd )
				)
				( attribute "RELATIVE_PROPAGATION_DELAY" "0.00 MIL,195.00 MIL"
					( Parent
						( matchGroupRef "@baseboard_fab2_lib.baseboard_fab2(sch_1):\MG_DQ-DQS_FAR_DIMM_NG_M_G_BYTE6\" )
					)
					( Units "uMatchProp" "ns" 1.000000)
					( Status sCSetFlattened )
					( Origin gBackEnd )
				)
				( attribute "RELATIVE_PROPAGATION_DELAY_SCOPE" "G"
					( Parent
						( matchGroupRef "@baseboard_fab2_lib.baseboard_fab2(sch_1):\MG_DQ_FAR_DIMM_NG_M_G_BYTE6\" )
					)
					( Status sCSetFlattened )
					( Origin gBackEnd )
				)
				( attribute "RELATIVE_PROPAGATION_DELAY" "-50.00 MIL,50.00 MIL"
					( Parent
						( matchGroupRef "@baseboard_fab2_lib.baseboard_fab2(sch_1):\MG_DQ_FAR_DIMM_NG_M_G_BYTE6\" )
					)
					( Units "uMatchProp" "ns" 1.000000)
					( Status sCSetFlattened )
					( Origin gBackEnd )
				)
			)
			( pinPair "@baseboard_fab2_lib.baseboard_fab2(sch_1):\PP2802\"
				( pinRef "@baseboard_fab2_lib.baseboard_fab2(sch_1):page57_i172:DDR0_DQ(55)" )
				( pinRef "@baseboard_fab2_lib.baseboard_fab2(sch_1):page78_i13:DQ(55)" )
				( attribute "RELATIVE_PROPAGATION_DELAY_SCOPE" "G"
					( Parent
						( matchGroupRef "@baseboard_fab2_lib.baseboard_fab2(sch_1):\MG_DQ-DQS_NEAR_DIMM_NG_M_G_BYTE6\" )
					)
					( Status sCSetFlattened )
					( Origin gBackEnd )
				)
				( attribute "RELATIVE_PROPAGATION_DELAY" "0.00 MIL,195.00 MIL"
					( Parent
						( matchGroupRef "@baseboard_fab2_lib.baseboard_fab2(sch_1):\MG_DQ-DQS_NEAR_DIMM_NG_M_G_BYTE6\" )
					)
					( Units "uMatchProp" "ns" 1.000000)
					( Status sCSetFlattened )
					( Origin gBackEnd )
				)
				( attribute "RELATIVE_PROPAGATION_DELAY_SCOPE" "G"
					( Parent
						( matchGroupRef "@baseboard_fab2_lib.baseboard_fab2(sch_1):\MG_DQ_NEAR_DIMM_NG_M_G_BYTE6\" )
					)
					( Status sCSetFlattened )
					( Origin gBackEnd )
				)
				( attribute "RELATIVE_PROPAGATION_DELAY" "-50.00 MIL,50.00 MIL"
					( Parent
						( matchGroupRef "@baseboard_fab2_lib.baseboard_fab2(sch_1):\MG_DQ_NEAR_DIMM_NG_M_G_BYTE6\" )
					)
					( Units "uMatchProp" "ns" 1.000000)
					( Status sCSetFlattened )
					( Origin gBackEnd )
				)
			)
			( pinPair "@baseboard_fab2_lib.baseboard_fab2(sch_1):\PP2755\"
				( pinRef "@baseboard_fab2_lib.baseboard_fab2(sch_1):page57_i172:DDR0_DQ(56)" )
				( pinRef "@baseboard_fab2_lib.baseboard_fab2(sch_1):page77_i111:DQ(57)" )
				( attribute "RELATIVE_PROPAGATION_DELAY_SCOPE" "G"
					( Parent
						( matchGroupRef "@baseboard_fab2_lib.baseboard_fab2(sch_1):\MG_DQ-DQS_FAR_DIMM_NG_M_G_BYTE7\" )
					)
					( Status sCSetFlattened )
					( Origin gBackEnd )
				)
				( attribute "RELATIVE_PROPAGATION_DELAY" "0.00 MIL,195.00 MIL"
					( Parent
						( matchGroupRef "@baseboard_fab2_lib.baseboard_fab2(sch_1):\MG_DQ-DQS_FAR_DIMM_NG_M_G_BYTE7\" )
					)
					( Units "uMatchProp" "ns" 1.000000)
					( Status sCSetFlattened )
					( Origin gBackEnd )
				)
				( attribute "RELATIVE_PROPAGATION_DELAY_SCOPE" "G"
					( Parent
						( matchGroupRef "@baseboard_fab2_lib.baseboard_fab2(sch_1):\MG_DQ_FAR_DIMM_NG_M_G_BYTE7\" )
					)
					( Status sCSetFlattened )
					( Origin gBackEnd )
				)
				( attribute "RELATIVE_PROPAGATION_DELAY" "-50.00 MIL,50.00 MIL"
					( Parent
						( matchGroupRef "@baseboard_fab2_lib.baseboard_fab2(sch_1):\MG_DQ_FAR_DIMM_NG_M_G_BYTE7\" )
					)
					( Units "uMatchProp" "ns" 1.000000)
					( Status sCSetFlattened )
					( Origin gBackEnd )
				)
			)
			( pinPair "@baseboard_fab2_lib.baseboard_fab2(sch_1):\PP2757\"
				( pinRef "@baseboard_fab2_lib.baseboard_fab2(sch_1):page57_i172:DDR0_DQ(56)" )
				( pinRef "@baseboard_fab2_lib.baseboard_fab2(sch_1):page78_i13:DQ(56)" )
				( attribute "RELATIVE_PROPAGATION_DELAY_SCOPE" "G"
					( Parent
						( matchGroupRef "@baseboard_fab2_lib.baseboard_fab2(sch_1):\MG_DQ-DQS_NEAR_DIMM_NG_M_G_BYTE7\" )
					)
					( Status sCSetFlattened )
					( Origin gBackEnd )
				)
				( attribute "RELATIVE_PROPAGATION_DELAY" "0.00 MIL,195.00 MIL"
					( Parent
						( matchGroupRef "@baseboard_fab2_lib.baseboard_fab2(sch_1):\MG_DQ-DQS_NEAR_DIMM_NG_M_G_BYTE7\" )
					)
					( Units "uMatchProp" "ns" 1.000000)
					( Status sCSetFlattened )
					( Origin gBackEnd )
				)
				( attribute "RELATIVE_PROPAGATION_DELAY_SCOPE" "G"
					( Parent
						( matchGroupRef "@baseboard_fab2_lib.baseboard_fab2(sch_1):\MG_DQ_NEAR_DIMM_NG_M_G_BYTE7\" )
					)
					( Status sCSetFlattened )
					( Origin gBackEnd )
				)
				( attribute "RELATIVE_PROPAGATION_DELAY" "-50.00 MIL,50.00 MIL"
					( Parent
						( matchGroupRef "@baseboard_fab2_lib.baseboard_fab2(sch_1):\MG_DQ_NEAR_DIMM_NG_M_G_BYTE7\" )
					)
					( Units "uMatchProp" "ns" 1.000000)
					( Status sCSetFlattened )
					( Origin gBackEnd )
				)
			)
			( pinPair "@baseboard_fab2_lib.baseboard_fab2(sch_1):\PP2758\"
				( pinRef "@baseboard_fab2_lib.baseboard_fab2(sch_1):page57_i172:DDR0_DQ(57)" )
				( pinRef "@baseboard_fab2_lib.baseboard_fab2(sch_1):page77_i111:DQ(56)" )
				( attribute "RELATIVE_PROPAGATION_DELAY_SCOPE" "G"
					( Parent
						( matchGroupRef "@baseboard_fab2_lib.baseboard_fab2(sch_1):\MG_DQ-DQS_FAR_DIMM_NG_M_G_BYTE7\" )
					)
					( Status sCSetFlattened )
					( Origin gBackEnd )
				)
				( attribute "RELATIVE_PROPAGATION_DELAY" "0.00 MIL,195.00 MIL"
					( Parent
						( matchGroupRef "@baseboard_fab2_lib.baseboard_fab2(sch_1):\MG_DQ-DQS_FAR_DIMM_NG_M_G_BYTE7\" )
					)
					( Units "uMatchProp" "ns" 1.000000)
					( Status sCSetFlattened )
					( Origin gBackEnd )
				)
				( attribute "RELATIVE_PROPAGATION_DELAY_SCOPE" "G"
					( Parent
						( matchGroupRef "@baseboard_fab2_lib.baseboard_fab2(sch_1):\MG_DQ_FAR_DIMM_NG_M_G_BYTE7\" )
					)
					( Status sCSetFlattened )
					( Origin gBackEnd )
				)
				( attribute "RELATIVE_PROPAGATION_DELAY" "-50.00 MIL,50.00 MIL"
					( Parent
						( matchGroupRef "@baseboard_fab2_lib.baseboard_fab2(sch_1):\MG_DQ_FAR_DIMM_NG_M_G_BYTE7\" )
					)
					( Units "uMatchProp" "ns" 1.000000)
					( Status sCSetFlattened )
					( Origin gBackEnd )
				)
			)
			( pinPair "@baseboard_fab2_lib.baseboard_fab2(sch_1):\PP2760\"
				( pinRef "@baseboard_fab2_lib.baseboard_fab2(sch_1):page78_i13:DQ(57)" )
				( pinRef "@baseboard_fab2_lib.baseboard_fab2(sch_1):page57_i172:DDR0_DQ(57)" )
				( attribute "RELATIVE_PROPAGATION_DELAY_SCOPE" "G"
					( Parent
						( matchGroupRef "@baseboard_fab2_lib.baseboard_fab2(sch_1):\MG_DQ-DQS_NEAR_DIMM_NG_M_G_BYTE7\" )
					)
					( Status sCSetFlattened )
					( Origin gBackEnd )
				)
				( attribute "RELATIVE_PROPAGATION_DELAY" "0.00 MIL,195.00 MIL"
					( Parent
						( matchGroupRef "@baseboard_fab2_lib.baseboard_fab2(sch_1):\MG_DQ-DQS_NEAR_DIMM_NG_M_G_BYTE7\" )
					)
					( Units "uMatchProp" "ns" 1.000000)
					( Status sCSetFlattened )
					( Origin gBackEnd )
				)
				( attribute "RELATIVE_PROPAGATION_DELAY_SCOPE" "G"
					( Parent
						( matchGroupRef "@baseboard_fab2_lib.baseboard_fab2(sch_1):\MG_DQ_NEAR_DIMM_NG_M_G_BYTE7\" )
					)
					( Status sCSetFlattened )
					( Origin gBackEnd )
				)
				( attribute "RELATIVE_PROPAGATION_DELAY" "-50.00 MIL,50.00 MIL"
					( Parent
						( matchGroupRef "@baseboard_fab2_lib.baseboard_fab2(sch_1):\MG_DQ_NEAR_DIMM_NG_M_G_BYTE7\" )
					)
					( Units "uMatchProp" "ns" 1.000000)
					( Status sCSetFlattened )
					( Origin gBackEnd )
				)
			)
			( pinPair "@baseboard_fab2_lib.baseboard_fab2(sch_1):\PP2761\"
				( pinRef "@baseboard_fab2_lib.baseboard_fab2(sch_1):page57_i172:DDR0_DQ(58)" )
				( pinRef "@baseboard_fab2_lib.baseboard_fab2(sch_1):page77_i111:DQ(59)" )
				( attribute "RELATIVE_PROPAGATION_DELAY_SCOPE" "G"
					( Parent
						( matchGroupRef "@baseboard_fab2_lib.baseboard_fab2(sch_1):\MG_DQ-DQS_FAR_DIMM_NG_M_G_BYTE7\" )
					)
					( Status sCSetFlattened )
					( Origin gBackEnd )
				)
				( attribute "RELATIVE_PROPAGATION_DELAY" "0.00 MIL,195.00 MIL"
					( Parent
						( matchGroupRef "@baseboard_fab2_lib.baseboard_fab2(sch_1):\MG_DQ-DQS_FAR_DIMM_NG_M_G_BYTE7\" )
					)
					( Units "uMatchProp" "ns" 1.000000)
					( Status sCSetFlattened )
					( Origin gBackEnd )
				)
				( attribute "RELATIVE_PROPAGATION_DELAY_SCOPE" "G"
					( Parent
						( matchGroupRef "@baseboard_fab2_lib.baseboard_fab2(sch_1):\MG_DQ_FAR_DIMM_NG_M_G_BYTE7\" )
					)
					( Status sCSetFlattened )
					( Origin gBackEnd )
				)
				( attribute "RELATIVE_PROPAGATION_DELAY" "-50.00 MIL,50.00 MIL"
					( Parent
						( matchGroupRef "@baseboard_fab2_lib.baseboard_fab2(sch_1):\MG_DQ_FAR_DIMM_NG_M_G_BYTE7\" )
					)
					( Units "uMatchProp" "ns" 1.000000)
					( Status sCSetFlattened )
					( Origin gBackEnd )
				)
			)
			( pinPair "@baseboard_fab2_lib.baseboard_fab2(sch_1):\PP2763\"
				( pinRef "@baseboard_fab2_lib.baseboard_fab2(sch_1):page78_i13:DQ(58)" )
				( pinRef "@baseboard_fab2_lib.baseboard_fab2(sch_1):page57_i172:DDR0_DQ(58)" )
				( attribute "RELATIVE_PROPAGATION_DELAY_SCOPE" "G"
					( Parent
						( matchGroupRef "@baseboard_fab2_lib.baseboard_fab2(sch_1):\MG_DQ-DQS_NEAR_DIMM_NG_M_G_BYTE7\" )
					)
					( Status sCSetFlattened )
					( Origin gBackEnd )
				)
				( attribute "RELATIVE_PROPAGATION_DELAY" "0.00 MIL,195.00 MIL"
					( Parent
						( matchGroupRef "@baseboard_fab2_lib.baseboard_fab2(sch_1):\MG_DQ-DQS_NEAR_DIMM_NG_M_G_BYTE7\" )
					)
					( Units "uMatchProp" "ns" 1.000000)
					( Status sCSetFlattened )
					( Origin gBackEnd )
				)
				( attribute "RELATIVE_PROPAGATION_DELAY_SCOPE" "G"
					( Parent
						( matchGroupRef "@baseboard_fab2_lib.baseboard_fab2(sch_1):\MG_DQ_NEAR_DIMM_NG_M_G_BYTE7\" )
					)
					( Status sCSetFlattened )
					( Origin gBackEnd )
				)
				( attribute "RELATIVE_PROPAGATION_DELAY" "-50.00 MIL,50.00 MIL"
					( Parent
						( matchGroupRef "@baseboard_fab2_lib.baseboard_fab2(sch_1):\MG_DQ_NEAR_DIMM_NG_M_G_BYTE7\" )
					)
					( Units "uMatchProp" "ns" 1.000000)
					( Status sCSetFlattened )
					( Origin gBackEnd )
				)
			)
			( pinPair "@baseboard_fab2_lib.baseboard_fab2(sch_1):\PP2764\"
				( pinRef "@baseboard_fab2_lib.baseboard_fab2(sch_1):page57_i172:DDR0_DQ(59)" )
				( pinRef "@baseboard_fab2_lib.baseboard_fab2(sch_1):page77_i111:DQ(58)" )
				( attribute "RELATIVE_PROPAGATION_DELAY_SCOPE" "G"
					( Parent
						( matchGroupRef "@baseboard_fab2_lib.baseboard_fab2(sch_1):\MG_DQ-DQS_FAR_DIMM_NG_M_G_BYTE7\" )
					)
					( Status sCSetFlattened )
					( Origin gBackEnd )
				)
				( attribute "RELATIVE_PROPAGATION_DELAY" "0.00 MIL,195.00 MIL"
					( Parent
						( matchGroupRef "@baseboard_fab2_lib.baseboard_fab2(sch_1):\MG_DQ-DQS_FAR_DIMM_NG_M_G_BYTE7\" )
					)
					( Units "uMatchProp" "ns" 1.000000)
					( Status sCSetFlattened )
					( Origin gBackEnd )
				)
				( attribute "RELATIVE_PROPAGATION_DELAY_SCOPE" "G"
					( Parent
						( matchGroupRef "@baseboard_fab2_lib.baseboard_fab2(sch_1):\MG_DQ_FAR_DIMM_NG_M_G_BYTE7\" )
					)
					( Status sCSetFlattened )
					( Origin gBackEnd )
				)
				( attribute "RELATIVE_PROPAGATION_DELAY" "-50.00 MIL,50.00 MIL"
					( Parent
						( matchGroupRef "@baseboard_fab2_lib.baseboard_fab2(sch_1):\MG_DQ_FAR_DIMM_NG_M_G_BYTE7\" )
					)
					( Units "uMatchProp" "ns" 1.000000)
					( Status sCSetFlattened )
					( Origin gBackEnd )
				)
			)
			( pinPair "@baseboard_fab2_lib.baseboard_fab2(sch_1):\PP2766\"
				( pinRef "@baseboard_fab2_lib.baseboard_fab2(sch_1):page78_i13:DQ(59)" )
				( pinRef "@baseboard_fab2_lib.baseboard_fab2(sch_1):page57_i172:DDR0_DQ(59)" )
				( attribute "RELATIVE_PROPAGATION_DELAY_SCOPE" "G"
					( Parent
						( matchGroupRef "@baseboard_fab2_lib.baseboard_fab2(sch_1):\MG_DQ-DQS_NEAR_DIMM_NG_M_G_BYTE7\" )
					)
					( Status sCSetFlattened )
					( Origin gBackEnd )
				)
				( attribute "RELATIVE_PROPAGATION_DELAY" "0.00 MIL,195.00 MIL"
					( Parent
						( matchGroupRef "@baseboard_fab2_lib.baseboard_fab2(sch_1):\MG_DQ-DQS_NEAR_DIMM_NG_M_G_BYTE7\" )
					)
					( Units "uMatchProp" "ns" 1.000000)
					( Status sCSetFlattened )
					( Origin gBackEnd )
				)
				( attribute "RELATIVE_PROPAGATION_DELAY_SCOPE" "G"
					( Parent
						( matchGroupRef "@baseboard_fab2_lib.baseboard_fab2(sch_1):\MG_DQ_NEAR_DIMM_NG_M_G_BYTE7\" )
					)
					( Status sCSetFlattened )
					( Origin gBackEnd )
				)
				( attribute "RELATIVE_PROPAGATION_DELAY" "-50.00 MIL,50.00 MIL"
					( Parent
						( matchGroupRef "@baseboard_fab2_lib.baseboard_fab2(sch_1):\MG_DQ_NEAR_DIMM_NG_M_G_BYTE7\" )
					)
					( Units "uMatchProp" "ns" 1.000000)
					( Status sCSetFlattened )
					( Origin gBackEnd )
				)
			)
			( pinPair "@baseboard_fab2_lib.baseboard_fab2(sch_1):\PP2767\"
				( pinRef "@baseboard_fab2_lib.baseboard_fab2(sch_1):page57_i172:DDR0_DQ(60)" )
				( pinRef "@baseboard_fab2_lib.baseboard_fab2(sch_1):page77_i111:DQ(61)" )
				( attribute "RELATIVE_PROPAGATION_DELAY_SCOPE" "G"
					( Parent
						( matchGroupRef "@baseboard_fab2_lib.baseboard_fab2(sch_1):\MG_DQ-DQS_FAR_DIMM_NG_M_G_BYTE7\" )
					)
					( Status sCSetFlattened )
					( Origin gBackEnd )
				)
				( attribute "RELATIVE_PROPAGATION_DELAY" "0.00 MIL,195.00 MIL"
					( Parent
						( matchGroupRef "@baseboard_fab2_lib.baseboard_fab2(sch_1):\MG_DQ-DQS_FAR_DIMM_NG_M_G_BYTE7\" )
					)
					( Units "uMatchProp" "ns" 1.000000)
					( Status sCSetFlattened )
					( Origin gBackEnd )
				)
				( attribute "RELATIVE_PROPAGATION_DELAY_SCOPE" "G"
					( Parent
						( matchGroupRef "@baseboard_fab2_lib.baseboard_fab2(sch_1):\MG_DQ_FAR_DIMM_NG_M_G_BYTE7\" )
					)
					( Status sCSetFlattened )
					( Origin gBackEnd )
				)
				( attribute "RELATIVE_PROPAGATION_DELAY" "-50.00 MIL,50.00 MIL"
					( Parent
						( matchGroupRef "@baseboard_fab2_lib.baseboard_fab2(sch_1):\MG_DQ_FAR_DIMM_NG_M_G_BYTE7\" )
					)
					( Units "uMatchProp" "ns" 1.000000)
					( Status sCSetFlattened )
					( Origin gBackEnd )
				)
			)
			( pinPair "@baseboard_fab2_lib.baseboard_fab2(sch_1):\PP2769\"
				( pinRef "@baseboard_fab2_lib.baseboard_fab2(sch_1):page78_i13:DQ(60)" )
				( pinRef "@baseboard_fab2_lib.baseboard_fab2(sch_1):page57_i172:DDR0_DQ(60)" )
				( attribute "RELATIVE_PROPAGATION_DELAY_SCOPE" "G"
					( Parent
						( matchGroupRef "@baseboard_fab2_lib.baseboard_fab2(sch_1):\MG_DQ-DQS_NEAR_DIMM_NG_M_G_BYTE7\" )
					)
					( Status sCSetFlattened )
					( Origin gBackEnd )
				)
				( attribute "RELATIVE_PROPAGATION_DELAY" "0.00 MIL,195.00 MIL"
					( Parent
						( matchGroupRef "@baseboard_fab2_lib.baseboard_fab2(sch_1):\MG_DQ-DQS_NEAR_DIMM_NG_M_G_BYTE7\" )
					)
					( Units "uMatchProp" "ns" 1.000000)
					( Status sCSetFlattened )
					( Origin gBackEnd )
				)
				( attribute "RELATIVE_PROPAGATION_DELAY_SCOPE" "G"
					( Parent
						( matchGroupRef "@baseboard_fab2_lib.baseboard_fab2(sch_1):\MG_DQ_NEAR_DIMM_NG_M_G_BYTE7\" )
					)
					( Status sCSetFlattened )
					( Origin gBackEnd )
				)
				( attribute "RELATIVE_PROPAGATION_DELAY" "-50.00 MIL,50.00 MIL"
					( Parent
						( matchGroupRef "@baseboard_fab2_lib.baseboard_fab2(sch_1):\MG_DQ_NEAR_DIMM_NG_M_G_BYTE7\" )
					)
					( Units "uMatchProp" "ns" 1.000000)
					( Status sCSetFlattened )
					( Origin gBackEnd )
				)
			)
			( pinPair "@baseboard_fab2_lib.baseboard_fab2(sch_1):\PP2770\"
				( pinRef "@baseboard_fab2_lib.baseboard_fab2(sch_1):page57_i172:DDR0_DQ(61)" )
				( pinRef "@baseboard_fab2_lib.baseboard_fab2(sch_1):page77_i111:DQ(60)" )
				( attribute "RELATIVE_PROPAGATION_DELAY_SCOPE" "G"
					( Parent
						( matchGroupRef "@baseboard_fab2_lib.baseboard_fab2(sch_1):\MG_DQ-DQS_FAR_DIMM_NG_M_G_BYTE7\" )
					)
					( Status sCSetFlattened )
					( Origin gBackEnd )
				)
				( attribute "RELATIVE_PROPAGATION_DELAY" "0.00 MIL,195.00 MIL"
					( Parent
						( matchGroupRef "@baseboard_fab2_lib.baseboard_fab2(sch_1):\MG_DQ-DQS_FAR_DIMM_NG_M_G_BYTE7\" )
					)
					( Units "uMatchProp" "ns" 1.000000)
					( Status sCSetFlattened )
					( Origin gBackEnd )
				)
				( attribute "RELATIVE_PROPAGATION_DELAY_SCOPE" "G"
					( Parent
						( matchGroupRef "@baseboard_fab2_lib.baseboard_fab2(sch_1):\MG_DQ_FAR_DIMM_NG_M_G_BYTE7\" )
					)
					( Status sCSetFlattened )
					( Origin gBackEnd )
				)
				( attribute "RELATIVE_PROPAGATION_DELAY" "-50.00 MIL,50.00 MIL"
					( Parent
						( matchGroupRef "@baseboard_fab2_lib.baseboard_fab2(sch_1):\MG_DQ_FAR_DIMM_NG_M_G_BYTE7\" )
					)
					( Units "uMatchProp" "ns" 1.000000)
					( Status sCSetFlattened )
					( Origin gBackEnd )
				)
			)
			( pinPair "@baseboard_fab2_lib.baseboard_fab2(sch_1):\PP2772\"
				( pinRef "@baseboard_fab2_lib.baseboard_fab2(sch_1):page78_i13:DQ(61)" )
				( pinRef "@baseboard_fab2_lib.baseboard_fab2(sch_1):page57_i172:DDR0_DQ(61)" )
				( attribute "RELATIVE_PROPAGATION_DELAY_SCOPE" "G"
					( Parent
						( matchGroupRef "@baseboard_fab2_lib.baseboard_fab2(sch_1):\MG_DQ-DQS_NEAR_DIMM_NG_M_G_BYTE7\" )
					)
					( Status sCSetFlattened )
					( Origin gBackEnd )
				)
				( attribute "RELATIVE_PROPAGATION_DELAY" "0.00 MIL,195.00 MIL"
					( Parent
						( matchGroupRef "@baseboard_fab2_lib.baseboard_fab2(sch_1):\MG_DQ-DQS_NEAR_DIMM_NG_M_G_BYTE7\" )
					)
					( Units "uMatchProp" "ns" 1.000000)
					( Status sCSetFlattened )
					( Origin gBackEnd )
				)
				( attribute "RELATIVE_PROPAGATION_DELAY_SCOPE" "G"
					( Parent
						( matchGroupRef "@baseboard_fab2_lib.baseboard_fab2(sch_1):\MG_DQ_NEAR_DIMM_NG_M_G_BYTE7\" )
					)
					( Status sCSetFlattened )
					( Origin gBackEnd )
				)
				( attribute "RELATIVE_PROPAGATION_DELAY" "-50.00 MIL,50.00 MIL"
					( Parent
						( matchGroupRef "@baseboard_fab2_lib.baseboard_fab2(sch_1):\MG_DQ_NEAR_DIMM_NG_M_G_BYTE7\" )
					)
					( Units "uMatchProp" "ns" 1.000000)
					( Status sCSetFlattened )
					( Origin gBackEnd )
				)
			)
			( pinPair "@baseboard_fab2_lib.baseboard_fab2(sch_1):\PP2773\"
				( pinRef "@baseboard_fab2_lib.baseboard_fab2(sch_1):page57_i172:DDR0_DQ(62)" )
				( pinRef "@baseboard_fab2_lib.baseboard_fab2(sch_1):page77_i111:DQ(63)" )
				( attribute "RELATIVE_PROPAGATION_DELAY_SCOPE" "G"
					( Parent
						( matchGroupRef "@baseboard_fab2_lib.baseboard_fab2(sch_1):\MG_DQ-DQS_FAR_DIMM_NG_M_G_BYTE7\" )
					)
					( Status sCSetFlattened )
					( Origin gBackEnd )
				)
				( attribute "RELATIVE_PROPAGATION_DELAY" "0.00 MIL,195.00 MIL"
					( Parent
						( matchGroupRef "@baseboard_fab2_lib.baseboard_fab2(sch_1):\MG_DQ-DQS_FAR_DIMM_NG_M_G_BYTE7\" )
					)
					( Units "uMatchProp" "ns" 1.000000)
					( Status sCSetFlattened )
					( Origin gBackEnd )
				)
				( attribute "RELATIVE_PROPAGATION_DELAY_SCOPE" "G"
					( Parent
						( matchGroupRef "@baseboard_fab2_lib.baseboard_fab2(sch_1):\MG_DQ_FAR_DIMM_NG_M_G_BYTE7\" )
					)
					( Status sCSetFlattened )
					( Origin gBackEnd )
				)
				( attribute "RELATIVE_PROPAGATION_DELAY" "-50.00 MIL,50.00 MIL"
					( Parent
						( matchGroupRef "@baseboard_fab2_lib.baseboard_fab2(sch_1):\MG_DQ_FAR_DIMM_NG_M_G_BYTE7\" )
					)
					( Units "uMatchProp" "ns" 1.000000)
					( Status sCSetFlattened )
					( Origin gBackEnd )
				)
			)
			( pinPair "@baseboard_fab2_lib.baseboard_fab2(sch_1):\PP2775\"
				( pinRef "@baseboard_fab2_lib.baseboard_fab2(sch_1):page78_i13:DQ(62)" )
				( pinRef "@baseboard_fab2_lib.baseboard_fab2(sch_1):page57_i172:DDR0_DQ(62)" )
				( attribute "RELATIVE_PROPAGATION_DELAY_SCOPE" "G"
					( Parent
						( matchGroupRef "@baseboard_fab2_lib.baseboard_fab2(sch_1):\MG_DQ-DQS_NEAR_DIMM_NG_M_G_BYTE7\" )
					)
					( Status sCSetFlattened )
					( Origin gBackEnd )
				)
				( attribute "RELATIVE_PROPAGATION_DELAY" "0.00 MIL,195.00 MIL"
					( Parent
						( matchGroupRef "@baseboard_fab2_lib.baseboard_fab2(sch_1):\MG_DQ-DQS_NEAR_DIMM_NG_M_G_BYTE7\" )
					)
					( Units "uMatchProp" "ns" 1.000000)
					( Status sCSetFlattened )
					( Origin gBackEnd )
				)
				( attribute "RELATIVE_PROPAGATION_DELAY_SCOPE" "G"
					( Parent
						( matchGroupRef "@baseboard_fab2_lib.baseboard_fab2(sch_1):\MG_DQ_NEAR_DIMM_NG_M_G_BYTE7\" )
					)
					( Status sCSetFlattened )
					( Origin gBackEnd )
				)
				( attribute "RELATIVE_PROPAGATION_DELAY" "-50.00 MIL,50.00 MIL"
					( Parent
						( matchGroupRef "@baseboard_fab2_lib.baseboard_fab2(sch_1):\MG_DQ_NEAR_DIMM_NG_M_G_BYTE7\" )
					)
					( Units "uMatchProp" "ns" 1.000000)
					( Status sCSetFlattened )
					( Origin gBackEnd )
				)
			)
			( pinPair "@baseboard_fab2_lib.baseboard_fab2(sch_1):\PP2776\"
				( pinRef "@baseboard_fab2_lib.baseboard_fab2(sch_1):page57_i172:DDR0_DQ(63)" )
				( pinRef "@baseboard_fab2_lib.baseboard_fab2(sch_1):page77_i111:DQ(62)" )
				( attribute "RELATIVE_PROPAGATION_DELAY_SCOPE" "G"
					( Parent
						( matchGroupRef "@baseboard_fab2_lib.baseboard_fab2(sch_1):\MG_DQ-DQS_FAR_DIMM_NG_M_G_BYTE7\" )
					)
					( Status sCSetFlattened )
					( Origin gBackEnd )
				)
				( attribute "RELATIVE_PROPAGATION_DELAY" "0.00 MIL,195.00 MIL"
					( Parent
						( matchGroupRef "@baseboard_fab2_lib.baseboard_fab2(sch_1):\MG_DQ-DQS_FAR_DIMM_NG_M_G_BYTE7\" )
					)
					( Units "uMatchProp" "ns" 1.000000)
					( Status sCSetFlattened )
					( Origin gBackEnd )
				)
				( attribute "RELATIVE_PROPAGATION_DELAY_SCOPE" "G"
					( Parent
						( matchGroupRef "@baseboard_fab2_lib.baseboard_fab2(sch_1):\MG_DQ_FAR_DIMM_NG_M_G_BYTE7\" )
					)
					( Status sCSetFlattened )
					( Origin gBackEnd )
				)
				( attribute "RELATIVE_PROPAGATION_DELAY" "-50.00 MIL,50.00 MIL"
					( Parent
						( matchGroupRef "@baseboard_fab2_lib.baseboard_fab2(sch_1):\MG_DQ_FAR_DIMM_NG_M_G_BYTE7\" )
					)
					( Units "uMatchProp" "ns" 1.000000)
					( Status sCSetFlattened )
					( Origin gBackEnd )
				)
			)
			( pinPair "@baseboard_fab2_lib.baseboard_fab2(sch_1):\PP2778\"
				( pinRef "@baseboard_fab2_lib.baseboard_fab2(sch_1):page78_i13:DQ(63)" )
				( pinRef "@baseboard_fab2_lib.baseboard_fab2(sch_1):page57_i172:DDR0_DQ(63)" )
				( attribute "RELATIVE_PROPAGATION_DELAY_SCOPE" "G"
					( Parent
						( matchGroupRef "@baseboard_fab2_lib.baseboard_fab2(sch_1):\MG_DQ-DQS_NEAR_DIMM_NG_M_G_BYTE7\" )
					)
					( Status sCSetFlattened )
					( Origin gBackEnd )
				)
				( attribute "RELATIVE_PROPAGATION_DELAY" "0.00 MIL,195.00 MIL"
					( Parent
						( matchGroupRef "@baseboard_fab2_lib.baseboard_fab2(sch_1):\MG_DQ-DQS_NEAR_DIMM_NG_M_G_BYTE7\" )
					)
					( Units "uMatchProp" "ns" 1.000000)
					( Status sCSetFlattened )
					( Origin gBackEnd )
				)
				( attribute "RELATIVE_PROPAGATION_DELAY_SCOPE" "G"
					( Parent
						( matchGroupRef "@baseboard_fab2_lib.baseboard_fab2(sch_1):\MG_DQ_NEAR_DIMM_NG_M_G_BYTE7\" )
					)
					( Status sCSetFlattened )
					( Origin gBackEnd )
				)
				( attribute "RELATIVE_PROPAGATION_DELAY" "-50.00 MIL,50.00 MIL"
					( Parent
						( matchGroupRef "@baseboard_fab2_lib.baseboard_fab2(sch_1):\MG_DQ_NEAR_DIMM_NG_M_G_BYTE7\" )
					)
					( Units "uMatchProp" "ns" 1.000000)
					( Status sCSetFlattened )
					( Origin gBackEnd )
				)
			)
			( pinPair "@baseboard_fab2_lib.baseboard_fab2(sch_1):\PP2707\"
				( pinRef "@baseboard_fab2_lib.baseboard_fab2(sch_1):page58_i172:DDR1_DQ(0)" )
				( pinRef "@baseboard_fab2_lib.baseboard_fab2(sch_1):page79_i111:DQ(1)" )
				( attribute "RELATIVE_PROPAGATION_DELAY_SCOPE" "G"
					( Parent
						( matchGroupRef "@baseboard_fab2_lib.baseboard_fab2(sch_1):\MG_DQ-DQS_FAR_DIMM_NG_M_H_BYTE0\" )
					)
					( Status sCSetFlattened )
					( Origin gBackEnd )
				)
				( attribute "RELATIVE_PROPAGATION_DELAY" "0.00 MIL,195.00 MIL"
					( Parent
						( matchGroupRef "@baseboard_fab2_lib.baseboard_fab2(sch_1):\MG_DQ-DQS_FAR_DIMM_NG_M_H_BYTE0\" )
					)
					( Units "uMatchProp" "ns" 1.000000)
					( Status sCSetFlattened )
					( Origin gBackEnd )
				)
				( attribute "RELATIVE_PROPAGATION_DELAY_SCOPE" "G"
					( Parent
						( matchGroupRef "@baseboard_fab2_lib.baseboard_fab2(sch_1):\MG_DQ_FAR_DIMM_NG_M_H_BYTE0\" )
					)
					( Status sCSetFlattened )
					( Origin gBackEnd )
				)
				( attribute "RELATIVE_PROPAGATION_DELAY" "-50.00 MIL,50.00 MIL"
					( Parent
						( matchGroupRef "@baseboard_fab2_lib.baseboard_fab2(sch_1):\MG_DQ_FAR_DIMM_NG_M_H_BYTE0\" )
					)
					( Units "uMatchProp" "ns" 1.000000)
					( Status sCSetFlattened )
					( Origin gBackEnd )
				)
			)
			( pinPair "@baseboard_fab2_lib.baseboard_fab2(sch_1):\PP2708\"
				( pinRef "@baseboard_fab2_lib.baseboard_fab2(sch_1):page58_i172:DDR1_DQ(0)" )
				( pinRef "@baseboard_fab2_lib.baseboard_fab2(sch_1):page80_i24:DQ(0)" )
				( attribute "RELATIVE_PROPAGATION_DELAY_SCOPE" "G"
					( Parent
						( matchGroupRef "@baseboard_fab2_lib.baseboard_fab2(sch_1):\MG_DQ-DQS_NEAR_DIMM_NG_M_H_BYTE0\" )
					)
					( Status sCSetFlattened )
					( Origin gBackEnd )
				)
				( attribute "RELATIVE_PROPAGATION_DELAY" "0.00 MIL,195.00 MIL"
					( Parent
						( matchGroupRef "@baseboard_fab2_lib.baseboard_fab2(sch_1):\MG_DQ-DQS_NEAR_DIMM_NG_M_H_BYTE0\" )
					)
					( Units "uMatchProp" "ns" 1.000000)
					( Status sCSetFlattened )
					( Origin gBackEnd )
				)
				( attribute "RELATIVE_PROPAGATION_DELAY_SCOPE" "G"
					( Parent
						( matchGroupRef "@baseboard_fab2_lib.baseboard_fab2(sch_1):\MG_DQ_NEAR_DIMM_NG_M_H_BYTE0\" )
					)
					( Status sCSetFlattened )
					( Origin gBackEnd )
				)
				( attribute "RELATIVE_PROPAGATION_DELAY" "-50.00 MIL,50.00 MIL"
					( Parent
						( matchGroupRef "@baseboard_fab2_lib.baseboard_fab2(sch_1):\MG_DQ_NEAR_DIMM_NG_M_H_BYTE0\" )
					)
					( Units "uMatchProp" "ns" 1.000000)
					( Status sCSetFlattened )
					( Origin gBackEnd )
				)
			)
			( pinPair "@baseboard_fab2_lib.baseboard_fab2(sch_1):\PP2710\"
				( pinRef "@baseboard_fab2_lib.baseboard_fab2(sch_1):page58_i172:DDR1_DQ(1)" )
				( pinRef "@baseboard_fab2_lib.baseboard_fab2(sch_1):page79_i111:DQ(0)" )
				( attribute "RELATIVE_PROPAGATION_DELAY_SCOPE" "G"
					( Parent
						( matchGroupRef "@baseboard_fab2_lib.baseboard_fab2(sch_1):\MG_DQ-DQS_FAR_DIMM_NG_M_H_BYTE0\" )
					)
					( Status sCSetFlattened )
					( Origin gBackEnd )
				)
				( attribute "RELATIVE_PROPAGATION_DELAY" "0.00 MIL,195.00 MIL"
					( Parent
						( matchGroupRef "@baseboard_fab2_lib.baseboard_fab2(sch_1):\MG_DQ-DQS_FAR_DIMM_NG_M_H_BYTE0\" )
					)
					( Units "uMatchProp" "ns" 1.000000)
					( Status sCSetFlattened )
					( Origin gBackEnd )
				)
				( attribute "RELATIVE_PROPAGATION_DELAY_SCOPE" "G"
					( Parent
						( matchGroupRef "@baseboard_fab2_lib.baseboard_fab2(sch_1):\MG_DQ_FAR_DIMM_NG_M_H_BYTE0\" )
					)
					( Status sCSetFlattened )
					( Origin gBackEnd )
				)
				( attribute "RELATIVE_PROPAGATION_DELAY" "-50.00 MIL,50.00 MIL"
					( Parent
						( matchGroupRef "@baseboard_fab2_lib.baseboard_fab2(sch_1):\MG_DQ_FAR_DIMM_NG_M_H_BYTE0\" )
					)
					( Units "uMatchProp" "ns" 1.000000)
					( Status sCSetFlattened )
					( Origin gBackEnd )
				)
			)
			( pinPair "@baseboard_fab2_lib.baseboard_fab2(sch_1):\PP2711\"
				( pinRef "@baseboard_fab2_lib.baseboard_fab2(sch_1):page58_i172:DDR1_DQ(1)" )
				( pinRef "@baseboard_fab2_lib.baseboard_fab2(sch_1):page80_i24:DQ(1)" )
				( attribute "RELATIVE_PROPAGATION_DELAY_SCOPE" "G"
					( Parent
						( matchGroupRef "@baseboard_fab2_lib.baseboard_fab2(sch_1):\MG_DQ-DQS_NEAR_DIMM_NG_M_H_BYTE0\" )
					)
					( Status sCSetFlattened )
					( Origin gBackEnd )
				)
				( attribute "RELATIVE_PROPAGATION_DELAY" "0.00 MIL,195.00 MIL"
					( Parent
						( matchGroupRef "@baseboard_fab2_lib.baseboard_fab2(sch_1):\MG_DQ-DQS_NEAR_DIMM_NG_M_H_BYTE0\" )
					)
					( Units "uMatchProp" "ns" 1.000000)
					( Status sCSetFlattened )
					( Origin gBackEnd )
				)
				( attribute "RELATIVE_PROPAGATION_DELAY_SCOPE" "G"
					( Parent
						( matchGroupRef "@baseboard_fab2_lib.baseboard_fab2(sch_1):\MG_DQ_NEAR_DIMM_NG_M_H_BYTE0\" )
					)
					( Status sCSetFlattened )
					( Origin gBackEnd )
				)
				( attribute "RELATIVE_PROPAGATION_DELAY" "-50.00 MIL,50.00 MIL"
					( Parent
						( matchGroupRef "@baseboard_fab2_lib.baseboard_fab2(sch_1):\MG_DQ_NEAR_DIMM_NG_M_H_BYTE0\" )
					)
					( Units "uMatchProp" "ns" 1.000000)
					( Status sCSetFlattened )
					( Origin gBackEnd )
				)
			)
			( pinPair "@baseboard_fab2_lib.baseboard_fab2(sch_1):\PP2713\"
				( pinRef "@baseboard_fab2_lib.baseboard_fab2(sch_1):page58_i172:DDR1_DQ(2)" )
				( pinRef "@baseboard_fab2_lib.baseboard_fab2(sch_1):page79_i111:DQ(3)" )
				( attribute "RELATIVE_PROPAGATION_DELAY_SCOPE" "G"
					( Parent
						( matchGroupRef "@baseboard_fab2_lib.baseboard_fab2(sch_1):\MG_DQ-DQS_FAR_DIMM_NG_M_H_BYTE0\" )
					)
					( Status sCSetFlattened )
					( Origin gBackEnd )
				)
				( attribute "RELATIVE_PROPAGATION_DELAY" "0.00 MIL,195.00 MIL"
					( Parent
						( matchGroupRef "@baseboard_fab2_lib.baseboard_fab2(sch_1):\MG_DQ-DQS_FAR_DIMM_NG_M_H_BYTE0\" )
					)
					( Units "uMatchProp" "ns" 1.000000)
					( Status sCSetFlattened )
					( Origin gBackEnd )
				)
				( attribute "RELATIVE_PROPAGATION_DELAY_SCOPE" "G"
					( Parent
						( matchGroupRef "@baseboard_fab2_lib.baseboard_fab2(sch_1):\MG_DQ_FAR_DIMM_NG_M_H_BYTE0\" )
					)
					( Status sCSetFlattened )
					( Origin gBackEnd )
				)
				( attribute "RELATIVE_PROPAGATION_DELAY" "-50.00 MIL,50.00 MIL"
					( Parent
						( matchGroupRef "@baseboard_fab2_lib.baseboard_fab2(sch_1):\MG_DQ_FAR_DIMM_NG_M_H_BYTE0\" )
					)
					( Units "uMatchProp" "ns" 1.000000)
					( Status sCSetFlattened )
					( Origin gBackEnd )
				)
			)
			( pinPair "@baseboard_fab2_lib.baseboard_fab2(sch_1):\PP2714\"
				( pinRef "@baseboard_fab2_lib.baseboard_fab2(sch_1):page58_i172:DDR1_DQ(2)" )
				( pinRef "@baseboard_fab2_lib.baseboard_fab2(sch_1):page80_i24:DQ(2)" )
				( attribute "RELATIVE_PROPAGATION_DELAY_SCOPE" "G"
					( Parent
						( matchGroupRef "@baseboard_fab2_lib.baseboard_fab2(sch_1):\MG_DQ-DQS_NEAR_DIMM_NG_M_H_BYTE0\" )
					)
					( Status sCSetFlattened )
					( Origin gBackEnd )
				)
				( attribute "RELATIVE_PROPAGATION_DELAY" "0.00 MIL,195.00 MIL"
					( Parent
						( matchGroupRef "@baseboard_fab2_lib.baseboard_fab2(sch_1):\MG_DQ-DQS_NEAR_DIMM_NG_M_H_BYTE0\" )
					)
					( Units "uMatchProp" "ns" 1.000000)
					( Status sCSetFlattened )
					( Origin gBackEnd )
				)
				( attribute "RELATIVE_PROPAGATION_DELAY_SCOPE" "G"
					( Parent
						( matchGroupRef "@baseboard_fab2_lib.baseboard_fab2(sch_1):\MG_DQ_NEAR_DIMM_NG_M_H_BYTE0\" )
					)
					( Status sCSetFlattened )
					( Origin gBackEnd )
				)
				( attribute "RELATIVE_PROPAGATION_DELAY" "-50.00 MIL,50.00 MIL"
					( Parent
						( matchGroupRef "@baseboard_fab2_lib.baseboard_fab2(sch_1):\MG_DQ_NEAR_DIMM_NG_M_H_BYTE0\" )
					)
					( Units "uMatchProp" "ns" 1.000000)
					( Status sCSetFlattened )
					( Origin gBackEnd )
				)
			)
			( pinPair "@baseboard_fab2_lib.baseboard_fab2(sch_1):\PP2716\"
				( pinRef "@baseboard_fab2_lib.baseboard_fab2(sch_1):page58_i172:DDR1_DQ(3)" )
				( pinRef "@baseboard_fab2_lib.baseboard_fab2(sch_1):page79_i111:DQ(2)" )
				( attribute "RELATIVE_PROPAGATION_DELAY_SCOPE" "G"
					( Parent
						( matchGroupRef "@baseboard_fab2_lib.baseboard_fab2(sch_1):\MG_DQ-DQS_FAR_DIMM_NG_M_H_BYTE0\" )
					)
					( Status sCSetFlattened )
					( Origin gBackEnd )
				)
				( attribute "RELATIVE_PROPAGATION_DELAY" "0.00 MIL,195.00 MIL"
					( Parent
						( matchGroupRef "@baseboard_fab2_lib.baseboard_fab2(sch_1):\MG_DQ-DQS_FAR_DIMM_NG_M_H_BYTE0\" )
					)
					( Units "uMatchProp" "ns" 1.000000)
					( Status sCSetFlattened )
					( Origin gBackEnd )
				)
				( attribute "RELATIVE_PROPAGATION_DELAY_SCOPE" "G"
					( Parent
						( matchGroupRef "@baseboard_fab2_lib.baseboard_fab2(sch_1):\MG_DQ_FAR_DIMM_NG_M_H_BYTE0\" )
					)
					( Status sCSetFlattened )
					( Origin gBackEnd )
				)
				( attribute "RELATIVE_PROPAGATION_DELAY" "-50.00 MIL,50.00 MIL"
					( Parent
						( matchGroupRef "@baseboard_fab2_lib.baseboard_fab2(sch_1):\MG_DQ_FAR_DIMM_NG_M_H_BYTE0\" )
					)
					( Units "uMatchProp" "ns" 1.000000)
					( Status sCSetFlattened )
					( Origin gBackEnd )
				)
			)
			( pinPair "@baseboard_fab2_lib.baseboard_fab2(sch_1):\PP2717\"
				( pinRef "@baseboard_fab2_lib.baseboard_fab2(sch_1):page58_i172:DDR1_DQ(3)" )
				( pinRef "@baseboard_fab2_lib.baseboard_fab2(sch_1):page80_i24:DQ(3)" )
				( attribute "RELATIVE_PROPAGATION_DELAY_SCOPE" "G"
					( Parent
						( matchGroupRef "@baseboard_fab2_lib.baseboard_fab2(sch_1):\MG_DQ-DQS_NEAR_DIMM_NG_M_H_BYTE0\" )
					)
					( Status sCSetFlattened )
					( Origin gBackEnd )
				)
				( attribute "RELATIVE_PROPAGATION_DELAY" "0.00 MIL,195.00 MIL"
					( Parent
						( matchGroupRef "@baseboard_fab2_lib.baseboard_fab2(sch_1):\MG_DQ-DQS_NEAR_DIMM_NG_M_H_BYTE0\" )
					)
					( Units "uMatchProp" "ns" 1.000000)
					( Status sCSetFlattened )
					( Origin gBackEnd )
				)
				( attribute "RELATIVE_PROPAGATION_DELAY_SCOPE" "G"
					( Parent
						( matchGroupRef "@baseboard_fab2_lib.baseboard_fab2(sch_1):\MG_DQ_NEAR_DIMM_NG_M_H_BYTE0\" )
					)
					( Status sCSetFlattened )
					( Origin gBackEnd )
				)
				( attribute "RELATIVE_PROPAGATION_DELAY" "-50.00 MIL,50.00 MIL"
					( Parent
						( matchGroupRef "@baseboard_fab2_lib.baseboard_fab2(sch_1):\MG_DQ_NEAR_DIMM_NG_M_H_BYTE0\" )
					)
					( Units "uMatchProp" "ns" 1.000000)
					( Status sCSetFlattened )
					( Origin gBackEnd )
				)
			)
			( pinPair "@baseboard_fab2_lib.baseboard_fab2(sch_1):\PP2719\"
				( pinRef "@baseboard_fab2_lib.baseboard_fab2(sch_1):page58_i172:DDR1_DQ(4)" )
				( pinRef "@baseboard_fab2_lib.baseboard_fab2(sch_1):page79_i111:DQ(5)" )
				( attribute "RELATIVE_PROPAGATION_DELAY_SCOPE" "G"
					( Parent
						( matchGroupRef "@baseboard_fab2_lib.baseboard_fab2(sch_1):\MG_DQ-DQS_FAR_DIMM_NG_M_H_BYTE0\" )
					)
					( Status sCSetFlattened )
					( Origin gBackEnd )
				)
				( attribute "RELATIVE_PROPAGATION_DELAY" "0.00 MIL,195.00 MIL"
					( Parent
						( matchGroupRef "@baseboard_fab2_lib.baseboard_fab2(sch_1):\MG_DQ-DQS_FAR_DIMM_NG_M_H_BYTE0\" )
					)
					( Units "uMatchProp" "ns" 1.000000)
					( Status sCSetFlattened )
					( Origin gBackEnd )
				)
				( attribute "RELATIVE_PROPAGATION_DELAY_SCOPE" "G"
					( Parent
						( matchGroupRef "@baseboard_fab2_lib.baseboard_fab2(sch_1):\MG_DQ_FAR_DIMM_NG_M_H_BYTE0\" )
					)
					( Status sCSetFlattened )
					( Origin gBackEnd )
				)
				( attribute "RELATIVE_PROPAGATION_DELAY" "-50.00 MIL,50.00 MIL"
					( Parent
						( matchGroupRef "@baseboard_fab2_lib.baseboard_fab2(sch_1):\MG_DQ_FAR_DIMM_NG_M_H_BYTE0\" )
					)
					( Units "uMatchProp" "ns" 1.000000)
					( Status sCSetFlattened )
					( Origin gBackEnd )
				)
			)
			( pinPair "@baseboard_fab2_lib.baseboard_fab2(sch_1):\PP2720\"
				( pinRef "@baseboard_fab2_lib.baseboard_fab2(sch_1):page58_i172:DDR1_DQ(4)" )
				( pinRef "@baseboard_fab2_lib.baseboard_fab2(sch_1):page80_i24:DQ(4)" )
				( attribute "RELATIVE_PROPAGATION_DELAY_SCOPE" "G"
					( Parent
						( matchGroupRef "@baseboard_fab2_lib.baseboard_fab2(sch_1):\MG_DQ-DQS_NEAR_DIMM_NG_M_H_BYTE0\" )
					)
					( Status sCSetFlattened )
					( Origin gBackEnd )
				)
				( attribute "RELATIVE_PROPAGATION_DELAY" "0.00 MIL,195.00 MIL"
					( Parent
						( matchGroupRef "@baseboard_fab2_lib.baseboard_fab2(sch_1):\MG_DQ-DQS_NEAR_DIMM_NG_M_H_BYTE0\" )
					)
					( Units "uMatchProp" "ns" 1.000000)
					( Status sCSetFlattened )
					( Origin gBackEnd )
				)
				( attribute "RELATIVE_PROPAGATION_DELAY_SCOPE" "G"
					( Parent
						( matchGroupRef "@baseboard_fab2_lib.baseboard_fab2(sch_1):\MG_DQ_NEAR_DIMM_NG_M_H_BYTE0\" )
					)
					( Status sCSetFlattened )
					( Origin gBackEnd )
				)
				( attribute "RELATIVE_PROPAGATION_DELAY" "-50.00 MIL,50.00 MIL"
					( Parent
						( matchGroupRef "@baseboard_fab2_lib.baseboard_fab2(sch_1):\MG_DQ_NEAR_DIMM_NG_M_H_BYTE0\" )
					)
					( Units "uMatchProp" "ns" 1.000000)
					( Status sCSetFlattened )
					( Origin gBackEnd )
				)
			)
			( pinPair "@baseboard_fab2_lib.baseboard_fab2(sch_1):\PP2722\"
				( pinRef "@baseboard_fab2_lib.baseboard_fab2(sch_1):page58_i172:DDR1_DQ(5)" )
				( pinRef "@baseboard_fab2_lib.baseboard_fab2(sch_1):page79_i111:DQ(4)" )
				( attribute "RELATIVE_PROPAGATION_DELAY_SCOPE" "G"
					( Parent
						( matchGroupRef "@baseboard_fab2_lib.baseboard_fab2(sch_1):\MG_DQ-DQS_FAR_DIMM_NG_M_H_BYTE0\" )
					)
					( Status sCSetFlattened )
					( Origin gBackEnd )
				)
				( attribute "RELATIVE_PROPAGATION_DELAY" "0.00 MIL,195.00 MIL"
					( Parent
						( matchGroupRef "@baseboard_fab2_lib.baseboard_fab2(sch_1):\MG_DQ-DQS_FAR_DIMM_NG_M_H_BYTE0\" )
					)
					( Units "uMatchProp" "ns" 1.000000)
					( Status sCSetFlattened )
					( Origin gBackEnd )
				)
				( attribute "RELATIVE_PROPAGATION_DELAY_SCOPE" "G"
					( Parent
						( matchGroupRef "@baseboard_fab2_lib.baseboard_fab2(sch_1):\MG_DQ_FAR_DIMM_NG_M_H_BYTE0\" )
					)
					( Status sCSetFlattened )
					( Origin gBackEnd )
				)
				( attribute "RELATIVE_PROPAGATION_DELAY" "-50.00 MIL,50.00 MIL"
					( Parent
						( matchGroupRef "@baseboard_fab2_lib.baseboard_fab2(sch_1):\MG_DQ_FAR_DIMM_NG_M_H_BYTE0\" )
					)
					( Units "uMatchProp" "ns" 1.000000)
					( Status sCSetFlattened )
					( Origin gBackEnd )
				)
			)
			( pinPair "@baseboard_fab2_lib.baseboard_fab2(sch_1):\PP2723\"
				( pinRef "@baseboard_fab2_lib.baseboard_fab2(sch_1):page58_i172:DDR1_DQ(5)" )
				( pinRef "@baseboard_fab2_lib.baseboard_fab2(sch_1):page80_i24:DQ(5)" )
				( attribute "RELATIVE_PROPAGATION_DELAY_SCOPE" "G"
					( Parent
						( matchGroupRef "@baseboard_fab2_lib.baseboard_fab2(sch_1):\MG_DQ-DQS_NEAR_DIMM_NG_M_H_BYTE0\" )
					)
					( Status sCSetFlattened )
					( Origin gBackEnd )
				)
				( attribute "RELATIVE_PROPAGATION_DELAY" "0.00 MIL,195.00 MIL"
					( Parent
						( matchGroupRef "@baseboard_fab2_lib.baseboard_fab2(sch_1):\MG_DQ-DQS_NEAR_DIMM_NG_M_H_BYTE0\" )
					)
					( Units "uMatchProp" "ns" 1.000000)
					( Status sCSetFlattened )
					( Origin gBackEnd )
				)
				( attribute "RELATIVE_PROPAGATION_DELAY_SCOPE" "G"
					( Parent
						( matchGroupRef "@baseboard_fab2_lib.baseboard_fab2(sch_1):\MG_DQ_NEAR_DIMM_NG_M_H_BYTE0\" )
					)
					( Status sCSetFlattened )
					( Origin gBackEnd )
				)
				( attribute "RELATIVE_PROPAGATION_DELAY" "-50.00 MIL,50.00 MIL"
					( Parent
						( matchGroupRef "@baseboard_fab2_lib.baseboard_fab2(sch_1):\MG_DQ_NEAR_DIMM_NG_M_H_BYTE0\" )
					)
					( Units "uMatchProp" "ns" 1.000000)
					( Status sCSetFlattened )
					( Origin gBackEnd )
				)
			)
			( pinPair "@baseboard_fab2_lib.baseboard_fab2(sch_1):\PP2725\"
				( pinRef "@baseboard_fab2_lib.baseboard_fab2(sch_1):page58_i172:DDR1_DQ(6)" )
				( pinRef "@baseboard_fab2_lib.baseboard_fab2(sch_1):page79_i111:DQ(7)" )
				( attribute "RELATIVE_PROPAGATION_DELAY_SCOPE" "G"
					( Parent
						( matchGroupRef "@baseboard_fab2_lib.baseboard_fab2(sch_1):\MG_DQ-DQS_FAR_DIMM_NG_M_H_BYTE0\" )
					)
					( Status sCSetFlattened )
					( Origin gBackEnd )
				)
				( attribute "RELATIVE_PROPAGATION_DELAY" "0.00 MIL,195.00 MIL"
					( Parent
						( matchGroupRef "@baseboard_fab2_lib.baseboard_fab2(sch_1):\MG_DQ-DQS_FAR_DIMM_NG_M_H_BYTE0\" )
					)
					( Units "uMatchProp" "ns" 1.000000)
					( Status sCSetFlattened )
					( Origin gBackEnd )
				)
				( attribute "RELATIVE_PROPAGATION_DELAY_SCOPE" "G"
					( Parent
						( matchGroupRef "@baseboard_fab2_lib.baseboard_fab2(sch_1):\MG_DQ_FAR_DIMM_NG_M_H_BYTE0\" )
					)
					( Status sCSetFlattened )
					( Origin gBackEnd )
				)
				( attribute "RELATIVE_PROPAGATION_DELAY" "-50.00 MIL,50.00 MIL"
					( Parent
						( matchGroupRef "@baseboard_fab2_lib.baseboard_fab2(sch_1):\MG_DQ_FAR_DIMM_NG_M_H_BYTE0\" )
					)
					( Units "uMatchProp" "ns" 1.000000)
					( Status sCSetFlattened )
					( Origin gBackEnd )
				)
			)
			( pinPair "@baseboard_fab2_lib.baseboard_fab2(sch_1):\PP2726\"
				( pinRef "@baseboard_fab2_lib.baseboard_fab2(sch_1):page58_i172:DDR1_DQ(6)" )
				( pinRef "@baseboard_fab2_lib.baseboard_fab2(sch_1):page80_i24:DQ(6)" )
				( attribute "RELATIVE_PROPAGATION_DELAY_SCOPE" "G"
					( Parent
						( matchGroupRef "@baseboard_fab2_lib.baseboard_fab2(sch_1):\MG_DQ-DQS_NEAR_DIMM_NG_M_H_BYTE0\" )
					)
					( Status sCSetFlattened )
					( Origin gBackEnd )
				)
				( attribute "RELATIVE_PROPAGATION_DELAY" "0.00 MIL,195.00 MIL"
					( Parent
						( matchGroupRef "@baseboard_fab2_lib.baseboard_fab2(sch_1):\MG_DQ-DQS_NEAR_DIMM_NG_M_H_BYTE0\" )
					)
					( Units "uMatchProp" "ns" 1.000000)
					( Status sCSetFlattened )
					( Origin gBackEnd )
				)
				( attribute "RELATIVE_PROPAGATION_DELAY_SCOPE" "G"
					( Parent
						( matchGroupRef "@baseboard_fab2_lib.baseboard_fab2(sch_1):\MG_DQ_NEAR_DIMM_NG_M_H_BYTE0\" )
					)
					( Status sCSetFlattened )
					( Origin gBackEnd )
				)
				( attribute "RELATIVE_PROPAGATION_DELAY" "-50.00 MIL,50.00 MIL"
					( Parent
						( matchGroupRef "@baseboard_fab2_lib.baseboard_fab2(sch_1):\MG_DQ_NEAR_DIMM_NG_M_H_BYTE0\" )
					)
					( Units "uMatchProp" "ns" 1.000000)
					( Status sCSetFlattened )
					( Origin gBackEnd )
				)
			)
			( pinPair "@baseboard_fab2_lib.baseboard_fab2(sch_1):\PP2728\"
				( pinRef "@baseboard_fab2_lib.baseboard_fab2(sch_1):page58_i172:DDR1_DQ(7)" )
				( pinRef "@baseboard_fab2_lib.baseboard_fab2(sch_1):page79_i111:DQ(6)" )
				( attribute "RELATIVE_PROPAGATION_DELAY_SCOPE" "G"
					( Parent
						( matchGroupRef "@baseboard_fab2_lib.baseboard_fab2(sch_1):\MG_DQ-DQS_FAR_DIMM_NG_M_H_BYTE0\" )
					)
					( Status sCSetFlattened )
					( Origin gBackEnd )
				)
				( attribute "RELATIVE_PROPAGATION_DELAY" "0.00 MIL,195.00 MIL"
					( Parent
						( matchGroupRef "@baseboard_fab2_lib.baseboard_fab2(sch_1):\MG_DQ-DQS_FAR_DIMM_NG_M_H_BYTE0\" )
					)
					( Units "uMatchProp" "ns" 1.000000)
					( Status sCSetFlattened )
					( Origin gBackEnd )
				)
				( attribute "RELATIVE_PROPAGATION_DELAY_SCOPE" "G"
					( Parent
						( matchGroupRef "@baseboard_fab2_lib.baseboard_fab2(sch_1):\MG_DQ_FAR_DIMM_NG_M_H_BYTE0\" )
					)
					( Status sCSetFlattened )
					( Origin gBackEnd )
				)
				( attribute "RELATIVE_PROPAGATION_DELAY" "-50.00 MIL,50.00 MIL"
					( Parent
						( matchGroupRef "@baseboard_fab2_lib.baseboard_fab2(sch_1):\MG_DQ_FAR_DIMM_NG_M_H_BYTE0\" )
					)
					( Units "uMatchProp" "ns" 1.000000)
					( Status sCSetFlattened )
					( Origin gBackEnd )
				)
			)
			( pinPair "@baseboard_fab2_lib.baseboard_fab2(sch_1):\PP2729\"
				( pinRef "@baseboard_fab2_lib.baseboard_fab2(sch_1):page58_i172:DDR1_DQ(7)" )
				( pinRef "@baseboard_fab2_lib.baseboard_fab2(sch_1):page80_i24:DQ(7)" )
				( attribute "RELATIVE_PROPAGATION_DELAY_SCOPE" "G"
					( Parent
						( matchGroupRef "@baseboard_fab2_lib.baseboard_fab2(sch_1):\MG_DQ-DQS_NEAR_DIMM_NG_M_H_BYTE0\" )
					)
					( Status sCSetFlattened )
					( Origin gBackEnd )
				)
				( attribute "RELATIVE_PROPAGATION_DELAY" "0.00 MIL,195.00 MIL"
					( Parent
						( matchGroupRef "@baseboard_fab2_lib.baseboard_fab2(sch_1):\MG_DQ-DQS_NEAR_DIMM_NG_M_H_BYTE0\" )
					)
					( Units "uMatchProp" "ns" 1.000000)
					( Status sCSetFlattened )
					( Origin gBackEnd )
				)
				( attribute "RELATIVE_PROPAGATION_DELAY_SCOPE" "G"
					( Parent
						( matchGroupRef "@baseboard_fab2_lib.baseboard_fab2(sch_1):\MG_DQ_NEAR_DIMM_NG_M_H_BYTE0\" )
					)
					( Status sCSetFlattened )
					( Origin gBackEnd )
				)
				( attribute "RELATIVE_PROPAGATION_DELAY" "-50.00 MIL,50.00 MIL"
					( Parent
						( matchGroupRef "@baseboard_fab2_lib.baseboard_fab2(sch_1):\MG_DQ_NEAR_DIMM_NG_M_H_BYTE0\" )
					)
					( Units "uMatchProp" "ns" 1.000000)
					( Status sCSetFlattened )
					( Origin gBackEnd )
				)
			)
			( pinPair "@baseboard_fab2_lib.baseboard_fab2(sch_1):\PP2683\"
				( pinRef "@baseboard_fab2_lib.baseboard_fab2(sch_1):page58_i172:DDR1_DQ(8)" )
				( pinRef "@baseboard_fab2_lib.baseboard_fab2(sch_1):page79_i111:DQ(9)" )
				( attribute "RELATIVE_PROPAGATION_DELAY_SCOPE" "G"
					( Parent
						( matchGroupRef "@baseboard_fab2_lib.baseboard_fab2(sch_1):\MG_DQ-DQS_FAR_DIMM_NG_M_H_BYTE1\" )
					)
					( Status sCSetFlattened )
					( Origin gBackEnd )
				)
				( attribute "RELATIVE_PROPAGATION_DELAY" "0.00 MIL,195.00 MIL"
					( Parent
						( matchGroupRef "@baseboard_fab2_lib.baseboard_fab2(sch_1):\MG_DQ-DQS_FAR_DIMM_NG_M_H_BYTE1\" )
					)
					( Units "uMatchProp" "ns" 1.000000)
					( Status sCSetFlattened )
					( Origin gBackEnd )
				)
				( attribute "RELATIVE_PROPAGATION_DELAY_SCOPE" "G"
					( Parent
						( matchGroupRef "@baseboard_fab2_lib.baseboard_fab2(sch_1):\MG_DQ_FAR_DIMM_NG_M_H_BYTE1\" )
					)
					( Status sCSetFlattened )
					( Origin gBackEnd )
				)
				( attribute "RELATIVE_PROPAGATION_DELAY" "-50.00 MIL,50.00 MIL"
					( Parent
						( matchGroupRef "@baseboard_fab2_lib.baseboard_fab2(sch_1):\MG_DQ_FAR_DIMM_NG_M_H_BYTE1\" )
					)
					( Units "uMatchProp" "ns" 1.000000)
					( Status sCSetFlattened )
					( Origin gBackEnd )
				)
			)
			( pinPair "@baseboard_fab2_lib.baseboard_fab2(sch_1):\PP2684\"
				( pinRef "@baseboard_fab2_lib.baseboard_fab2(sch_1):page58_i172:DDR1_DQ(8)" )
				( pinRef "@baseboard_fab2_lib.baseboard_fab2(sch_1):page80_i24:DQ(8)" )
				( attribute "RELATIVE_PROPAGATION_DELAY_SCOPE" "G"
					( Parent
						( matchGroupRef "@baseboard_fab2_lib.baseboard_fab2(sch_1):\MG_DQ-DQS_NEAR_DIMM_NG_M_H_BYTE1\" )
					)
					( Status sCSetFlattened )
					( Origin gBackEnd )
				)
				( attribute "RELATIVE_PROPAGATION_DELAY" "0.00 MIL,195.00 MIL"
					( Parent
						( matchGroupRef "@baseboard_fab2_lib.baseboard_fab2(sch_1):\MG_DQ-DQS_NEAR_DIMM_NG_M_H_BYTE1\" )
					)
					( Units "uMatchProp" "ns" 1.000000)
					( Status sCSetFlattened )
					( Origin gBackEnd )
				)
				( attribute "RELATIVE_PROPAGATION_DELAY_SCOPE" "G"
					( Parent
						( matchGroupRef "@baseboard_fab2_lib.baseboard_fab2(sch_1):\MG_DQ_NEAR_DIMM_NG_M_H_BYTE1\" )
					)
					( Status sCSetFlattened )
					( Origin gBackEnd )
				)
				( attribute "RELATIVE_PROPAGATION_DELAY" "-50.00 MIL,50.00 MIL"
					( Parent
						( matchGroupRef "@baseboard_fab2_lib.baseboard_fab2(sch_1):\MG_DQ_NEAR_DIMM_NG_M_H_BYTE1\" )
					)
					( Units "uMatchProp" "ns" 1.000000)
					( Status sCSetFlattened )
					( Origin gBackEnd )
				)
			)
			( pinPair "@baseboard_fab2_lib.baseboard_fab2(sch_1):\PP2686\"
				( pinRef "@baseboard_fab2_lib.baseboard_fab2(sch_1):page58_i172:DDR1_DQ(9)" )
				( pinRef "@baseboard_fab2_lib.baseboard_fab2(sch_1):page79_i111:DQ(8)" )
				( attribute "RELATIVE_PROPAGATION_DELAY_SCOPE" "G"
					( Parent
						( matchGroupRef "@baseboard_fab2_lib.baseboard_fab2(sch_1):\MG_DQ-DQS_FAR_DIMM_NG_M_H_BYTE1\" )
					)
					( Status sCSetFlattened )
					( Origin gBackEnd )
				)
				( attribute "RELATIVE_PROPAGATION_DELAY" "0.00 MIL,195.00 MIL"
					( Parent
						( matchGroupRef "@baseboard_fab2_lib.baseboard_fab2(sch_1):\MG_DQ-DQS_FAR_DIMM_NG_M_H_BYTE1\" )
					)
					( Units "uMatchProp" "ns" 1.000000)
					( Status sCSetFlattened )
					( Origin gBackEnd )
				)
				( attribute "RELATIVE_PROPAGATION_DELAY_SCOPE" "G"
					( Parent
						( matchGroupRef "@baseboard_fab2_lib.baseboard_fab2(sch_1):\MG_DQ_FAR_DIMM_NG_M_H_BYTE1\" )
					)
					( Status sCSetFlattened )
					( Origin gBackEnd )
				)
				( attribute "RELATIVE_PROPAGATION_DELAY" "-50.00 MIL,50.00 MIL"
					( Parent
						( matchGroupRef "@baseboard_fab2_lib.baseboard_fab2(sch_1):\MG_DQ_FAR_DIMM_NG_M_H_BYTE1\" )
					)
					( Units "uMatchProp" "ns" 1.000000)
					( Status sCSetFlattened )
					( Origin gBackEnd )
				)
			)
			( pinPair "@baseboard_fab2_lib.baseboard_fab2(sch_1):\PP2687\"
				( pinRef "@baseboard_fab2_lib.baseboard_fab2(sch_1):page58_i172:DDR1_DQ(9)" )
				( pinRef "@baseboard_fab2_lib.baseboard_fab2(sch_1):page80_i24:DQ(9)" )
				( attribute "RELATIVE_PROPAGATION_DELAY_SCOPE" "G"
					( Parent
						( matchGroupRef "@baseboard_fab2_lib.baseboard_fab2(sch_1):\MG_DQ-DQS_NEAR_DIMM_NG_M_H_BYTE1\" )
					)
					( Status sCSetFlattened )
					( Origin gBackEnd )
				)
				( attribute "RELATIVE_PROPAGATION_DELAY" "0.00 MIL,195.00 MIL"
					( Parent
						( matchGroupRef "@baseboard_fab2_lib.baseboard_fab2(sch_1):\MG_DQ-DQS_NEAR_DIMM_NG_M_H_BYTE1\" )
					)
					( Units "uMatchProp" "ns" 1.000000)
					( Status sCSetFlattened )
					( Origin gBackEnd )
				)
				( attribute "RELATIVE_PROPAGATION_DELAY_SCOPE" "G"
					( Parent
						( matchGroupRef "@baseboard_fab2_lib.baseboard_fab2(sch_1):\MG_DQ_NEAR_DIMM_NG_M_H_BYTE1\" )
					)
					( Status sCSetFlattened )
					( Origin gBackEnd )
				)
				( attribute "RELATIVE_PROPAGATION_DELAY" "-50.00 MIL,50.00 MIL"
					( Parent
						( matchGroupRef "@baseboard_fab2_lib.baseboard_fab2(sch_1):\MG_DQ_NEAR_DIMM_NG_M_H_BYTE1\" )
					)
					( Units "uMatchProp" "ns" 1.000000)
					( Status sCSetFlattened )
					( Origin gBackEnd )
				)
			)
			( pinPair "@baseboard_fab2_lib.baseboard_fab2(sch_1):\PP2689\"
				( pinRef "@baseboard_fab2_lib.baseboard_fab2(sch_1):page58_i172:DDR1_DQ(10)" )
				( pinRef "@baseboard_fab2_lib.baseboard_fab2(sch_1):page79_i111:DQ(11)" )
				( attribute "RELATIVE_PROPAGATION_DELAY_SCOPE" "G"
					( Parent
						( matchGroupRef "@baseboard_fab2_lib.baseboard_fab2(sch_1):\MG_DQ-DQS_FAR_DIMM_NG_M_H_BYTE1\" )
					)
					( Status sCSetFlattened )
					( Origin gBackEnd )
				)
				( attribute "RELATIVE_PROPAGATION_DELAY" "0.00 MIL,195.00 MIL"
					( Parent
						( matchGroupRef "@baseboard_fab2_lib.baseboard_fab2(sch_1):\MG_DQ-DQS_FAR_DIMM_NG_M_H_BYTE1\" )
					)
					( Units "uMatchProp" "ns" 1.000000)
					( Status sCSetFlattened )
					( Origin gBackEnd )
				)
				( attribute "RELATIVE_PROPAGATION_DELAY_SCOPE" "G"
					( Parent
						( matchGroupRef "@baseboard_fab2_lib.baseboard_fab2(sch_1):\MG_DQ_FAR_DIMM_NG_M_H_BYTE1\" )
					)
					( Status sCSetFlattened )
					( Origin gBackEnd )
				)
				( attribute "RELATIVE_PROPAGATION_DELAY" "-50.00 MIL,50.00 MIL"
					( Parent
						( matchGroupRef "@baseboard_fab2_lib.baseboard_fab2(sch_1):\MG_DQ_FAR_DIMM_NG_M_H_BYTE1\" )
					)
					( Units "uMatchProp" "ns" 1.000000)
					( Status sCSetFlattened )
					( Origin gBackEnd )
				)
			)
			( pinPair "@baseboard_fab2_lib.baseboard_fab2(sch_1):\PP2690\"
				( pinRef "@baseboard_fab2_lib.baseboard_fab2(sch_1):page58_i172:DDR1_DQ(10)" )
				( pinRef "@baseboard_fab2_lib.baseboard_fab2(sch_1):page80_i24:DQ(10)" )
				( attribute "RELATIVE_PROPAGATION_DELAY_SCOPE" "G"
					( Parent
						( matchGroupRef "@baseboard_fab2_lib.baseboard_fab2(sch_1):\MG_DQ-DQS_NEAR_DIMM_NG_M_H_BYTE1\" )
					)
					( Status sCSetFlattened )
					( Origin gBackEnd )
				)
				( attribute "RELATIVE_PROPAGATION_DELAY" "0.00 MIL,195.00 MIL"
					( Parent
						( matchGroupRef "@baseboard_fab2_lib.baseboard_fab2(sch_1):\MG_DQ-DQS_NEAR_DIMM_NG_M_H_BYTE1\" )
					)
					( Units "uMatchProp" "ns" 1.000000)
					( Status sCSetFlattened )
					( Origin gBackEnd )
				)
				( attribute "RELATIVE_PROPAGATION_DELAY_SCOPE" "G"
					( Parent
						( matchGroupRef "@baseboard_fab2_lib.baseboard_fab2(sch_1):\MG_DQ_NEAR_DIMM_NG_M_H_BYTE1\" )
					)
					( Status sCSetFlattened )
					( Origin gBackEnd )
				)
				( attribute "RELATIVE_PROPAGATION_DELAY" "-50.00 MIL,50.00 MIL"
					( Parent
						( matchGroupRef "@baseboard_fab2_lib.baseboard_fab2(sch_1):\MG_DQ_NEAR_DIMM_NG_M_H_BYTE1\" )
					)
					( Units "uMatchProp" "ns" 1.000000)
					( Status sCSetFlattened )
					( Origin gBackEnd )
				)
			)
			( pinPair "@baseboard_fab2_lib.baseboard_fab2(sch_1):\PP2692\"
				( pinRef "@baseboard_fab2_lib.baseboard_fab2(sch_1):page58_i172:DDR1_DQ(11)" )
				( pinRef "@baseboard_fab2_lib.baseboard_fab2(sch_1):page79_i111:DQ(10)" )
				( attribute "RELATIVE_PROPAGATION_DELAY_SCOPE" "G"
					( Parent
						( matchGroupRef "@baseboard_fab2_lib.baseboard_fab2(sch_1):\MG_DQ-DQS_FAR_DIMM_NG_M_H_BYTE1\" )
					)
					( Status sCSetFlattened )
					( Origin gBackEnd )
				)
				( attribute "RELATIVE_PROPAGATION_DELAY" "0.00 MIL,195.00 MIL"
					( Parent
						( matchGroupRef "@baseboard_fab2_lib.baseboard_fab2(sch_1):\MG_DQ-DQS_FAR_DIMM_NG_M_H_BYTE1\" )
					)
					( Units "uMatchProp" "ns" 1.000000)
					( Status sCSetFlattened )
					( Origin gBackEnd )
				)
				( attribute "RELATIVE_PROPAGATION_DELAY_SCOPE" "G"
					( Parent
						( matchGroupRef "@baseboard_fab2_lib.baseboard_fab2(sch_1):\MG_DQ_FAR_DIMM_NG_M_H_BYTE1\" )
					)
					( Status sCSetFlattened )
					( Origin gBackEnd )
				)
				( attribute "RELATIVE_PROPAGATION_DELAY" "-50.00 MIL,50.00 MIL"
					( Parent
						( matchGroupRef "@baseboard_fab2_lib.baseboard_fab2(sch_1):\MG_DQ_FAR_DIMM_NG_M_H_BYTE1\" )
					)
					( Units "uMatchProp" "ns" 1.000000)
					( Status sCSetFlattened )
					( Origin gBackEnd )
				)
			)
			( pinPair "@baseboard_fab2_lib.baseboard_fab2(sch_1):\PP2693\"
				( pinRef "@baseboard_fab2_lib.baseboard_fab2(sch_1):page58_i172:DDR1_DQ(11)" )
				( pinRef "@baseboard_fab2_lib.baseboard_fab2(sch_1):page80_i24:DQ(11)" )
				( attribute "RELATIVE_PROPAGATION_DELAY_SCOPE" "G"
					( Parent
						( matchGroupRef "@baseboard_fab2_lib.baseboard_fab2(sch_1):\MG_DQ-DQS_NEAR_DIMM_NG_M_H_BYTE1\" )
					)
					( Status sCSetFlattened )
					( Origin gBackEnd )
				)
				( attribute "RELATIVE_PROPAGATION_DELAY" "0.00 MIL,195.00 MIL"
					( Parent
						( matchGroupRef "@baseboard_fab2_lib.baseboard_fab2(sch_1):\MG_DQ-DQS_NEAR_DIMM_NG_M_H_BYTE1\" )
					)
					( Units "uMatchProp" "ns" 1.000000)
					( Status sCSetFlattened )
					( Origin gBackEnd )
				)
				( attribute "RELATIVE_PROPAGATION_DELAY_SCOPE" "G"
					( Parent
						( matchGroupRef "@baseboard_fab2_lib.baseboard_fab2(sch_1):\MG_DQ_NEAR_DIMM_NG_M_H_BYTE1\" )
					)
					( Status sCSetFlattened )
					( Origin gBackEnd )
				)
				( attribute "RELATIVE_PROPAGATION_DELAY" "-50.00 MIL,50.00 MIL"
					( Parent
						( matchGroupRef "@baseboard_fab2_lib.baseboard_fab2(sch_1):\MG_DQ_NEAR_DIMM_NG_M_H_BYTE1\" )
					)
					( Units "uMatchProp" "ns" 1.000000)
					( Status sCSetFlattened )
					( Origin gBackEnd )
				)
			)
			( pinPair "@baseboard_fab2_lib.baseboard_fab2(sch_1):\PP2695\"
				( pinRef "@baseboard_fab2_lib.baseboard_fab2(sch_1):page58_i172:DDR1_DQ(12)" )
				( pinRef "@baseboard_fab2_lib.baseboard_fab2(sch_1):page79_i111:DQ(13)" )
				( attribute "RELATIVE_PROPAGATION_DELAY_SCOPE" "G"
					( Parent
						( matchGroupRef "@baseboard_fab2_lib.baseboard_fab2(sch_1):\MG_DQ-DQS_FAR_DIMM_NG_M_H_BYTE1\" )
					)
					( Status sCSetFlattened )
					( Origin gBackEnd )
				)
				( attribute "RELATIVE_PROPAGATION_DELAY" "0.00 MIL,195.00 MIL"
					( Parent
						( matchGroupRef "@baseboard_fab2_lib.baseboard_fab2(sch_1):\MG_DQ-DQS_FAR_DIMM_NG_M_H_BYTE1\" )
					)
					( Units "uMatchProp" "ns" 1.000000)
					( Status sCSetFlattened )
					( Origin gBackEnd )
				)
				( attribute "RELATIVE_PROPAGATION_DELAY_SCOPE" "G"
					( Parent
						( matchGroupRef "@baseboard_fab2_lib.baseboard_fab2(sch_1):\MG_DQ_FAR_DIMM_NG_M_H_BYTE1\" )
					)
					( Status sCSetFlattened )
					( Origin gBackEnd )
				)
				( attribute "RELATIVE_PROPAGATION_DELAY" "-50.00 MIL,50.00 MIL"
					( Parent
						( matchGroupRef "@baseboard_fab2_lib.baseboard_fab2(sch_1):\MG_DQ_FAR_DIMM_NG_M_H_BYTE1\" )
					)
					( Units "uMatchProp" "ns" 1.000000)
					( Status sCSetFlattened )
					( Origin gBackEnd )
				)
			)
			( pinPair "@baseboard_fab2_lib.baseboard_fab2(sch_1):\PP2696\"
				( pinRef "@baseboard_fab2_lib.baseboard_fab2(sch_1):page58_i172:DDR1_DQ(12)" )
				( pinRef "@baseboard_fab2_lib.baseboard_fab2(sch_1):page80_i24:DQ(12)" )
				( attribute "RELATIVE_PROPAGATION_DELAY_SCOPE" "G"
					( Parent
						( matchGroupRef "@baseboard_fab2_lib.baseboard_fab2(sch_1):\MG_DQ-DQS_NEAR_DIMM_NG_M_H_BYTE1\" )
					)
					( Status sCSetFlattened )
					( Origin gBackEnd )
				)
				( attribute "RELATIVE_PROPAGATION_DELAY" "0.00 MIL,195.00 MIL"
					( Parent
						( matchGroupRef "@baseboard_fab2_lib.baseboard_fab2(sch_1):\MG_DQ-DQS_NEAR_DIMM_NG_M_H_BYTE1\" )
					)
					( Units "uMatchProp" "ns" 1.000000)
					( Status sCSetFlattened )
					( Origin gBackEnd )
				)
				( attribute "RELATIVE_PROPAGATION_DELAY_SCOPE" "G"
					( Parent
						( matchGroupRef "@baseboard_fab2_lib.baseboard_fab2(sch_1):\MG_DQ_NEAR_DIMM_NG_M_H_BYTE1\" )
					)
					( Status sCSetFlattened )
					( Origin gBackEnd )
				)
				( attribute "RELATIVE_PROPAGATION_DELAY" "-50.00 MIL,50.00 MIL"
					( Parent
						( matchGroupRef "@baseboard_fab2_lib.baseboard_fab2(sch_1):\MG_DQ_NEAR_DIMM_NG_M_H_BYTE1\" )
					)
					( Units "uMatchProp" "ns" 1.000000)
					( Status sCSetFlattened )
					( Origin gBackEnd )
				)
			)
			( pinPair "@baseboard_fab2_lib.baseboard_fab2(sch_1):\PP2662\"
				( pinRef "@baseboard_fab2_lib.baseboard_fab2(sch_1):page58_i172:DDR1_DQ(17)" )
				( pinRef "@baseboard_fab2_lib.baseboard_fab2(sch_1):page79_i111:DQ(16)" )
				( attribute "RELATIVE_PROPAGATION_DELAY_SCOPE" "G"
					( Parent
						( matchGroupRef "@baseboard_fab2_lib.baseboard_fab2(sch_1):\MG_DQ-DQS_FAR_DIMM_NG_M_H_BYTE2\" )
					)
					( Status sCSetFlattened )
					( Origin gBackEnd )
				)
				( attribute "RELATIVE_PROPAGATION_DELAY" "0.00 MIL,195.00 MIL"
					( Parent
						( matchGroupRef "@baseboard_fab2_lib.baseboard_fab2(sch_1):\MG_DQ-DQS_FAR_DIMM_NG_M_H_BYTE2\" )
					)
					( Units "uMatchProp" "ns" 1.000000)
					( Status sCSetFlattened )
					( Origin gBackEnd )
				)
				( attribute "RELATIVE_PROPAGATION_DELAY_SCOPE" "G"
					( Parent
						( matchGroupRef "@baseboard_fab2_lib.baseboard_fab2(sch_1):\MG_DQ_FAR_DIMM_NG_M_H_BYTE2\" )
					)
					( Status sCSetFlattened )
					( Origin gBackEnd )
				)
				( attribute "RELATIVE_PROPAGATION_DELAY" "-50.00 MIL,50.00 MIL"
					( Parent
						( matchGroupRef "@baseboard_fab2_lib.baseboard_fab2(sch_1):\MG_DQ_FAR_DIMM_NG_M_H_BYTE2\" )
					)
					( Units "uMatchProp" "ns" 1.000000)
					( Status sCSetFlattened )
					( Origin gBackEnd )
				)
			)
			( pinPair "@baseboard_fab2_lib.baseboard_fab2(sch_1):\PP2663\"
				( pinRef "@baseboard_fab2_lib.baseboard_fab2(sch_1):page58_i172:DDR1_DQ(17)" )
				( pinRef "@baseboard_fab2_lib.baseboard_fab2(sch_1):page80_i24:DQ(17)" )
				( attribute "RELATIVE_PROPAGATION_DELAY_SCOPE" "G"
					( Parent
						( matchGroupRef "@baseboard_fab2_lib.baseboard_fab2(sch_1):\MG_DQ-DQS_NEAR_DIMM_NG_M_H_BYTE2\" )
					)
					( Status sCSetFlattened )
					( Origin gBackEnd )
				)
				( attribute "RELATIVE_PROPAGATION_DELAY" "0.00 MIL,195.00 MIL"
					( Parent
						( matchGroupRef "@baseboard_fab2_lib.baseboard_fab2(sch_1):\MG_DQ-DQS_NEAR_DIMM_NG_M_H_BYTE2\" )
					)
					( Units "uMatchProp" "ns" 1.000000)
					( Status sCSetFlattened )
					( Origin gBackEnd )
				)
				( attribute "RELATIVE_PROPAGATION_DELAY_SCOPE" "G"
					( Parent
						( matchGroupRef "@baseboard_fab2_lib.baseboard_fab2(sch_1):\MG_DQ_NEAR_DIMM_NG_M_H_BYTE2\" )
					)
					( Status sCSetFlattened )
					( Origin gBackEnd )
				)
				( attribute "RELATIVE_PROPAGATION_DELAY" "-50.00 MIL,50.00 MIL"
					( Parent
						( matchGroupRef "@baseboard_fab2_lib.baseboard_fab2(sch_1):\MG_DQ_NEAR_DIMM_NG_M_H_BYTE2\" )
					)
					( Units "uMatchProp" "ns" 1.000000)
					( Status sCSetFlattened )
					( Origin gBackEnd )
				)
			)
			( pinPair "@baseboard_fab2_lib.baseboard_fab2(sch_1):\PP2665\"
				( pinRef "@baseboard_fab2_lib.baseboard_fab2(sch_1):page58_i172:DDR1_DQ(18)" )
				( pinRef "@baseboard_fab2_lib.baseboard_fab2(sch_1):page79_i111:DQ(19)" )
				( attribute "RELATIVE_PROPAGATION_DELAY_SCOPE" "G"
					( Parent
						( matchGroupRef "@baseboard_fab2_lib.baseboard_fab2(sch_1):\MG_DQ-DQS_FAR_DIMM_NG_M_H_BYTE2\" )
					)
					( Status sCSetFlattened )
					( Origin gBackEnd )
				)
				( attribute "RELATIVE_PROPAGATION_DELAY" "0.00 MIL,195.00 MIL"
					( Parent
						( matchGroupRef "@baseboard_fab2_lib.baseboard_fab2(sch_1):\MG_DQ-DQS_FAR_DIMM_NG_M_H_BYTE2\" )
					)
					( Units "uMatchProp" "ns" 1.000000)
					( Status sCSetFlattened )
					( Origin gBackEnd )
				)
				( attribute "RELATIVE_PROPAGATION_DELAY_SCOPE" "G"
					( Parent
						( matchGroupRef "@baseboard_fab2_lib.baseboard_fab2(sch_1):\MG_DQ_FAR_DIMM_NG_M_H_BYTE2\" )
					)
					( Status sCSetFlattened )
					( Origin gBackEnd )
				)
				( attribute "RELATIVE_PROPAGATION_DELAY" "-50.00 MIL,50.00 MIL"
					( Parent
						( matchGroupRef "@baseboard_fab2_lib.baseboard_fab2(sch_1):\MG_DQ_FAR_DIMM_NG_M_H_BYTE2\" )
					)
					( Units "uMatchProp" "ns" 1.000000)
					( Status sCSetFlattened )
					( Origin gBackEnd )
				)
			)
			( pinPair "@baseboard_fab2_lib.baseboard_fab2(sch_1):\PP2666\"
				( pinRef "@baseboard_fab2_lib.baseboard_fab2(sch_1):page58_i172:DDR1_DQ(18)" )
				( pinRef "@baseboard_fab2_lib.baseboard_fab2(sch_1):page80_i24:DQ(18)" )
				( attribute "RELATIVE_PROPAGATION_DELAY_SCOPE" "G"
					( Parent
						( matchGroupRef "@baseboard_fab2_lib.baseboard_fab2(sch_1):\MG_DQ-DQS_NEAR_DIMM_NG_M_H_BYTE2\" )
					)
					( Status sCSetFlattened )
					( Origin gBackEnd )
				)
				( attribute "RELATIVE_PROPAGATION_DELAY" "0.00 MIL,195.00 MIL"
					( Parent
						( matchGroupRef "@baseboard_fab2_lib.baseboard_fab2(sch_1):\MG_DQ-DQS_NEAR_DIMM_NG_M_H_BYTE2\" )
					)
					( Units "uMatchProp" "ns" 1.000000)
					( Status sCSetFlattened )
					( Origin gBackEnd )
				)
				( attribute "RELATIVE_PROPAGATION_DELAY_SCOPE" "G"
					( Parent
						( matchGroupRef "@baseboard_fab2_lib.baseboard_fab2(sch_1):\MG_DQ_NEAR_DIMM_NG_M_H_BYTE2\" )
					)
					( Status sCSetFlattened )
					( Origin gBackEnd )
				)
				( attribute "RELATIVE_PROPAGATION_DELAY" "-50.00 MIL,50.00 MIL"
					( Parent
						( matchGroupRef "@baseboard_fab2_lib.baseboard_fab2(sch_1):\MG_DQ_NEAR_DIMM_NG_M_H_BYTE2\" )
					)
					( Units "uMatchProp" "ns" 1.000000)
					( Status sCSetFlattened )
					( Origin gBackEnd )
				)
			)
			( pinPair "@baseboard_fab2_lib.baseboard_fab2(sch_1):\PP2668\"
				( pinRef "@baseboard_fab2_lib.baseboard_fab2(sch_1):page58_i172:DDR1_DQ(19)" )
				( pinRef "@baseboard_fab2_lib.baseboard_fab2(sch_1):page79_i111:DQ(18)" )
				( attribute "RELATIVE_PROPAGATION_DELAY_SCOPE" "G"
					( Parent
						( matchGroupRef "@baseboard_fab2_lib.baseboard_fab2(sch_1):\MG_DQ-DQS_FAR_DIMM_NG_M_H_BYTE2\" )
					)
					( Status sCSetFlattened )
					( Origin gBackEnd )
				)
				( attribute "RELATIVE_PROPAGATION_DELAY" "0.00 MIL,195.00 MIL"
					( Parent
						( matchGroupRef "@baseboard_fab2_lib.baseboard_fab2(sch_1):\MG_DQ-DQS_FAR_DIMM_NG_M_H_BYTE2\" )
					)
					( Units "uMatchProp" "ns" 1.000000)
					( Status sCSetFlattened )
					( Origin gBackEnd )
				)
				( attribute "RELATIVE_PROPAGATION_DELAY_SCOPE" "G"
					( Parent
						( matchGroupRef "@baseboard_fab2_lib.baseboard_fab2(sch_1):\MG_DQ_FAR_DIMM_NG_M_H_BYTE2\" )
					)
					( Status sCSetFlattened )
					( Origin gBackEnd )
				)
				( attribute "RELATIVE_PROPAGATION_DELAY" "-50.00 MIL,50.00 MIL"
					( Parent
						( matchGroupRef "@baseboard_fab2_lib.baseboard_fab2(sch_1):\MG_DQ_FAR_DIMM_NG_M_H_BYTE2\" )
					)
					( Units "uMatchProp" "ns" 1.000000)
					( Status sCSetFlattened )
					( Origin gBackEnd )
				)
			)
			( pinPair "@baseboard_fab2_lib.baseboard_fab2(sch_1):\PP2669\"
				( pinRef "@baseboard_fab2_lib.baseboard_fab2(sch_1):page58_i172:DDR1_DQ(19)" )
				( pinRef "@baseboard_fab2_lib.baseboard_fab2(sch_1):page80_i24:DQ(19)" )
				( attribute "RELATIVE_PROPAGATION_DELAY_SCOPE" "G"
					( Parent
						( matchGroupRef "@baseboard_fab2_lib.baseboard_fab2(sch_1):\MG_DQ-DQS_NEAR_DIMM_NG_M_H_BYTE2\" )
					)
					( Status sCSetFlattened )
					( Origin gBackEnd )
				)
				( attribute "RELATIVE_PROPAGATION_DELAY" "0.00 MIL,195.00 MIL"
					( Parent
						( matchGroupRef "@baseboard_fab2_lib.baseboard_fab2(sch_1):\MG_DQ-DQS_NEAR_DIMM_NG_M_H_BYTE2\" )
					)
					( Units "uMatchProp" "ns" 1.000000)
					( Status sCSetFlattened )
					( Origin gBackEnd )
				)
				( attribute "RELATIVE_PROPAGATION_DELAY_SCOPE" "G"
					( Parent
						( matchGroupRef "@baseboard_fab2_lib.baseboard_fab2(sch_1):\MG_DQ_NEAR_DIMM_NG_M_H_BYTE2\" )
					)
					( Status sCSetFlattened )
					( Origin gBackEnd )
				)
				( attribute "RELATIVE_PROPAGATION_DELAY" "-50.00 MIL,50.00 MIL"
					( Parent
						( matchGroupRef "@baseboard_fab2_lib.baseboard_fab2(sch_1):\MG_DQ_NEAR_DIMM_NG_M_H_BYTE2\" )
					)
					( Units "uMatchProp" "ns" 1.000000)
					( Status sCSetFlattened )
					( Origin gBackEnd )
				)
			)
			( pinPair "@baseboard_fab2_lib.baseboard_fab2(sch_1):\PP2671\"
				( pinRef "@baseboard_fab2_lib.baseboard_fab2(sch_1):page58_i172:DDR1_DQ(20)" )
				( pinRef "@baseboard_fab2_lib.baseboard_fab2(sch_1):page79_i111:DQ(21)" )
				( attribute "RELATIVE_PROPAGATION_DELAY_SCOPE" "G"
					( Parent
						( matchGroupRef "@baseboard_fab2_lib.baseboard_fab2(sch_1):\MG_DQ-DQS_FAR_DIMM_NG_M_H_BYTE2\" )
					)
					( Status sCSetFlattened )
					( Origin gBackEnd )
				)
				( attribute "RELATIVE_PROPAGATION_DELAY" "0.00 MIL,195.00 MIL"
					( Parent
						( matchGroupRef "@baseboard_fab2_lib.baseboard_fab2(sch_1):\MG_DQ-DQS_FAR_DIMM_NG_M_H_BYTE2\" )
					)
					( Units "uMatchProp" "ns" 1.000000)
					( Status sCSetFlattened )
					( Origin gBackEnd )
				)
				( attribute "RELATIVE_PROPAGATION_DELAY_SCOPE" "G"
					( Parent
						( matchGroupRef "@baseboard_fab2_lib.baseboard_fab2(sch_1):\MG_DQ_FAR_DIMM_NG_M_H_BYTE2\" )
					)
					( Status sCSetFlattened )
					( Origin gBackEnd )
				)
				( attribute "RELATIVE_PROPAGATION_DELAY" "-50.00 MIL,50.00 MIL"
					( Parent
						( matchGroupRef "@baseboard_fab2_lib.baseboard_fab2(sch_1):\MG_DQ_FAR_DIMM_NG_M_H_BYTE2\" )
					)
					( Units "uMatchProp" "ns" 1.000000)
					( Status sCSetFlattened )
					( Origin gBackEnd )
				)
			)
			( pinPair "@baseboard_fab2_lib.baseboard_fab2(sch_1):\PP2672\"
				( pinRef "@baseboard_fab2_lib.baseboard_fab2(sch_1):page58_i172:DDR1_DQ(20)" )
				( pinRef "@baseboard_fab2_lib.baseboard_fab2(sch_1):page80_i24:DQ(20)" )
				( attribute "RELATIVE_PROPAGATION_DELAY_SCOPE" "G"
					( Parent
						( matchGroupRef "@baseboard_fab2_lib.baseboard_fab2(sch_1):\MG_DQ-DQS_NEAR_DIMM_NG_M_H_BYTE2\" )
					)
					( Status sCSetFlattened )
					( Origin gBackEnd )
				)
				( attribute "RELATIVE_PROPAGATION_DELAY" "0.00 MIL,195.00 MIL"
					( Parent
						( matchGroupRef "@baseboard_fab2_lib.baseboard_fab2(sch_1):\MG_DQ-DQS_NEAR_DIMM_NG_M_H_BYTE2\" )
					)
					( Units "uMatchProp" "ns" 1.000000)
					( Status sCSetFlattened )
					( Origin gBackEnd )
				)
				( attribute "RELATIVE_PROPAGATION_DELAY_SCOPE" "G"
					( Parent
						( matchGroupRef "@baseboard_fab2_lib.baseboard_fab2(sch_1):\MG_DQ_NEAR_DIMM_NG_M_H_BYTE2\" )
					)
					( Status sCSetFlattened )
					( Origin gBackEnd )
				)
				( attribute "RELATIVE_PROPAGATION_DELAY" "-50.00 MIL,50.00 MIL"
					( Parent
						( matchGroupRef "@baseboard_fab2_lib.baseboard_fab2(sch_1):\MG_DQ_NEAR_DIMM_NG_M_H_BYTE2\" )
					)
					( Units "uMatchProp" "ns" 1.000000)
					( Status sCSetFlattened )
					( Origin gBackEnd )
				)
			)
			( pinPair "@baseboard_fab2_lib.baseboard_fab2(sch_1):\PP2674\"
				( pinRef "@baseboard_fab2_lib.baseboard_fab2(sch_1):page58_i172:DDR1_DQ(21)" )
				( pinRef "@baseboard_fab2_lib.baseboard_fab2(sch_1):page79_i111:DQ(20)" )
				( attribute "RELATIVE_PROPAGATION_DELAY_SCOPE" "G"
					( Parent
						( matchGroupRef "@baseboard_fab2_lib.baseboard_fab2(sch_1):\MG_DQ-DQS_FAR_DIMM_NG_M_H_BYTE2\" )
					)
					( Status sCSetFlattened )
					( Origin gBackEnd )
				)
				( attribute "RELATIVE_PROPAGATION_DELAY" "0.00 MIL,195.00 MIL"
					( Parent
						( matchGroupRef "@baseboard_fab2_lib.baseboard_fab2(sch_1):\MG_DQ-DQS_FAR_DIMM_NG_M_H_BYTE2\" )
					)
					( Units "uMatchProp" "ns" 1.000000)
					( Status sCSetFlattened )
					( Origin gBackEnd )
				)
				( attribute "RELATIVE_PROPAGATION_DELAY_SCOPE" "G"
					( Parent
						( matchGroupRef "@baseboard_fab2_lib.baseboard_fab2(sch_1):\MG_DQ_FAR_DIMM_NG_M_H_BYTE2\" )
					)
					( Status sCSetFlattened )
					( Origin gBackEnd )
				)
				( attribute "RELATIVE_PROPAGATION_DELAY" "-50.00 MIL,50.00 MIL"
					( Parent
						( matchGroupRef "@baseboard_fab2_lib.baseboard_fab2(sch_1):\MG_DQ_FAR_DIMM_NG_M_H_BYTE2\" )
					)
					( Units "uMatchProp" "ns" 1.000000)
					( Status sCSetFlattened )
					( Origin gBackEnd )
				)
			)
			( pinPair "@baseboard_fab2_lib.baseboard_fab2(sch_1):\PP2675\"
				( pinRef "@baseboard_fab2_lib.baseboard_fab2(sch_1):page58_i172:DDR1_DQ(21)" )
				( pinRef "@baseboard_fab2_lib.baseboard_fab2(sch_1):page80_i24:DQ(21)" )
				( attribute "RELATIVE_PROPAGATION_DELAY_SCOPE" "G"
					( Parent
						( matchGroupRef "@baseboard_fab2_lib.baseboard_fab2(sch_1):\MG_DQ-DQS_NEAR_DIMM_NG_M_H_BYTE2\" )
					)
					( Status sCSetFlattened )
					( Origin gBackEnd )
				)
				( attribute "RELATIVE_PROPAGATION_DELAY" "0.00 MIL,195.00 MIL"
					( Parent
						( matchGroupRef "@baseboard_fab2_lib.baseboard_fab2(sch_1):\MG_DQ-DQS_NEAR_DIMM_NG_M_H_BYTE2\" )
					)
					( Units "uMatchProp" "ns" 1.000000)
					( Status sCSetFlattened )
					( Origin gBackEnd )
				)
				( attribute "RELATIVE_PROPAGATION_DELAY_SCOPE" "G"
					( Parent
						( matchGroupRef "@baseboard_fab2_lib.baseboard_fab2(sch_1):\MG_DQ_NEAR_DIMM_NG_M_H_BYTE2\" )
					)
					( Status sCSetFlattened )
					( Origin gBackEnd )
				)
				( attribute "RELATIVE_PROPAGATION_DELAY" "-50.00 MIL,50.00 MIL"
					( Parent
						( matchGroupRef "@baseboard_fab2_lib.baseboard_fab2(sch_1):\MG_DQ_NEAR_DIMM_NG_M_H_BYTE2\" )
					)
					( Units "uMatchProp" "ns" 1.000000)
					( Status sCSetFlattened )
					( Origin gBackEnd )
				)
			)
			( pinPair "@baseboard_fab2_lib.baseboard_fab2(sch_1):\PP2677\"
				( pinRef "@baseboard_fab2_lib.baseboard_fab2(sch_1):page58_i172:DDR1_DQ(22)" )
				( pinRef "@baseboard_fab2_lib.baseboard_fab2(sch_1):page79_i111:DQ(23)" )
				( attribute "RELATIVE_PROPAGATION_DELAY_SCOPE" "G"
					( Parent
						( matchGroupRef "@baseboard_fab2_lib.baseboard_fab2(sch_1):\MG_DQ-DQS_FAR_DIMM_NG_M_H_BYTE2\" )
					)
					( Status sCSetFlattened )
					( Origin gBackEnd )
				)
				( attribute "RELATIVE_PROPAGATION_DELAY" "0.00 MIL,195.00 MIL"
					( Parent
						( matchGroupRef "@baseboard_fab2_lib.baseboard_fab2(sch_1):\MG_DQ-DQS_FAR_DIMM_NG_M_H_BYTE2\" )
					)
					( Units "uMatchProp" "ns" 1.000000)
					( Status sCSetFlattened )
					( Origin gBackEnd )
				)
				( attribute "RELATIVE_PROPAGATION_DELAY_SCOPE" "G"
					( Parent
						( matchGroupRef "@baseboard_fab2_lib.baseboard_fab2(sch_1):\MG_DQ_FAR_DIMM_NG_M_H_BYTE2\" )
					)
					( Status sCSetFlattened )
					( Origin gBackEnd )
				)
				( attribute "RELATIVE_PROPAGATION_DELAY" "-50.00 MIL,50.00 MIL"
					( Parent
						( matchGroupRef "@baseboard_fab2_lib.baseboard_fab2(sch_1):\MG_DQ_FAR_DIMM_NG_M_H_BYTE2\" )
					)
					( Units "uMatchProp" "ns" 1.000000)
					( Status sCSetFlattened )
					( Origin gBackEnd )
				)
			)
			( pinPair "@baseboard_fab2_lib.baseboard_fab2(sch_1):\PP2678\"
				( pinRef "@baseboard_fab2_lib.baseboard_fab2(sch_1):page58_i172:DDR1_DQ(22)" )
				( pinRef "@baseboard_fab2_lib.baseboard_fab2(sch_1):page80_i24:DQ(22)" )
				( attribute "RELATIVE_PROPAGATION_DELAY_SCOPE" "G"
					( Parent
						( matchGroupRef "@baseboard_fab2_lib.baseboard_fab2(sch_1):\MG_DQ-DQS_NEAR_DIMM_NG_M_H_BYTE2\" )
					)
					( Status sCSetFlattened )
					( Origin gBackEnd )
				)
				( attribute "RELATIVE_PROPAGATION_DELAY" "0.00 MIL,195.00 MIL"
					( Parent
						( matchGroupRef "@baseboard_fab2_lib.baseboard_fab2(sch_1):\MG_DQ-DQS_NEAR_DIMM_NG_M_H_BYTE2\" )
					)
					( Units "uMatchProp" "ns" 1.000000)
					( Status sCSetFlattened )
					( Origin gBackEnd )
				)
				( attribute "RELATIVE_PROPAGATION_DELAY_SCOPE" "G"
					( Parent
						( matchGroupRef "@baseboard_fab2_lib.baseboard_fab2(sch_1):\MG_DQ_NEAR_DIMM_NG_M_H_BYTE2\" )
					)
					( Status sCSetFlattened )
					( Origin gBackEnd )
				)
				( attribute "RELATIVE_PROPAGATION_DELAY" "-50.00 MIL,50.00 MIL"
					( Parent
						( matchGroupRef "@baseboard_fab2_lib.baseboard_fab2(sch_1):\MG_DQ_NEAR_DIMM_NG_M_H_BYTE2\" )
					)
					( Units "uMatchProp" "ns" 1.000000)
					( Status sCSetFlattened )
					( Origin gBackEnd )
				)
			)
			( pinPair "@baseboard_fab2_lib.baseboard_fab2(sch_1):\PP2680\"
				( pinRef "@baseboard_fab2_lib.baseboard_fab2(sch_1):page58_i172:DDR1_DQ(23)" )
				( pinRef "@baseboard_fab2_lib.baseboard_fab2(sch_1):page79_i111:DQ(22)" )
				( attribute "RELATIVE_PROPAGATION_DELAY_SCOPE" "G"
					( Parent
						( matchGroupRef "@baseboard_fab2_lib.baseboard_fab2(sch_1):\MG_DQ-DQS_FAR_DIMM_NG_M_H_BYTE2\" )
					)
					( Status sCSetFlattened )
					( Origin gBackEnd )
				)
				( attribute "RELATIVE_PROPAGATION_DELAY" "0.00 MIL,195.00 MIL"
					( Parent
						( matchGroupRef "@baseboard_fab2_lib.baseboard_fab2(sch_1):\MG_DQ-DQS_FAR_DIMM_NG_M_H_BYTE2\" )
					)
					( Units "uMatchProp" "ns" 1.000000)
					( Status sCSetFlattened )
					( Origin gBackEnd )
				)
				( attribute "RELATIVE_PROPAGATION_DELAY_SCOPE" "G"
					( Parent
						( matchGroupRef "@baseboard_fab2_lib.baseboard_fab2(sch_1):\MG_DQ_FAR_DIMM_NG_M_H_BYTE2\" )
					)
					( Status sCSetFlattened )
					( Origin gBackEnd )
				)
				( attribute "RELATIVE_PROPAGATION_DELAY" "-50.00 MIL,50.00 MIL"
					( Parent
						( matchGroupRef "@baseboard_fab2_lib.baseboard_fab2(sch_1):\MG_DQ_FAR_DIMM_NG_M_H_BYTE2\" )
					)
					( Units "uMatchProp" "ns" 1.000000)
					( Status sCSetFlattened )
					( Origin gBackEnd )
				)
			)
			( pinPair "@baseboard_fab2_lib.baseboard_fab2(sch_1):\PP2681\"
				( pinRef "@baseboard_fab2_lib.baseboard_fab2(sch_1):page58_i172:DDR1_DQ(23)" )
				( pinRef "@baseboard_fab2_lib.baseboard_fab2(sch_1):page80_i24:DQ(23)" )
				( attribute "RELATIVE_PROPAGATION_DELAY_SCOPE" "G"
					( Parent
						( matchGroupRef "@baseboard_fab2_lib.baseboard_fab2(sch_1):\MG_DQ-DQS_NEAR_DIMM_NG_M_H_BYTE2\" )
					)
					( Status sCSetFlattened )
					( Origin gBackEnd )
				)
				( attribute "RELATIVE_PROPAGATION_DELAY" "0.00 MIL,195.00 MIL"
					( Parent
						( matchGroupRef "@baseboard_fab2_lib.baseboard_fab2(sch_1):\MG_DQ-DQS_NEAR_DIMM_NG_M_H_BYTE2\" )
					)
					( Units "uMatchProp" "ns" 1.000000)
					( Status sCSetFlattened )
					( Origin gBackEnd )
				)
				( attribute "RELATIVE_PROPAGATION_DELAY_SCOPE" "G"
					( Parent
						( matchGroupRef "@baseboard_fab2_lib.baseboard_fab2(sch_1):\MG_DQ_NEAR_DIMM_NG_M_H_BYTE2\" )
					)
					( Status sCSetFlattened )
					( Origin gBackEnd )
				)
				( attribute "RELATIVE_PROPAGATION_DELAY" "-50.00 MIL,50.00 MIL"
					( Parent
						( matchGroupRef "@baseboard_fab2_lib.baseboard_fab2(sch_1):\MG_DQ_NEAR_DIMM_NG_M_H_BYTE2\" )
					)
					( Units "uMatchProp" "ns" 1.000000)
					( Status sCSetFlattened )
					( Origin gBackEnd )
				)
			)
			( pinPair "@baseboard_fab2_lib.baseboard_fab2(sch_1):\PP2635\"
				( pinRef "@baseboard_fab2_lib.baseboard_fab2(sch_1):page58_i172:DDR1_DQ(24)" )
				( pinRef "@baseboard_fab2_lib.baseboard_fab2(sch_1):page79_i111:DQ(25)" )
				( attribute "RELATIVE_PROPAGATION_DELAY_SCOPE" "G"
					( Parent
						( matchGroupRef "@baseboard_fab2_lib.baseboard_fab2(sch_1):\MG_DQ-DQS_FAR_DIMM_NG_M_H_BYTE3\" )
					)
					( Status sCSetFlattened )
					( Origin gBackEnd )
				)
				( attribute "RELATIVE_PROPAGATION_DELAY" "0.00 MIL,195.00 MIL"
					( Parent
						( matchGroupRef "@baseboard_fab2_lib.baseboard_fab2(sch_1):\MG_DQ-DQS_FAR_DIMM_NG_M_H_BYTE3\" )
					)
					( Units "uMatchProp" "ns" 1.000000)
					( Status sCSetFlattened )
					( Origin gBackEnd )
				)
				( attribute "RELATIVE_PROPAGATION_DELAY_SCOPE" "G"
					( Parent
						( matchGroupRef "@crescent_city_bb_fab1_lib.crescent_city_bb_fab1(sch_1):\MG_DQ_FAR_DIMM_NG_M_H_BYTE3\" )
					)
					( Origin gBackEnd )
				)
				( attribute "RELATIVE_PROPAGATION_DELAY" "-52.12 MIL,50.00 MIL"
					( Parent
						( matchGroupRef "@crescent_city_bb_fab1_lib.crescent_city_bb_fab1(sch_1):\MG_DQ_FAR_DIMM_NG_M_H_BYTE3\" )
					)
					( Units "uMatchProp" "ns" 1.000000)
					( Origin gBackEnd )
				)
			)
			( pinPair "@baseboard_fab2_lib.baseboard_fab2(sch_1):\PP2636\"
				( pinRef "@baseboard_fab2_lib.baseboard_fab2(sch_1):page58_i172:DDR1_DQ(24)" )
				( pinRef "@baseboard_fab2_lib.baseboard_fab2(sch_1):page80_i24:DQ(24)" )
				( attribute "RELATIVE_PROPAGATION_DELAY_SCOPE" "G"
					( Parent
						( matchGroupRef "@baseboard_fab2_lib.baseboard_fab2(sch_1):\MG_DQ-DQS_NEAR_DIMM_NG_M_H_BYTE3\" )
					)
					( Status sCSetFlattened )
					( Origin gBackEnd )
				)
				( attribute "RELATIVE_PROPAGATION_DELAY" "0.00 MIL,195.00 MIL"
					( Parent
						( matchGroupRef "@baseboard_fab2_lib.baseboard_fab2(sch_1):\MG_DQ-DQS_NEAR_DIMM_NG_M_H_BYTE3\" )
					)
					( Units "uMatchProp" "ns" 1.000000)
					( Status sCSetFlattened )
					( Origin gBackEnd )
				)
				( attribute "RELATIVE_PROPAGATION_DELAY_SCOPE" "G"
					( Parent
						( matchGroupRef "@crescent_city_bb_fab1_lib.crescent_city_bb_fab1(sch_1):\MG_DQ_NEAR_DIMM_NG_M_H_BYTE3\" )
					)
					( Origin gBackEnd )
				)
				( attribute "RELATIVE_PROPAGATION_DELAY" "-52.12 MIL,50.00 MIL"
					( Parent
						( matchGroupRef "@crescent_city_bb_fab1_lib.crescent_city_bb_fab1(sch_1):\MG_DQ_NEAR_DIMM_NG_M_H_BYTE3\" )
					)
					( Units "uMatchProp" "ns" 1.000000)
					( Origin gBackEnd )
				)
			)
			( pinPair "@baseboard_fab2_lib.baseboard_fab2(sch_1):\PP2638\"
				( pinRef "@baseboard_fab2_lib.baseboard_fab2(sch_1):page58_i172:DDR1_DQ(25)" )
				( pinRef "@baseboard_fab2_lib.baseboard_fab2(sch_1):page79_i111:DQ(24)" )
				( attribute "RELATIVE_PROPAGATION_DELAY_SCOPE" "G"
					( Parent
						( matchGroupRef "@baseboard_fab2_lib.baseboard_fab2(sch_1):\MG_DQ-DQS_FAR_DIMM_NG_M_H_BYTE3\" )
					)
					( Status sCSetFlattened )
					( Origin gBackEnd )
				)
				( attribute "RELATIVE_PROPAGATION_DELAY" "0.00 MIL,195.00 MIL"
					( Parent
						( matchGroupRef "@baseboard_fab2_lib.baseboard_fab2(sch_1):\MG_DQ-DQS_FAR_DIMM_NG_M_H_BYTE3\" )
					)
					( Units "uMatchProp" "ns" 1.000000)
					( Status sCSetFlattened )
					( Origin gBackEnd )
				)
				( attribute "RELATIVE_PROPAGATION_DELAY_SCOPE" "G"
					( Parent
						( matchGroupRef "@crescent_city_bb_fab1_lib.crescent_city_bb_fab1(sch_1):\MG_DQ_FAR_DIMM_NG_M_H_BYTE3\" )
					)
					( Origin gBackEnd )
				)
				( attribute "RELATIVE_PROPAGATION_DELAY" "-50.86 MIL,50.00 MIL"
					( Parent
						( matchGroupRef "@crescent_city_bb_fab1_lib.crescent_city_bb_fab1(sch_1):\MG_DQ_FAR_DIMM_NG_M_H_BYTE3\" )
					)
					( Units "uMatchProp" "ns" 1.000000)
					( Origin gBackEnd )
				)
			)
			( pinPair "@baseboard_fab2_lib.baseboard_fab2(sch_1):\PP2639\"
				( pinRef "@baseboard_fab2_lib.baseboard_fab2(sch_1):page58_i172:DDR1_DQ(25)" )
				( pinRef "@baseboard_fab2_lib.baseboard_fab2(sch_1):page80_i24:DQ(25)" )
				( attribute "RELATIVE_PROPAGATION_DELAY_SCOPE" "G"
					( Parent
						( matchGroupRef "@baseboard_fab2_lib.baseboard_fab2(sch_1):\MG_DQ-DQS_NEAR_DIMM_NG_M_H_BYTE3\" )
					)
					( Status sCSetFlattened )
					( Origin gBackEnd )
				)
				( attribute "RELATIVE_PROPAGATION_DELAY" "0.00 MIL,195.00 MIL"
					( Parent
						( matchGroupRef "@baseboard_fab2_lib.baseboard_fab2(sch_1):\MG_DQ-DQS_NEAR_DIMM_NG_M_H_BYTE3\" )
					)
					( Units "uMatchProp" "ns" 1.000000)
					( Status sCSetFlattened )
					( Origin gBackEnd )
				)
				( attribute "RELATIVE_PROPAGATION_DELAY_SCOPE" "G"
					( Parent
						( matchGroupRef "@crescent_city_bb_fab1_lib.crescent_city_bb_fab1(sch_1):\MG_DQ_NEAR_DIMM_NG_M_H_BYTE3\" )
					)
					( Origin gBackEnd )
				)
				( attribute "RELATIVE_PROPAGATION_DELAY" "-50.86 MIL,50.00 MIL"
					( Parent
						( matchGroupRef "@crescent_city_bb_fab1_lib.crescent_city_bb_fab1(sch_1):\MG_DQ_NEAR_DIMM_NG_M_H_BYTE3\" )
					)
					( Units "uMatchProp" "ns" 1.000000)
					( Origin gBackEnd )
				)
			)
			( pinPair "@baseboard_fab2_lib.baseboard_fab2(sch_1):\PP2641\"
				( pinRef "@baseboard_fab2_lib.baseboard_fab2(sch_1):page58_i172:DDR1_DQ(26)" )
				( pinRef "@baseboard_fab2_lib.baseboard_fab2(sch_1):page79_i111:DQ(27)" )
				( attribute "RELATIVE_PROPAGATION_DELAY_SCOPE" "G"
					( Parent
						( matchGroupRef "@baseboard_fab2_lib.baseboard_fab2(sch_1):\MG_DQ-DQS_FAR_DIMM_NG_M_H_BYTE3\" )
					)
					( Status sCSetFlattened )
					( Origin gBackEnd )
				)
				( attribute "RELATIVE_PROPAGATION_DELAY" "0.00 MIL,195.00 MIL"
					( Parent
						( matchGroupRef "@baseboard_fab2_lib.baseboard_fab2(sch_1):\MG_DQ-DQS_FAR_DIMM_NG_M_H_BYTE3\" )
					)
					( Units "uMatchProp" "ns" 1.000000)
					( Status sCSetFlattened )
					( Origin gBackEnd )
				)
				( attribute "RELATIVE_PROPAGATION_DELAY_SCOPE" "G"
					( Parent
						( matchGroupRef "@crescent_city_bb_fab1_lib.crescent_city_bb_fab1(sch_1):\MG_DQ_FAR_DIMM_NG_M_H_BYTE3\" )
					)
					( Origin gBackEnd )
				)
				( attribute "RELATIVE_PROPAGATION_DELAY" "-47.38 MIL,50.00 MIL"
					( Parent
						( matchGroupRef "@crescent_city_bb_fab1_lib.crescent_city_bb_fab1(sch_1):\MG_DQ_FAR_DIMM_NG_M_H_BYTE3\" )
					)
					( Units "uMatchProp" "ns" 1.000000)
					( Origin gBackEnd )
				)
			)
			( pinPair "@baseboard_fab2_lib.baseboard_fab2(sch_1):\PP2642\"
				( pinRef "@baseboard_fab2_lib.baseboard_fab2(sch_1):page58_i172:DDR1_DQ(26)" )
				( pinRef "@baseboard_fab2_lib.baseboard_fab2(sch_1):page80_i24:DQ(26)" )
				( attribute "RELATIVE_PROPAGATION_DELAY_SCOPE" "G"
					( Parent
						( matchGroupRef "@baseboard_fab2_lib.baseboard_fab2(sch_1):\MG_DQ-DQS_NEAR_DIMM_NG_M_H_BYTE3\" )
					)
					( Status sCSetFlattened )
					( Origin gBackEnd )
				)
				( attribute "RELATIVE_PROPAGATION_DELAY" "0.00 MIL,195.00 MIL"
					( Parent
						( matchGroupRef "@baseboard_fab2_lib.baseboard_fab2(sch_1):\MG_DQ-DQS_NEAR_DIMM_NG_M_H_BYTE3\" )
					)
					( Units "uMatchProp" "ns" 1.000000)
					( Status sCSetFlattened )
					( Origin gBackEnd )
				)
				( attribute "RELATIVE_PROPAGATION_DELAY_SCOPE" "G"
					( Parent
						( matchGroupRef "@crescent_city_bb_fab1_lib.crescent_city_bb_fab1(sch_1):\MG_DQ_NEAR_DIMM_NG_M_H_BYTE3\" )
					)
					( Origin gBackEnd )
				)
				( attribute "RELATIVE_PROPAGATION_DELAY" "-47.38 MIL,50.00 MIL"
					( Parent
						( matchGroupRef "@crescent_city_bb_fab1_lib.crescent_city_bb_fab1(sch_1):\MG_DQ_NEAR_DIMM_NG_M_H_BYTE3\" )
					)
					( Units "uMatchProp" "ns" 1.000000)
					( Origin gBackEnd )
				)
			)
			( pinPair "@baseboard_fab2_lib.baseboard_fab2(sch_1):\PP2644\"
				( pinRef "@baseboard_fab2_lib.baseboard_fab2(sch_1):page58_i172:DDR1_DQ(27)" )
				( pinRef "@baseboard_fab2_lib.baseboard_fab2(sch_1):page79_i111:DQ(26)" )
				( attribute "RELATIVE_PROPAGATION_DELAY_SCOPE" "G"
					( Parent
						( matchGroupRef "@baseboard_fab2_lib.baseboard_fab2(sch_1):\MG_DQ-DQS_FAR_DIMM_NG_M_H_BYTE3\" )
					)
					( Status sCSetFlattened )
					( Origin gBackEnd )
				)
				( attribute "RELATIVE_PROPAGATION_DELAY" "0.00 MIL,195.00 MIL"
					( Parent
						( matchGroupRef "@baseboard_fab2_lib.baseboard_fab2(sch_1):\MG_DQ-DQS_FAR_DIMM_NG_M_H_BYTE3\" )
					)
					( Units "uMatchProp" "ns" 1.000000)
					( Status sCSetFlattened )
					( Origin gBackEnd )
				)
				( attribute "RELATIVE_PROPAGATION_DELAY_SCOPE" "G"
					( Parent
						( matchGroupRef "@crescent_city_bb_fab1_lib.crescent_city_bb_fab1(sch_1):\MG_DQ_FAR_DIMM_NG_M_H_BYTE3\" )
					)
					( Origin gBackEnd )
				)
				( attribute "RELATIVE_PROPAGATION_DELAY" "-13.53 MIL,50.00 MIL"
					( Parent
						( matchGroupRef "@crescent_city_bb_fab1_lib.crescent_city_bb_fab1(sch_1):\MG_DQ_FAR_DIMM_NG_M_H_BYTE3\" )
					)
					( Units "uMatchProp" "ns" 1.000000)
					( Origin gBackEnd )
				)
			)
			( pinPair "@baseboard_fab2_lib.baseboard_fab2(sch_1):\PP2645\"
				( pinRef "@baseboard_fab2_lib.baseboard_fab2(sch_1):page58_i172:DDR1_DQ(27)" )
				( pinRef "@baseboard_fab2_lib.baseboard_fab2(sch_1):page80_i24:DQ(27)" )
				( attribute "RELATIVE_PROPAGATION_DELAY_SCOPE" "G"
					( Parent
						( matchGroupRef "@baseboard_fab2_lib.baseboard_fab2(sch_1):\MG_DQ-DQS_NEAR_DIMM_NG_M_H_BYTE3\" )
					)
					( Status sCSetFlattened )
					( Origin gBackEnd )
				)
				( attribute "RELATIVE_PROPAGATION_DELAY" "0.00 MIL,195.00 MIL"
					( Parent
						( matchGroupRef "@baseboard_fab2_lib.baseboard_fab2(sch_1):\MG_DQ-DQS_NEAR_DIMM_NG_M_H_BYTE3\" )
					)
					( Units "uMatchProp" "ns" 1.000000)
					( Status sCSetFlattened )
					( Origin gBackEnd )
				)
				( attribute "RELATIVE_PROPAGATION_DELAY_SCOPE" "G"
					( Parent
						( matchGroupRef "@crescent_city_bb_fab1_lib.crescent_city_bb_fab1(sch_1):\MG_DQ_NEAR_DIMM_NG_M_H_BYTE3\" )
					)
					( Origin gBackEnd )
				)
				( attribute "RELATIVE_PROPAGATION_DELAY" "-13.53 MIL,50.00 MIL"
					( Parent
						( matchGroupRef "@crescent_city_bb_fab1_lib.crescent_city_bb_fab1(sch_1):\MG_DQ_NEAR_DIMM_NG_M_H_BYTE3\" )
					)
					( Units "uMatchProp" "ns" 1.000000)
					( Origin gBackEnd )
				)
			)
			( pinPair "@baseboard_fab2_lib.baseboard_fab2(sch_1):\PP2647\"
				( pinRef "@baseboard_fab2_lib.baseboard_fab2(sch_1):page58_i172:DDR1_DQ(28)" )
				( pinRef "@baseboard_fab2_lib.baseboard_fab2(sch_1):page79_i111:DQ(29)" )
				( attribute "RELATIVE_PROPAGATION_DELAY_SCOPE" "G"
					( Parent
						( matchGroupRef "@baseboard_fab2_lib.baseboard_fab2(sch_1):\MG_DQ-DQS_FAR_DIMM_NG_M_H_BYTE3\" )
					)
					( Status sCSetFlattened )
					( Origin gBackEnd )
				)
				( attribute "RELATIVE_PROPAGATION_DELAY" "0.00 MIL,195.00 MIL"
					( Parent
						( matchGroupRef "@baseboard_fab2_lib.baseboard_fab2(sch_1):\MG_DQ-DQS_FAR_DIMM_NG_M_H_BYTE3\" )
					)
					( Units "uMatchProp" "ns" 1.000000)
					( Status sCSetFlattened )
					( Origin gBackEnd )
				)
				( attribute "RELATIVE_PROPAGATION_DELAY_SCOPE" "G"
					( Parent
						( matchGroupRef "@crescent_city_bb_fab1_lib.crescent_city_bb_fab1(sch_1):\MG_DQ_FAR_DIMM_NG_M_H_BYTE3\" )
					)
					( Origin gBackEnd )
				)
				( attribute "RELATIVE_PROPAGATION_DELAY" "-15.88 MIL,50.00 MIL"
					( Parent
						( matchGroupRef "@crescent_city_bb_fab1_lib.crescent_city_bb_fab1(sch_1):\MG_DQ_FAR_DIMM_NG_M_H_BYTE3\" )
					)
					( Units "uMatchProp" "ns" 1.000000)
					( Origin gBackEnd )
				)
			)
			( pinPair "@baseboard_fab2_lib.baseboard_fab2(sch_1):\PP2648\"
				( pinRef "@baseboard_fab2_lib.baseboard_fab2(sch_1):page58_i172:DDR1_DQ(28)" )
				( pinRef "@baseboard_fab2_lib.baseboard_fab2(sch_1):page80_i24:DQ(28)" )
				( attribute "RELATIVE_PROPAGATION_DELAY_SCOPE" "G"
					( Parent
						( matchGroupRef "@baseboard_fab2_lib.baseboard_fab2(sch_1):\MG_DQ-DQS_NEAR_DIMM_NG_M_H_BYTE3\" )
					)
					( Status sCSetFlattened )
					( Origin gBackEnd )
				)
				( attribute "RELATIVE_PROPAGATION_DELAY" "0.00 MIL,195.00 MIL"
					( Parent
						( matchGroupRef "@baseboard_fab2_lib.baseboard_fab2(sch_1):\MG_DQ-DQS_NEAR_DIMM_NG_M_H_BYTE3\" )
					)
					( Units "uMatchProp" "ns" 1.000000)
					( Status sCSetFlattened )
					( Origin gBackEnd )
				)
				( attribute "RELATIVE_PROPAGATION_DELAY_SCOPE" "G"
					( Parent
						( matchGroupRef "@crescent_city_bb_fab1_lib.crescent_city_bb_fab1(sch_1):\MG_DQ_NEAR_DIMM_NG_M_H_BYTE3\" )
					)
					( Origin gBackEnd )
				)
				( attribute "RELATIVE_PROPAGATION_DELAY" "-15.88 MIL,50.00 MIL"
					( Parent
						( matchGroupRef "@crescent_city_bb_fab1_lib.crescent_city_bb_fab1(sch_1):\MG_DQ_NEAR_DIMM_NG_M_H_BYTE3\" )
					)
					( Units "uMatchProp" "ns" 1.000000)
					( Origin gBackEnd )
				)
			)
			( pinPair "@baseboard_fab2_lib.baseboard_fab2(sch_1):\PP2650\"
				( pinRef "@baseboard_fab2_lib.baseboard_fab2(sch_1):page58_i172:DDR1_DQ(29)" )
				( pinRef "@baseboard_fab2_lib.baseboard_fab2(sch_1):page79_i111:DQ(28)" )
				( attribute "RELATIVE_PROPAGATION_DELAY_SCOPE" "G"
					( Parent
						( matchGroupRef "@baseboard_fab2_lib.baseboard_fab2(sch_1):\MG_DQ-DQS_FAR_DIMM_NG_M_H_BYTE3\" )
					)
					( Status sCSetFlattened )
					( Origin gBackEnd )
				)
				( attribute "RELATIVE_PROPAGATION_DELAY" "0.00 MIL,195.00 MIL"
					( Parent
						( matchGroupRef "@baseboard_fab2_lib.baseboard_fab2(sch_1):\MG_DQ-DQS_FAR_DIMM_NG_M_H_BYTE3\" )
					)
					( Units "uMatchProp" "ns" 1.000000)
					( Status sCSetFlattened )
					( Origin gBackEnd )
				)
				( attribute "RELATIVE_PROPAGATION_DELAY_SCOPE" "G"
					( Parent
						( matchGroupRef "@crescent_city_bb_fab1_lib.crescent_city_bb_fab1(sch_1):\MG_DQ_FAR_DIMM_NG_M_H_BYTE3\" )
					)
					( Origin gBackEnd )
				)
				( attribute "RELATIVE_PROPAGATION_DELAY" "TARGET,TARGET"
					( Parent
						( matchGroupRef "@crescent_city_bb_fab1_lib.crescent_city_bb_fab1(sch_1):\MG_DQ_FAR_DIMM_NG_M_H_BYTE3\" )
					)
					( Units "uMatchProp" "ns" 1.000000)
					( Origin gBackEnd )
				)
			)
			( pinPair "@baseboard_fab2_lib.baseboard_fab2(sch_1):\PP2651\"
				( pinRef "@baseboard_fab2_lib.baseboard_fab2(sch_1):page58_i172:DDR1_DQ(29)" )
				( pinRef "@baseboard_fab2_lib.baseboard_fab2(sch_1):page80_i24:DQ(29)" )
				( attribute "RELATIVE_PROPAGATION_DELAY_SCOPE" "G"
					( Parent
						( matchGroupRef "@baseboard_fab2_lib.baseboard_fab2(sch_1):\MG_DQ-DQS_NEAR_DIMM_NG_M_H_BYTE3\" )
					)
					( Status sCSetFlattened )
					( Origin gBackEnd )
				)
				( attribute "RELATIVE_PROPAGATION_DELAY" "0.00 MIL,195.00 MIL"
					( Parent
						( matchGroupRef "@baseboard_fab2_lib.baseboard_fab2(sch_1):\MG_DQ-DQS_NEAR_DIMM_NG_M_H_BYTE3\" )
					)
					( Units "uMatchProp" "ns" 1.000000)
					( Status sCSetFlattened )
					( Origin gBackEnd )
				)
				( attribute "RELATIVE_PROPAGATION_DELAY_SCOPE" "G"
					( Parent
						( matchGroupRef "@crescent_city_bb_fab1_lib.crescent_city_bb_fab1(sch_1):\MG_DQ_NEAR_DIMM_NG_M_H_BYTE3\" )
					)
					( Origin gBackEnd )
				)
				( attribute "RELATIVE_PROPAGATION_DELAY" "TARGET,TARGET"
					( Parent
						( matchGroupRef "@crescent_city_bb_fab1_lib.crescent_city_bb_fab1(sch_1):\MG_DQ_NEAR_DIMM_NG_M_H_BYTE3\" )
					)
					( Units "uMatchProp" "ns" 1.000000)
					( Origin gBackEnd )
				)
			)
			( pinPair "@baseboard_fab2_lib.baseboard_fab2(sch_1):\PP2653\"
				( pinRef "@baseboard_fab2_lib.baseboard_fab2(sch_1):page58_i172:DDR1_DQ(30)" )
				( pinRef "@baseboard_fab2_lib.baseboard_fab2(sch_1):page79_i111:DQ(31)" )
				( attribute "RELATIVE_PROPAGATION_DELAY_SCOPE" "G"
					( Parent
						( matchGroupRef "@baseboard_fab2_lib.baseboard_fab2(sch_1):\MG_DQ-DQS_FAR_DIMM_NG_M_H_BYTE3\" )
					)
					( Status sCSetFlattened )
					( Origin gBackEnd )
				)
				( attribute "RELATIVE_PROPAGATION_DELAY" "0.00 MIL,195.00 MIL"
					( Parent
						( matchGroupRef "@baseboard_fab2_lib.baseboard_fab2(sch_1):\MG_DQ-DQS_FAR_DIMM_NG_M_H_BYTE3\" )
					)
					( Units "uMatchProp" "ns" 1.000000)
					( Status sCSetFlattened )
					( Origin gBackEnd )
				)
				( attribute "RELATIVE_PROPAGATION_DELAY_SCOPE" "G"
					( Parent
						( matchGroupRef "@crescent_city_bb_fab1_lib.crescent_city_bb_fab1(sch_1):\MG_DQ_FAR_DIMM_NG_M_H_BYTE3\" )
					)
					( Origin gBackEnd )
				)
				( attribute "RELATIVE_PROPAGATION_DELAY" "-48.40 MIL,50.00 MIL"
					( Parent
						( matchGroupRef "@crescent_city_bb_fab1_lib.crescent_city_bb_fab1(sch_1):\MG_DQ_FAR_DIMM_NG_M_H_BYTE3\" )
					)
					( Units "uMatchProp" "ns" 1.000000)
					( Origin gBackEnd )
				)
			)
			( pinPair "@baseboard_fab2_lib.baseboard_fab2(sch_1):\PP2654\"
				( pinRef "@baseboard_fab2_lib.baseboard_fab2(sch_1):page58_i172:DDR1_DQ(30)" )
				( pinRef "@baseboard_fab2_lib.baseboard_fab2(sch_1):page80_i24:DQ(30)" )
				( attribute "RELATIVE_PROPAGATION_DELAY_SCOPE" "G"
					( Parent
						( matchGroupRef "@baseboard_fab2_lib.baseboard_fab2(sch_1):\MG_DQ-DQS_NEAR_DIMM_NG_M_H_BYTE3\" )
					)
					( Status sCSetFlattened )
					( Origin gBackEnd )
				)
				( attribute "RELATIVE_PROPAGATION_DELAY" "0.00 MIL,195.00 MIL"
					( Parent
						( matchGroupRef "@baseboard_fab2_lib.baseboard_fab2(sch_1):\MG_DQ-DQS_NEAR_DIMM_NG_M_H_BYTE3\" )
					)
					( Units "uMatchProp" "ns" 1.000000)
					( Status sCSetFlattened )
					( Origin gBackEnd )
				)
				( attribute "RELATIVE_PROPAGATION_DELAY_SCOPE" "G"
					( Parent
						( matchGroupRef "@crescent_city_bb_fab1_lib.crescent_city_bb_fab1(sch_1):\MG_DQ_NEAR_DIMM_NG_M_H_BYTE3\" )
					)
					( Origin gBackEnd )
				)
				( attribute "RELATIVE_PROPAGATION_DELAY" "-48.40 MIL,50.00 MIL"
					( Parent
						( matchGroupRef "@crescent_city_bb_fab1_lib.crescent_city_bb_fab1(sch_1):\MG_DQ_NEAR_DIMM_NG_M_H_BYTE3\" )
					)
					( Units "uMatchProp" "ns" 1.000000)
					( Origin gBackEnd )
				)
			)
			( pinPair "@baseboard_fab2_lib.baseboard_fab2(sch_1):\PP2656\"
				( pinRef "@baseboard_fab2_lib.baseboard_fab2(sch_1):page58_i172:DDR1_DQ(31)" )
				( pinRef "@baseboard_fab2_lib.baseboard_fab2(sch_1):page79_i111:DQ(30)" )
				( attribute "RELATIVE_PROPAGATION_DELAY_SCOPE" "G"
					( Parent
						( matchGroupRef "@baseboard_fab2_lib.baseboard_fab2(sch_1):\MG_DQ-DQS_FAR_DIMM_NG_M_H_BYTE3\" )
					)
					( Status sCSetFlattened )
					( Origin gBackEnd )
				)
				( attribute "RELATIVE_PROPAGATION_DELAY" "0.00 MIL,195.00 MIL"
					( Parent
						( matchGroupRef "@baseboard_fab2_lib.baseboard_fab2(sch_1):\MG_DQ-DQS_FAR_DIMM_NG_M_H_BYTE3\" )
					)
					( Units "uMatchProp" "ns" 1.000000)
					( Status sCSetFlattened )
					( Origin gBackEnd )
				)
				( attribute "RELATIVE_PROPAGATION_DELAY_SCOPE" "G"
					( Parent
						( matchGroupRef "@crescent_city_bb_fab1_lib.crescent_city_bb_fab1(sch_1):\MG_DQ_FAR_DIMM_NG_M_H_BYTE3\" )
					)
					( Origin gBackEnd )
				)
				( attribute "RELATIVE_PROPAGATION_DELAY" "-46.39 MIL,50.00 MIL"
					( Parent
						( matchGroupRef "@crescent_city_bb_fab1_lib.crescent_city_bb_fab1(sch_1):\MG_DQ_FAR_DIMM_NG_M_H_BYTE3\" )
					)
					( Units "uMatchProp" "ns" 1.000000)
					( Origin gBackEnd )
				)
			)
			( pinPair "@baseboard_fab2_lib.baseboard_fab2(sch_1):\PP2657\"
				( pinRef "@baseboard_fab2_lib.baseboard_fab2(sch_1):page58_i172:DDR1_DQ(31)" )
				( pinRef "@baseboard_fab2_lib.baseboard_fab2(sch_1):page80_i24:DQ(31)" )
				( attribute "RELATIVE_PROPAGATION_DELAY_SCOPE" "G"
					( Parent
						( matchGroupRef "@baseboard_fab2_lib.baseboard_fab2(sch_1):\MG_DQ-DQS_NEAR_DIMM_NG_M_H_BYTE3\" )
					)
					( Status sCSetFlattened )
					( Origin gBackEnd )
				)
				( attribute "RELATIVE_PROPAGATION_DELAY" "0.00 MIL,195.00 MIL"
					( Parent
						( matchGroupRef "@baseboard_fab2_lib.baseboard_fab2(sch_1):\MG_DQ-DQS_NEAR_DIMM_NG_M_H_BYTE3\" )
					)
					( Units "uMatchProp" "ns" 1.000000)
					( Status sCSetFlattened )
					( Origin gBackEnd )
				)
				( attribute "RELATIVE_PROPAGATION_DELAY_SCOPE" "G"
					( Parent
						( matchGroupRef "@crescent_city_bb_fab1_lib.crescent_city_bb_fab1(sch_1):\MG_DQ_NEAR_DIMM_NG_M_H_BYTE3\" )
					)
					( Origin gBackEnd )
				)
				( attribute "RELATIVE_PROPAGATION_DELAY" "-46.39 MIL,50.00 MIL"
					( Parent
						( matchGroupRef "@crescent_city_bb_fab1_lib.crescent_city_bb_fab1(sch_1):\MG_DQ_NEAR_DIMM_NG_M_H_BYTE3\" )
					)
					( Units "uMatchProp" "ns" 1.000000)
					( Origin gBackEnd )
				)
			)
			( pinPair "@baseboard_fab2_lib.baseboard_fab2(sch_1):\PP2611\"
				( pinRef "@baseboard_fab2_lib.baseboard_fab2(sch_1):page58_i172:DDR1_DQ(32)" )
				( pinRef "@baseboard_fab2_lib.baseboard_fab2(sch_1):page79_i111:DQ(33)" )
				( attribute "RELATIVE_PROPAGATION_DELAY_SCOPE" "G"
					( Parent
						( matchGroupRef "@baseboard_fab2_lib.baseboard_fab2(sch_1):\MG_DQ-DQS_FAR_DIMM_NG_M_H_BYTE4\" )
					)
					( Status sCSetFlattened )
					( Origin gBackEnd )
				)
				( attribute "RELATIVE_PROPAGATION_DELAY" "0.00 MIL,195.00 MIL"
					( Parent
						( matchGroupRef "@baseboard_fab2_lib.baseboard_fab2(sch_1):\MG_DQ-DQS_FAR_DIMM_NG_M_H_BYTE4\" )
					)
					( Units "uMatchProp" "ns" 1.000000)
					( Status sCSetFlattened )
					( Origin gBackEnd )
				)
				( attribute "RELATIVE_PROPAGATION_DELAY_SCOPE" "G"
					( Parent
						( matchGroupRef "@crescent_city_bb_fab1_lib.crescent_city_bb_fab1(sch_1):\MG_DQ_FAR_DIMM_NG_M_H_BYTE4\" )
					)
					( Status sCSetFlattened )
					( Origin gBackEnd )
				)
				( attribute "RELATIVE_PROPAGATION_DELAY" "-50.00 MIL,50.00 MIL"
					( Parent
						( matchGroupRef "@crescent_city_bb_fab1_lib.crescent_city_bb_fab1(sch_1):\MG_DQ_FAR_DIMM_NG_M_H_BYTE4\" )
					)
					( Units "uMatchProp" "ns" 1.000000)
					( Status sCSetFlattened )
					( Origin gBackEnd )
				)
			)
			( pinPair "@baseboard_fab2_lib.baseboard_fab2(sch_1):\PP2613\"
				( pinRef "@baseboard_fab2_lib.baseboard_fab2(sch_1):page58_i172:DDR1_DQ(32)" )
				( pinRef "@baseboard_fab2_lib.baseboard_fab2(sch_1):page80_i24:DQ(32)" )
				( attribute "RELATIVE_PROPAGATION_DELAY_SCOPE" "G"
					( Parent
						( matchGroupRef "@baseboard_fab2_lib.baseboard_fab2(sch_1):\MG_DQ-DQS_NEAR_DIMM_NG_M_H_BYTE4\" )
					)
					( Status sCSetFlattened )
					( Origin gBackEnd )
				)
				( attribute "RELATIVE_PROPAGATION_DELAY" "0.00 MIL,195.00 MIL"
					( Parent
						( matchGroupRef "@baseboard_fab2_lib.baseboard_fab2(sch_1):\MG_DQ-DQS_NEAR_DIMM_NG_M_H_BYTE4\" )
					)
					( Units "uMatchProp" "ns" 1.000000)
					( Status sCSetFlattened )
					( Origin gBackEnd )
				)
				( attribute "RELATIVE_PROPAGATION_DELAY_SCOPE" "G"
					( Parent
						( matchGroupRef "@crescent_city_bb_fab1_lib.crescent_city_bb_fab1(sch_1):\MG_DQ_NEAR_DIMM_NG_M_H_BYTE4\" )
					)
					( Status sCSetFlattened )
					( Origin gBackEnd )
				)
				( attribute "RELATIVE_PROPAGATION_DELAY" "-50.00 MIL,50.00 MIL"
					( Parent
						( matchGroupRef "@crescent_city_bb_fab1_lib.crescent_city_bb_fab1(sch_1):\MG_DQ_NEAR_DIMM_NG_M_H_BYTE4\" )
					)
					( Units "uMatchProp" "ns" 1.000000)
					( Status sCSetFlattened )
					( Origin gBackEnd )
				)
			)
			( pinPair "@baseboard_fab2_lib.baseboard_fab2(sch_1):\PP2614\"
				( pinRef "@baseboard_fab2_lib.baseboard_fab2(sch_1):page58_i172:DDR1_DQ(33)" )
				( pinRef "@baseboard_fab2_lib.baseboard_fab2(sch_1):page79_i111:DQ(32)" )
				( attribute "RELATIVE_PROPAGATION_DELAY_SCOPE" "G"
					( Parent
						( matchGroupRef "@baseboard_fab2_lib.baseboard_fab2(sch_1):\MG_DQ-DQS_FAR_DIMM_NG_M_H_BYTE4\" )
					)
					( Status sCSetFlattened )
					( Origin gBackEnd )
				)
				( attribute "RELATIVE_PROPAGATION_DELAY" "0.00 MIL,195.00 MIL"
					( Parent
						( matchGroupRef "@baseboard_fab2_lib.baseboard_fab2(sch_1):\MG_DQ-DQS_FAR_DIMM_NG_M_H_BYTE4\" )
					)
					( Units "uMatchProp" "ns" 1.000000)
					( Status sCSetFlattened )
					( Origin gBackEnd )
				)
				( attribute "RELATIVE_PROPAGATION_DELAY_SCOPE" "G"
					( Parent
						( matchGroupRef "@crescent_city_bb_fab1_lib.crescent_city_bb_fab1(sch_1):\MG_DQ_FAR_DIMM_NG_M_H_BYTE4\" )
					)
					( Status sCSetFlattened )
					( Origin gBackEnd )
				)
				( attribute "RELATIVE_PROPAGATION_DELAY" "-50.00 MIL,50.00 MIL"
					( Parent
						( matchGroupRef "@crescent_city_bb_fab1_lib.crescent_city_bb_fab1(sch_1):\MG_DQ_FAR_DIMM_NG_M_H_BYTE4\" )
					)
					( Units "uMatchProp" "ns" 1.000000)
					( Status sCSetFlattened )
					( Origin gBackEnd )
				)
			)
			( pinPair "@baseboard_fab2_lib.baseboard_fab2(sch_1):\PP2616\"
				( pinRef "@baseboard_fab2_lib.baseboard_fab2(sch_1):page80_i24:DQ(33)" )
				( pinRef "@baseboard_fab2_lib.baseboard_fab2(sch_1):page58_i172:DDR1_DQ(33)" )
				( attribute "RELATIVE_PROPAGATION_DELAY_SCOPE" "G"
					( Parent
						( matchGroupRef "@baseboard_fab2_lib.baseboard_fab2(sch_1):\MG_DQ-DQS_NEAR_DIMM_NG_M_H_BYTE4\" )
					)
					( Status sCSetFlattened )
					( Origin gBackEnd )
				)
				( attribute "RELATIVE_PROPAGATION_DELAY" "0.00 MIL,195.00 MIL"
					( Parent
						( matchGroupRef "@baseboard_fab2_lib.baseboard_fab2(sch_1):\MG_DQ-DQS_NEAR_DIMM_NG_M_H_BYTE4\" )
					)
					( Units "uMatchProp" "ns" 1.000000)
					( Status sCSetFlattened )
					( Origin gBackEnd )
				)
				( attribute "RELATIVE_PROPAGATION_DELAY_SCOPE" "G"
					( Parent
						( matchGroupRef "@crescent_city_bb_fab1_lib.crescent_city_bb_fab1(sch_1):\MG_DQ_NEAR_DIMM_NG_M_H_BYTE4\" )
					)
					( Status sCSetFlattened )
					( Origin gBackEnd )
				)
				( attribute "RELATIVE_PROPAGATION_DELAY" "-50.00 MIL,50.00 MIL"
					( Parent
						( matchGroupRef "@crescent_city_bb_fab1_lib.crescent_city_bb_fab1(sch_1):\MG_DQ_NEAR_DIMM_NG_M_H_BYTE4\" )
					)
					( Units "uMatchProp" "ns" 1.000000)
					( Status sCSetFlattened )
					( Origin gBackEnd )
				)
			)
			( pinPair "@baseboard_fab2_lib.baseboard_fab2(sch_1):\PP2617\"
				( pinRef "@baseboard_fab2_lib.baseboard_fab2(sch_1):page58_i172:DDR1_DQ(34)" )
				( pinRef "@baseboard_fab2_lib.baseboard_fab2(sch_1):page79_i111:DQ(35)" )
				( attribute "RELATIVE_PROPAGATION_DELAY_SCOPE" "G"
					( Parent
						( matchGroupRef "@baseboard_fab2_lib.baseboard_fab2(sch_1):\MG_DQ-DQS_FAR_DIMM_NG_M_H_BYTE4\" )
					)
					( Status sCSetFlattened )
					( Origin gBackEnd )
				)
				( attribute "RELATIVE_PROPAGATION_DELAY" "0.00 MIL,195.00 MIL"
					( Parent
						( matchGroupRef "@baseboard_fab2_lib.baseboard_fab2(sch_1):\MG_DQ-DQS_FAR_DIMM_NG_M_H_BYTE4\" )
					)
					( Units "uMatchProp" "ns" 1.000000)
					( Status sCSetFlattened )
					( Origin gBackEnd )
				)
				( attribute "RELATIVE_PROPAGATION_DELAY_SCOPE" "G"
					( Parent
						( matchGroupRef "@crescent_city_bb_fab1_lib.crescent_city_bb_fab1(sch_1):\MG_DQ_FAR_DIMM_NG_M_H_BYTE4\" )
					)
					( Status sCSetFlattened )
					( Origin gBackEnd )
				)
				( attribute "RELATIVE_PROPAGATION_DELAY" "-50.00 MIL,50.00 MIL"
					( Parent
						( matchGroupRef "@crescent_city_bb_fab1_lib.crescent_city_bb_fab1(sch_1):\MG_DQ_FAR_DIMM_NG_M_H_BYTE4\" )
					)
					( Units "uMatchProp" "ns" 1.000000)
					( Status sCSetFlattened )
					( Origin gBackEnd )
				)
			)
			( pinPair "@baseboard_fab2_lib.baseboard_fab2(sch_1):\PP2619\"
				( pinRef "@baseboard_fab2_lib.baseboard_fab2(sch_1):page58_i172:DDR1_DQ(34)" )
				( pinRef "@baseboard_fab2_lib.baseboard_fab2(sch_1):page80_i24:DQ(34)" )
				( attribute "RELATIVE_PROPAGATION_DELAY_SCOPE" "G"
					( Parent
						( matchGroupRef "@baseboard_fab2_lib.baseboard_fab2(sch_1):\MG_DQ-DQS_NEAR_DIMM_NG_M_H_BYTE4\" )
					)
					( Status sCSetFlattened )
					( Origin gBackEnd )
				)
				( attribute "RELATIVE_PROPAGATION_DELAY" "0.00 MIL,195.00 MIL"
					( Parent
						( matchGroupRef "@baseboard_fab2_lib.baseboard_fab2(sch_1):\MG_DQ-DQS_NEAR_DIMM_NG_M_H_BYTE4\" )
					)
					( Units "uMatchProp" "ns" 1.000000)
					( Status sCSetFlattened )
					( Origin gBackEnd )
				)
				( attribute "RELATIVE_PROPAGATION_DELAY_SCOPE" "G"
					( Parent
						( matchGroupRef "@crescent_city_bb_fab1_lib.crescent_city_bb_fab1(sch_1):\MG_DQ_NEAR_DIMM_NG_M_H_BYTE4\" )
					)
					( Status sCSetFlattened )
					( Origin gBackEnd )
				)
				( attribute "RELATIVE_PROPAGATION_DELAY" "-50.00 MIL,50.00 MIL"
					( Parent
						( matchGroupRef "@crescent_city_bb_fab1_lib.crescent_city_bb_fab1(sch_1):\MG_DQ_NEAR_DIMM_NG_M_H_BYTE4\" )
					)
					( Units "uMatchProp" "ns" 1.000000)
					( Status sCSetFlattened )
					( Origin gBackEnd )
				)
			)
			( pinPair "@baseboard_fab2_lib.baseboard_fab2(sch_1):\PP2620\"
				( pinRef "@baseboard_fab2_lib.baseboard_fab2(sch_1):page58_i172:DDR1_DQ(35)" )
				( pinRef "@baseboard_fab2_lib.baseboard_fab2(sch_1):page79_i111:DQ(34)" )
				( attribute "RELATIVE_PROPAGATION_DELAY_SCOPE" "G"
					( Parent
						( matchGroupRef "@baseboard_fab2_lib.baseboard_fab2(sch_1):\MG_DQ-DQS_FAR_DIMM_NG_M_H_BYTE4\" )
					)
					( Status sCSetFlattened )
					( Origin gBackEnd )
				)
				( attribute "RELATIVE_PROPAGATION_DELAY" "0.00 MIL,195.00 MIL"
					( Parent
						( matchGroupRef "@baseboard_fab2_lib.baseboard_fab2(sch_1):\MG_DQ-DQS_FAR_DIMM_NG_M_H_BYTE4\" )
					)
					( Units "uMatchProp" "ns" 1.000000)
					( Status sCSetFlattened )
					( Origin gBackEnd )
				)
				( attribute "RELATIVE_PROPAGATION_DELAY_SCOPE" "G"
					( Parent
						( matchGroupRef "@crescent_city_bb_fab1_lib.crescent_city_bb_fab1(sch_1):\MG_DQ_FAR_DIMM_NG_M_H_BYTE4\" )
					)
					( Status sCSetFlattened )
					( Origin gBackEnd )
				)
				( attribute "RELATIVE_PROPAGATION_DELAY" "-50.00 MIL,50.00 MIL"
					( Parent
						( matchGroupRef "@crescent_city_bb_fab1_lib.crescent_city_bb_fab1(sch_1):\MG_DQ_FAR_DIMM_NG_M_H_BYTE4\" )
					)
					( Units "uMatchProp" "ns" 1.000000)
					( Status sCSetFlattened )
					( Origin gBackEnd )
				)
			)
			( pinPair "@baseboard_fab2_lib.baseboard_fab2(sch_1):\PP2622\"
				( pinRef "@baseboard_fab2_lib.baseboard_fab2(sch_1):page58_i172:DDR1_DQ(35)" )
				( pinRef "@baseboard_fab2_lib.baseboard_fab2(sch_1):page80_i24:DQ(35)" )
				( attribute "RELATIVE_PROPAGATION_DELAY_SCOPE" "G"
					( Parent
						( matchGroupRef "@baseboard_fab2_lib.baseboard_fab2(sch_1):\MG_DQ-DQS_NEAR_DIMM_NG_M_H_BYTE4\" )
					)
					( Status sCSetFlattened )
					( Origin gBackEnd )
				)
				( attribute "RELATIVE_PROPAGATION_DELAY" "0.00 MIL,195.00 MIL"
					( Parent
						( matchGroupRef "@baseboard_fab2_lib.baseboard_fab2(sch_1):\MG_DQ-DQS_NEAR_DIMM_NG_M_H_BYTE4\" )
					)
					( Units "uMatchProp" "ns" 1.000000)
					( Status sCSetFlattened )
					( Origin gBackEnd )
				)
				( attribute "RELATIVE_PROPAGATION_DELAY_SCOPE" "G"
					( Parent
						( matchGroupRef "@crescent_city_bb_fab1_lib.crescent_city_bb_fab1(sch_1):\MG_DQ_NEAR_DIMM_NG_M_H_BYTE4\" )
					)
					( Status sCSetFlattened )
					( Origin gBackEnd )
				)
				( attribute "RELATIVE_PROPAGATION_DELAY" "-50.00 MIL,50.00 MIL"
					( Parent
						( matchGroupRef "@crescent_city_bb_fab1_lib.crescent_city_bb_fab1(sch_1):\MG_DQ_NEAR_DIMM_NG_M_H_BYTE4\" )
					)
					( Units "uMatchProp" "ns" 1.000000)
					( Status sCSetFlattened )
					( Origin gBackEnd )
				)
			)
			( pinPair "@baseboard_fab2_lib.baseboard_fab2(sch_1):\PP2623\"
				( pinRef "@baseboard_fab2_lib.baseboard_fab2(sch_1):page58_i172:DDR1_DQ(36)" )
				( pinRef "@baseboard_fab2_lib.baseboard_fab2(sch_1):page79_i111:DQ(37)" )
				( attribute "RELATIVE_PROPAGATION_DELAY_SCOPE" "G"
					( Parent
						( matchGroupRef "@baseboard_fab2_lib.baseboard_fab2(sch_1):\MG_DQ-DQS_FAR_DIMM_NG_M_H_BYTE4\" )
					)
					( Status sCSetFlattened )
					( Origin gBackEnd )
				)
				( attribute "RELATIVE_PROPAGATION_DELAY" "0.00 MIL,195.00 MIL"
					( Parent
						( matchGroupRef "@baseboard_fab2_lib.baseboard_fab2(sch_1):\MG_DQ-DQS_FAR_DIMM_NG_M_H_BYTE4\" )
					)
					( Units "uMatchProp" "ns" 1.000000)
					( Status sCSetFlattened )
					( Origin gBackEnd )
				)
				( attribute "RELATIVE_PROPAGATION_DELAY_SCOPE" "G"
					( Parent
						( matchGroupRef "@crescent_city_bb_fab1_lib.crescent_city_bb_fab1(sch_1):\MG_DQ_FAR_DIMM_NG_M_H_BYTE4\" )
					)
					( Status sCSetFlattened )
					( Origin gBackEnd )
				)
				( attribute "RELATIVE_PROPAGATION_DELAY" "-50.00 MIL,50.00 MIL"
					( Parent
						( matchGroupRef "@crescent_city_bb_fab1_lib.crescent_city_bb_fab1(sch_1):\MG_DQ_FAR_DIMM_NG_M_H_BYTE4\" )
					)
					( Units "uMatchProp" "ns" 1.000000)
					( Status sCSetFlattened )
					( Origin gBackEnd )
				)
			)
			( pinPair "@baseboard_fab2_lib.baseboard_fab2(sch_1):\PP2625\"
				( pinRef "@baseboard_fab2_lib.baseboard_fab2(sch_1):page80_i24:DQ(36)" )
				( pinRef "@baseboard_fab2_lib.baseboard_fab2(sch_1):page58_i172:DDR1_DQ(36)" )
				( attribute "RELATIVE_PROPAGATION_DELAY_SCOPE" "G"
					( Parent
						( matchGroupRef "@baseboard_fab2_lib.baseboard_fab2(sch_1):\MG_DQ-DQS_NEAR_DIMM_NG_M_H_BYTE4\" )
					)
					( Status sCSetFlattened )
					( Origin gBackEnd )
				)
				( attribute "RELATIVE_PROPAGATION_DELAY" "0.00 MIL,195.00 MIL"
					( Parent
						( matchGroupRef "@baseboard_fab2_lib.baseboard_fab2(sch_1):\MG_DQ-DQS_NEAR_DIMM_NG_M_H_BYTE4\" )
					)
					( Units "uMatchProp" "ns" 1.000000)
					( Status sCSetFlattened )
					( Origin gBackEnd )
				)
				( attribute "RELATIVE_PROPAGATION_DELAY_SCOPE" "G"
					( Parent
						( matchGroupRef "@crescent_city_bb_fab1_lib.crescent_city_bb_fab1(sch_1):\MG_DQ_NEAR_DIMM_NG_M_H_BYTE4\" )
					)
					( Status sCSetFlattened )
					( Origin gBackEnd )
				)
				( attribute "RELATIVE_PROPAGATION_DELAY" "-50.00 MIL,50.00 MIL"
					( Parent
						( matchGroupRef "@crescent_city_bb_fab1_lib.crescent_city_bb_fab1(sch_1):\MG_DQ_NEAR_DIMM_NG_M_H_BYTE4\" )
					)
					( Units "uMatchProp" "ns" 1.000000)
					( Status sCSetFlattened )
					( Origin gBackEnd )
				)
			)
			( pinPair "@baseboard_fab2_lib.baseboard_fab2(sch_1):\PP2626\"
				( pinRef "@baseboard_fab2_lib.baseboard_fab2(sch_1):page58_i172:DDR1_DQ(37)" )
				( pinRef "@baseboard_fab2_lib.baseboard_fab2(sch_1):page79_i111:DQ(36)" )
				( attribute "RELATIVE_PROPAGATION_DELAY_SCOPE" "G"
					( Parent
						( matchGroupRef "@baseboard_fab2_lib.baseboard_fab2(sch_1):\MG_DQ-DQS_FAR_DIMM_NG_M_H_BYTE4\" )
					)
					( Status sCSetFlattened )
					( Origin gBackEnd )
				)
				( attribute "RELATIVE_PROPAGATION_DELAY" "0.00 MIL,195.00 MIL"
					( Parent
						( matchGroupRef "@baseboard_fab2_lib.baseboard_fab2(sch_1):\MG_DQ-DQS_FAR_DIMM_NG_M_H_BYTE4\" )
					)
					( Units "uMatchProp" "ns" 1.000000)
					( Status sCSetFlattened )
					( Origin gBackEnd )
				)
				( attribute "RELATIVE_PROPAGATION_DELAY_SCOPE" "G"
					( Parent
						( matchGroupRef "@crescent_city_bb_fab1_lib.crescent_city_bb_fab1(sch_1):\MG_DQ_FAR_DIMM_NG_M_H_BYTE4\" )
					)
					( Origin gBackEnd )
				)
				( attribute "RELATIVE_PROPAGATION_DELAY" "TARGET,TARGET"
					( Parent
						( matchGroupRef "@crescent_city_bb_fab1_lib.crescent_city_bb_fab1(sch_1):\MG_DQ_FAR_DIMM_NG_M_H_BYTE4\" )
					)
					( Units "uMatchProp" "ns" 1.000000)
					( Origin gBackEnd )
				)
			)
			( pinPair "@baseboard_fab2_lib.baseboard_fab2(sch_1):\PP2628\"
				( pinRef "@baseboard_fab2_lib.baseboard_fab2(sch_1):page58_i172:DDR1_DQ(37)" )
				( pinRef "@baseboard_fab2_lib.baseboard_fab2(sch_1):page80_i24:DQ(37)" )
				( attribute "RELATIVE_PROPAGATION_DELAY_SCOPE" "G"
					( Parent
						( matchGroupRef "@baseboard_fab2_lib.baseboard_fab2(sch_1):\MG_DQ-DQS_NEAR_DIMM_NG_M_H_BYTE4\" )
					)
					( Status sCSetFlattened )
					( Origin gBackEnd )
				)
				( attribute "RELATIVE_PROPAGATION_DELAY" "0.00 MIL,195.00 MIL"
					( Parent
						( matchGroupRef "@baseboard_fab2_lib.baseboard_fab2(sch_1):\MG_DQ-DQS_NEAR_DIMM_NG_M_H_BYTE4\" )
					)
					( Units "uMatchProp" "ns" 1.000000)
					( Status sCSetFlattened )
					( Origin gBackEnd )
				)
				( attribute "RELATIVE_PROPAGATION_DELAY_SCOPE" "G"
					( Parent
						( matchGroupRef "@crescent_city_bb_fab1_lib.crescent_city_bb_fab1(sch_1):\MG_DQ_NEAR_DIMM_NG_M_H_BYTE4\" )
					)
					( Origin gBackEnd )
				)
				( attribute "RELATIVE_PROPAGATION_DELAY" "TARGET,TARGET"
					( Parent
						( matchGroupRef "@crescent_city_bb_fab1_lib.crescent_city_bb_fab1(sch_1):\MG_DQ_NEAR_DIMM_NG_M_H_BYTE4\" )
					)
					( Units "uMatchProp" "ns" 1.000000)
					( Origin gBackEnd )
				)
			)
			( pinPair "@baseboard_fab2_lib.baseboard_fab2(sch_1):\PP2629\"
				( pinRef "@baseboard_fab2_lib.baseboard_fab2(sch_1):page58_i172:DDR1_DQ(38)" )
				( pinRef "@baseboard_fab2_lib.baseboard_fab2(sch_1):page79_i111:DQ(39)" )
				( attribute "RELATIVE_PROPAGATION_DELAY_SCOPE" "G"
					( Parent
						( matchGroupRef "@baseboard_fab2_lib.baseboard_fab2(sch_1):\MG_DQ-DQS_FAR_DIMM_NG_M_H_BYTE4\" )
					)
					( Status sCSetFlattened )
					( Origin gBackEnd )
				)
				( attribute "RELATIVE_PROPAGATION_DELAY" "0.00 MIL,195.00 MIL"
					( Parent
						( matchGroupRef "@baseboard_fab2_lib.baseboard_fab2(sch_1):\MG_DQ-DQS_FAR_DIMM_NG_M_H_BYTE4\" )
					)
					( Units "uMatchProp" "ns" 1.000000)
					( Status sCSetFlattened )
					( Origin gBackEnd )
				)
				( attribute "RELATIVE_PROPAGATION_DELAY_SCOPE" "G"
					( Parent
						( matchGroupRef "@crescent_city_bb_fab1_lib.crescent_city_bb_fab1(sch_1):\MG_DQ_FAR_DIMM_NG_M_H_BYTE4\" )
					)
					( Status sCSetFlattened )
					( Origin gBackEnd )
				)
				( attribute "RELATIVE_PROPAGATION_DELAY" "-50.00 MIL,50.00 MIL"
					( Parent
						( matchGroupRef "@crescent_city_bb_fab1_lib.crescent_city_bb_fab1(sch_1):\MG_DQ_FAR_DIMM_NG_M_H_BYTE4\" )
					)
					( Units "uMatchProp" "ns" 1.000000)
					( Status sCSetFlattened )
					( Origin gBackEnd )
				)
			)
			( pinPair "@baseboard_fab2_lib.baseboard_fab2(sch_1):\PP2631\"
				( pinRef "@baseboard_fab2_lib.baseboard_fab2(sch_1):page58_i172:DDR1_DQ(38)" )
				( pinRef "@baseboard_fab2_lib.baseboard_fab2(sch_1):page80_i24:DQ(38)" )
				( attribute "RELATIVE_PROPAGATION_DELAY_SCOPE" "G"
					( Parent
						( matchGroupRef "@baseboard_fab2_lib.baseboard_fab2(sch_1):\MG_DQ-DQS_NEAR_DIMM_NG_M_H_BYTE4\" )
					)
					( Status sCSetFlattened )
					( Origin gBackEnd )
				)
				( attribute "RELATIVE_PROPAGATION_DELAY" "0.00 MIL,195.00 MIL"
					( Parent
						( matchGroupRef "@baseboard_fab2_lib.baseboard_fab2(sch_1):\MG_DQ-DQS_NEAR_DIMM_NG_M_H_BYTE4\" )
					)
					( Units "uMatchProp" "ns" 1.000000)
					( Status sCSetFlattened )
					( Origin gBackEnd )
				)
				( attribute "RELATIVE_PROPAGATION_DELAY_SCOPE" "G"
					( Parent
						( matchGroupRef "@crescent_city_bb_fab1_lib.crescent_city_bb_fab1(sch_1):\MG_DQ_NEAR_DIMM_NG_M_H_BYTE4\" )
					)
					( Status sCSetFlattened )
					( Origin gBackEnd )
				)
				( attribute "RELATIVE_PROPAGATION_DELAY" "-50.00 MIL,50.00 MIL"
					( Parent
						( matchGroupRef "@crescent_city_bb_fab1_lib.crescent_city_bb_fab1(sch_1):\MG_DQ_NEAR_DIMM_NG_M_H_BYTE4\" )
					)
					( Units "uMatchProp" "ns" 1.000000)
					( Status sCSetFlattened )
					( Origin gBackEnd )
				)
			)
			( pinPair "@baseboard_fab2_lib.baseboard_fab2(sch_1):\PP2632\"
				( pinRef "@baseboard_fab2_lib.baseboard_fab2(sch_1):page58_i172:DDR1_DQ(39)" )
				( pinRef "@baseboard_fab2_lib.baseboard_fab2(sch_1):page79_i111:DQ(38)" )
				( attribute "RELATIVE_PROPAGATION_DELAY_SCOPE" "G"
					( Parent
						( matchGroupRef "@baseboard_fab2_lib.baseboard_fab2(sch_1):\MG_DQ-DQS_FAR_DIMM_NG_M_H_BYTE4\" )
					)
					( Status sCSetFlattened )
					( Origin gBackEnd )
				)
				( attribute "RELATIVE_PROPAGATION_DELAY" "0.00 MIL,195.00 MIL"
					( Parent
						( matchGroupRef "@baseboard_fab2_lib.baseboard_fab2(sch_1):\MG_DQ-DQS_FAR_DIMM_NG_M_H_BYTE4\" )
					)
					( Units "uMatchProp" "ns" 1.000000)
					( Status sCSetFlattened )
					( Origin gBackEnd )
				)
				( attribute "RELATIVE_PROPAGATION_DELAY_SCOPE" "G"
					( Parent
						( matchGroupRef "@crescent_city_bb_fab1_lib.crescent_city_bb_fab1(sch_1):\MG_DQ_FAR_DIMM_NG_M_H_BYTE4\" )
					)
					( Status sCSetFlattened )
					( Origin gBackEnd )
				)
				( attribute "RELATIVE_PROPAGATION_DELAY" "-50.00 MIL,50.00 MIL"
					( Parent
						( matchGroupRef "@crescent_city_bb_fab1_lib.crescent_city_bb_fab1(sch_1):\MG_DQ_FAR_DIMM_NG_M_H_BYTE4\" )
					)
					( Units "uMatchProp" "ns" 1.000000)
					( Status sCSetFlattened )
					( Origin gBackEnd )
				)
			)
			( pinPair "@baseboard_fab2_lib.baseboard_fab2(sch_1):\PP2634\"
				( pinRef "@baseboard_fab2_lib.baseboard_fab2(sch_1):page58_i172:DDR1_DQ(39)" )
				( pinRef "@baseboard_fab2_lib.baseboard_fab2(sch_1):page80_i24:DQ(39)" )
				( attribute "RELATIVE_PROPAGATION_DELAY_SCOPE" "G"
					( Parent
						( matchGroupRef "@baseboard_fab2_lib.baseboard_fab2(sch_1):\MG_DQ-DQS_NEAR_DIMM_NG_M_H_BYTE4\" )
					)
					( Status sCSetFlattened )
					( Origin gBackEnd )
				)
				( attribute "RELATIVE_PROPAGATION_DELAY" "0.00 MIL,195.00 MIL"
					( Parent
						( matchGroupRef "@baseboard_fab2_lib.baseboard_fab2(sch_1):\MG_DQ-DQS_NEAR_DIMM_NG_M_H_BYTE4\" )
					)
					( Units "uMatchProp" "ns" 1.000000)
					( Status sCSetFlattened )
					( Origin gBackEnd )
				)
				( attribute "RELATIVE_PROPAGATION_DELAY_SCOPE" "G"
					( Parent
						( matchGroupRef "@crescent_city_bb_fab1_lib.crescent_city_bb_fab1(sch_1):\MG_DQ_NEAR_DIMM_NG_M_H_BYTE4\" )
					)
					( Status sCSetFlattened )
					( Origin gBackEnd )
				)
				( attribute "RELATIVE_PROPAGATION_DELAY" "-50.00 MIL,50.00 MIL"
					( Parent
						( matchGroupRef "@crescent_city_bb_fab1_lib.crescent_city_bb_fab1(sch_1):\MG_DQ_NEAR_DIMM_NG_M_H_BYTE4\" )
					)
					( Units "uMatchProp" "ns" 1.000000)
					( Status sCSetFlattened )
					( Origin gBackEnd )
				)
			)
			( pinPair "@baseboard_fab2_lib.baseboard_fab2(sch_1):\PP2587\"
				( pinRef "@baseboard_fab2_lib.baseboard_fab2(sch_1):page58_i172:DDR1_DQ(40)" )
				( pinRef "@baseboard_fab2_lib.baseboard_fab2(sch_1):page79_i111:DQ(41)" )
				( attribute "RELATIVE_PROPAGATION_DELAY_SCOPE" "G"
					( Parent
						( matchGroupRef "@baseboard_fab2_lib.baseboard_fab2(sch_1):\MG_DQ-DQS_FAR_DIMM_NG_M_H_BYTE5\" )
					)
					( Status sCSetFlattened )
					( Origin gBackEnd )
				)
				( attribute "RELATIVE_PROPAGATION_DELAY" "0.00 MIL,195.00 MIL"
					( Parent
						( matchGroupRef "@baseboard_fab2_lib.baseboard_fab2(sch_1):\MG_DQ-DQS_FAR_DIMM_NG_M_H_BYTE5\" )
					)
					( Units "uMatchProp" "ns" 1.000000)
					( Status sCSetFlattened )
					( Origin gBackEnd )
				)
				( attribute "RELATIVE_PROPAGATION_DELAY_SCOPE" "G"
					( Parent
						( matchGroupRef "@baseboard_fab2_lib.baseboard_fab2(sch_1):\MG_DQ_FAR_DIMM_NG_M_H_BYTE5\" )
					)
					( Status sCSetFlattened )
					( Origin gBackEnd )
				)
				( attribute "RELATIVE_PROPAGATION_DELAY" "-50.00 MIL,50.00 MIL"
					( Parent
						( matchGroupRef "@baseboard_fab2_lib.baseboard_fab2(sch_1):\MG_DQ_FAR_DIMM_NG_M_H_BYTE5\" )
					)
					( Units "uMatchProp" "ns" 1.000000)
					( Status sCSetFlattened )
					( Origin gBackEnd )
				)
			)
			( pinPair "@baseboard_fab2_lib.baseboard_fab2(sch_1):\PP2589\"
				( pinRef "@baseboard_fab2_lib.baseboard_fab2(sch_1):page58_i172:DDR1_DQ(40)" )
				( pinRef "@baseboard_fab2_lib.baseboard_fab2(sch_1):page80_i24:DQ(40)" )
				( attribute "RELATIVE_PROPAGATION_DELAY_SCOPE" "G"
					( Parent
						( matchGroupRef "@baseboard_fab2_lib.baseboard_fab2(sch_1):\MG_DQ-DQS_NEAR_DIMM_NG_M_H_BYTE5\" )
					)
					( Status sCSetFlattened )
					( Origin gBackEnd )
				)
				( attribute "RELATIVE_PROPAGATION_DELAY" "0.00 MIL,195.00 MIL"
					( Parent
						( matchGroupRef "@baseboard_fab2_lib.baseboard_fab2(sch_1):\MG_DQ-DQS_NEAR_DIMM_NG_M_H_BYTE5\" )
					)
					( Units "uMatchProp" "ns" 1.000000)
					( Status sCSetFlattened )
					( Origin gBackEnd )
				)
				( attribute "RELATIVE_PROPAGATION_DELAY_SCOPE" "G"
					( Parent
						( matchGroupRef "@baseboard_fab2_lib.baseboard_fab2(sch_1):\MG_DQ_NEAR_DIMM_NG_M_H_BYTE5\" )
					)
					( Status sCSetFlattened )
					( Origin gBackEnd )
				)
				( attribute "RELATIVE_PROPAGATION_DELAY" "-50.00 MIL,50.00 MIL"
					( Parent
						( matchGroupRef "@baseboard_fab2_lib.baseboard_fab2(sch_1):\MG_DQ_NEAR_DIMM_NG_M_H_BYTE5\" )
					)
					( Units "uMatchProp" "ns" 1.000000)
					( Status sCSetFlattened )
					( Origin gBackEnd )
				)
			)
			( pinPair "@baseboard_fab2_lib.baseboard_fab2(sch_1):\PP2590\"
				( pinRef "@baseboard_fab2_lib.baseboard_fab2(sch_1):page58_i172:DDR1_DQ(41)" )
				( pinRef "@baseboard_fab2_lib.baseboard_fab2(sch_1):page79_i111:DQ(40)" )
				( attribute "RELATIVE_PROPAGATION_DELAY_SCOPE" "G"
					( Parent
						( matchGroupRef "@baseboard_fab2_lib.baseboard_fab2(sch_1):\MG_DQ-DQS_FAR_DIMM_NG_M_H_BYTE5\" )
					)
					( Status sCSetFlattened )
					( Origin gBackEnd )
				)
				( attribute "RELATIVE_PROPAGATION_DELAY" "0.00 MIL,195.00 MIL"
					( Parent
						( matchGroupRef "@baseboard_fab2_lib.baseboard_fab2(sch_1):\MG_DQ-DQS_FAR_DIMM_NG_M_H_BYTE5\" )
					)
					( Units "uMatchProp" "ns" 1.000000)
					( Status sCSetFlattened )
					( Origin gBackEnd )
				)
				( attribute "RELATIVE_PROPAGATION_DELAY_SCOPE" "G"
					( Parent
						( matchGroupRef "@baseboard_fab2_lib.baseboard_fab2(sch_1):\MG_DQ_FAR_DIMM_NG_M_H_BYTE5\" )
					)
					( Status sCSetFlattened )
					( Origin gBackEnd )
				)
				( attribute "RELATIVE_PROPAGATION_DELAY" "-50.00 MIL,50.00 MIL"
					( Parent
						( matchGroupRef "@baseboard_fab2_lib.baseboard_fab2(sch_1):\MG_DQ_FAR_DIMM_NG_M_H_BYTE5\" )
					)
					( Units "uMatchProp" "ns" 1.000000)
					( Status sCSetFlattened )
					( Origin gBackEnd )
				)
			)
			( pinPair "@baseboard_fab2_lib.baseboard_fab2(sch_1):\PP2592\"
				( pinRef "@baseboard_fab2_lib.baseboard_fab2(sch_1):page58_i172:DDR1_DQ(41)" )
				( pinRef "@baseboard_fab2_lib.baseboard_fab2(sch_1):page80_i24:DQ(41)" )
				( attribute "RELATIVE_PROPAGATION_DELAY_SCOPE" "G"
					( Parent
						( matchGroupRef "@baseboard_fab2_lib.baseboard_fab2(sch_1):\MG_DQ-DQS_NEAR_DIMM_NG_M_H_BYTE5\" )
					)
					( Status sCSetFlattened )
					( Origin gBackEnd )
				)
				( attribute "RELATIVE_PROPAGATION_DELAY" "0.00 MIL,195.00 MIL"
					( Parent
						( matchGroupRef "@baseboard_fab2_lib.baseboard_fab2(sch_1):\MG_DQ-DQS_NEAR_DIMM_NG_M_H_BYTE5\" )
					)
					( Units "uMatchProp" "ns" 1.000000)
					( Status sCSetFlattened )
					( Origin gBackEnd )
				)
				( attribute "RELATIVE_PROPAGATION_DELAY_SCOPE" "G"
					( Parent
						( matchGroupRef "@baseboard_fab2_lib.baseboard_fab2(sch_1):\MG_DQ_NEAR_DIMM_NG_M_H_BYTE5\" )
					)
					( Status sCSetFlattened )
					( Origin gBackEnd )
				)
				( attribute "RELATIVE_PROPAGATION_DELAY" "-50.00 MIL,50.00 MIL"
					( Parent
						( matchGroupRef "@baseboard_fab2_lib.baseboard_fab2(sch_1):\MG_DQ_NEAR_DIMM_NG_M_H_BYTE5\" )
					)
					( Units "uMatchProp" "ns" 1.000000)
					( Status sCSetFlattened )
					( Origin gBackEnd )
				)
			)
			( pinPair "@baseboard_fab2_lib.baseboard_fab2(sch_1):\PP2593\"
				( pinRef "@baseboard_fab2_lib.baseboard_fab2(sch_1):page58_i172:DDR1_DQ(42)" )
				( pinRef "@baseboard_fab2_lib.baseboard_fab2(sch_1):page79_i111:DQ(43)" )
				( attribute "RELATIVE_PROPAGATION_DELAY_SCOPE" "G"
					( Parent
						( matchGroupRef "@baseboard_fab2_lib.baseboard_fab2(sch_1):\MG_DQ-DQS_FAR_DIMM_NG_M_H_BYTE5\" )
					)
					( Status sCSetFlattened )
					( Origin gBackEnd )
				)
				( attribute "RELATIVE_PROPAGATION_DELAY" "0.00 MIL,195.00 MIL"
					( Parent
						( matchGroupRef "@baseboard_fab2_lib.baseboard_fab2(sch_1):\MG_DQ-DQS_FAR_DIMM_NG_M_H_BYTE5\" )
					)
					( Units "uMatchProp" "ns" 1.000000)
					( Status sCSetFlattened )
					( Origin gBackEnd )
				)
				( attribute "RELATIVE_PROPAGATION_DELAY_SCOPE" "G"
					( Parent
						( matchGroupRef "@baseboard_fab2_lib.baseboard_fab2(sch_1):\MG_DQ_FAR_DIMM_NG_M_H_BYTE5\" )
					)
					( Status sCSetFlattened )
					( Origin gBackEnd )
				)
				( attribute "RELATIVE_PROPAGATION_DELAY" "-50.00 MIL,50.00 MIL"
					( Parent
						( matchGroupRef "@baseboard_fab2_lib.baseboard_fab2(sch_1):\MG_DQ_FAR_DIMM_NG_M_H_BYTE5\" )
					)
					( Units "uMatchProp" "ns" 1.000000)
					( Status sCSetFlattened )
					( Origin gBackEnd )
				)
			)
			( pinPair "@baseboard_fab2_lib.baseboard_fab2(sch_1):\PP2595\"
				( pinRef "@baseboard_fab2_lib.baseboard_fab2(sch_1):page58_i172:DDR1_DQ(42)" )
				( pinRef "@baseboard_fab2_lib.baseboard_fab2(sch_1):page80_i24:DQ(42)" )
				( attribute "RELATIVE_PROPAGATION_DELAY_SCOPE" "G"
					( Parent
						( matchGroupRef "@baseboard_fab2_lib.baseboard_fab2(sch_1):\MG_DQ-DQS_NEAR_DIMM_NG_M_H_BYTE5\" )
					)
					( Status sCSetFlattened )
					( Origin gBackEnd )
				)
				( attribute "RELATIVE_PROPAGATION_DELAY" "0.00 MIL,195.00 MIL"
					( Parent
						( matchGroupRef "@baseboard_fab2_lib.baseboard_fab2(sch_1):\MG_DQ-DQS_NEAR_DIMM_NG_M_H_BYTE5\" )
					)
					( Units "uMatchProp" "ns" 1.000000)
					( Status sCSetFlattened )
					( Origin gBackEnd )
				)
				( attribute "RELATIVE_PROPAGATION_DELAY_SCOPE" "G"
					( Parent
						( matchGroupRef "@baseboard_fab2_lib.baseboard_fab2(sch_1):\MG_DQ_NEAR_DIMM_NG_M_H_BYTE5\" )
					)
					( Status sCSetFlattened )
					( Origin gBackEnd )
				)
				( attribute "RELATIVE_PROPAGATION_DELAY" "-50.00 MIL,50.00 MIL"
					( Parent
						( matchGroupRef "@baseboard_fab2_lib.baseboard_fab2(sch_1):\MG_DQ_NEAR_DIMM_NG_M_H_BYTE5\" )
					)
					( Units "uMatchProp" "ns" 1.000000)
					( Status sCSetFlattened )
					( Origin gBackEnd )
				)
			)
			( pinPair "@baseboard_fab2_lib.baseboard_fab2(sch_1):\PP2596\"
				( pinRef "@baseboard_fab2_lib.baseboard_fab2(sch_1):page58_i172:DDR1_DQ(43)" )
				( pinRef "@baseboard_fab2_lib.baseboard_fab2(sch_1):page79_i111:DQ(42)" )
				( attribute "RELATIVE_PROPAGATION_DELAY_SCOPE" "G"
					( Parent
						( matchGroupRef "@baseboard_fab2_lib.baseboard_fab2(sch_1):\MG_DQ-DQS_FAR_DIMM_NG_M_H_BYTE5\" )
					)
					( Status sCSetFlattened )
					( Origin gBackEnd )
				)
				( attribute "RELATIVE_PROPAGATION_DELAY" "0.00 MIL,195.00 MIL"
					( Parent
						( matchGroupRef "@baseboard_fab2_lib.baseboard_fab2(sch_1):\MG_DQ-DQS_FAR_DIMM_NG_M_H_BYTE5\" )
					)
					( Units "uMatchProp" "ns" 1.000000)
					( Status sCSetFlattened )
					( Origin gBackEnd )
				)
				( attribute "RELATIVE_PROPAGATION_DELAY_SCOPE" "G"
					( Parent
						( matchGroupRef "@baseboard_fab2_lib.baseboard_fab2(sch_1):\MG_DQ_FAR_DIMM_NG_M_H_BYTE5\" )
					)
					( Status sCSetFlattened )
					( Origin gBackEnd )
				)
				( attribute "RELATIVE_PROPAGATION_DELAY" "-50.00 MIL,50.00 MIL"
					( Parent
						( matchGroupRef "@baseboard_fab2_lib.baseboard_fab2(sch_1):\MG_DQ_FAR_DIMM_NG_M_H_BYTE5\" )
					)
					( Units "uMatchProp" "ns" 1.000000)
					( Status sCSetFlattened )
					( Origin gBackEnd )
				)
			)
			( pinPair "@baseboard_fab2_lib.baseboard_fab2(sch_1):\PP2598\"
				( pinRef "@baseboard_fab2_lib.baseboard_fab2(sch_1):page58_i172:DDR1_DQ(43)" )
				( pinRef "@baseboard_fab2_lib.baseboard_fab2(sch_1):page80_i24:DQ(43)" )
				( attribute "RELATIVE_PROPAGATION_DELAY_SCOPE" "G"
					( Parent
						( matchGroupRef "@baseboard_fab2_lib.baseboard_fab2(sch_1):\MG_DQ-DQS_NEAR_DIMM_NG_M_H_BYTE5\" )
					)
					( Status sCSetFlattened )
					( Origin gBackEnd )
				)
				( attribute "RELATIVE_PROPAGATION_DELAY" "0.00 MIL,195.00 MIL"
					( Parent
						( matchGroupRef "@baseboard_fab2_lib.baseboard_fab2(sch_1):\MG_DQ-DQS_NEAR_DIMM_NG_M_H_BYTE5\" )
					)
					( Units "uMatchProp" "ns" 1.000000)
					( Status sCSetFlattened )
					( Origin gBackEnd )
				)
				( attribute "RELATIVE_PROPAGATION_DELAY_SCOPE" "G"
					( Parent
						( matchGroupRef "@baseboard_fab2_lib.baseboard_fab2(sch_1):\MG_DQ_NEAR_DIMM_NG_M_H_BYTE5\" )
					)
					( Status sCSetFlattened )
					( Origin gBackEnd )
				)
				( attribute "RELATIVE_PROPAGATION_DELAY" "-50.00 MIL,50.00 MIL"
					( Parent
						( matchGroupRef "@baseboard_fab2_lib.baseboard_fab2(sch_1):\MG_DQ_NEAR_DIMM_NG_M_H_BYTE5\" )
					)
					( Units "uMatchProp" "ns" 1.000000)
					( Status sCSetFlattened )
					( Origin gBackEnd )
				)
			)
			( pinPair "@baseboard_fab2_lib.baseboard_fab2(sch_1):\PP2599\"
				( pinRef "@baseboard_fab2_lib.baseboard_fab2(sch_1):page58_i172:DDR1_DQ(44)" )
				( pinRef "@baseboard_fab2_lib.baseboard_fab2(sch_1):page79_i111:DQ(45)" )
				( attribute "RELATIVE_PROPAGATION_DELAY_SCOPE" "G"
					( Parent
						( matchGroupRef "@baseboard_fab2_lib.baseboard_fab2(sch_1):\MG_DQ-DQS_FAR_DIMM_NG_M_H_BYTE5\" )
					)
					( Status sCSetFlattened )
					( Origin gBackEnd )
				)
				( attribute "RELATIVE_PROPAGATION_DELAY" "0.00 MIL,195.00 MIL"
					( Parent
						( matchGroupRef "@baseboard_fab2_lib.baseboard_fab2(sch_1):\MG_DQ-DQS_FAR_DIMM_NG_M_H_BYTE5\" )
					)
					( Units "uMatchProp" "ns" 1.000000)
					( Status sCSetFlattened )
					( Origin gBackEnd )
				)
				( attribute "RELATIVE_PROPAGATION_DELAY_SCOPE" "G"
					( Parent
						( matchGroupRef "@baseboard_fab2_lib.baseboard_fab2(sch_1):\MG_DQ_FAR_DIMM_NG_M_H_BYTE5\" )
					)
					( Status sCSetFlattened )
					( Origin gBackEnd )
				)
				( attribute "RELATIVE_PROPAGATION_DELAY" "-50.00 MIL,50.00 MIL"
					( Parent
						( matchGroupRef "@baseboard_fab2_lib.baseboard_fab2(sch_1):\MG_DQ_FAR_DIMM_NG_M_H_BYTE5\" )
					)
					( Units "uMatchProp" "ns" 1.000000)
					( Status sCSetFlattened )
					( Origin gBackEnd )
				)
			)
			( pinPair "@baseboard_fab2_lib.baseboard_fab2(sch_1):\PP2601\"
				( pinRef "@baseboard_fab2_lib.baseboard_fab2(sch_1):page58_i172:DDR1_DQ(44)" )
				( pinRef "@baseboard_fab2_lib.baseboard_fab2(sch_1):page80_i24:DQ(44)" )
				( attribute "RELATIVE_PROPAGATION_DELAY_SCOPE" "G"
					( Parent
						( matchGroupRef "@baseboard_fab2_lib.baseboard_fab2(sch_1):\MG_DQ-DQS_NEAR_DIMM_NG_M_H_BYTE5\" )
					)
					( Status sCSetFlattened )
					( Origin gBackEnd )
				)
				( attribute "RELATIVE_PROPAGATION_DELAY" "0.00 MIL,195.00 MIL"
					( Parent
						( matchGroupRef "@baseboard_fab2_lib.baseboard_fab2(sch_1):\MG_DQ-DQS_NEAR_DIMM_NG_M_H_BYTE5\" )
					)
					( Units "uMatchProp" "ns" 1.000000)
					( Status sCSetFlattened )
					( Origin gBackEnd )
				)
				( attribute "RELATIVE_PROPAGATION_DELAY_SCOPE" "G"
					( Parent
						( matchGroupRef "@baseboard_fab2_lib.baseboard_fab2(sch_1):\MG_DQ_NEAR_DIMM_NG_M_H_BYTE5\" )
					)
					( Status sCSetFlattened )
					( Origin gBackEnd )
				)
				( attribute "RELATIVE_PROPAGATION_DELAY" "-50.00 MIL,50.00 MIL"
					( Parent
						( matchGroupRef "@baseboard_fab2_lib.baseboard_fab2(sch_1):\MG_DQ_NEAR_DIMM_NG_M_H_BYTE5\" )
					)
					( Units "uMatchProp" "ns" 1.000000)
					( Status sCSetFlattened )
					( Origin gBackEnd )
				)
			)
			( pinPair "@baseboard_fab2_lib.baseboard_fab2(sch_1):\PP2602\"
				( pinRef "@baseboard_fab2_lib.baseboard_fab2(sch_1):page58_i172:DDR1_DQ(45)" )
				( pinRef "@baseboard_fab2_lib.baseboard_fab2(sch_1):page79_i111:DQ(44)" )
				( attribute "RELATIVE_PROPAGATION_DELAY_SCOPE" "G"
					( Parent
						( matchGroupRef "@baseboard_fab2_lib.baseboard_fab2(sch_1):\MG_DQ-DQS_FAR_DIMM_NG_M_H_BYTE5\" )
					)
					( Status sCSetFlattened )
					( Origin gBackEnd )
				)
				( attribute "RELATIVE_PROPAGATION_DELAY" "0.00 MIL,195.00 MIL"
					( Parent
						( matchGroupRef "@baseboard_fab2_lib.baseboard_fab2(sch_1):\MG_DQ-DQS_FAR_DIMM_NG_M_H_BYTE5\" )
					)
					( Units "uMatchProp" "ns" 1.000000)
					( Status sCSetFlattened )
					( Origin gBackEnd )
				)
				( attribute "RELATIVE_PROPAGATION_DELAY_SCOPE" "G"
					( Parent
						( matchGroupRef "@baseboard_fab2_lib.baseboard_fab2(sch_1):\MG_DQ_FAR_DIMM_NG_M_H_BYTE5\" )
					)
					( Status sCSetFlattened )
					( Origin gBackEnd )
				)
				( attribute "RELATIVE_PROPAGATION_DELAY" "-50.00 MIL,50.00 MIL"
					( Parent
						( matchGroupRef "@baseboard_fab2_lib.baseboard_fab2(sch_1):\MG_DQ_FAR_DIMM_NG_M_H_BYTE5\" )
					)
					( Units "uMatchProp" "ns" 1.000000)
					( Status sCSetFlattened )
					( Origin gBackEnd )
				)
			)
			( pinPair "@baseboard_fab2_lib.baseboard_fab2(sch_1):\PP2604\"
				( pinRef "@baseboard_fab2_lib.baseboard_fab2(sch_1):page58_i172:DDR1_DQ(45)" )
				( pinRef "@baseboard_fab2_lib.baseboard_fab2(sch_1):page80_i24:DQ(45)" )
				( attribute "RELATIVE_PROPAGATION_DELAY_SCOPE" "G"
					( Parent
						( matchGroupRef "@baseboard_fab2_lib.baseboard_fab2(sch_1):\MG_DQ-DQS_NEAR_DIMM_NG_M_H_BYTE5\" )
					)
					( Status sCSetFlattened )
					( Origin gBackEnd )
				)
				( attribute "RELATIVE_PROPAGATION_DELAY" "0.00 MIL,195.00 MIL"
					( Parent
						( matchGroupRef "@baseboard_fab2_lib.baseboard_fab2(sch_1):\MG_DQ-DQS_NEAR_DIMM_NG_M_H_BYTE5\" )
					)
					( Units "uMatchProp" "ns" 1.000000)
					( Status sCSetFlattened )
					( Origin gBackEnd )
				)
				( attribute "RELATIVE_PROPAGATION_DELAY_SCOPE" "G"
					( Parent
						( matchGroupRef "@baseboard_fab2_lib.baseboard_fab2(sch_1):\MG_DQ_NEAR_DIMM_NG_M_H_BYTE5\" )
					)
					( Status sCSetFlattened )
					( Origin gBackEnd )
				)
				( attribute "RELATIVE_PROPAGATION_DELAY" "-50.00 MIL,50.00 MIL"
					( Parent
						( matchGroupRef "@baseboard_fab2_lib.baseboard_fab2(sch_1):\MG_DQ_NEAR_DIMM_NG_M_H_BYTE5\" )
					)
					( Units "uMatchProp" "ns" 1.000000)
					( Status sCSetFlattened )
					( Origin gBackEnd )
				)
			)
			( pinPair "@baseboard_fab2_lib.baseboard_fab2(sch_1):\PP2605\"
				( pinRef "@baseboard_fab2_lib.baseboard_fab2(sch_1):page58_i172:DDR1_DQ(46)" )
				( pinRef "@baseboard_fab2_lib.baseboard_fab2(sch_1):page79_i111:DQ(47)" )
				( attribute "RELATIVE_PROPAGATION_DELAY_SCOPE" "G"
					( Parent
						( matchGroupRef "@baseboard_fab2_lib.baseboard_fab2(sch_1):\MG_DQ-DQS_FAR_DIMM_NG_M_H_BYTE5\" )
					)
					( Status sCSetFlattened )
					( Origin gBackEnd )
				)
				( attribute "RELATIVE_PROPAGATION_DELAY" "0.00 MIL,195.00 MIL"
					( Parent
						( matchGroupRef "@baseboard_fab2_lib.baseboard_fab2(sch_1):\MG_DQ-DQS_FAR_DIMM_NG_M_H_BYTE5\" )
					)
					( Units "uMatchProp" "ns" 1.000000)
					( Status sCSetFlattened )
					( Origin gBackEnd )
				)
				( attribute "RELATIVE_PROPAGATION_DELAY_SCOPE" "G"
					( Parent
						( matchGroupRef "@baseboard_fab2_lib.baseboard_fab2(sch_1):\MG_DQ_FAR_DIMM_NG_M_H_BYTE5\" )
					)
					( Status sCSetFlattened )
					( Origin gBackEnd )
				)
				( attribute "RELATIVE_PROPAGATION_DELAY" "-50.00 MIL,50.00 MIL"
					( Parent
						( matchGroupRef "@baseboard_fab2_lib.baseboard_fab2(sch_1):\MG_DQ_FAR_DIMM_NG_M_H_BYTE5\" )
					)
					( Units "uMatchProp" "ns" 1.000000)
					( Status sCSetFlattened )
					( Origin gBackEnd )
				)
			)
			( pinPair "@baseboard_fab2_lib.baseboard_fab2(sch_1):\PP2607\"
				( pinRef "@baseboard_fab2_lib.baseboard_fab2(sch_1):page58_i172:DDR1_DQ(46)" )
				( pinRef "@baseboard_fab2_lib.baseboard_fab2(sch_1):page80_i24:DQ(46)" )
				( attribute "RELATIVE_PROPAGATION_DELAY_SCOPE" "G"
					( Parent
						( matchGroupRef "@baseboard_fab2_lib.baseboard_fab2(sch_1):\MG_DQ-DQS_NEAR_DIMM_NG_M_H_BYTE5\" )
					)
					( Status sCSetFlattened )
					( Origin gBackEnd )
				)
				( attribute "RELATIVE_PROPAGATION_DELAY" "0.00 MIL,195.00 MIL"
					( Parent
						( matchGroupRef "@baseboard_fab2_lib.baseboard_fab2(sch_1):\MG_DQ-DQS_NEAR_DIMM_NG_M_H_BYTE5\" )
					)
					( Units "uMatchProp" "ns" 1.000000)
					( Status sCSetFlattened )
					( Origin gBackEnd )
				)
				( attribute "RELATIVE_PROPAGATION_DELAY_SCOPE" "G"
					( Parent
						( matchGroupRef "@baseboard_fab2_lib.baseboard_fab2(sch_1):\MG_DQ_NEAR_DIMM_NG_M_H_BYTE5\" )
					)
					( Status sCSetFlattened )
					( Origin gBackEnd )
				)
				( attribute "RELATIVE_PROPAGATION_DELAY" "-50.00 MIL,50.00 MIL"
					( Parent
						( matchGroupRef "@baseboard_fab2_lib.baseboard_fab2(sch_1):\MG_DQ_NEAR_DIMM_NG_M_H_BYTE5\" )
					)
					( Units "uMatchProp" "ns" 1.000000)
					( Status sCSetFlattened )
					( Origin gBackEnd )
				)
			)
			( pinPair "@baseboard_fab2_lib.baseboard_fab2(sch_1):\PP2608\"
				( pinRef "@baseboard_fab2_lib.baseboard_fab2(sch_1):page58_i172:DDR1_DQ(47)" )
				( pinRef "@baseboard_fab2_lib.baseboard_fab2(sch_1):page79_i111:DQ(46)" )
				( attribute "RELATIVE_PROPAGATION_DELAY_SCOPE" "G"
					( Parent
						( matchGroupRef "@baseboard_fab2_lib.baseboard_fab2(sch_1):\MG_DQ-DQS_FAR_DIMM_NG_M_H_BYTE5\" )
					)
					( Status sCSetFlattened )
					( Origin gBackEnd )
				)
				( attribute "RELATIVE_PROPAGATION_DELAY" "0.00 MIL,195.00 MIL"
					( Parent
						( matchGroupRef "@baseboard_fab2_lib.baseboard_fab2(sch_1):\MG_DQ-DQS_FAR_DIMM_NG_M_H_BYTE5\" )
					)
					( Units "uMatchProp" "ns" 1.000000)
					( Status sCSetFlattened )
					( Origin gBackEnd )
				)
				( attribute "RELATIVE_PROPAGATION_DELAY_SCOPE" "G"
					( Parent
						( matchGroupRef "@baseboard_fab2_lib.baseboard_fab2(sch_1):\MG_DQ_FAR_DIMM_NG_M_H_BYTE5\" )
					)
					( Status sCSetFlattened )
					( Origin gBackEnd )
				)
				( attribute "RELATIVE_PROPAGATION_DELAY" "-50.00 MIL,50.00 MIL"
					( Parent
						( matchGroupRef "@baseboard_fab2_lib.baseboard_fab2(sch_1):\MG_DQ_FAR_DIMM_NG_M_H_BYTE5\" )
					)
					( Units "uMatchProp" "ns" 1.000000)
					( Status sCSetFlattened )
					( Origin gBackEnd )
				)
			)
			( pinPair "@baseboard_fab2_lib.baseboard_fab2(sch_1):\PP2610\"
				( pinRef "@baseboard_fab2_lib.baseboard_fab2(sch_1):page58_i172:DDR1_DQ(47)" )
				( pinRef "@baseboard_fab2_lib.baseboard_fab2(sch_1):page80_i24:DQ(47)" )
				( attribute "RELATIVE_PROPAGATION_DELAY_SCOPE" "G"
					( Parent
						( matchGroupRef "@baseboard_fab2_lib.baseboard_fab2(sch_1):\MG_DQ-DQS_NEAR_DIMM_NG_M_H_BYTE5\" )
					)
					( Status sCSetFlattened )
					( Origin gBackEnd )
				)
				( attribute "RELATIVE_PROPAGATION_DELAY" "0.00 MIL,195.00 MIL"
					( Parent
						( matchGroupRef "@baseboard_fab2_lib.baseboard_fab2(sch_1):\MG_DQ-DQS_NEAR_DIMM_NG_M_H_BYTE5\" )
					)
					( Units "uMatchProp" "ns" 1.000000)
					( Status sCSetFlattened )
					( Origin gBackEnd )
				)
				( attribute "RELATIVE_PROPAGATION_DELAY_SCOPE" "G"
					( Parent
						( matchGroupRef "@baseboard_fab2_lib.baseboard_fab2(sch_1):\MG_DQ_NEAR_DIMM_NG_M_H_BYTE5\" )
					)
					( Status sCSetFlattened )
					( Origin gBackEnd )
				)
				( attribute "RELATIVE_PROPAGATION_DELAY" "-50.00 MIL,50.00 MIL"
					( Parent
						( matchGroupRef "@baseboard_fab2_lib.baseboard_fab2(sch_1):\MG_DQ_NEAR_DIMM_NG_M_H_BYTE5\" )
					)
					( Units "uMatchProp" "ns" 1.000000)
					( Status sCSetFlattened )
					( Origin gBackEnd )
				)
			)
			( pinPair "@baseboard_fab2_lib.baseboard_fab2(sch_1):\PP2563\"
				( pinRef "@baseboard_fab2_lib.baseboard_fab2(sch_1):page58_i172:DDR1_DQ(48)" )
				( pinRef "@baseboard_fab2_lib.baseboard_fab2(sch_1):page79_i111:DQ(49)" )
				( attribute "RELATIVE_PROPAGATION_DELAY_SCOPE" "G"
					( Parent
						( matchGroupRef "@baseboard_fab2_lib.baseboard_fab2(sch_1):\MG_DQ-DQS_FAR_DIMM_NG_M_H_BYTE6\" )
					)
					( Status sCSetFlattened )
					( Origin gBackEnd )
				)
				( attribute "RELATIVE_PROPAGATION_DELAY" "0.00 MIL,195.00 MIL"
					( Parent
						( matchGroupRef "@baseboard_fab2_lib.baseboard_fab2(sch_1):\MG_DQ-DQS_FAR_DIMM_NG_M_H_BYTE6\" )
					)
					( Units "uMatchProp" "ns" 1.000000)
					( Status sCSetFlattened )
					( Origin gBackEnd )
				)
				( attribute "RELATIVE_PROPAGATION_DELAY_SCOPE" "G"
					( Parent
						( matchGroupRef "@baseboard_fab2_lib.baseboard_fab2(sch_1):\MG_DQ_FAR_DIMM_NG_M_H_BYTE6\" )
					)
					( Status sCSetFlattened )
					( Origin gBackEnd )
				)
				( attribute "RELATIVE_PROPAGATION_DELAY" "-50.00 MIL,50.00 MIL"
					( Parent
						( matchGroupRef "@baseboard_fab2_lib.baseboard_fab2(sch_1):\MG_DQ_FAR_DIMM_NG_M_H_BYTE6\" )
					)
					( Units "uMatchProp" "ns" 1.000000)
					( Status sCSetFlattened )
					( Origin gBackEnd )
				)
			)
			( pinPair "@baseboard_fab2_lib.baseboard_fab2(sch_1):\PP2565\"
				( pinRef "@baseboard_fab2_lib.baseboard_fab2(sch_1):page58_i172:DDR1_DQ(48)" )
				( pinRef "@baseboard_fab2_lib.baseboard_fab2(sch_1):page80_i24:DQ(48)" )
				( attribute "RELATIVE_PROPAGATION_DELAY_SCOPE" "G"
					( Parent
						( matchGroupRef "@baseboard_fab2_lib.baseboard_fab2(sch_1):\MG_DQ-DQS_NEAR_DIMM_NG_M_H_BYTE6\" )
					)
					( Status sCSetFlattened )
					( Origin gBackEnd )
				)
				( attribute "RELATIVE_PROPAGATION_DELAY" "0.00 MIL,195.00 MIL"
					( Parent
						( matchGroupRef "@baseboard_fab2_lib.baseboard_fab2(sch_1):\MG_DQ-DQS_NEAR_DIMM_NG_M_H_BYTE6\" )
					)
					( Units "uMatchProp" "ns" 1.000000)
					( Status sCSetFlattened )
					( Origin gBackEnd )
				)
				( attribute "RELATIVE_PROPAGATION_DELAY_SCOPE" "G"
					( Parent
						( matchGroupRef "@baseboard_fab2_lib.baseboard_fab2(sch_1):\MG_DQ_NEAR_DIMM_NG_M_H_BYTE6\" )
					)
					( Status sCSetFlattened )
					( Origin gBackEnd )
				)
				( attribute "RELATIVE_PROPAGATION_DELAY" "-50.00 MIL,50.00 MIL"
					( Parent
						( matchGroupRef "@baseboard_fab2_lib.baseboard_fab2(sch_1):\MG_DQ_NEAR_DIMM_NG_M_H_BYTE6\" )
					)
					( Units "uMatchProp" "ns" 1.000000)
					( Status sCSetFlattened )
					( Origin gBackEnd )
				)
			)
			( pinPair "@baseboard_fab2_lib.baseboard_fab2(sch_1):\PP2566\"
				( pinRef "@baseboard_fab2_lib.baseboard_fab2(sch_1):page58_i172:DDR1_DQ(49)" )
				( pinRef "@baseboard_fab2_lib.baseboard_fab2(sch_1):page79_i111:DQ(48)" )
				( attribute "RELATIVE_PROPAGATION_DELAY_SCOPE" "G"
					( Parent
						( matchGroupRef "@baseboard_fab2_lib.baseboard_fab2(sch_1):\MG_DQ-DQS_FAR_DIMM_NG_M_H_BYTE6\" )
					)
					( Status sCSetFlattened )
					( Origin gBackEnd )
				)
				( attribute "RELATIVE_PROPAGATION_DELAY" "0.00 MIL,195.00 MIL"
					( Parent
						( matchGroupRef "@baseboard_fab2_lib.baseboard_fab2(sch_1):\MG_DQ-DQS_FAR_DIMM_NG_M_H_BYTE6\" )
					)
					( Units "uMatchProp" "ns" 1.000000)
					( Status sCSetFlattened )
					( Origin gBackEnd )
				)
				( attribute "RELATIVE_PROPAGATION_DELAY_SCOPE" "G"
					( Parent
						( matchGroupRef "@baseboard_fab2_lib.baseboard_fab2(sch_1):\MG_DQ_FAR_DIMM_NG_M_H_BYTE6\" )
					)
					( Status sCSetFlattened )
					( Origin gBackEnd )
				)
				( attribute "RELATIVE_PROPAGATION_DELAY" "-50.00 MIL,50.00 MIL"
					( Parent
						( matchGroupRef "@baseboard_fab2_lib.baseboard_fab2(sch_1):\MG_DQ_FAR_DIMM_NG_M_H_BYTE6\" )
					)
					( Units "uMatchProp" "ns" 1.000000)
					( Status sCSetFlattened )
					( Origin gBackEnd )
				)
			)
			( pinPair "@baseboard_fab2_lib.baseboard_fab2(sch_1):\PP2568\"
				( pinRef "@baseboard_fab2_lib.baseboard_fab2(sch_1):page80_i24:DQ(49)" )
				( pinRef "@baseboard_fab2_lib.baseboard_fab2(sch_1):page58_i172:DDR1_DQ(49)" )
				( attribute "RELATIVE_PROPAGATION_DELAY_SCOPE" "G"
					( Parent
						( matchGroupRef "@baseboard_fab2_lib.baseboard_fab2(sch_1):\MG_DQ-DQS_NEAR_DIMM_NG_M_H_BYTE6\" )
					)
					( Status sCSetFlattened )
					( Origin gBackEnd )
				)
				( attribute "RELATIVE_PROPAGATION_DELAY" "0.00 MIL,195.00 MIL"
					( Parent
						( matchGroupRef "@baseboard_fab2_lib.baseboard_fab2(sch_1):\MG_DQ-DQS_NEAR_DIMM_NG_M_H_BYTE6\" )
					)
					( Units "uMatchProp" "ns" 1.000000)
					( Status sCSetFlattened )
					( Origin gBackEnd )
				)
				( attribute "RELATIVE_PROPAGATION_DELAY_SCOPE" "G"
					( Parent
						( matchGroupRef "@baseboard_fab2_lib.baseboard_fab2(sch_1):\MG_DQ_NEAR_DIMM_NG_M_H_BYTE6\" )
					)
					( Status sCSetFlattened )
					( Origin gBackEnd )
				)
				( attribute "RELATIVE_PROPAGATION_DELAY" "-50.00 MIL,50.00 MIL"
					( Parent
						( matchGroupRef "@baseboard_fab2_lib.baseboard_fab2(sch_1):\MG_DQ_NEAR_DIMM_NG_M_H_BYTE6\" )
					)
					( Units "uMatchProp" "ns" 1.000000)
					( Status sCSetFlattened )
					( Origin gBackEnd )
				)
			)
			( pinPair "@baseboard_fab2_lib.baseboard_fab2(sch_1):\PP2569\"
				( pinRef "@baseboard_fab2_lib.baseboard_fab2(sch_1):page58_i172:DDR1_DQ(50)" )
				( pinRef "@baseboard_fab2_lib.baseboard_fab2(sch_1):page79_i111:DQ(51)" )
				( attribute "RELATIVE_PROPAGATION_DELAY_SCOPE" "G"
					( Parent
						( matchGroupRef "@baseboard_fab2_lib.baseboard_fab2(sch_1):\MG_DQ-DQS_FAR_DIMM_NG_M_H_BYTE6\" )
					)
					( Status sCSetFlattened )
					( Origin gBackEnd )
				)
				( attribute "RELATIVE_PROPAGATION_DELAY" "0.00 MIL,195.00 MIL"
					( Parent
						( matchGroupRef "@baseboard_fab2_lib.baseboard_fab2(sch_1):\MG_DQ-DQS_FAR_DIMM_NG_M_H_BYTE6\" )
					)
					( Units "uMatchProp" "ns" 1.000000)
					( Status sCSetFlattened )
					( Origin gBackEnd )
				)
				( attribute "RELATIVE_PROPAGATION_DELAY_SCOPE" "G"
					( Parent
						( matchGroupRef "@baseboard_fab2_lib.baseboard_fab2(sch_1):\MG_DQ_FAR_DIMM_NG_M_H_BYTE6\" )
					)
					( Status sCSetFlattened )
					( Origin gBackEnd )
				)
				( attribute "RELATIVE_PROPAGATION_DELAY" "-50.00 MIL,50.00 MIL"
					( Parent
						( matchGroupRef "@baseboard_fab2_lib.baseboard_fab2(sch_1):\MG_DQ_FAR_DIMM_NG_M_H_BYTE6\" )
					)
					( Units "uMatchProp" "ns" 1.000000)
					( Status sCSetFlattened )
					( Origin gBackEnd )
				)
			)
			( pinPair "@baseboard_fab2_lib.baseboard_fab2(sch_1):\PP2571\"
				( pinRef "@baseboard_fab2_lib.baseboard_fab2(sch_1):page58_i172:DDR1_DQ(50)" )
				( pinRef "@baseboard_fab2_lib.baseboard_fab2(sch_1):page80_i24:DQ(50)" )
				( attribute "RELATIVE_PROPAGATION_DELAY_SCOPE" "G"
					( Parent
						( matchGroupRef "@baseboard_fab2_lib.baseboard_fab2(sch_1):\MG_DQ-DQS_NEAR_DIMM_NG_M_H_BYTE6\" )
					)
					( Status sCSetFlattened )
					( Origin gBackEnd )
				)
				( attribute "RELATIVE_PROPAGATION_DELAY" "0.00 MIL,195.00 MIL"
					( Parent
						( matchGroupRef "@baseboard_fab2_lib.baseboard_fab2(sch_1):\MG_DQ-DQS_NEAR_DIMM_NG_M_H_BYTE6\" )
					)
					( Units "uMatchProp" "ns" 1.000000)
					( Status sCSetFlattened )
					( Origin gBackEnd )
				)
				( attribute "RELATIVE_PROPAGATION_DELAY_SCOPE" "G"
					( Parent
						( matchGroupRef "@baseboard_fab2_lib.baseboard_fab2(sch_1):\MG_DQ_NEAR_DIMM_NG_M_H_BYTE6\" )
					)
					( Status sCSetFlattened )
					( Origin gBackEnd )
				)
				( attribute "RELATIVE_PROPAGATION_DELAY" "-50.00 MIL,50.00 MIL"
					( Parent
						( matchGroupRef "@baseboard_fab2_lib.baseboard_fab2(sch_1):\MG_DQ_NEAR_DIMM_NG_M_H_BYTE6\" )
					)
					( Units "uMatchProp" "ns" 1.000000)
					( Status sCSetFlattened )
					( Origin gBackEnd )
				)
			)
			( pinPair "@baseboard_fab2_lib.baseboard_fab2(sch_1):\PP2572\"
				( pinRef "@baseboard_fab2_lib.baseboard_fab2(sch_1):page58_i172:DDR1_DQ(51)" )
				( pinRef "@baseboard_fab2_lib.baseboard_fab2(sch_1):page79_i111:DQ(50)" )
				( attribute "RELATIVE_PROPAGATION_DELAY_SCOPE" "G"
					( Parent
						( matchGroupRef "@baseboard_fab2_lib.baseboard_fab2(sch_1):\MG_DQ-DQS_FAR_DIMM_NG_M_H_BYTE6\" )
					)
					( Status sCSetFlattened )
					( Origin gBackEnd )
				)
				( attribute "RELATIVE_PROPAGATION_DELAY" "0.00 MIL,195.00 MIL"
					( Parent
						( matchGroupRef "@baseboard_fab2_lib.baseboard_fab2(sch_1):\MG_DQ-DQS_FAR_DIMM_NG_M_H_BYTE6\" )
					)
					( Units "uMatchProp" "ns" 1.000000)
					( Status sCSetFlattened )
					( Origin gBackEnd )
				)
				( attribute "RELATIVE_PROPAGATION_DELAY_SCOPE" "G"
					( Parent
						( matchGroupRef "@baseboard_fab2_lib.baseboard_fab2(sch_1):\MG_DQ_FAR_DIMM_NG_M_H_BYTE6\" )
					)
					( Status sCSetFlattened )
					( Origin gBackEnd )
				)
				( attribute "RELATIVE_PROPAGATION_DELAY" "-50.00 MIL,50.00 MIL"
					( Parent
						( matchGroupRef "@baseboard_fab2_lib.baseboard_fab2(sch_1):\MG_DQ_FAR_DIMM_NG_M_H_BYTE6\" )
					)
					( Units "uMatchProp" "ns" 1.000000)
					( Status sCSetFlattened )
					( Origin gBackEnd )
				)
			)
			( pinPair "@baseboard_fab2_lib.baseboard_fab2(sch_1):\PP2574\"
				( pinRef "@baseboard_fab2_lib.baseboard_fab2(sch_1):page58_i172:DDR1_DQ(51)" )
				( pinRef "@baseboard_fab2_lib.baseboard_fab2(sch_1):page80_i24:DQ(51)" )
				( attribute "RELATIVE_PROPAGATION_DELAY_SCOPE" "G"
					( Parent
						( matchGroupRef "@baseboard_fab2_lib.baseboard_fab2(sch_1):\MG_DQ-DQS_NEAR_DIMM_NG_M_H_BYTE6\" )
					)
					( Status sCSetFlattened )
					( Origin gBackEnd )
				)
				( attribute "RELATIVE_PROPAGATION_DELAY" "0.00 MIL,195.00 MIL"
					( Parent
						( matchGroupRef "@baseboard_fab2_lib.baseboard_fab2(sch_1):\MG_DQ-DQS_NEAR_DIMM_NG_M_H_BYTE6\" )
					)
					( Units "uMatchProp" "ns" 1.000000)
					( Status sCSetFlattened )
					( Origin gBackEnd )
				)
				( attribute "RELATIVE_PROPAGATION_DELAY_SCOPE" "G"
					( Parent
						( matchGroupRef "@baseboard_fab2_lib.baseboard_fab2(sch_1):\MG_DQ_NEAR_DIMM_NG_M_H_BYTE6\" )
					)
					( Status sCSetFlattened )
					( Origin gBackEnd )
				)
				( attribute "RELATIVE_PROPAGATION_DELAY" "-50.00 MIL,50.00 MIL"
					( Parent
						( matchGroupRef "@baseboard_fab2_lib.baseboard_fab2(sch_1):\MG_DQ_NEAR_DIMM_NG_M_H_BYTE6\" )
					)
					( Units "uMatchProp" "ns" 1.000000)
					( Status sCSetFlattened )
					( Origin gBackEnd )
				)
			)
			( pinPair "@baseboard_fab2_lib.baseboard_fab2(sch_1):\PP2575\"
				( pinRef "@baseboard_fab2_lib.baseboard_fab2(sch_1):page58_i172:DDR1_DQ(52)" )
				( pinRef "@baseboard_fab2_lib.baseboard_fab2(sch_1):page79_i111:DQ(53)" )
				( attribute "RELATIVE_PROPAGATION_DELAY_SCOPE" "G"
					( Parent
						( matchGroupRef "@baseboard_fab2_lib.baseboard_fab2(sch_1):\MG_DQ-DQS_FAR_DIMM_NG_M_H_BYTE6\" )
					)
					( Status sCSetFlattened )
					( Origin gBackEnd )
				)
				( attribute "RELATIVE_PROPAGATION_DELAY" "0.00 MIL,195.00 MIL"
					( Parent
						( matchGroupRef "@baseboard_fab2_lib.baseboard_fab2(sch_1):\MG_DQ-DQS_FAR_DIMM_NG_M_H_BYTE6\" )
					)
					( Units "uMatchProp" "ns" 1.000000)
					( Status sCSetFlattened )
					( Origin gBackEnd )
				)
				( attribute "RELATIVE_PROPAGATION_DELAY_SCOPE" "G"
					( Parent
						( matchGroupRef "@baseboard_fab2_lib.baseboard_fab2(sch_1):\MG_DQ_FAR_DIMM_NG_M_H_BYTE6\" )
					)
					( Status sCSetFlattened )
					( Origin gBackEnd )
				)
				( attribute "RELATIVE_PROPAGATION_DELAY" "-50.00 MIL,50.00 MIL"
					( Parent
						( matchGroupRef "@baseboard_fab2_lib.baseboard_fab2(sch_1):\MG_DQ_FAR_DIMM_NG_M_H_BYTE6\" )
					)
					( Units "uMatchProp" "ns" 1.000000)
					( Status sCSetFlattened )
					( Origin gBackEnd )
				)
			)
			( pinPair "@baseboard_fab2_lib.baseboard_fab2(sch_1):\PP2577\"
				( pinRef "@baseboard_fab2_lib.baseboard_fab2(sch_1):page58_i172:DDR1_DQ(52)" )
				( pinRef "@baseboard_fab2_lib.baseboard_fab2(sch_1):page80_i24:DQ(52)" )
				( attribute "RELATIVE_PROPAGATION_DELAY_SCOPE" "G"
					( Parent
						( matchGroupRef "@baseboard_fab2_lib.baseboard_fab2(sch_1):\MG_DQ-DQS_NEAR_DIMM_NG_M_H_BYTE6\" )
					)
					( Status sCSetFlattened )
					( Origin gBackEnd )
				)
				( attribute "RELATIVE_PROPAGATION_DELAY" "0.00 MIL,195.00 MIL"
					( Parent
						( matchGroupRef "@baseboard_fab2_lib.baseboard_fab2(sch_1):\MG_DQ-DQS_NEAR_DIMM_NG_M_H_BYTE6\" )
					)
					( Units "uMatchProp" "ns" 1.000000)
					( Status sCSetFlattened )
					( Origin gBackEnd )
				)
				( attribute "RELATIVE_PROPAGATION_DELAY_SCOPE" "G"
					( Parent
						( matchGroupRef "@baseboard_fab2_lib.baseboard_fab2(sch_1):\MG_DQ_NEAR_DIMM_NG_M_H_BYTE6\" )
					)
					( Status sCSetFlattened )
					( Origin gBackEnd )
				)
				( attribute "RELATIVE_PROPAGATION_DELAY" "-50.00 MIL,50.00 MIL"
					( Parent
						( matchGroupRef "@baseboard_fab2_lib.baseboard_fab2(sch_1):\MG_DQ_NEAR_DIMM_NG_M_H_BYTE6\" )
					)
					( Units "uMatchProp" "ns" 1.000000)
					( Status sCSetFlattened )
					( Origin gBackEnd )
				)
			)
			( pinPair "@baseboard_fab2_lib.baseboard_fab2(sch_1):\PP2578\"
				( pinRef "@baseboard_fab2_lib.baseboard_fab2(sch_1):page58_i172:DDR1_DQ(53)" )
				( pinRef "@baseboard_fab2_lib.baseboard_fab2(sch_1):page79_i111:DQ(52)" )
				( attribute "RELATIVE_PROPAGATION_DELAY_SCOPE" "G"
					( Parent
						( matchGroupRef "@baseboard_fab2_lib.baseboard_fab2(sch_1):\MG_DQ-DQS_FAR_DIMM_NG_M_H_BYTE6\" )
					)
					( Status sCSetFlattened )
					( Origin gBackEnd )
				)
				( attribute "RELATIVE_PROPAGATION_DELAY" "0.00 MIL,195.00 MIL"
					( Parent
						( matchGroupRef "@baseboard_fab2_lib.baseboard_fab2(sch_1):\MG_DQ-DQS_FAR_DIMM_NG_M_H_BYTE6\" )
					)
					( Units "uMatchProp" "ns" 1.000000)
					( Status sCSetFlattened )
					( Origin gBackEnd )
				)
				( attribute "RELATIVE_PROPAGATION_DELAY_SCOPE" "G"
					( Parent
						( matchGroupRef "@baseboard_fab2_lib.baseboard_fab2(sch_1):\MG_DQ_FAR_DIMM_NG_M_H_BYTE6\" )
					)
					( Status sCSetFlattened )
					( Origin gBackEnd )
				)
				( attribute "RELATIVE_PROPAGATION_DELAY" "-50.00 MIL,50.00 MIL"
					( Parent
						( matchGroupRef "@baseboard_fab2_lib.baseboard_fab2(sch_1):\MG_DQ_FAR_DIMM_NG_M_H_BYTE6\" )
					)
					( Units "uMatchProp" "ns" 1.000000)
					( Status sCSetFlattened )
					( Origin gBackEnd )
				)
			)
			( pinPair "@baseboard_fab2_lib.baseboard_fab2(sch_1):\PP2580\"
				( pinRef "@baseboard_fab2_lib.baseboard_fab2(sch_1):page58_i172:DDR1_DQ(53)" )
				( pinRef "@baseboard_fab2_lib.baseboard_fab2(sch_1):page80_i24:DQ(53)" )
				( attribute "RELATIVE_PROPAGATION_DELAY_SCOPE" "G"
					( Parent
						( matchGroupRef "@baseboard_fab2_lib.baseboard_fab2(sch_1):\MG_DQ-DQS_NEAR_DIMM_NG_M_H_BYTE6\" )
					)
					( Status sCSetFlattened )
					( Origin gBackEnd )
				)
				( attribute "RELATIVE_PROPAGATION_DELAY" "0.00 MIL,195.00 MIL"
					( Parent
						( matchGroupRef "@baseboard_fab2_lib.baseboard_fab2(sch_1):\MG_DQ-DQS_NEAR_DIMM_NG_M_H_BYTE6\" )
					)
					( Units "uMatchProp" "ns" 1.000000)
					( Status sCSetFlattened )
					( Origin gBackEnd )
				)
				( attribute "RELATIVE_PROPAGATION_DELAY_SCOPE" "G"
					( Parent
						( matchGroupRef "@baseboard_fab2_lib.baseboard_fab2(sch_1):\MG_DQ_NEAR_DIMM_NG_M_H_BYTE6\" )
					)
					( Status sCSetFlattened )
					( Origin gBackEnd )
				)
				( attribute "RELATIVE_PROPAGATION_DELAY" "-50.00 MIL,50.00 MIL"
					( Parent
						( matchGroupRef "@baseboard_fab2_lib.baseboard_fab2(sch_1):\MG_DQ_NEAR_DIMM_NG_M_H_BYTE6\" )
					)
					( Units "uMatchProp" "ns" 1.000000)
					( Status sCSetFlattened )
					( Origin gBackEnd )
				)
			)
			( pinPair "@baseboard_fab2_lib.baseboard_fab2(sch_1):\PP2581\"
				( pinRef "@baseboard_fab2_lib.baseboard_fab2(sch_1):page58_i172:DDR1_DQ(54)" )
				( pinRef "@baseboard_fab2_lib.baseboard_fab2(sch_1):page79_i111:DQ(55)" )
				( attribute "RELATIVE_PROPAGATION_DELAY_SCOPE" "G"
					( Parent
						( matchGroupRef "@baseboard_fab2_lib.baseboard_fab2(sch_1):\MG_DQ-DQS_FAR_DIMM_NG_M_H_BYTE6\" )
					)
					( Status sCSetFlattened )
					( Origin gBackEnd )
				)
				( attribute "RELATIVE_PROPAGATION_DELAY" "0.00 MIL,195.00 MIL"
					( Parent
						( matchGroupRef "@baseboard_fab2_lib.baseboard_fab2(sch_1):\MG_DQ-DQS_FAR_DIMM_NG_M_H_BYTE6\" )
					)
					( Units "uMatchProp" "ns" 1.000000)
					( Status sCSetFlattened )
					( Origin gBackEnd )
				)
				( attribute "RELATIVE_PROPAGATION_DELAY_SCOPE" "G"
					( Parent
						( matchGroupRef "@baseboard_fab2_lib.baseboard_fab2(sch_1):\MG_DQ_FAR_DIMM_NG_M_H_BYTE6\" )
					)
					( Status sCSetFlattened )
					( Origin gBackEnd )
				)
				( attribute "RELATIVE_PROPAGATION_DELAY" "-50.00 MIL,50.00 MIL"
					( Parent
						( matchGroupRef "@baseboard_fab2_lib.baseboard_fab2(sch_1):\MG_DQ_FAR_DIMM_NG_M_H_BYTE6\" )
					)
					( Units "uMatchProp" "ns" 1.000000)
					( Status sCSetFlattened )
					( Origin gBackEnd )
				)
			)
			( pinPair "@baseboard_fab2_lib.baseboard_fab2(sch_1):\PP2583\"
				( pinRef "@baseboard_fab2_lib.baseboard_fab2(sch_1):page58_i172:DDR1_DQ(54)" )
				( pinRef "@baseboard_fab2_lib.baseboard_fab2(sch_1):page80_i24:DQ(54)" )
				( attribute "RELATIVE_PROPAGATION_DELAY_SCOPE" "G"
					( Parent
						( matchGroupRef "@baseboard_fab2_lib.baseboard_fab2(sch_1):\MG_DQ-DQS_NEAR_DIMM_NG_M_H_BYTE6\" )
					)
					( Status sCSetFlattened )
					( Origin gBackEnd )
				)
				( attribute "RELATIVE_PROPAGATION_DELAY" "0.00 MIL,195.00 MIL"
					( Parent
						( matchGroupRef "@baseboard_fab2_lib.baseboard_fab2(sch_1):\MG_DQ-DQS_NEAR_DIMM_NG_M_H_BYTE6\" )
					)
					( Units "uMatchProp" "ns" 1.000000)
					( Status sCSetFlattened )
					( Origin gBackEnd )
				)
				( attribute "RELATIVE_PROPAGATION_DELAY_SCOPE" "G"
					( Parent
						( matchGroupRef "@baseboard_fab2_lib.baseboard_fab2(sch_1):\MG_DQ_NEAR_DIMM_NG_M_H_BYTE6\" )
					)
					( Status sCSetFlattened )
					( Origin gBackEnd )
				)
				( attribute "RELATIVE_PROPAGATION_DELAY" "-50.00 MIL,50.00 MIL"
					( Parent
						( matchGroupRef "@baseboard_fab2_lib.baseboard_fab2(sch_1):\MG_DQ_NEAR_DIMM_NG_M_H_BYTE6\" )
					)
					( Units "uMatchProp" "ns" 1.000000)
					( Status sCSetFlattened )
					( Origin gBackEnd )
				)
			)
			( pinPair "@baseboard_fab2_lib.baseboard_fab2(sch_1):\PP2584\"
				( pinRef "@baseboard_fab2_lib.baseboard_fab2(sch_1):page58_i172:DDR1_DQ(55)" )
				( pinRef "@baseboard_fab2_lib.baseboard_fab2(sch_1):page79_i111:DQ(54)" )
				( attribute "RELATIVE_PROPAGATION_DELAY_SCOPE" "G"
					( Parent
						( matchGroupRef "@baseboard_fab2_lib.baseboard_fab2(sch_1):\MG_DQ-DQS_FAR_DIMM_NG_M_H_BYTE6\" )
					)
					( Status sCSetFlattened )
					( Origin gBackEnd )
				)
				( attribute "RELATIVE_PROPAGATION_DELAY" "0.00 MIL,195.00 MIL"
					( Parent
						( matchGroupRef "@baseboard_fab2_lib.baseboard_fab2(sch_1):\MG_DQ-DQS_FAR_DIMM_NG_M_H_BYTE6\" )
					)
					( Units "uMatchProp" "ns" 1.000000)
					( Status sCSetFlattened )
					( Origin gBackEnd )
				)
				( attribute "RELATIVE_PROPAGATION_DELAY_SCOPE" "G"
					( Parent
						( matchGroupRef "@baseboard_fab2_lib.baseboard_fab2(sch_1):\MG_DQ_FAR_DIMM_NG_M_H_BYTE6\" )
					)
					( Status sCSetFlattened )
					( Origin gBackEnd )
				)
				( attribute "RELATIVE_PROPAGATION_DELAY" "-50.00 MIL,50.00 MIL"
					( Parent
						( matchGroupRef "@baseboard_fab2_lib.baseboard_fab2(sch_1):\MG_DQ_FAR_DIMM_NG_M_H_BYTE6\" )
					)
					( Units "uMatchProp" "ns" 1.000000)
					( Status sCSetFlattened )
					( Origin gBackEnd )
				)
			)
			( pinPair "@baseboard_fab2_lib.baseboard_fab2(sch_1):\PP2586\"
				( pinRef "@baseboard_fab2_lib.baseboard_fab2(sch_1):page58_i172:DDR1_DQ(55)" )
				( pinRef "@baseboard_fab2_lib.baseboard_fab2(sch_1):page80_i24:DQ(55)" )
				( attribute "RELATIVE_PROPAGATION_DELAY_SCOPE" "G"
					( Parent
						( matchGroupRef "@baseboard_fab2_lib.baseboard_fab2(sch_1):\MG_DQ-DQS_NEAR_DIMM_NG_M_H_BYTE6\" )
					)
					( Status sCSetFlattened )
					( Origin gBackEnd )
				)
				( attribute "RELATIVE_PROPAGATION_DELAY" "0.00 MIL,195.00 MIL"
					( Parent
						( matchGroupRef "@baseboard_fab2_lib.baseboard_fab2(sch_1):\MG_DQ-DQS_NEAR_DIMM_NG_M_H_BYTE6\" )
					)
					( Units "uMatchProp" "ns" 1.000000)
					( Status sCSetFlattened )
					( Origin gBackEnd )
				)
				( attribute "RELATIVE_PROPAGATION_DELAY_SCOPE" "G"
					( Parent
						( matchGroupRef "@baseboard_fab2_lib.baseboard_fab2(sch_1):\MG_DQ_NEAR_DIMM_NG_M_H_BYTE6\" )
					)
					( Status sCSetFlattened )
					( Origin gBackEnd )
				)
				( attribute "RELATIVE_PROPAGATION_DELAY" "-50.00 MIL,50.00 MIL"
					( Parent
						( matchGroupRef "@baseboard_fab2_lib.baseboard_fab2(sch_1):\MG_DQ_NEAR_DIMM_NG_M_H_BYTE6\" )
					)
					( Units "uMatchProp" "ns" 1.000000)
					( Status sCSetFlattened )
					( Origin gBackEnd )
				)
			)
			( pinPair "@baseboard_fab2_lib.baseboard_fab2(sch_1):\PP2539\"
				( pinRef "@baseboard_fab2_lib.baseboard_fab2(sch_1):page58_i172:DDR1_DQ(56)" )
				( pinRef "@baseboard_fab2_lib.baseboard_fab2(sch_1):page79_i111:DQ(57)" )
				( attribute "RELATIVE_PROPAGATION_DELAY_SCOPE" "G"
					( Parent
						( matchGroupRef "@baseboard_fab2_lib.baseboard_fab2(sch_1):\MG_DQ-DQS_FAR_DIMM_NG_M_H_BYTE7\" )
					)
					( Status sCSetFlattened )
					( Origin gBackEnd )
				)
				( attribute "RELATIVE_PROPAGATION_DELAY" "0.00 MIL,195.00 MIL"
					( Parent
						( matchGroupRef "@baseboard_fab2_lib.baseboard_fab2(sch_1):\MG_DQ-DQS_FAR_DIMM_NG_M_H_BYTE7\" )
					)
					( Units "uMatchProp" "ns" 1.000000)
					( Status sCSetFlattened )
					( Origin gBackEnd )
				)
				( attribute "RELATIVE_PROPAGATION_DELAY_SCOPE" "G"
					( Parent
						( matchGroupRef "@baseboard_fab2_lib.baseboard_fab2(sch_1):\MG_DQ_FAR_DIMM_NG_M_H_BYTE7\" )
					)
					( Status sCSetFlattened )
					( Origin gBackEnd )
				)
				( attribute "RELATIVE_PROPAGATION_DELAY" "-50.00 MIL,50.00 MIL"
					( Parent
						( matchGroupRef "@baseboard_fab2_lib.baseboard_fab2(sch_1):\MG_DQ_FAR_DIMM_NG_M_H_BYTE7\" )
					)
					( Units "uMatchProp" "ns" 1.000000)
					( Status sCSetFlattened )
					( Origin gBackEnd )
				)
			)
			( pinPair "@baseboard_fab2_lib.baseboard_fab2(sch_1):\PP2541\"
				( pinRef "@baseboard_fab2_lib.baseboard_fab2(sch_1):page58_i172:DDR1_DQ(56)" )
				( pinRef "@baseboard_fab2_lib.baseboard_fab2(sch_1):page80_i24:DQ(56)" )
				( attribute "RELATIVE_PROPAGATION_DELAY_SCOPE" "G"
					( Parent
						( matchGroupRef "@baseboard_fab2_lib.baseboard_fab2(sch_1):\MG_DQ-DQS_NEAR_DIMM_NG_M_H_BYTE7\" )
					)
					( Status sCSetFlattened )
					( Origin gBackEnd )
				)
				( attribute "RELATIVE_PROPAGATION_DELAY" "0.00 MIL,195.00 MIL"
					( Parent
						( matchGroupRef "@baseboard_fab2_lib.baseboard_fab2(sch_1):\MG_DQ-DQS_NEAR_DIMM_NG_M_H_BYTE7\" )
					)
					( Units "uMatchProp" "ns" 1.000000)
					( Status sCSetFlattened )
					( Origin gBackEnd )
				)
				( attribute "RELATIVE_PROPAGATION_DELAY_SCOPE" "G"
					( Parent
						( matchGroupRef "@baseboard_fab2_lib.baseboard_fab2(sch_1):\MG_DQ_NEAR_DIMM_NG_M_H_BYTE7\" )
					)
					( Status sCSetFlattened )
					( Origin gBackEnd )
				)
				( attribute "RELATIVE_PROPAGATION_DELAY" "-50.00 MIL,50.00 MIL"
					( Parent
						( matchGroupRef "@baseboard_fab2_lib.baseboard_fab2(sch_1):\MG_DQ_NEAR_DIMM_NG_M_H_BYTE7\" )
					)
					( Units "uMatchProp" "ns" 1.000000)
					( Status sCSetFlattened )
					( Origin gBackEnd )
				)
			)
			( pinPair "@baseboard_fab2_lib.baseboard_fab2(sch_1):\PP2542\"
				( pinRef "@baseboard_fab2_lib.baseboard_fab2(sch_1):page58_i172:DDR1_DQ(57)" )
				( pinRef "@baseboard_fab2_lib.baseboard_fab2(sch_1):page79_i111:DQ(56)" )
				( attribute "RELATIVE_PROPAGATION_DELAY_SCOPE" "G"
					( Parent
						( matchGroupRef "@baseboard_fab2_lib.baseboard_fab2(sch_1):\MG_DQ-DQS_FAR_DIMM_NG_M_H_BYTE7\" )
					)
					( Status sCSetFlattened )
					( Origin gBackEnd )
				)
				( attribute "RELATIVE_PROPAGATION_DELAY" "0.00 MIL,195.00 MIL"
					( Parent
						( matchGroupRef "@baseboard_fab2_lib.baseboard_fab2(sch_1):\MG_DQ-DQS_FAR_DIMM_NG_M_H_BYTE7\" )
					)
					( Units "uMatchProp" "ns" 1.000000)
					( Status sCSetFlattened )
					( Origin gBackEnd )
				)
				( attribute "RELATIVE_PROPAGATION_DELAY_SCOPE" "G"
					( Parent
						( matchGroupRef "@baseboard_fab2_lib.baseboard_fab2(sch_1):\MG_DQ_FAR_DIMM_NG_M_H_BYTE7\" )
					)
					( Status sCSetFlattened )
					( Origin gBackEnd )
				)
				( attribute "RELATIVE_PROPAGATION_DELAY" "-50.00 MIL,50.00 MIL"
					( Parent
						( matchGroupRef "@baseboard_fab2_lib.baseboard_fab2(sch_1):\MG_DQ_FAR_DIMM_NG_M_H_BYTE7\" )
					)
					( Units "uMatchProp" "ns" 1.000000)
					( Status sCSetFlattened )
					( Origin gBackEnd )
				)
			)
			( pinPair "@baseboard_fab2_lib.baseboard_fab2(sch_1):\PP2544\"
				( pinRef "@baseboard_fab2_lib.baseboard_fab2(sch_1):page58_i172:DDR1_DQ(57)" )
				( pinRef "@baseboard_fab2_lib.baseboard_fab2(sch_1):page80_i24:DQ(57)" )
				( attribute "RELATIVE_PROPAGATION_DELAY_SCOPE" "G"
					( Parent
						( matchGroupRef "@baseboard_fab2_lib.baseboard_fab2(sch_1):\MG_DQ-DQS_NEAR_DIMM_NG_M_H_BYTE7\" )
					)
					( Status sCSetFlattened )
					( Origin gBackEnd )
				)
				( attribute "RELATIVE_PROPAGATION_DELAY" "0.00 MIL,195.00 MIL"
					( Parent
						( matchGroupRef "@baseboard_fab2_lib.baseboard_fab2(sch_1):\MG_DQ-DQS_NEAR_DIMM_NG_M_H_BYTE7\" )
					)
					( Units "uMatchProp" "ns" 1.000000)
					( Status sCSetFlattened )
					( Origin gBackEnd )
				)
				( attribute "RELATIVE_PROPAGATION_DELAY_SCOPE" "G"
					( Parent
						( matchGroupRef "@baseboard_fab2_lib.baseboard_fab2(sch_1):\MG_DQ_NEAR_DIMM_NG_M_H_BYTE7\" )
					)
					( Status sCSetFlattened )
					( Origin gBackEnd )
				)
				( attribute "RELATIVE_PROPAGATION_DELAY" "-50.00 MIL,50.00 MIL"
					( Parent
						( matchGroupRef "@baseboard_fab2_lib.baseboard_fab2(sch_1):\MG_DQ_NEAR_DIMM_NG_M_H_BYTE7\" )
					)
					( Units "uMatchProp" "ns" 1.000000)
					( Status sCSetFlattened )
					( Origin gBackEnd )
				)
			)
			( pinPair "@baseboard_fab2_lib.baseboard_fab2(sch_1):\PP2545\"
				( pinRef "@baseboard_fab2_lib.baseboard_fab2(sch_1):page58_i172:DDR1_DQ(58)" )
				( pinRef "@baseboard_fab2_lib.baseboard_fab2(sch_1):page79_i111:DQ(59)" )
				( attribute "RELATIVE_PROPAGATION_DELAY_SCOPE" "G"
					( Parent
						( matchGroupRef "@baseboard_fab2_lib.baseboard_fab2(sch_1):\MG_DQ-DQS_FAR_DIMM_NG_M_H_BYTE7\" )
					)
					( Status sCSetFlattened )
					( Origin gBackEnd )
				)
				( attribute "RELATIVE_PROPAGATION_DELAY" "0.00 MIL,195.00 MIL"
					( Parent
						( matchGroupRef "@baseboard_fab2_lib.baseboard_fab2(sch_1):\MG_DQ-DQS_FAR_DIMM_NG_M_H_BYTE7\" )
					)
					( Units "uMatchProp" "ns" 1.000000)
					( Status sCSetFlattened )
					( Origin gBackEnd )
				)
				( attribute "RELATIVE_PROPAGATION_DELAY_SCOPE" "G"
					( Parent
						( matchGroupRef "@baseboard_fab2_lib.baseboard_fab2(sch_1):\MG_DQ_FAR_DIMM_NG_M_H_BYTE7\" )
					)
					( Status sCSetFlattened )
					( Origin gBackEnd )
				)
				( attribute "RELATIVE_PROPAGATION_DELAY" "-50.00 MIL,50.00 MIL"
					( Parent
						( matchGroupRef "@baseboard_fab2_lib.baseboard_fab2(sch_1):\MG_DQ_FAR_DIMM_NG_M_H_BYTE7\" )
					)
					( Units "uMatchProp" "ns" 1.000000)
					( Status sCSetFlattened )
					( Origin gBackEnd )
				)
			)
			( pinPair "@baseboard_fab2_lib.baseboard_fab2(sch_1):\PP2547\"
				( pinRef "@baseboard_fab2_lib.baseboard_fab2(sch_1):page58_i172:DDR1_DQ(58)" )
				( pinRef "@baseboard_fab2_lib.baseboard_fab2(sch_1):page80_i24:DQ(58)" )
				( attribute "RELATIVE_PROPAGATION_DELAY_SCOPE" "G"
					( Parent
						( matchGroupRef "@baseboard_fab2_lib.baseboard_fab2(sch_1):\MG_DQ-DQS_NEAR_DIMM_NG_M_H_BYTE7\" )
					)
					( Status sCSetFlattened )
					( Origin gBackEnd )
				)
				( attribute "RELATIVE_PROPAGATION_DELAY" "0.00 MIL,195.00 MIL"
					( Parent
						( matchGroupRef "@baseboard_fab2_lib.baseboard_fab2(sch_1):\MG_DQ-DQS_NEAR_DIMM_NG_M_H_BYTE7\" )
					)
					( Units "uMatchProp" "ns" 1.000000)
					( Status sCSetFlattened )
					( Origin gBackEnd )
				)
				( attribute "RELATIVE_PROPAGATION_DELAY_SCOPE" "G"
					( Parent
						( matchGroupRef "@baseboard_fab2_lib.baseboard_fab2(sch_1):\MG_DQ_NEAR_DIMM_NG_M_H_BYTE7\" )
					)
					( Status sCSetFlattened )
					( Origin gBackEnd )
				)
				( attribute "RELATIVE_PROPAGATION_DELAY" "-50.00 MIL,50.00 MIL"
					( Parent
						( matchGroupRef "@baseboard_fab2_lib.baseboard_fab2(sch_1):\MG_DQ_NEAR_DIMM_NG_M_H_BYTE7\" )
					)
					( Units "uMatchProp" "ns" 1.000000)
					( Status sCSetFlattened )
					( Origin gBackEnd )
				)
			)
			( pinPair "@baseboard_fab2_lib.baseboard_fab2(sch_1):\PP2548\"
				( pinRef "@baseboard_fab2_lib.baseboard_fab2(sch_1):page58_i172:DDR1_DQ(59)" )
				( pinRef "@baseboard_fab2_lib.baseboard_fab2(sch_1):page79_i111:DQ(58)" )
				( attribute "RELATIVE_PROPAGATION_DELAY_SCOPE" "G"
					( Parent
						( matchGroupRef "@baseboard_fab2_lib.baseboard_fab2(sch_1):\MG_DQ-DQS_FAR_DIMM_NG_M_H_BYTE7\" )
					)
					( Status sCSetFlattened )
					( Origin gBackEnd )
				)
				( attribute "RELATIVE_PROPAGATION_DELAY" "0.00 MIL,195.00 MIL"
					( Parent
						( matchGroupRef "@baseboard_fab2_lib.baseboard_fab2(sch_1):\MG_DQ-DQS_FAR_DIMM_NG_M_H_BYTE7\" )
					)
					( Units "uMatchProp" "ns" 1.000000)
					( Status sCSetFlattened )
					( Origin gBackEnd )
				)
				( attribute "RELATIVE_PROPAGATION_DELAY_SCOPE" "G"
					( Parent
						( matchGroupRef "@baseboard_fab2_lib.baseboard_fab2(sch_1):\MG_DQ_FAR_DIMM_NG_M_H_BYTE7\" )
					)
					( Status sCSetFlattened )
					( Origin gBackEnd )
				)
				( attribute "RELATIVE_PROPAGATION_DELAY" "-50.00 MIL,50.00 MIL"
					( Parent
						( matchGroupRef "@baseboard_fab2_lib.baseboard_fab2(sch_1):\MG_DQ_FAR_DIMM_NG_M_H_BYTE7\" )
					)
					( Units "uMatchProp" "ns" 1.000000)
					( Status sCSetFlattened )
					( Origin gBackEnd )
				)
			)
			( pinPair "@baseboard_fab2_lib.baseboard_fab2(sch_1):\PP2550\"
				( pinRef "@baseboard_fab2_lib.baseboard_fab2(sch_1):page58_i172:DDR1_DQ(59)" )
				( pinRef "@baseboard_fab2_lib.baseboard_fab2(sch_1):page80_i24:DQ(59)" )
				( attribute "RELATIVE_PROPAGATION_DELAY_SCOPE" "G"
					( Parent
						( matchGroupRef "@baseboard_fab2_lib.baseboard_fab2(sch_1):\MG_DQ-DQS_NEAR_DIMM_NG_M_H_BYTE7\" )
					)
					( Status sCSetFlattened )
					( Origin gBackEnd )
				)
				( attribute "RELATIVE_PROPAGATION_DELAY" "0.00 MIL,195.00 MIL"
					( Parent
						( matchGroupRef "@baseboard_fab2_lib.baseboard_fab2(sch_1):\MG_DQ-DQS_NEAR_DIMM_NG_M_H_BYTE7\" )
					)
					( Units "uMatchProp" "ns" 1.000000)
					( Status sCSetFlattened )
					( Origin gBackEnd )
				)
				( attribute "RELATIVE_PROPAGATION_DELAY_SCOPE" "G"
					( Parent
						( matchGroupRef "@baseboard_fab2_lib.baseboard_fab2(sch_1):\MG_DQ_NEAR_DIMM_NG_M_H_BYTE7\" )
					)
					( Status sCSetFlattened )
					( Origin gBackEnd )
				)
				( attribute "RELATIVE_PROPAGATION_DELAY" "-50.00 MIL,50.00 MIL"
					( Parent
						( matchGroupRef "@baseboard_fab2_lib.baseboard_fab2(sch_1):\MG_DQ_NEAR_DIMM_NG_M_H_BYTE7\" )
					)
					( Units "uMatchProp" "ns" 1.000000)
					( Status sCSetFlattened )
					( Origin gBackEnd )
				)
			)
			( pinPair "@baseboard_fab2_lib.baseboard_fab2(sch_1):\PP2551\"
				( pinRef "@baseboard_fab2_lib.baseboard_fab2(sch_1):page58_i172:DDR1_DQ(60)" )
				( pinRef "@baseboard_fab2_lib.baseboard_fab2(sch_1):page79_i111:DQ(61)" )
				( attribute "RELATIVE_PROPAGATION_DELAY_SCOPE" "G"
					( Parent
						( matchGroupRef "@baseboard_fab2_lib.baseboard_fab2(sch_1):\MG_DQ-DQS_FAR_DIMM_NG_M_H_BYTE7\" )
					)
					( Status sCSetFlattened )
					( Origin gBackEnd )
				)
				( attribute "RELATIVE_PROPAGATION_DELAY" "0.00 MIL,195.00 MIL"
					( Parent
						( matchGroupRef "@baseboard_fab2_lib.baseboard_fab2(sch_1):\MG_DQ-DQS_FAR_DIMM_NG_M_H_BYTE7\" )
					)
					( Units "uMatchProp" "ns" 1.000000)
					( Status sCSetFlattened )
					( Origin gBackEnd )
				)
				( attribute "RELATIVE_PROPAGATION_DELAY_SCOPE" "G"
					( Parent
						( matchGroupRef "@baseboard_fab2_lib.baseboard_fab2(sch_1):\MG_DQ_FAR_DIMM_NG_M_H_BYTE7\" )
					)
					( Status sCSetFlattened )
					( Origin gBackEnd )
				)
				( attribute "RELATIVE_PROPAGATION_DELAY" "-50.00 MIL,50.00 MIL"
					( Parent
						( matchGroupRef "@baseboard_fab2_lib.baseboard_fab2(sch_1):\MG_DQ_FAR_DIMM_NG_M_H_BYTE7\" )
					)
					( Units "uMatchProp" "ns" 1.000000)
					( Status sCSetFlattened )
					( Origin gBackEnd )
				)
			)
			( pinPair "@baseboard_fab2_lib.baseboard_fab2(sch_1):\PP2553\"
				( pinRef "@baseboard_fab2_lib.baseboard_fab2(sch_1):page58_i172:DDR1_DQ(60)" )
				( pinRef "@baseboard_fab2_lib.baseboard_fab2(sch_1):page80_i24:DQ(60)" )
				( attribute "RELATIVE_PROPAGATION_DELAY_SCOPE" "G"
					( Parent
						( matchGroupRef "@baseboard_fab2_lib.baseboard_fab2(sch_1):\MG_DQ-DQS_NEAR_DIMM_NG_M_H_BYTE7\" )
					)
					( Status sCSetFlattened )
					( Origin gBackEnd )
				)
				( attribute "RELATIVE_PROPAGATION_DELAY" "0.00 MIL,195.00 MIL"
					( Parent
						( matchGroupRef "@baseboard_fab2_lib.baseboard_fab2(sch_1):\MG_DQ-DQS_NEAR_DIMM_NG_M_H_BYTE7\" )
					)
					( Units "uMatchProp" "ns" 1.000000)
					( Status sCSetFlattened )
					( Origin gBackEnd )
				)
				( attribute "RELATIVE_PROPAGATION_DELAY_SCOPE" "G"
					( Parent
						( matchGroupRef "@baseboard_fab2_lib.baseboard_fab2(sch_1):\MG_DQ_NEAR_DIMM_NG_M_H_BYTE7\" )
					)
					( Status sCSetFlattened )
					( Origin gBackEnd )
				)
				( attribute "RELATIVE_PROPAGATION_DELAY" "-50.00 MIL,50.00 MIL"
					( Parent
						( matchGroupRef "@baseboard_fab2_lib.baseboard_fab2(sch_1):\MG_DQ_NEAR_DIMM_NG_M_H_BYTE7\" )
					)
					( Units "uMatchProp" "ns" 1.000000)
					( Status sCSetFlattened )
					( Origin gBackEnd )
				)
			)
			( pinPair "@baseboard_fab2_lib.baseboard_fab2(sch_1):\PP2554\"
				( pinRef "@baseboard_fab2_lib.baseboard_fab2(sch_1):page58_i172:DDR1_DQ(61)" )
				( pinRef "@baseboard_fab2_lib.baseboard_fab2(sch_1):page79_i111:DQ(60)" )
				( attribute "RELATIVE_PROPAGATION_DELAY_SCOPE" "G"
					( Parent
						( matchGroupRef "@baseboard_fab2_lib.baseboard_fab2(sch_1):\MG_DQ-DQS_FAR_DIMM_NG_M_H_BYTE7\" )
					)
					( Status sCSetFlattened )
					( Origin gBackEnd )
				)
				( attribute "RELATIVE_PROPAGATION_DELAY" "0.00 MIL,195.00 MIL"
					( Parent
						( matchGroupRef "@baseboard_fab2_lib.baseboard_fab2(sch_1):\MG_DQ-DQS_FAR_DIMM_NG_M_H_BYTE7\" )
					)
					( Units "uMatchProp" "ns" 1.000000)
					( Status sCSetFlattened )
					( Origin gBackEnd )
				)
				( attribute "RELATIVE_PROPAGATION_DELAY_SCOPE" "G"
					( Parent
						( matchGroupRef "@baseboard_fab2_lib.baseboard_fab2(sch_1):\MG_DQ_FAR_DIMM_NG_M_H_BYTE7\" )
					)
					( Status sCSetFlattened )
					( Origin gBackEnd )
				)
				( attribute "RELATIVE_PROPAGATION_DELAY" "-50.00 MIL,50.00 MIL"
					( Parent
						( matchGroupRef "@baseboard_fab2_lib.baseboard_fab2(sch_1):\MG_DQ_FAR_DIMM_NG_M_H_BYTE7\" )
					)
					( Units "uMatchProp" "ns" 1.000000)
					( Status sCSetFlattened )
					( Origin gBackEnd )
				)
			)
			( pinPair "@baseboard_fab2_lib.baseboard_fab2(sch_1):\PP2556\"
				( pinRef "@baseboard_fab2_lib.baseboard_fab2(sch_1):page58_i172:DDR1_DQ(61)" )
				( pinRef "@baseboard_fab2_lib.baseboard_fab2(sch_1):page80_i24:DQ(61)" )
				( attribute "RELATIVE_PROPAGATION_DELAY_SCOPE" "G"
					( Parent
						( matchGroupRef "@baseboard_fab2_lib.baseboard_fab2(sch_1):\MG_DQ-DQS_NEAR_DIMM_NG_M_H_BYTE7\" )
					)
					( Status sCSetFlattened )
					( Origin gBackEnd )
				)
				( attribute "RELATIVE_PROPAGATION_DELAY" "0.00 MIL,195.00 MIL"
					( Parent
						( matchGroupRef "@baseboard_fab2_lib.baseboard_fab2(sch_1):\MG_DQ-DQS_NEAR_DIMM_NG_M_H_BYTE7\" )
					)
					( Units "uMatchProp" "ns" 1.000000)
					( Status sCSetFlattened )
					( Origin gBackEnd )
				)
				( attribute "RELATIVE_PROPAGATION_DELAY_SCOPE" "G"
					( Parent
						( matchGroupRef "@baseboard_fab2_lib.baseboard_fab2(sch_1):\MG_DQ_NEAR_DIMM_NG_M_H_BYTE7\" )
					)
					( Status sCSetFlattened )
					( Origin gBackEnd )
				)
				( attribute "RELATIVE_PROPAGATION_DELAY" "-50.00 MIL,50.00 MIL"
					( Parent
						( matchGroupRef "@baseboard_fab2_lib.baseboard_fab2(sch_1):\MG_DQ_NEAR_DIMM_NG_M_H_BYTE7\" )
					)
					( Units "uMatchProp" "ns" 1.000000)
					( Status sCSetFlattened )
					( Origin gBackEnd )
				)
			)
			( pinPair "@baseboard_fab2_lib.baseboard_fab2(sch_1):\PP2557\"
				( pinRef "@baseboard_fab2_lib.baseboard_fab2(sch_1):page58_i172:DDR1_DQ(62)" )
				( pinRef "@baseboard_fab2_lib.baseboard_fab2(sch_1):page79_i111:DQ(63)" )
				( attribute "RELATIVE_PROPAGATION_DELAY_SCOPE" "G"
					( Parent
						( matchGroupRef "@baseboard_fab2_lib.baseboard_fab2(sch_1):\MG_DQ-DQS_FAR_DIMM_NG_M_H_BYTE7\" )
					)
					( Status sCSetFlattened )
					( Origin gBackEnd )
				)
				( attribute "RELATIVE_PROPAGATION_DELAY" "0.00 MIL,195.00 MIL"
					( Parent
						( matchGroupRef "@baseboard_fab2_lib.baseboard_fab2(sch_1):\MG_DQ-DQS_FAR_DIMM_NG_M_H_BYTE7\" )
					)
					( Units "uMatchProp" "ns" 1.000000)
					( Status sCSetFlattened )
					( Origin gBackEnd )
				)
				( attribute "RELATIVE_PROPAGATION_DELAY_SCOPE" "G"
					( Parent
						( matchGroupRef "@baseboard_fab2_lib.baseboard_fab2(sch_1):\MG_DQ_FAR_DIMM_NG_M_H_BYTE7\" )
					)
					( Status sCSetFlattened )
					( Origin gBackEnd )
				)
				( attribute "RELATIVE_PROPAGATION_DELAY" "-50.00 MIL,50.00 MIL"
					( Parent
						( matchGroupRef "@baseboard_fab2_lib.baseboard_fab2(sch_1):\MG_DQ_FAR_DIMM_NG_M_H_BYTE7\" )
					)
					( Units "uMatchProp" "ns" 1.000000)
					( Status sCSetFlattened )
					( Origin gBackEnd )
				)
			)
			( pinPair "@baseboard_fab2_lib.baseboard_fab2(sch_1):\PP2559\"
				( pinRef "@baseboard_fab2_lib.baseboard_fab2(sch_1):page58_i172:DDR1_DQ(62)" )
				( pinRef "@baseboard_fab2_lib.baseboard_fab2(sch_1):page80_i24:DQ(62)" )
				( attribute "RELATIVE_PROPAGATION_DELAY_SCOPE" "G"
					( Parent
						( matchGroupRef "@baseboard_fab2_lib.baseboard_fab2(sch_1):\MG_DQ-DQS_NEAR_DIMM_NG_M_H_BYTE7\" )
					)
					( Status sCSetFlattened )
					( Origin gBackEnd )
				)
				( attribute "RELATIVE_PROPAGATION_DELAY" "0.00 MIL,195.00 MIL"
					( Parent
						( matchGroupRef "@baseboard_fab2_lib.baseboard_fab2(sch_1):\MG_DQ-DQS_NEAR_DIMM_NG_M_H_BYTE7\" )
					)
					( Units "uMatchProp" "ns" 1.000000)
					( Status sCSetFlattened )
					( Origin gBackEnd )
				)
				( attribute "RELATIVE_PROPAGATION_DELAY_SCOPE" "G"
					( Parent
						( matchGroupRef "@baseboard_fab2_lib.baseboard_fab2(sch_1):\MG_DQ_NEAR_DIMM_NG_M_H_BYTE7\" )
					)
					( Status sCSetFlattened )
					( Origin gBackEnd )
				)
				( attribute "RELATIVE_PROPAGATION_DELAY" "-50.00 MIL,50.00 MIL"
					( Parent
						( matchGroupRef "@baseboard_fab2_lib.baseboard_fab2(sch_1):\MG_DQ_NEAR_DIMM_NG_M_H_BYTE7\" )
					)
					( Units "uMatchProp" "ns" 1.000000)
					( Status sCSetFlattened )
					( Origin gBackEnd )
				)
			)
			( pinPair "@baseboard_fab2_lib.baseboard_fab2(sch_1):\PP2560\"
				( pinRef "@baseboard_fab2_lib.baseboard_fab2(sch_1):page58_i172:DDR1_DQ(63)" )
				( pinRef "@baseboard_fab2_lib.baseboard_fab2(sch_1):page79_i111:DQ(62)" )
				( attribute "RELATIVE_PROPAGATION_DELAY_SCOPE" "G"
					( Parent
						( matchGroupRef "@baseboard_fab2_lib.baseboard_fab2(sch_1):\MG_DQ-DQS_FAR_DIMM_NG_M_H_BYTE7\" )
					)
					( Status sCSetFlattened )
					( Origin gBackEnd )
				)
				( attribute "RELATIVE_PROPAGATION_DELAY" "0.00 MIL,195.00 MIL"
					( Parent
						( matchGroupRef "@baseboard_fab2_lib.baseboard_fab2(sch_1):\MG_DQ-DQS_FAR_DIMM_NG_M_H_BYTE7\" )
					)
					( Units "uMatchProp" "ns" 1.000000)
					( Status sCSetFlattened )
					( Origin gBackEnd )
				)
				( attribute "RELATIVE_PROPAGATION_DELAY_SCOPE" "G"
					( Parent
						( matchGroupRef "@baseboard_fab2_lib.baseboard_fab2(sch_1):\MG_DQ_FAR_DIMM_NG_M_H_BYTE7\" )
					)
					( Status sCSetFlattened )
					( Origin gBackEnd )
				)
				( attribute "RELATIVE_PROPAGATION_DELAY" "-50.00 MIL,50.00 MIL"
					( Parent
						( matchGroupRef "@baseboard_fab2_lib.baseboard_fab2(sch_1):\MG_DQ_FAR_DIMM_NG_M_H_BYTE7\" )
					)
					( Units "uMatchProp" "ns" 1.000000)
					( Status sCSetFlattened )
					( Origin gBackEnd )
				)
			)
			( pinPair "@baseboard_fab2_lib.baseboard_fab2(sch_1):\PP2562\"
				( pinRef "@baseboard_fab2_lib.baseboard_fab2(sch_1):page58_i172:DDR1_DQ(63)" )
				( pinRef "@baseboard_fab2_lib.baseboard_fab2(sch_1):page80_i24:DQ(63)" )
				( attribute "RELATIVE_PROPAGATION_DELAY_SCOPE" "G"
					( Parent
						( matchGroupRef "@baseboard_fab2_lib.baseboard_fab2(sch_1):\MG_DQ-DQS_NEAR_DIMM_NG_M_H_BYTE7\" )
					)
					( Status sCSetFlattened )
					( Origin gBackEnd )
				)
				( attribute "RELATIVE_PROPAGATION_DELAY" "0.00 MIL,195.00 MIL"
					( Parent
						( matchGroupRef "@baseboard_fab2_lib.baseboard_fab2(sch_1):\MG_DQ-DQS_NEAR_DIMM_NG_M_H_BYTE7\" )
					)
					( Units "uMatchProp" "ns" 1.000000)
					( Status sCSetFlattened )
					( Origin gBackEnd )
				)
				( attribute "RELATIVE_PROPAGATION_DELAY_SCOPE" "G"
					( Parent
						( matchGroupRef "@baseboard_fab2_lib.baseboard_fab2(sch_1):\MG_DQ_NEAR_DIMM_NG_M_H_BYTE7\" )
					)
					( Status sCSetFlattened )
					( Origin gBackEnd )
				)
				( attribute "RELATIVE_PROPAGATION_DELAY" "-50.00 MIL,50.00 MIL"
					( Parent
						( matchGroupRef "@baseboard_fab2_lib.baseboard_fab2(sch_1):\MG_DQ_NEAR_DIMM_NG_M_H_BYTE7\" )
					)
					( Units "uMatchProp" "ns" 1.000000)
					( Status sCSetFlattened )
					( Origin gBackEnd )
				)
			)
			( pinPair "@baseboard_fab2_lib.baseboard_fab2(sch_1):\PP2491\"
				( pinRef "@baseboard_fab2_lib.baseboard_fab2(sch_1):page59_i172:DDR2_DQ(0)" )
				( pinRef "@baseboard_fab2_lib.baseboard_fab2(sch_1):page81_i186:DQ(1)" )
				( attribute "RELATIVE_PROPAGATION_DELAY_SCOPE" "G"
					( Parent
						( matchGroupRef "@baseboard_fab2_lib.baseboard_fab2(sch_1):\MG_DQ-DQS_FAR_DIMM_NG_M_J_BYTE0\" )
					)
					( Status sCSetFlattened )
					( Origin gBackEnd )
				)
				( attribute "RELATIVE_PROPAGATION_DELAY" "0.00 MIL,195.00 MIL"
					( Parent
						( matchGroupRef "@baseboard_fab2_lib.baseboard_fab2(sch_1):\MG_DQ-DQS_FAR_DIMM_NG_M_J_BYTE0\" )
					)
					( Units "uMatchProp" "ns" 1.000000)
					( Status sCSetFlattened )
					( Origin gBackEnd )
				)
				( attribute "RELATIVE_PROPAGATION_DELAY_SCOPE" "G"
					( Parent
						( matchGroupRef "@baseboard_fab2_lib.baseboard_fab2(sch_1):\MG_DQ_FAR_DIMM_NG_M_J_BYTE0\" )
					)
					( Status sCSetFlattened )
					( Origin gBackEnd )
				)
				( attribute "RELATIVE_PROPAGATION_DELAY" "-50.00 MIL,50.00 MIL"
					( Parent
						( matchGroupRef "@baseboard_fab2_lib.baseboard_fab2(sch_1):\MG_DQ_FAR_DIMM_NG_M_J_BYTE0\" )
					)
					( Units "uMatchProp" "ns" 1.000000)
					( Status sCSetFlattened )
					( Origin gBackEnd )
				)
			)
			( pinPair "@baseboard_fab2_lib.baseboard_fab2(sch_1):\PP2492\"
				( pinRef "@baseboard_fab2_lib.baseboard_fab2(sch_1):page59_i172:DDR2_DQ(0)" )
				( pinRef "@baseboard_fab2_lib.baseboard_fab2(sch_1):page82_i187:DQ(0)" )
				( attribute "RELATIVE_PROPAGATION_DELAY_SCOPE" "G"
					( Parent
						( matchGroupRef "@baseboard_fab2_lib.baseboard_fab2(sch_1):\MG_DQ-DQS_NEAR_DIMM_NG_M_J_BYTE0\" )
					)
					( Status sCSetFlattened )
					( Origin gBackEnd )
				)
				( attribute "RELATIVE_PROPAGATION_DELAY" "0.00 MIL,195.00 MIL"
					( Parent
						( matchGroupRef "@baseboard_fab2_lib.baseboard_fab2(sch_1):\MG_DQ-DQS_NEAR_DIMM_NG_M_J_BYTE0\" )
					)
					( Units "uMatchProp" "ns" 1.000000)
					( Status sCSetFlattened )
					( Origin gBackEnd )
				)
				( attribute "RELATIVE_PROPAGATION_DELAY_SCOPE" "G"
					( Parent
						( matchGroupRef "@baseboard_fab2_lib.baseboard_fab2(sch_1):\MG_DQ_NEAR_DIMM_NG_M_J_BYTE0\" )
					)
					( Status sCSetFlattened )
					( Origin gBackEnd )
				)
				( attribute "RELATIVE_PROPAGATION_DELAY" "-50.00 MIL,50.00 MIL"
					( Parent
						( matchGroupRef "@baseboard_fab2_lib.baseboard_fab2(sch_1):\MG_DQ_NEAR_DIMM_NG_M_J_BYTE0\" )
					)
					( Units "uMatchProp" "ns" 1.000000)
					( Status sCSetFlattened )
					( Origin gBackEnd )
				)
			)
			( pinPair "@baseboard_fab2_lib.baseboard_fab2(sch_1):\PP2494\"
				( pinRef "@baseboard_fab2_lib.baseboard_fab2(sch_1):page59_i172:DDR2_DQ(1)" )
				( pinRef "@baseboard_fab2_lib.baseboard_fab2(sch_1):page81_i186:DQ(0)" )
				( attribute "RELATIVE_PROPAGATION_DELAY_SCOPE" "G"
					( Parent
						( matchGroupRef "@baseboard_fab2_lib.baseboard_fab2(sch_1):\MG_DQ-DQS_FAR_DIMM_NG_M_J_BYTE0\" )
					)
					( Status sCSetFlattened )
					( Origin gBackEnd )
				)
				( attribute "RELATIVE_PROPAGATION_DELAY" "0.00 MIL,195.00 MIL"
					( Parent
						( matchGroupRef "@baseboard_fab2_lib.baseboard_fab2(sch_1):\MG_DQ-DQS_FAR_DIMM_NG_M_J_BYTE0\" )
					)
					( Units "uMatchProp" "ns" 1.000000)
					( Status sCSetFlattened )
					( Origin gBackEnd )
				)
				( attribute "RELATIVE_PROPAGATION_DELAY_SCOPE" "G"
					( Parent
						( matchGroupRef "@baseboard_fab2_lib.baseboard_fab2(sch_1):\MG_DQ_FAR_DIMM_NG_M_J_BYTE0\" )
					)
					( Status sCSetFlattened )
					( Origin gBackEnd )
				)
				( attribute "RELATIVE_PROPAGATION_DELAY" "-50.00 MIL,50.00 MIL"
					( Parent
						( matchGroupRef "@baseboard_fab2_lib.baseboard_fab2(sch_1):\MG_DQ_FAR_DIMM_NG_M_J_BYTE0\" )
					)
					( Units "uMatchProp" "ns" 1.000000)
					( Status sCSetFlattened )
					( Origin gBackEnd )
				)
			)
			( pinPair "@baseboard_fab2_lib.baseboard_fab2(sch_1):\PP2495\"
				( pinRef "@baseboard_fab2_lib.baseboard_fab2(sch_1):page59_i172:DDR2_DQ(1)" )
				( pinRef "@baseboard_fab2_lib.baseboard_fab2(sch_1):page82_i187:DQ(1)" )
				( attribute "RELATIVE_PROPAGATION_DELAY_SCOPE" "G"
					( Parent
						( matchGroupRef "@baseboard_fab2_lib.baseboard_fab2(sch_1):\MG_DQ-DQS_NEAR_DIMM_NG_M_J_BYTE0\" )
					)
					( Status sCSetFlattened )
					( Origin gBackEnd )
				)
				( attribute "RELATIVE_PROPAGATION_DELAY" "0.00 MIL,195.00 MIL"
					( Parent
						( matchGroupRef "@baseboard_fab2_lib.baseboard_fab2(sch_1):\MG_DQ-DQS_NEAR_DIMM_NG_M_J_BYTE0\" )
					)
					( Units "uMatchProp" "ns" 1.000000)
					( Status sCSetFlattened )
					( Origin gBackEnd )
				)
				( attribute "RELATIVE_PROPAGATION_DELAY_SCOPE" "G"
					( Parent
						( matchGroupRef "@baseboard_fab2_lib.baseboard_fab2(sch_1):\MG_DQ_NEAR_DIMM_NG_M_J_BYTE0\" )
					)
					( Status sCSetFlattened )
					( Origin gBackEnd )
				)
				( attribute "RELATIVE_PROPAGATION_DELAY" "-50.00 MIL,50.00 MIL"
					( Parent
						( matchGroupRef "@baseboard_fab2_lib.baseboard_fab2(sch_1):\MG_DQ_NEAR_DIMM_NG_M_J_BYTE0\" )
					)
					( Units "uMatchProp" "ns" 1.000000)
					( Status sCSetFlattened )
					( Origin gBackEnd )
				)
			)
			( pinPair "@baseboard_fab2_lib.baseboard_fab2(sch_1):\PP2497\"
				( pinRef "@baseboard_fab2_lib.baseboard_fab2(sch_1):page59_i172:DDR2_DQ(2)" )
				( pinRef "@baseboard_fab2_lib.baseboard_fab2(sch_1):page81_i186:DQ(3)" )
				( attribute "RELATIVE_PROPAGATION_DELAY_SCOPE" "G"
					( Parent
						( matchGroupRef "@baseboard_fab2_lib.baseboard_fab2(sch_1):\MG_DQ-DQS_FAR_DIMM_NG_M_J_BYTE0\" )
					)
					( Status sCSetFlattened )
					( Origin gBackEnd )
				)
				( attribute "RELATIVE_PROPAGATION_DELAY" "0.00 MIL,195.00 MIL"
					( Parent
						( matchGroupRef "@baseboard_fab2_lib.baseboard_fab2(sch_1):\MG_DQ-DQS_FAR_DIMM_NG_M_J_BYTE0\" )
					)
					( Units "uMatchProp" "ns" 1.000000)
					( Status sCSetFlattened )
					( Origin gBackEnd )
				)
				( attribute "RELATIVE_PROPAGATION_DELAY_SCOPE" "G"
					( Parent
						( matchGroupRef "@baseboard_fab2_lib.baseboard_fab2(sch_1):\MG_DQ_FAR_DIMM_NG_M_J_BYTE0\" )
					)
					( Status sCSetFlattened )
					( Origin gBackEnd )
				)
				( attribute "RELATIVE_PROPAGATION_DELAY" "-50.00 MIL,50.00 MIL"
					( Parent
						( matchGroupRef "@baseboard_fab2_lib.baseboard_fab2(sch_1):\MG_DQ_FAR_DIMM_NG_M_J_BYTE0\" )
					)
					( Units "uMatchProp" "ns" 1.000000)
					( Status sCSetFlattened )
					( Origin gBackEnd )
				)
			)
			( pinPair "@baseboard_fab2_lib.baseboard_fab2(sch_1):\PP2498\"
				( pinRef "@baseboard_fab2_lib.baseboard_fab2(sch_1):page59_i172:DDR2_DQ(2)" )
				( pinRef "@baseboard_fab2_lib.baseboard_fab2(sch_1):page82_i187:DQ(2)" )
				( attribute "RELATIVE_PROPAGATION_DELAY_SCOPE" "G"
					( Parent
						( matchGroupRef "@baseboard_fab2_lib.baseboard_fab2(sch_1):\MG_DQ-DQS_NEAR_DIMM_NG_M_J_BYTE0\" )
					)
					( Status sCSetFlattened )
					( Origin gBackEnd )
				)
				( attribute "RELATIVE_PROPAGATION_DELAY" "0.00 MIL,195.00 MIL"
					( Parent
						( matchGroupRef "@baseboard_fab2_lib.baseboard_fab2(sch_1):\MG_DQ-DQS_NEAR_DIMM_NG_M_J_BYTE0\" )
					)
					( Units "uMatchProp" "ns" 1.000000)
					( Status sCSetFlattened )
					( Origin gBackEnd )
				)
				( attribute "RELATIVE_PROPAGATION_DELAY_SCOPE" "G"
					( Parent
						( matchGroupRef "@baseboard_fab2_lib.baseboard_fab2(sch_1):\MG_DQ_NEAR_DIMM_NG_M_J_BYTE0\" )
					)
					( Status sCSetFlattened )
					( Origin gBackEnd )
				)
				( attribute "RELATIVE_PROPAGATION_DELAY" "-50.00 MIL,50.00 MIL"
					( Parent
						( matchGroupRef "@baseboard_fab2_lib.baseboard_fab2(sch_1):\MG_DQ_NEAR_DIMM_NG_M_J_BYTE0\" )
					)
					( Units "uMatchProp" "ns" 1.000000)
					( Status sCSetFlattened )
					( Origin gBackEnd )
				)
			)
			( pinPair "@baseboard_fab2_lib.baseboard_fab2(sch_1):\PP2500\"
				( pinRef "@baseboard_fab2_lib.baseboard_fab2(sch_1):page59_i172:DDR2_DQ(3)" )
				( pinRef "@baseboard_fab2_lib.baseboard_fab2(sch_1):page81_i186:DQ(2)" )
				( attribute "RELATIVE_PROPAGATION_DELAY_SCOPE" "G"
					( Parent
						( matchGroupRef "@baseboard_fab2_lib.baseboard_fab2(sch_1):\MG_DQ-DQS_FAR_DIMM_NG_M_J_BYTE0\" )
					)
					( Status sCSetFlattened )
					( Origin gBackEnd )
				)
				( attribute "RELATIVE_PROPAGATION_DELAY" "0.00 MIL,195.00 MIL"
					( Parent
						( matchGroupRef "@baseboard_fab2_lib.baseboard_fab2(sch_1):\MG_DQ-DQS_FAR_DIMM_NG_M_J_BYTE0\" )
					)
					( Units "uMatchProp" "ns" 1.000000)
					( Status sCSetFlattened )
					( Origin gBackEnd )
				)
				( attribute "RELATIVE_PROPAGATION_DELAY_SCOPE" "G"
					( Parent
						( matchGroupRef "@baseboard_fab2_lib.baseboard_fab2(sch_1):\MG_DQ_FAR_DIMM_NG_M_J_BYTE0\" )
					)
					( Status sCSetFlattened )
					( Origin gBackEnd )
				)
				( attribute "RELATIVE_PROPAGATION_DELAY" "-50.00 MIL,50.00 MIL"
					( Parent
						( matchGroupRef "@baseboard_fab2_lib.baseboard_fab2(sch_1):\MG_DQ_FAR_DIMM_NG_M_J_BYTE0\" )
					)
					( Units "uMatchProp" "ns" 1.000000)
					( Status sCSetFlattened )
					( Origin gBackEnd )
				)
			)
			( pinPair "@baseboard_fab2_lib.baseboard_fab2(sch_1):\PP2501\"
				( pinRef "@baseboard_fab2_lib.baseboard_fab2(sch_1):page59_i172:DDR2_DQ(3)" )
				( pinRef "@baseboard_fab2_lib.baseboard_fab2(sch_1):page82_i187:DQ(3)" )
				( attribute "RELATIVE_PROPAGATION_DELAY_SCOPE" "G"
					( Parent
						( matchGroupRef "@baseboard_fab2_lib.baseboard_fab2(sch_1):\MG_DQ-DQS_NEAR_DIMM_NG_M_J_BYTE0\" )
					)
					( Status sCSetFlattened )
					( Origin gBackEnd )
				)
				( attribute "RELATIVE_PROPAGATION_DELAY" "0.00 MIL,195.00 MIL"
					( Parent
						( matchGroupRef "@baseboard_fab2_lib.baseboard_fab2(sch_1):\MG_DQ-DQS_NEAR_DIMM_NG_M_J_BYTE0\" )
					)
					( Units "uMatchProp" "ns" 1.000000)
					( Status sCSetFlattened )
					( Origin gBackEnd )
				)
				( attribute "RELATIVE_PROPAGATION_DELAY_SCOPE" "G"
					( Parent
						( matchGroupRef "@baseboard_fab2_lib.baseboard_fab2(sch_1):\MG_DQ_NEAR_DIMM_NG_M_J_BYTE0\" )
					)
					( Status sCSetFlattened )
					( Origin gBackEnd )
				)
				( attribute "RELATIVE_PROPAGATION_DELAY" "-50.00 MIL,50.00 MIL"
					( Parent
						( matchGroupRef "@baseboard_fab2_lib.baseboard_fab2(sch_1):\MG_DQ_NEAR_DIMM_NG_M_J_BYTE0\" )
					)
					( Units "uMatchProp" "ns" 1.000000)
					( Status sCSetFlattened )
					( Origin gBackEnd )
				)
			)
			( pinPair "@baseboard_fab2_lib.baseboard_fab2(sch_1):\PP2503\"
				( pinRef "@baseboard_fab2_lib.baseboard_fab2(sch_1):page59_i172:DDR2_DQ(4)" )
				( pinRef "@baseboard_fab2_lib.baseboard_fab2(sch_1):page81_i186:DQ(5)" )
				( attribute "RELATIVE_PROPAGATION_DELAY_SCOPE" "G"
					( Parent
						( matchGroupRef "@baseboard_fab2_lib.baseboard_fab2(sch_1):\MG_DQ-DQS_FAR_DIMM_NG_M_J_BYTE0\" )
					)
					( Status sCSetFlattened )
					( Origin gBackEnd )
				)
				( attribute "RELATIVE_PROPAGATION_DELAY" "0.00 MIL,195.00 MIL"
					( Parent
						( matchGroupRef "@baseboard_fab2_lib.baseboard_fab2(sch_1):\MG_DQ-DQS_FAR_DIMM_NG_M_J_BYTE0\" )
					)
					( Units "uMatchProp" "ns" 1.000000)
					( Status sCSetFlattened )
					( Origin gBackEnd )
				)
				( attribute "RELATIVE_PROPAGATION_DELAY_SCOPE" "G"
					( Parent
						( matchGroupRef "@baseboard_fab2_lib.baseboard_fab2(sch_1):\MG_DQ_FAR_DIMM_NG_M_J_BYTE0\" )
					)
					( Status sCSetFlattened )
					( Origin gBackEnd )
				)
				( attribute "RELATIVE_PROPAGATION_DELAY" "-50.00 MIL,50.00 MIL"
					( Parent
						( matchGroupRef "@baseboard_fab2_lib.baseboard_fab2(sch_1):\MG_DQ_FAR_DIMM_NG_M_J_BYTE0\" )
					)
					( Units "uMatchProp" "ns" 1.000000)
					( Status sCSetFlattened )
					( Origin gBackEnd )
				)
			)
			( pinPair "@baseboard_fab2_lib.baseboard_fab2(sch_1):\PP2504\"
				( pinRef "@baseboard_fab2_lib.baseboard_fab2(sch_1):page59_i172:DDR2_DQ(4)" )
				( pinRef "@baseboard_fab2_lib.baseboard_fab2(sch_1):page82_i187:DQ(4)" )
				( attribute "RELATIVE_PROPAGATION_DELAY_SCOPE" "G"
					( Parent
						( matchGroupRef "@baseboard_fab2_lib.baseboard_fab2(sch_1):\MG_DQ-DQS_NEAR_DIMM_NG_M_J_BYTE0\" )
					)
					( Status sCSetFlattened )
					( Origin gBackEnd )
				)
				( attribute "RELATIVE_PROPAGATION_DELAY" "0.00 MIL,195.00 MIL"
					( Parent
						( matchGroupRef "@baseboard_fab2_lib.baseboard_fab2(sch_1):\MG_DQ-DQS_NEAR_DIMM_NG_M_J_BYTE0\" )
					)
					( Units "uMatchProp" "ns" 1.000000)
					( Status sCSetFlattened )
					( Origin gBackEnd )
				)
				( attribute "RELATIVE_PROPAGATION_DELAY_SCOPE" "G"
					( Parent
						( matchGroupRef "@baseboard_fab2_lib.baseboard_fab2(sch_1):\MG_DQ_NEAR_DIMM_NG_M_J_BYTE0\" )
					)
					( Status sCSetFlattened )
					( Origin gBackEnd )
				)
				( attribute "RELATIVE_PROPAGATION_DELAY" "-50.00 MIL,50.00 MIL"
					( Parent
						( matchGroupRef "@baseboard_fab2_lib.baseboard_fab2(sch_1):\MG_DQ_NEAR_DIMM_NG_M_J_BYTE0\" )
					)
					( Units "uMatchProp" "ns" 1.000000)
					( Status sCSetFlattened )
					( Origin gBackEnd )
				)
			)
			( pinPair "@baseboard_fab2_lib.baseboard_fab2(sch_1):\PP2506\"
				( pinRef "@baseboard_fab2_lib.baseboard_fab2(sch_1):page59_i172:DDR2_DQ(5)" )
				( pinRef "@baseboard_fab2_lib.baseboard_fab2(sch_1):page81_i186:DQ(4)" )
				( attribute "RELATIVE_PROPAGATION_DELAY_SCOPE" "G"
					( Parent
						( matchGroupRef "@baseboard_fab2_lib.baseboard_fab2(sch_1):\MG_DQ-DQS_FAR_DIMM_NG_M_J_BYTE0\" )
					)
					( Status sCSetFlattened )
					( Origin gBackEnd )
				)
				( attribute "RELATIVE_PROPAGATION_DELAY" "0.00 MIL,195.00 MIL"
					( Parent
						( matchGroupRef "@baseboard_fab2_lib.baseboard_fab2(sch_1):\MG_DQ-DQS_FAR_DIMM_NG_M_J_BYTE0\" )
					)
					( Units "uMatchProp" "ns" 1.000000)
					( Status sCSetFlattened )
					( Origin gBackEnd )
				)
				( attribute "RELATIVE_PROPAGATION_DELAY_SCOPE" "G"
					( Parent
						( matchGroupRef "@baseboard_fab2_lib.baseboard_fab2(sch_1):\MG_DQ_FAR_DIMM_NG_M_J_BYTE0\" )
					)
					( Status sCSetFlattened )
					( Origin gBackEnd )
				)
				( attribute "RELATIVE_PROPAGATION_DELAY" "-50.00 MIL,50.00 MIL"
					( Parent
						( matchGroupRef "@baseboard_fab2_lib.baseboard_fab2(sch_1):\MG_DQ_FAR_DIMM_NG_M_J_BYTE0\" )
					)
					( Units "uMatchProp" "ns" 1.000000)
					( Status sCSetFlattened )
					( Origin gBackEnd )
				)
			)
			( pinPair "@baseboard_fab2_lib.baseboard_fab2(sch_1):\PP2507\"
				( pinRef "@baseboard_fab2_lib.baseboard_fab2(sch_1):page59_i172:DDR2_DQ(5)" )
				( pinRef "@baseboard_fab2_lib.baseboard_fab2(sch_1):page82_i187:DQ(5)" )
				( attribute "RELATIVE_PROPAGATION_DELAY_SCOPE" "G"
					( Parent
						( matchGroupRef "@baseboard_fab2_lib.baseboard_fab2(sch_1):\MG_DQ-DQS_NEAR_DIMM_NG_M_J_BYTE0\" )
					)
					( Status sCSetFlattened )
					( Origin gBackEnd )
				)
				( attribute "RELATIVE_PROPAGATION_DELAY" "0.00 MIL,195.00 MIL"
					( Parent
						( matchGroupRef "@baseboard_fab2_lib.baseboard_fab2(sch_1):\MG_DQ-DQS_NEAR_DIMM_NG_M_J_BYTE0\" )
					)
					( Units "uMatchProp" "ns" 1.000000)
					( Status sCSetFlattened )
					( Origin gBackEnd )
				)
				( attribute "RELATIVE_PROPAGATION_DELAY_SCOPE" "G"
					( Parent
						( matchGroupRef "@baseboard_fab2_lib.baseboard_fab2(sch_1):\MG_DQ_NEAR_DIMM_NG_M_J_BYTE0\" )
					)
					( Status sCSetFlattened )
					( Origin gBackEnd )
				)
				( attribute "RELATIVE_PROPAGATION_DELAY" "-50.00 MIL,50.00 MIL"
					( Parent
						( matchGroupRef "@baseboard_fab2_lib.baseboard_fab2(sch_1):\MG_DQ_NEAR_DIMM_NG_M_J_BYTE0\" )
					)
					( Units "uMatchProp" "ns" 1.000000)
					( Status sCSetFlattened )
					( Origin gBackEnd )
				)
			)
			( pinPair "@baseboard_fab2_lib.baseboard_fab2(sch_1):\PP2509\"
				( pinRef "@baseboard_fab2_lib.baseboard_fab2(sch_1):page59_i172:DDR2_DQ(6)" )
				( pinRef "@baseboard_fab2_lib.baseboard_fab2(sch_1):page81_i186:DQ(7)" )
				( attribute "RELATIVE_PROPAGATION_DELAY_SCOPE" "G"
					( Parent
						( matchGroupRef "@baseboard_fab2_lib.baseboard_fab2(sch_1):\MG_DQ-DQS_FAR_DIMM_NG_M_J_BYTE0\" )
					)
					( Status sCSetFlattened )
					( Origin gBackEnd )
				)
				( attribute "RELATIVE_PROPAGATION_DELAY" "0.00 MIL,195.00 MIL"
					( Parent
						( matchGroupRef "@baseboard_fab2_lib.baseboard_fab2(sch_1):\MG_DQ-DQS_FAR_DIMM_NG_M_J_BYTE0\" )
					)
					( Units "uMatchProp" "ns" 1.000000)
					( Status sCSetFlattened )
					( Origin gBackEnd )
				)
				( attribute "RELATIVE_PROPAGATION_DELAY_SCOPE" "G"
					( Parent
						( matchGroupRef "@baseboard_fab2_lib.baseboard_fab2(sch_1):\MG_DQ_FAR_DIMM_NG_M_J_BYTE0\" )
					)
					( Status sCSetFlattened )
					( Origin gBackEnd )
				)
				( attribute "RELATIVE_PROPAGATION_DELAY" "-50.00 MIL,50.00 MIL"
					( Parent
						( matchGroupRef "@baseboard_fab2_lib.baseboard_fab2(sch_1):\MG_DQ_FAR_DIMM_NG_M_J_BYTE0\" )
					)
					( Units "uMatchProp" "ns" 1.000000)
					( Status sCSetFlattened )
					( Origin gBackEnd )
				)
			)
			( pinPair "@baseboard_fab2_lib.baseboard_fab2(sch_1):\PP2510\"
				( pinRef "@baseboard_fab2_lib.baseboard_fab2(sch_1):page59_i172:DDR2_DQ(6)" )
				( pinRef "@baseboard_fab2_lib.baseboard_fab2(sch_1):page82_i187:DQ(6)" )
				( attribute "RELATIVE_PROPAGATION_DELAY_SCOPE" "G"
					( Parent
						( matchGroupRef "@baseboard_fab2_lib.baseboard_fab2(sch_1):\MG_DQ-DQS_NEAR_DIMM_NG_M_J_BYTE0\" )
					)
					( Status sCSetFlattened )
					( Origin gBackEnd )
				)
				( attribute "RELATIVE_PROPAGATION_DELAY" "0.00 MIL,195.00 MIL"
					( Parent
						( matchGroupRef "@baseboard_fab2_lib.baseboard_fab2(sch_1):\MG_DQ-DQS_NEAR_DIMM_NG_M_J_BYTE0\" )
					)
					( Units "uMatchProp" "ns" 1.000000)
					( Status sCSetFlattened )
					( Origin gBackEnd )
				)
				( attribute "RELATIVE_PROPAGATION_DELAY_SCOPE" "G"
					( Parent
						( matchGroupRef "@baseboard_fab2_lib.baseboard_fab2(sch_1):\MG_DQ_NEAR_DIMM_NG_M_J_BYTE0\" )
					)
					( Status sCSetFlattened )
					( Origin gBackEnd )
				)
				( attribute "RELATIVE_PROPAGATION_DELAY" "-50.00 MIL,50.00 MIL"
					( Parent
						( matchGroupRef "@baseboard_fab2_lib.baseboard_fab2(sch_1):\MG_DQ_NEAR_DIMM_NG_M_J_BYTE0\" )
					)
					( Units "uMatchProp" "ns" 1.000000)
					( Status sCSetFlattened )
					( Origin gBackEnd )
				)
			)
			( pinPair "@baseboard_fab2_lib.baseboard_fab2(sch_1):\PP2512\"
				( pinRef "@baseboard_fab2_lib.baseboard_fab2(sch_1):page59_i172:DDR2_DQ(7)" )
				( pinRef "@baseboard_fab2_lib.baseboard_fab2(sch_1):page81_i186:DQ(6)" )
				( attribute "RELATIVE_PROPAGATION_DELAY_SCOPE" "G"
					( Parent
						( matchGroupRef "@baseboard_fab2_lib.baseboard_fab2(sch_1):\MG_DQ-DQS_FAR_DIMM_NG_M_J_BYTE0\" )
					)
					( Status sCSetFlattened )
					( Origin gBackEnd )
				)
				( attribute "RELATIVE_PROPAGATION_DELAY" "0.00 MIL,195.00 MIL"
					( Parent
						( matchGroupRef "@baseboard_fab2_lib.baseboard_fab2(sch_1):\MG_DQ-DQS_FAR_DIMM_NG_M_J_BYTE0\" )
					)
					( Units "uMatchProp" "ns" 1.000000)
					( Status sCSetFlattened )
					( Origin gBackEnd )
				)
				( attribute "RELATIVE_PROPAGATION_DELAY_SCOPE" "G"
					( Parent
						( matchGroupRef "@baseboard_fab2_lib.baseboard_fab2(sch_1):\MG_DQ_FAR_DIMM_NG_M_J_BYTE0\" )
					)
					( Status sCSetFlattened )
					( Origin gBackEnd )
				)
				( attribute "RELATIVE_PROPAGATION_DELAY" "-50.00 MIL,50.00 MIL"
					( Parent
						( matchGroupRef "@baseboard_fab2_lib.baseboard_fab2(sch_1):\MG_DQ_FAR_DIMM_NG_M_J_BYTE0\" )
					)
					( Units "uMatchProp" "ns" 1.000000)
					( Status sCSetFlattened )
					( Origin gBackEnd )
				)
			)
			( pinPair "@baseboard_fab2_lib.baseboard_fab2(sch_1):\PP2513\"
				( pinRef "@baseboard_fab2_lib.baseboard_fab2(sch_1):page59_i172:DDR2_DQ(7)" )
				( pinRef "@baseboard_fab2_lib.baseboard_fab2(sch_1):page82_i187:DQ(7)" )
				( attribute "RELATIVE_PROPAGATION_DELAY_SCOPE" "G"
					( Parent
						( matchGroupRef "@baseboard_fab2_lib.baseboard_fab2(sch_1):\MG_DQ-DQS_NEAR_DIMM_NG_M_J_BYTE0\" )
					)
					( Status sCSetFlattened )
					( Origin gBackEnd )
				)
				( attribute "RELATIVE_PROPAGATION_DELAY" "0.00 MIL,195.00 MIL"
					( Parent
						( matchGroupRef "@baseboard_fab2_lib.baseboard_fab2(sch_1):\MG_DQ-DQS_NEAR_DIMM_NG_M_J_BYTE0\" )
					)
					( Units "uMatchProp" "ns" 1.000000)
					( Status sCSetFlattened )
					( Origin gBackEnd )
				)
				( attribute "RELATIVE_PROPAGATION_DELAY_SCOPE" "G"
					( Parent
						( matchGroupRef "@baseboard_fab2_lib.baseboard_fab2(sch_1):\MG_DQ_NEAR_DIMM_NG_M_J_BYTE0\" )
					)
					( Status sCSetFlattened )
					( Origin gBackEnd )
				)
				( attribute "RELATIVE_PROPAGATION_DELAY" "-50.00 MIL,50.00 MIL"
					( Parent
						( matchGroupRef "@baseboard_fab2_lib.baseboard_fab2(sch_1):\MG_DQ_NEAR_DIMM_NG_M_J_BYTE0\" )
					)
					( Units "uMatchProp" "ns" 1.000000)
					( Status sCSetFlattened )
					( Origin gBackEnd )
				)
			)
			( pinPair "@baseboard_fab2_lib.baseboard_fab2(sch_1):\PP2467\"
				( pinRef "@baseboard_fab2_lib.baseboard_fab2(sch_1):page59_i172:DDR2_DQ(8)" )
				( pinRef "@baseboard_fab2_lib.baseboard_fab2(sch_1):page81_i186:DQ(9)" )
				( attribute "RELATIVE_PROPAGATION_DELAY_SCOPE" "G"
					( Parent
						( matchGroupRef "@baseboard_fab2_lib.baseboard_fab2(sch_1):\MG_DQ-DQS_FAR_DIMM_NG_M_J_BYTE1\" )
					)
					( Status sCSetFlattened )
					( Origin gBackEnd )
				)
				( attribute "RELATIVE_PROPAGATION_DELAY" "0.00 MIL,195.00 MIL"
					( Parent
						( matchGroupRef "@baseboard_fab2_lib.baseboard_fab2(sch_1):\MG_DQ-DQS_FAR_DIMM_NG_M_J_BYTE1\" )
					)
					( Units "uMatchProp" "ns" 1.000000)
					( Status sCSetFlattened )
					( Origin gBackEnd )
				)
				( attribute "RELATIVE_PROPAGATION_DELAY_SCOPE" "G"
					( Parent
						( matchGroupRef "@baseboard_fab2_lib.baseboard_fab2(sch_1):\MG_DQ_FAR_DIMM_NG_M_J_BYTE1\" )
					)
					( Status sCSetFlattened )
					( Origin gBackEnd )
				)
				( attribute "RELATIVE_PROPAGATION_DELAY" "-50.00 MIL,50.00 MIL"
					( Parent
						( matchGroupRef "@baseboard_fab2_lib.baseboard_fab2(sch_1):\MG_DQ_FAR_DIMM_NG_M_J_BYTE1\" )
					)
					( Units "uMatchProp" "ns" 1.000000)
					( Status sCSetFlattened )
					( Origin gBackEnd )
				)
			)
			( pinPair "@baseboard_fab2_lib.baseboard_fab2(sch_1):\PP2468\"
				( pinRef "@baseboard_fab2_lib.baseboard_fab2(sch_1):page59_i172:DDR2_DQ(8)" )
				( pinRef "@baseboard_fab2_lib.baseboard_fab2(sch_1):page82_i187:DQ(8)" )
				( attribute "RELATIVE_PROPAGATION_DELAY_SCOPE" "G"
					( Parent
						( matchGroupRef "@baseboard_fab2_lib.baseboard_fab2(sch_1):\MG_DQ-DQS_NEAR_DIMM_NG_M_J_BYTE1\" )
					)
					( Status sCSetFlattened )
					( Origin gBackEnd )
				)
				( attribute "RELATIVE_PROPAGATION_DELAY" "0.00 MIL,195.00 MIL"
					( Parent
						( matchGroupRef "@baseboard_fab2_lib.baseboard_fab2(sch_1):\MG_DQ-DQS_NEAR_DIMM_NG_M_J_BYTE1\" )
					)
					( Units "uMatchProp" "ns" 1.000000)
					( Status sCSetFlattened )
					( Origin gBackEnd )
				)
				( attribute "RELATIVE_PROPAGATION_DELAY_SCOPE" "G"
					( Parent
						( matchGroupRef "@baseboard_fab2_lib.baseboard_fab2(sch_1):\MG_DQ_NEAR_DIMM_NG_M_J_BYTE1\" )
					)
					( Status sCSetFlattened )
					( Origin gBackEnd )
				)
				( attribute "RELATIVE_PROPAGATION_DELAY" "-50.00 MIL,50.00 MIL"
					( Parent
						( matchGroupRef "@baseboard_fab2_lib.baseboard_fab2(sch_1):\MG_DQ_NEAR_DIMM_NG_M_J_BYTE1\" )
					)
					( Units "uMatchProp" "ns" 1.000000)
					( Status sCSetFlattened )
					( Origin gBackEnd )
				)
			)
			( pinPair "@baseboard_fab2_lib.baseboard_fab2(sch_1):\PP2470\"
				( pinRef "@baseboard_fab2_lib.baseboard_fab2(sch_1):page59_i172:DDR2_DQ(9)" )
				( pinRef "@baseboard_fab2_lib.baseboard_fab2(sch_1):page81_i186:DQ(8)" )
				( attribute "RELATIVE_PROPAGATION_DELAY_SCOPE" "G"
					( Parent
						( matchGroupRef "@baseboard_fab2_lib.baseboard_fab2(sch_1):\MG_DQ-DQS_FAR_DIMM_NG_M_J_BYTE1\" )
					)
					( Status sCSetFlattened )
					( Origin gBackEnd )
				)
				( attribute "RELATIVE_PROPAGATION_DELAY" "0.00 MIL,195.00 MIL"
					( Parent
						( matchGroupRef "@baseboard_fab2_lib.baseboard_fab2(sch_1):\MG_DQ-DQS_FAR_DIMM_NG_M_J_BYTE1\" )
					)
					( Units "uMatchProp" "ns" 1.000000)
					( Status sCSetFlattened )
					( Origin gBackEnd )
				)
				( attribute "RELATIVE_PROPAGATION_DELAY_SCOPE" "G"
					( Parent
						( matchGroupRef "@baseboard_fab2_lib.baseboard_fab2(sch_1):\MG_DQ_FAR_DIMM_NG_M_J_BYTE1\" )
					)
					( Status sCSetFlattened )
					( Origin gBackEnd )
				)
				( attribute "RELATIVE_PROPAGATION_DELAY" "-50.00 MIL,50.00 MIL"
					( Parent
						( matchGroupRef "@baseboard_fab2_lib.baseboard_fab2(sch_1):\MG_DQ_FAR_DIMM_NG_M_J_BYTE1\" )
					)
					( Units "uMatchProp" "ns" 1.000000)
					( Status sCSetFlattened )
					( Origin gBackEnd )
				)
			)
			( pinPair "@baseboard_fab2_lib.baseboard_fab2(sch_1):\PP2471\"
				( pinRef "@baseboard_fab2_lib.baseboard_fab2(sch_1):page59_i172:DDR2_DQ(9)" )
				( pinRef "@baseboard_fab2_lib.baseboard_fab2(sch_1):page82_i187:DQ(9)" )
				( attribute "RELATIVE_PROPAGATION_DELAY_SCOPE" "G"
					( Parent
						( matchGroupRef "@baseboard_fab2_lib.baseboard_fab2(sch_1):\MG_DQ-DQS_NEAR_DIMM_NG_M_J_BYTE1\" )
					)
					( Status sCSetFlattened )
					( Origin gBackEnd )
				)
				( attribute "RELATIVE_PROPAGATION_DELAY" "0.00 MIL,195.00 MIL"
					( Parent
						( matchGroupRef "@baseboard_fab2_lib.baseboard_fab2(sch_1):\MG_DQ-DQS_NEAR_DIMM_NG_M_J_BYTE1\" )
					)
					( Units "uMatchProp" "ns" 1.000000)
					( Status sCSetFlattened )
					( Origin gBackEnd )
				)
				( attribute "RELATIVE_PROPAGATION_DELAY_SCOPE" "G"
					( Parent
						( matchGroupRef "@baseboard_fab2_lib.baseboard_fab2(sch_1):\MG_DQ_NEAR_DIMM_NG_M_J_BYTE1\" )
					)
					( Status sCSetFlattened )
					( Origin gBackEnd )
				)
				( attribute "RELATIVE_PROPAGATION_DELAY" "-50.00 MIL,50.00 MIL"
					( Parent
						( matchGroupRef "@baseboard_fab2_lib.baseboard_fab2(sch_1):\MG_DQ_NEAR_DIMM_NG_M_J_BYTE1\" )
					)
					( Units "uMatchProp" "ns" 1.000000)
					( Status sCSetFlattened )
					( Origin gBackEnd )
				)
			)
			( pinPair "@baseboard_fab2_lib.baseboard_fab2(sch_1):\PP2473\"
				( pinRef "@baseboard_fab2_lib.baseboard_fab2(sch_1):page59_i172:DDR2_DQ(10)" )
				( pinRef "@baseboard_fab2_lib.baseboard_fab2(sch_1):page81_i186:DQ(11)" )
				( attribute "RELATIVE_PROPAGATION_DELAY_SCOPE" "G"
					( Parent
						( matchGroupRef "@baseboard_fab2_lib.baseboard_fab2(sch_1):\MG_DQ-DQS_FAR_DIMM_NG_M_J_BYTE1\" )
					)
					( Status sCSetFlattened )
					( Origin gBackEnd )
				)
				( attribute "RELATIVE_PROPAGATION_DELAY" "0.00 MIL,195.00 MIL"
					( Parent
						( matchGroupRef "@baseboard_fab2_lib.baseboard_fab2(sch_1):\MG_DQ-DQS_FAR_DIMM_NG_M_J_BYTE1\" )
					)
					( Units "uMatchProp" "ns" 1.000000)
					( Status sCSetFlattened )
					( Origin gBackEnd )
				)
				( attribute "RELATIVE_PROPAGATION_DELAY_SCOPE" "G"
					( Parent
						( matchGroupRef "@baseboard_fab2_lib.baseboard_fab2(sch_1):\MG_DQ_FAR_DIMM_NG_M_J_BYTE1\" )
					)
					( Status sCSetFlattened )
					( Origin gBackEnd )
				)
				( attribute "RELATIVE_PROPAGATION_DELAY" "-50.00 MIL,50.00 MIL"
					( Parent
						( matchGroupRef "@baseboard_fab2_lib.baseboard_fab2(sch_1):\MG_DQ_FAR_DIMM_NG_M_J_BYTE1\" )
					)
					( Units "uMatchProp" "ns" 1.000000)
					( Status sCSetFlattened )
					( Origin gBackEnd )
				)
			)
			( pinPair "@baseboard_fab2_lib.baseboard_fab2(sch_1):\PP2474\"
				( pinRef "@baseboard_fab2_lib.baseboard_fab2(sch_1):page59_i172:DDR2_DQ(10)" )
				( pinRef "@baseboard_fab2_lib.baseboard_fab2(sch_1):page82_i187:DQ(10)" )
				( attribute "RELATIVE_PROPAGATION_DELAY_SCOPE" "G"
					( Parent
						( matchGroupRef "@baseboard_fab2_lib.baseboard_fab2(sch_1):\MG_DQ-DQS_NEAR_DIMM_NG_M_J_BYTE1\" )
					)
					( Status sCSetFlattened )
					( Origin gBackEnd )
				)
				( attribute "RELATIVE_PROPAGATION_DELAY" "0.00 MIL,195.00 MIL"
					( Parent
						( matchGroupRef "@baseboard_fab2_lib.baseboard_fab2(sch_1):\MG_DQ-DQS_NEAR_DIMM_NG_M_J_BYTE1\" )
					)
					( Units "uMatchProp" "ns" 1.000000)
					( Status sCSetFlattened )
					( Origin gBackEnd )
				)
				( attribute "RELATIVE_PROPAGATION_DELAY_SCOPE" "G"
					( Parent
						( matchGroupRef "@baseboard_fab2_lib.baseboard_fab2(sch_1):\MG_DQ_NEAR_DIMM_NG_M_J_BYTE1\" )
					)
					( Status sCSetFlattened )
					( Origin gBackEnd )
				)
				( attribute "RELATIVE_PROPAGATION_DELAY" "-50.00 MIL,50.00 MIL"
					( Parent
						( matchGroupRef "@baseboard_fab2_lib.baseboard_fab2(sch_1):\MG_DQ_NEAR_DIMM_NG_M_J_BYTE1\" )
					)
					( Units "uMatchProp" "ns" 1.000000)
					( Status sCSetFlattened )
					( Origin gBackEnd )
				)
			)
			( pinPair "@baseboard_fab2_lib.baseboard_fab2(sch_1):\PP2476\"
				( pinRef "@baseboard_fab2_lib.baseboard_fab2(sch_1):page59_i172:DDR2_DQ(11)" )
				( pinRef "@baseboard_fab2_lib.baseboard_fab2(sch_1):page81_i186:DQ(10)" )
				( attribute "RELATIVE_PROPAGATION_DELAY_SCOPE" "G"
					( Parent
						( matchGroupRef "@baseboard_fab2_lib.baseboard_fab2(sch_1):\MG_DQ-DQS_FAR_DIMM_NG_M_J_BYTE1\" )
					)
					( Status sCSetFlattened )
					( Origin gBackEnd )
				)
				( attribute "RELATIVE_PROPAGATION_DELAY" "0.00 MIL,195.00 MIL"
					( Parent
						( matchGroupRef "@baseboard_fab2_lib.baseboard_fab2(sch_1):\MG_DQ-DQS_FAR_DIMM_NG_M_J_BYTE1\" )
					)
					( Units "uMatchProp" "ns" 1.000000)
					( Status sCSetFlattened )
					( Origin gBackEnd )
				)
				( attribute "RELATIVE_PROPAGATION_DELAY_SCOPE" "G"
					( Parent
						( matchGroupRef "@baseboard_fab2_lib.baseboard_fab2(sch_1):\MG_DQ_FAR_DIMM_NG_M_J_BYTE1\" )
					)
					( Status sCSetFlattened )
					( Origin gBackEnd )
				)
				( attribute "RELATIVE_PROPAGATION_DELAY" "-50.00 MIL,50.00 MIL"
					( Parent
						( matchGroupRef "@baseboard_fab2_lib.baseboard_fab2(sch_1):\MG_DQ_FAR_DIMM_NG_M_J_BYTE1\" )
					)
					( Units "uMatchProp" "ns" 1.000000)
					( Status sCSetFlattened )
					( Origin gBackEnd )
				)
			)
			( pinPair "@baseboard_fab2_lib.baseboard_fab2(sch_1):\PP2477\"
				( pinRef "@baseboard_fab2_lib.baseboard_fab2(sch_1):page59_i172:DDR2_DQ(11)" )
				( pinRef "@baseboard_fab2_lib.baseboard_fab2(sch_1):page82_i187:DQ(11)" )
				( attribute "RELATIVE_PROPAGATION_DELAY_SCOPE" "G"
					( Parent
						( matchGroupRef "@baseboard_fab2_lib.baseboard_fab2(sch_1):\MG_DQ-DQS_NEAR_DIMM_NG_M_J_BYTE1\" )
					)
					( Status sCSetFlattened )
					( Origin gBackEnd )
				)
				( attribute "RELATIVE_PROPAGATION_DELAY" "0.00 MIL,195.00 MIL"
					( Parent
						( matchGroupRef "@baseboard_fab2_lib.baseboard_fab2(sch_1):\MG_DQ-DQS_NEAR_DIMM_NG_M_J_BYTE1\" )
					)
					( Units "uMatchProp" "ns" 1.000000)
					( Status sCSetFlattened )
					( Origin gBackEnd )
				)
				( attribute "RELATIVE_PROPAGATION_DELAY_SCOPE" "G"
					( Parent
						( matchGroupRef "@baseboard_fab2_lib.baseboard_fab2(sch_1):\MG_DQ_NEAR_DIMM_NG_M_J_BYTE1\" )
					)
					( Status sCSetFlattened )
					( Origin gBackEnd )
				)
				( attribute "RELATIVE_PROPAGATION_DELAY" "-50.00 MIL,50.00 MIL"
					( Parent
						( matchGroupRef "@baseboard_fab2_lib.baseboard_fab2(sch_1):\MG_DQ_NEAR_DIMM_NG_M_J_BYTE1\" )
					)
					( Units "uMatchProp" "ns" 1.000000)
					( Status sCSetFlattened )
					( Origin gBackEnd )
				)
			)
			( pinPair "@baseboard_fab2_lib.baseboard_fab2(sch_1):\PP2479\"
				( pinRef "@baseboard_fab2_lib.baseboard_fab2(sch_1):page59_i172:DDR2_DQ(12)" )
				( pinRef "@baseboard_fab2_lib.baseboard_fab2(sch_1):page81_i186:DQ(13)" )
				( attribute "RELATIVE_PROPAGATION_DELAY_SCOPE" "G"
					( Parent
						( matchGroupRef "@baseboard_fab2_lib.baseboard_fab2(sch_1):\MG_DQ-DQS_FAR_DIMM_NG_M_J_BYTE1\" )
					)
					( Status sCSetFlattened )
					( Origin gBackEnd )
				)
				( attribute "RELATIVE_PROPAGATION_DELAY" "0.00 MIL,195.00 MIL"
					( Parent
						( matchGroupRef "@baseboard_fab2_lib.baseboard_fab2(sch_1):\MG_DQ-DQS_FAR_DIMM_NG_M_J_BYTE1\" )
					)
					( Units "uMatchProp" "ns" 1.000000)
					( Status sCSetFlattened )
					( Origin gBackEnd )
				)
				( attribute "RELATIVE_PROPAGATION_DELAY_SCOPE" "G"
					( Parent
						( matchGroupRef "@baseboard_fab2_lib.baseboard_fab2(sch_1):\MG_DQ_FAR_DIMM_NG_M_J_BYTE1\" )
					)
					( Status sCSetFlattened )
					( Origin gBackEnd )
				)
				( attribute "RELATIVE_PROPAGATION_DELAY" "-50.00 MIL,50.00 MIL"
					( Parent
						( matchGroupRef "@baseboard_fab2_lib.baseboard_fab2(sch_1):\MG_DQ_FAR_DIMM_NG_M_J_BYTE1\" )
					)
					( Units "uMatchProp" "ns" 1.000000)
					( Status sCSetFlattened )
					( Origin gBackEnd )
				)
			)
			( pinPair "@baseboard_fab2_lib.baseboard_fab2(sch_1):\PP2480\"
				( pinRef "@baseboard_fab2_lib.baseboard_fab2(sch_1):page59_i172:DDR2_DQ(12)" )
				( pinRef "@baseboard_fab2_lib.baseboard_fab2(sch_1):page82_i187:DQ(12)" )
				( attribute "RELATIVE_PROPAGATION_DELAY_SCOPE" "G"
					( Parent
						( matchGroupRef "@baseboard_fab2_lib.baseboard_fab2(sch_1):\MG_DQ-DQS_NEAR_DIMM_NG_M_J_BYTE1\" )
					)
					( Status sCSetFlattened )
					( Origin gBackEnd )
				)
				( attribute "RELATIVE_PROPAGATION_DELAY" "0.00 MIL,195.00 MIL"
					( Parent
						( matchGroupRef "@baseboard_fab2_lib.baseboard_fab2(sch_1):\MG_DQ-DQS_NEAR_DIMM_NG_M_J_BYTE1\" )
					)
					( Units "uMatchProp" "ns" 1.000000)
					( Status sCSetFlattened )
					( Origin gBackEnd )
				)
				( attribute "RELATIVE_PROPAGATION_DELAY_SCOPE" "G"
					( Parent
						( matchGroupRef "@baseboard_fab2_lib.baseboard_fab2(sch_1):\MG_DQ_NEAR_DIMM_NG_M_J_BYTE1\" )
					)
					( Status sCSetFlattened )
					( Origin gBackEnd )
				)
				( attribute "RELATIVE_PROPAGATION_DELAY" "-50.00 MIL,50.00 MIL"
					( Parent
						( matchGroupRef "@baseboard_fab2_lib.baseboard_fab2(sch_1):\MG_DQ_NEAR_DIMM_NG_M_J_BYTE1\" )
					)
					( Units "uMatchProp" "ns" 1.000000)
					( Status sCSetFlattened )
					( Origin gBackEnd )
				)
			)
			( pinPair "@baseboard_fab2_lib.baseboard_fab2(sch_1):\PP2482\"
				( pinRef "@baseboard_fab2_lib.baseboard_fab2(sch_1):page59_i172:DDR2_DQ(13)" )
				( pinRef "@baseboard_fab2_lib.baseboard_fab2(sch_1):page81_i186:DQ(12)" )
				( attribute "RELATIVE_PROPAGATION_DELAY_SCOPE" "G"
					( Parent
						( matchGroupRef "@baseboard_fab2_lib.baseboard_fab2(sch_1):\MG_DQ-DQS_FAR_DIMM_NG_M_J_BYTE1\" )
					)
					( Status sCSetFlattened )
					( Origin gBackEnd )
				)
				( attribute "RELATIVE_PROPAGATION_DELAY" "0.00 MIL,195.00 MIL"
					( Parent
						( matchGroupRef "@baseboard_fab2_lib.baseboard_fab2(sch_1):\MG_DQ-DQS_FAR_DIMM_NG_M_J_BYTE1\" )
					)
					( Units "uMatchProp" "ns" 1.000000)
					( Status sCSetFlattened )
					( Origin gBackEnd )
				)
				( attribute "RELATIVE_PROPAGATION_DELAY_SCOPE" "G"
					( Parent
						( matchGroupRef "@baseboard_fab2_lib.baseboard_fab2(sch_1):\MG_DQ_FAR_DIMM_NG_M_J_BYTE1\" )
					)
					( Status sCSetFlattened )
					( Origin gBackEnd )
				)
				( attribute "RELATIVE_PROPAGATION_DELAY" "-50.00 MIL,50.00 MIL"
					( Parent
						( matchGroupRef "@baseboard_fab2_lib.baseboard_fab2(sch_1):\MG_DQ_FAR_DIMM_NG_M_J_BYTE1\" )
					)
					( Units "uMatchProp" "ns" 1.000000)
					( Status sCSetFlattened )
					( Origin gBackEnd )
				)
			)
			( pinPair "@baseboard_fab2_lib.baseboard_fab2(sch_1):\PP2483\"
				( pinRef "@baseboard_fab2_lib.baseboard_fab2(sch_1):page59_i172:DDR2_DQ(13)" )
				( pinRef "@baseboard_fab2_lib.baseboard_fab2(sch_1):page82_i187:DQ(13)" )
				( attribute "RELATIVE_PROPAGATION_DELAY_SCOPE" "G"
					( Parent
						( matchGroupRef "@baseboard_fab2_lib.baseboard_fab2(sch_1):\MG_DQ-DQS_NEAR_DIMM_NG_M_J_BYTE1\" )
					)
					( Status sCSetFlattened )
					( Origin gBackEnd )
				)
				( attribute "RELATIVE_PROPAGATION_DELAY" "0.00 MIL,195.00 MIL"
					( Parent
						( matchGroupRef "@baseboard_fab2_lib.baseboard_fab2(sch_1):\MG_DQ-DQS_NEAR_DIMM_NG_M_J_BYTE1\" )
					)
					( Units "uMatchProp" "ns" 1.000000)
					( Status sCSetFlattened )
					( Origin gBackEnd )
				)
				( attribute "RELATIVE_PROPAGATION_DELAY_SCOPE" "G"
					( Parent
						( matchGroupRef "@baseboard_fab2_lib.baseboard_fab2(sch_1):\MG_DQ_NEAR_DIMM_NG_M_J_BYTE1\" )
					)
					( Status sCSetFlattened )
					( Origin gBackEnd )
				)
				( attribute "RELATIVE_PROPAGATION_DELAY" "-50.00 MIL,50.00 MIL"
					( Parent
						( matchGroupRef "@baseboard_fab2_lib.baseboard_fab2(sch_1):\MG_DQ_NEAR_DIMM_NG_M_J_BYTE1\" )
					)
					( Units "uMatchProp" "ns" 1.000000)
					( Status sCSetFlattened )
					( Origin gBackEnd )
				)
			)
			( pinPair "@baseboard_fab2_lib.baseboard_fab2(sch_1):\PP2485\"
				( pinRef "@baseboard_fab2_lib.baseboard_fab2(sch_1):page59_i172:DDR2_DQ(14)" )
				( pinRef "@baseboard_fab2_lib.baseboard_fab2(sch_1):page81_i186:DQ(15)" )
				( attribute "RELATIVE_PROPAGATION_DELAY_SCOPE" "G"
					( Parent
						( matchGroupRef "@baseboard_fab2_lib.baseboard_fab2(sch_1):\MG_DQ-DQS_FAR_DIMM_NG_M_J_BYTE1\" )
					)
					( Status sCSetFlattened )
					( Origin gBackEnd )
				)
				( attribute "RELATIVE_PROPAGATION_DELAY" "0.00 MIL,195.00 MIL"
					( Parent
						( matchGroupRef "@baseboard_fab2_lib.baseboard_fab2(sch_1):\MG_DQ-DQS_FAR_DIMM_NG_M_J_BYTE1\" )
					)
					( Units "uMatchProp" "ns" 1.000000)
					( Status sCSetFlattened )
					( Origin gBackEnd )
				)
				( attribute "RELATIVE_PROPAGATION_DELAY_SCOPE" "G"
					( Parent
						( matchGroupRef "@baseboard_fab2_lib.baseboard_fab2(sch_1):\MG_DQ_FAR_DIMM_NG_M_J_BYTE1\" )
					)
					( Status sCSetFlattened )
					( Origin gBackEnd )
				)
				( attribute "RELATIVE_PROPAGATION_DELAY" "-50.00 MIL,50.00 MIL"
					( Parent
						( matchGroupRef "@baseboard_fab2_lib.baseboard_fab2(sch_1):\MG_DQ_FAR_DIMM_NG_M_J_BYTE1\" )
					)
					( Units "uMatchProp" "ns" 1.000000)
					( Status sCSetFlattened )
					( Origin gBackEnd )
				)
			)
			( pinPair "@baseboard_fab2_lib.baseboard_fab2(sch_1):\PP2486\"
				( pinRef "@baseboard_fab2_lib.baseboard_fab2(sch_1):page59_i172:DDR2_DQ(14)" )
				( pinRef "@baseboard_fab2_lib.baseboard_fab2(sch_1):page82_i187:DQ(14)" )
				( attribute "RELATIVE_PROPAGATION_DELAY_SCOPE" "G"
					( Parent
						( matchGroupRef "@baseboard_fab2_lib.baseboard_fab2(sch_1):\MG_DQ-DQS_NEAR_DIMM_NG_M_J_BYTE1\" )
					)
					( Status sCSetFlattened )
					( Origin gBackEnd )
				)
				( attribute "RELATIVE_PROPAGATION_DELAY" "0.00 MIL,195.00 MIL"
					( Parent
						( matchGroupRef "@baseboard_fab2_lib.baseboard_fab2(sch_1):\MG_DQ-DQS_NEAR_DIMM_NG_M_J_BYTE1\" )
					)
					( Units "uMatchProp" "ns" 1.000000)
					( Status sCSetFlattened )
					( Origin gBackEnd )
				)
				( attribute "RELATIVE_PROPAGATION_DELAY_SCOPE" "G"
					( Parent
						( matchGroupRef "@baseboard_fab2_lib.baseboard_fab2(sch_1):\MG_DQ_NEAR_DIMM_NG_M_J_BYTE1\" )
					)
					( Status sCSetFlattened )
					( Origin gBackEnd )
				)
				( attribute "RELATIVE_PROPAGATION_DELAY" "-50.00 MIL,50.00 MIL"
					( Parent
						( matchGroupRef "@baseboard_fab2_lib.baseboard_fab2(sch_1):\MG_DQ_NEAR_DIMM_NG_M_J_BYTE1\" )
					)
					( Units "uMatchProp" "ns" 1.000000)
					( Status sCSetFlattened )
					( Origin gBackEnd )
				)
			)
			( pinPair "@baseboard_fab2_lib.baseboard_fab2(sch_1):\PP2488\"
				( pinRef "@baseboard_fab2_lib.baseboard_fab2(sch_1):page59_i172:DDR2_DQ(15)" )
				( pinRef "@baseboard_fab2_lib.baseboard_fab2(sch_1):page81_i186:DQ(14)" )
				( attribute "RELATIVE_PROPAGATION_DELAY_SCOPE" "G"
					( Parent
						( matchGroupRef "@baseboard_fab2_lib.baseboard_fab2(sch_1):\MG_DQ-DQS_FAR_DIMM_NG_M_J_BYTE1\" )
					)
					( Status sCSetFlattened )
					( Origin gBackEnd )
				)
				( attribute "RELATIVE_PROPAGATION_DELAY" "0.00 MIL,195.00 MIL"
					( Parent
						( matchGroupRef "@baseboard_fab2_lib.baseboard_fab2(sch_1):\MG_DQ-DQS_FAR_DIMM_NG_M_J_BYTE1\" )
					)
					( Units "uMatchProp" "ns" 1.000000)
					( Status sCSetFlattened )
					( Origin gBackEnd )
				)
				( attribute "RELATIVE_PROPAGATION_DELAY_SCOPE" "G"
					( Parent
						( matchGroupRef "@baseboard_fab2_lib.baseboard_fab2(sch_1):\MG_DQ_FAR_DIMM_NG_M_J_BYTE1\" )
					)
					( Status sCSetFlattened )
					( Origin gBackEnd )
				)
				( attribute "RELATIVE_PROPAGATION_DELAY" "-50.00 MIL,50.00 MIL"
					( Parent
						( matchGroupRef "@baseboard_fab2_lib.baseboard_fab2(sch_1):\MG_DQ_FAR_DIMM_NG_M_J_BYTE1\" )
					)
					( Units "uMatchProp" "ns" 1.000000)
					( Status sCSetFlattened )
					( Origin gBackEnd )
				)
			)
			( pinPair "@baseboard_fab2_lib.baseboard_fab2(sch_1):\PP2489\"
				( pinRef "@baseboard_fab2_lib.baseboard_fab2(sch_1):page59_i172:DDR2_DQ(15)" )
				( pinRef "@baseboard_fab2_lib.baseboard_fab2(sch_1):page82_i187:DQ(15)" )
				( attribute "RELATIVE_PROPAGATION_DELAY_SCOPE" "G"
					( Parent
						( matchGroupRef "@baseboard_fab2_lib.baseboard_fab2(sch_1):\MG_DQ-DQS_NEAR_DIMM_NG_M_J_BYTE1\" )
					)
					( Status sCSetFlattened )
					( Origin gBackEnd )
				)
				( attribute "RELATIVE_PROPAGATION_DELAY" "0.00 MIL,195.00 MIL"
					( Parent
						( matchGroupRef "@baseboard_fab2_lib.baseboard_fab2(sch_1):\MG_DQ-DQS_NEAR_DIMM_NG_M_J_BYTE1\" )
					)
					( Units "uMatchProp" "ns" 1.000000)
					( Status sCSetFlattened )
					( Origin gBackEnd )
				)
				( attribute "RELATIVE_PROPAGATION_DELAY_SCOPE" "G"
					( Parent
						( matchGroupRef "@baseboard_fab2_lib.baseboard_fab2(sch_1):\MG_DQ_NEAR_DIMM_NG_M_J_BYTE1\" )
					)
					( Status sCSetFlattened )
					( Origin gBackEnd )
				)
				( attribute "RELATIVE_PROPAGATION_DELAY" "-50.00 MIL,50.00 MIL"
					( Parent
						( matchGroupRef "@baseboard_fab2_lib.baseboard_fab2(sch_1):\MG_DQ_NEAR_DIMM_NG_M_J_BYTE1\" )
					)
					( Units "uMatchProp" "ns" 1.000000)
					( Status sCSetFlattened )
					( Origin gBackEnd )
				)
			)
			( pinPair "@baseboard_fab2_lib.baseboard_fab2(sch_1):\PP2443\"
				( pinRef "@baseboard_fab2_lib.baseboard_fab2(sch_1):page59_i172:DDR2_DQ(16)" )
				( pinRef "@baseboard_fab2_lib.baseboard_fab2(sch_1):page81_i186:DQ(17)" )
				( attribute "RELATIVE_PROPAGATION_DELAY_SCOPE" "G"
					( Parent
						( matchGroupRef "@baseboard_fab2_lib.baseboard_fab2(sch_1):\MG_DQ-DQS_FAR_DIMM_NG_M_J_BYTE2\" )
					)
					( Status sCSetFlattened )
					( Origin gBackEnd )
				)
				( attribute "RELATIVE_PROPAGATION_DELAY" "0.00 MIL,195.00 MIL"
					( Parent
						( matchGroupRef "@baseboard_fab2_lib.baseboard_fab2(sch_1):\MG_DQ-DQS_FAR_DIMM_NG_M_J_BYTE2\" )
					)
					( Units "uMatchProp" "ns" 1.000000)
					( Status sCSetFlattened )
					( Origin gBackEnd )
				)
				( attribute "RELATIVE_PROPAGATION_DELAY_SCOPE" "G"
					( Parent
						( matchGroupRef "@baseboard_fab2_lib.baseboard_fab2(sch_1):\MG_DQ_FAR_DIMM_NG_M_J_BYTE2\" )
					)
					( Status sCSetFlattened )
					( Origin gBackEnd )
				)
				( attribute "RELATIVE_PROPAGATION_DELAY" "-50.00 MIL,50.00 MIL"
					( Parent
						( matchGroupRef "@baseboard_fab2_lib.baseboard_fab2(sch_1):\MG_DQ_FAR_DIMM_NG_M_J_BYTE2\" )
					)
					( Units "uMatchProp" "ns" 1.000000)
					( Status sCSetFlattened )
					( Origin gBackEnd )
				)
			)
			( pinPair "@baseboard_fab2_lib.baseboard_fab2(sch_1):\PP2444\"
				( pinRef "@baseboard_fab2_lib.baseboard_fab2(sch_1):page59_i172:DDR2_DQ(16)" )
				( pinRef "@baseboard_fab2_lib.baseboard_fab2(sch_1):page82_i187:DQ(16)" )
				( attribute "RELATIVE_PROPAGATION_DELAY_SCOPE" "G"
					( Parent
						( matchGroupRef "@baseboard_fab2_lib.baseboard_fab2(sch_1):\MG_DQ-DQS_NEAR_DIMM_NG_M_J_BYTE2\" )
					)
					( Status sCSetFlattened )
					( Origin gBackEnd )
				)
				( attribute "RELATIVE_PROPAGATION_DELAY" "0.00 MIL,195.00 MIL"
					( Parent
						( matchGroupRef "@baseboard_fab2_lib.baseboard_fab2(sch_1):\MG_DQ-DQS_NEAR_DIMM_NG_M_J_BYTE2\" )
					)
					( Units "uMatchProp" "ns" 1.000000)
					( Status sCSetFlattened )
					( Origin gBackEnd )
				)
				( attribute "RELATIVE_PROPAGATION_DELAY_SCOPE" "G"
					( Parent
						( matchGroupRef "@baseboard_fab2_lib.baseboard_fab2(sch_1):\MG_DQ_NEAR_DIMM_NG_M_J_BYTE2\" )
					)
					( Status sCSetFlattened )
					( Origin gBackEnd )
				)
				( attribute "RELATIVE_PROPAGATION_DELAY" "-50.00 MIL,50.00 MIL"
					( Parent
						( matchGroupRef "@baseboard_fab2_lib.baseboard_fab2(sch_1):\MG_DQ_NEAR_DIMM_NG_M_J_BYTE2\" )
					)
					( Units "uMatchProp" "ns" 1.000000)
					( Status sCSetFlattened )
					( Origin gBackEnd )
				)
			)
			( pinPair "@baseboard_fab2_lib.baseboard_fab2(sch_1):\PP2446\"
				( pinRef "@baseboard_fab2_lib.baseboard_fab2(sch_1):page59_i172:DDR2_DQ(17)" )
				( pinRef "@baseboard_fab2_lib.baseboard_fab2(sch_1):page81_i186:DQ(16)" )
				( attribute "RELATIVE_PROPAGATION_DELAY_SCOPE" "G"
					( Parent
						( matchGroupRef "@baseboard_fab2_lib.baseboard_fab2(sch_1):\MG_DQ-DQS_FAR_DIMM_NG_M_J_BYTE2\" )
					)
					( Status sCSetFlattened )
					( Origin gBackEnd )
				)
				( attribute "RELATIVE_PROPAGATION_DELAY" "0.00 MIL,195.00 MIL"
					( Parent
						( matchGroupRef "@baseboard_fab2_lib.baseboard_fab2(sch_1):\MG_DQ-DQS_FAR_DIMM_NG_M_J_BYTE2\" )
					)
					( Units "uMatchProp" "ns" 1.000000)
					( Status sCSetFlattened )
					( Origin gBackEnd )
				)
				( attribute "RELATIVE_PROPAGATION_DELAY_SCOPE" "G"
					( Parent
						( matchGroupRef "@baseboard_fab2_lib.baseboard_fab2(sch_1):\MG_DQ_FAR_DIMM_NG_M_J_BYTE2\" )
					)
					( Status sCSetFlattened )
					( Origin gBackEnd )
				)
				( attribute "RELATIVE_PROPAGATION_DELAY" "-50.00 MIL,50.00 MIL"
					( Parent
						( matchGroupRef "@baseboard_fab2_lib.baseboard_fab2(sch_1):\MG_DQ_FAR_DIMM_NG_M_J_BYTE2\" )
					)
					( Units "uMatchProp" "ns" 1.000000)
					( Status sCSetFlattened )
					( Origin gBackEnd )
				)
			)
			( pinPair "@baseboard_fab2_lib.baseboard_fab2(sch_1):\PP2447\"
				( pinRef "@baseboard_fab2_lib.baseboard_fab2(sch_1):page59_i172:DDR2_DQ(17)" )
				( pinRef "@baseboard_fab2_lib.baseboard_fab2(sch_1):page82_i187:DQ(17)" )
				( attribute "RELATIVE_PROPAGATION_DELAY_SCOPE" "G"
					( Parent
						( matchGroupRef "@baseboard_fab2_lib.baseboard_fab2(sch_1):\MG_DQ-DQS_NEAR_DIMM_NG_M_J_BYTE2\" )
					)
					( Status sCSetFlattened )
					( Origin gBackEnd )
				)
				( attribute "RELATIVE_PROPAGATION_DELAY" "0.00 MIL,195.00 MIL"
					( Parent
						( matchGroupRef "@baseboard_fab2_lib.baseboard_fab2(sch_1):\MG_DQ-DQS_NEAR_DIMM_NG_M_J_BYTE2\" )
					)
					( Units "uMatchProp" "ns" 1.000000)
					( Status sCSetFlattened )
					( Origin gBackEnd )
				)
				( attribute "RELATIVE_PROPAGATION_DELAY_SCOPE" "G"
					( Parent
						( matchGroupRef "@baseboard_fab2_lib.baseboard_fab2(sch_1):\MG_DQ_NEAR_DIMM_NG_M_J_BYTE2\" )
					)
					( Status sCSetFlattened )
					( Origin gBackEnd )
				)
				( attribute "RELATIVE_PROPAGATION_DELAY" "-50.00 MIL,50.00 MIL"
					( Parent
						( matchGroupRef "@baseboard_fab2_lib.baseboard_fab2(sch_1):\MG_DQ_NEAR_DIMM_NG_M_J_BYTE2\" )
					)
					( Units "uMatchProp" "ns" 1.000000)
					( Status sCSetFlattened )
					( Origin gBackEnd )
				)
			)
			( pinPair "@baseboard_fab2_lib.baseboard_fab2(sch_1):\PP2449\"
				( pinRef "@baseboard_fab2_lib.baseboard_fab2(sch_1):page59_i172:DDR2_DQ(18)" )
				( pinRef "@baseboard_fab2_lib.baseboard_fab2(sch_1):page81_i186:DQ(19)" )
				( attribute "RELATIVE_PROPAGATION_DELAY_SCOPE" "G"
					( Parent
						( matchGroupRef "@baseboard_fab2_lib.baseboard_fab2(sch_1):\MG_DQ-DQS_FAR_DIMM_NG_M_J_BYTE2\" )
					)
					( Status sCSetFlattened )
					( Origin gBackEnd )
				)
				( attribute "RELATIVE_PROPAGATION_DELAY" "0.00 MIL,195.00 MIL"
					( Parent
						( matchGroupRef "@baseboard_fab2_lib.baseboard_fab2(sch_1):\MG_DQ-DQS_FAR_DIMM_NG_M_J_BYTE2\" )
					)
					( Units "uMatchProp" "ns" 1.000000)
					( Status sCSetFlattened )
					( Origin gBackEnd )
				)
				( attribute "RELATIVE_PROPAGATION_DELAY_SCOPE" "G"
					( Parent
						( matchGroupRef "@baseboard_fab2_lib.baseboard_fab2(sch_1):\MG_DQ_FAR_DIMM_NG_M_J_BYTE2\" )
					)
					( Status sCSetFlattened )
					( Origin gBackEnd )
				)
				( attribute "RELATIVE_PROPAGATION_DELAY" "-50.00 MIL,50.00 MIL"
					( Parent
						( matchGroupRef "@baseboard_fab2_lib.baseboard_fab2(sch_1):\MG_DQ_FAR_DIMM_NG_M_J_BYTE2\" )
					)
					( Units "uMatchProp" "ns" 1.000000)
					( Status sCSetFlattened )
					( Origin gBackEnd )
				)
			)
			( pinPair "@baseboard_fab2_lib.baseboard_fab2(sch_1):\PP2450\"
				( pinRef "@baseboard_fab2_lib.baseboard_fab2(sch_1):page59_i172:DDR2_DQ(18)" )
				( pinRef "@baseboard_fab2_lib.baseboard_fab2(sch_1):page82_i187:DQ(18)" )
				( attribute "RELATIVE_PROPAGATION_DELAY_SCOPE" "G"
					( Parent
						( matchGroupRef "@baseboard_fab2_lib.baseboard_fab2(sch_1):\MG_DQ-DQS_NEAR_DIMM_NG_M_J_BYTE2\" )
					)
					( Status sCSetFlattened )
					( Origin gBackEnd )
				)
				( attribute "RELATIVE_PROPAGATION_DELAY" "0.00 MIL,195.00 MIL"
					( Parent
						( matchGroupRef "@baseboard_fab2_lib.baseboard_fab2(sch_1):\MG_DQ-DQS_NEAR_DIMM_NG_M_J_BYTE2\" )
					)
					( Units "uMatchProp" "ns" 1.000000)
					( Status sCSetFlattened )
					( Origin gBackEnd )
				)
				( attribute "RELATIVE_PROPAGATION_DELAY_SCOPE" "G"
					( Parent
						( matchGroupRef "@baseboard_fab2_lib.baseboard_fab2(sch_1):\MG_DQ_NEAR_DIMM_NG_M_J_BYTE2\" )
					)
					( Status sCSetFlattened )
					( Origin gBackEnd )
				)
				( attribute "RELATIVE_PROPAGATION_DELAY" "-50.00 MIL,50.00 MIL"
					( Parent
						( matchGroupRef "@baseboard_fab2_lib.baseboard_fab2(sch_1):\MG_DQ_NEAR_DIMM_NG_M_J_BYTE2\" )
					)
					( Units "uMatchProp" "ns" 1.000000)
					( Status sCSetFlattened )
					( Origin gBackEnd )
				)
			)
			( pinPair "@baseboard_fab2_lib.baseboard_fab2(sch_1):\PP2452\"
				( pinRef "@baseboard_fab2_lib.baseboard_fab2(sch_1):page59_i172:DDR2_DQ(19)" )
				( pinRef "@baseboard_fab2_lib.baseboard_fab2(sch_1):page81_i186:DQ(18)" )
				( attribute "RELATIVE_PROPAGATION_DELAY_SCOPE" "G"
					( Parent
						( matchGroupRef "@baseboard_fab2_lib.baseboard_fab2(sch_1):\MG_DQ-DQS_FAR_DIMM_NG_M_J_BYTE2\" )
					)
					( Status sCSetFlattened )
					( Origin gBackEnd )
				)
				( attribute "RELATIVE_PROPAGATION_DELAY" "0.00 MIL,195.00 MIL"
					( Parent
						( matchGroupRef "@baseboard_fab2_lib.baseboard_fab2(sch_1):\MG_DQ-DQS_FAR_DIMM_NG_M_J_BYTE2\" )
					)
					( Units "uMatchProp" "ns" 1.000000)
					( Status sCSetFlattened )
					( Origin gBackEnd )
				)
				( attribute "RELATIVE_PROPAGATION_DELAY_SCOPE" "G"
					( Parent
						( matchGroupRef "@baseboard_fab2_lib.baseboard_fab2(sch_1):\MG_DQ_FAR_DIMM_NG_M_J_BYTE2\" )
					)
					( Status sCSetFlattened )
					( Origin gBackEnd )
				)
				( attribute "RELATIVE_PROPAGATION_DELAY" "-50.00 MIL,50.00 MIL"
					( Parent
						( matchGroupRef "@baseboard_fab2_lib.baseboard_fab2(sch_1):\MG_DQ_FAR_DIMM_NG_M_J_BYTE2\" )
					)
					( Units "uMatchProp" "ns" 1.000000)
					( Status sCSetFlattened )
					( Origin gBackEnd )
				)
			)
			( pinPair "@baseboard_fab2_lib.baseboard_fab2(sch_1):\PP2453\"
				( pinRef "@baseboard_fab2_lib.baseboard_fab2(sch_1):page59_i172:DDR2_DQ(19)" )
				( pinRef "@baseboard_fab2_lib.baseboard_fab2(sch_1):page82_i187:DQ(19)" )
				( attribute "RELATIVE_PROPAGATION_DELAY_SCOPE" "G"
					( Parent
						( matchGroupRef "@baseboard_fab2_lib.baseboard_fab2(sch_1):\MG_DQ-DQS_NEAR_DIMM_NG_M_J_BYTE2\" )
					)
					( Status sCSetFlattened )
					( Origin gBackEnd )
				)
				( attribute "RELATIVE_PROPAGATION_DELAY" "0.00 MIL,195.00 MIL"
					( Parent
						( matchGroupRef "@baseboard_fab2_lib.baseboard_fab2(sch_1):\MG_DQ-DQS_NEAR_DIMM_NG_M_J_BYTE2\" )
					)
					( Units "uMatchProp" "ns" 1.000000)
					( Status sCSetFlattened )
					( Origin gBackEnd )
				)
				( attribute "RELATIVE_PROPAGATION_DELAY_SCOPE" "G"
					( Parent
						( matchGroupRef "@baseboard_fab2_lib.baseboard_fab2(sch_1):\MG_DQ_NEAR_DIMM_NG_M_J_BYTE2\" )
					)
					( Status sCSetFlattened )
					( Origin gBackEnd )
				)
				( attribute "RELATIVE_PROPAGATION_DELAY" "-50.00 MIL,50.00 MIL"
					( Parent
						( matchGroupRef "@baseboard_fab2_lib.baseboard_fab2(sch_1):\MG_DQ_NEAR_DIMM_NG_M_J_BYTE2\" )
					)
					( Units "uMatchProp" "ns" 1.000000)
					( Status sCSetFlattened )
					( Origin gBackEnd )
				)
			)
			( pinPair "@baseboard_fab2_lib.baseboard_fab2(sch_1):\PP2455\"
				( pinRef "@baseboard_fab2_lib.baseboard_fab2(sch_1):page59_i172:DDR2_DQ(20)" )
				( pinRef "@baseboard_fab2_lib.baseboard_fab2(sch_1):page81_i186:DQ(21)" )
				( attribute "RELATIVE_PROPAGATION_DELAY_SCOPE" "G"
					( Parent
						( matchGroupRef "@baseboard_fab2_lib.baseboard_fab2(sch_1):\MG_DQ-DQS_FAR_DIMM_NG_M_J_BYTE2\" )
					)
					( Status sCSetFlattened )
					( Origin gBackEnd )
				)
				( attribute "RELATIVE_PROPAGATION_DELAY" "0.00 MIL,195.00 MIL"
					( Parent
						( matchGroupRef "@baseboard_fab2_lib.baseboard_fab2(sch_1):\MG_DQ-DQS_FAR_DIMM_NG_M_J_BYTE2\" )
					)
					( Units "uMatchProp" "ns" 1.000000)
					( Status sCSetFlattened )
					( Origin gBackEnd )
				)
				( attribute "RELATIVE_PROPAGATION_DELAY_SCOPE" "G"
					( Parent
						( matchGroupRef "@baseboard_fab2_lib.baseboard_fab2(sch_1):\MG_DQ_FAR_DIMM_NG_M_J_BYTE2\" )
					)
					( Status sCSetFlattened )
					( Origin gBackEnd )
				)
				( attribute "RELATIVE_PROPAGATION_DELAY" "-50.00 MIL,50.00 MIL"
					( Parent
						( matchGroupRef "@baseboard_fab2_lib.baseboard_fab2(sch_1):\MG_DQ_FAR_DIMM_NG_M_J_BYTE2\" )
					)
					( Units "uMatchProp" "ns" 1.000000)
					( Status sCSetFlattened )
					( Origin gBackEnd )
				)
			)
			( pinPair "@baseboard_fab2_lib.baseboard_fab2(sch_1):\PP2456\"
				( pinRef "@baseboard_fab2_lib.baseboard_fab2(sch_1):page59_i172:DDR2_DQ(20)" )
				( pinRef "@baseboard_fab2_lib.baseboard_fab2(sch_1):page82_i187:DQ(20)" )
				( attribute "RELATIVE_PROPAGATION_DELAY_SCOPE" "G"
					( Parent
						( matchGroupRef "@baseboard_fab2_lib.baseboard_fab2(sch_1):\MG_DQ-DQS_NEAR_DIMM_NG_M_J_BYTE2\" )
					)
					( Status sCSetFlattened )
					( Origin gBackEnd )
				)
				( attribute "RELATIVE_PROPAGATION_DELAY" "0.00 MIL,195.00 MIL"
					( Parent
						( matchGroupRef "@baseboard_fab2_lib.baseboard_fab2(sch_1):\MG_DQ-DQS_NEAR_DIMM_NG_M_J_BYTE2\" )
					)
					( Units "uMatchProp" "ns" 1.000000)
					( Status sCSetFlattened )
					( Origin gBackEnd )
				)
				( attribute "RELATIVE_PROPAGATION_DELAY_SCOPE" "G"
					( Parent
						( matchGroupRef "@baseboard_fab2_lib.baseboard_fab2(sch_1):\MG_DQ_NEAR_DIMM_NG_M_J_BYTE2\" )
					)
					( Status sCSetFlattened )
					( Origin gBackEnd )
				)
				( attribute "RELATIVE_PROPAGATION_DELAY" "-50.00 MIL,50.00 MIL"
					( Parent
						( matchGroupRef "@baseboard_fab2_lib.baseboard_fab2(sch_1):\MG_DQ_NEAR_DIMM_NG_M_J_BYTE2\" )
					)
					( Units "uMatchProp" "ns" 1.000000)
					( Status sCSetFlattened )
					( Origin gBackEnd )
				)
			)
			( pinPair "@baseboard_fab2_lib.baseboard_fab2(sch_1):\PP5319\"
				( pinRef "@baseboard_fab2_lib.baseboard_fab2(sch_1):page23_i172:DDR0_DQ(8)" )
				( pinRef "@baseboard_fab2_lib.baseboard_fab2(sch_1):page43_i1:DQ(9)" )
				( attribute "RELATIVE_PROPAGATION_DELAY_SCOPE" "G"
					( Parent
						( matchGroupRef "@baseboard_fab2_lib.baseboard_fab2(sch_1):\MG_DQ-DQS_FAR_DIMM_NG_M_A_BYTE1\" )
					)
					( Status sCSetFlattened )
					( Origin gBackEnd )
				)
				( attribute "RELATIVE_PROPAGATION_DELAY" "0.00 MIL,195.00 MIL"
					( Parent
						( matchGroupRef "@baseboard_fab2_lib.baseboard_fab2(sch_1):\MG_DQ-DQS_FAR_DIMM_NG_M_A_BYTE1\" )
					)
					( Units "uMatchProp" "ns" 1.000000)
					( Status sCSetFlattened )
					( Origin gBackEnd )
				)
				( attribute "RELATIVE_PROPAGATION_DELAY_SCOPE" "G"
					( Parent
						( matchGroupRef "@baseboard_fab2_lib.baseboard_fab2(sch_1):\MG_DQ_FAR_DIMM_NG_M_A_BYTE1\" )
					)
					( Status sCSetFlattened )
					( Origin gBackEnd )
				)
				( attribute "RELATIVE_PROPAGATION_DELAY" "-50.00 MIL,50.00 MIL"
					( Parent
						( matchGroupRef "@baseboard_fab2_lib.baseboard_fab2(sch_1):\MG_DQ_FAR_DIMM_NG_M_A_BYTE1\" )
					)
					( Units "uMatchProp" "ns" 1.000000)
					( Status sCSetFlattened )
					( Origin gBackEnd )
				)
			)
			( pinPair "@baseboard_fab2_lib.baseboard_fab2(sch_1):\PP5321\"
				( pinRef "@baseboard_fab2_lib.baseboard_fab2(sch_1):page23_i172:DDR0_DQ(8)" )
				( pinRef "@baseboard_fab2_lib.baseboard_fab2(sch_1):page44_i13:DQ(8)" )
				( attribute "RELATIVE_PROPAGATION_DELAY_SCOPE" "G"
					( Parent
						( matchGroupRef "@baseboard_fab2_lib.baseboard_fab2(sch_1):\MG_DQ-DQS_NEAR_DIMM_NG_M_A_BYTE1\" )
					)
					( Status sCSetFlattened )
					( Origin gBackEnd )
				)
				( attribute "RELATIVE_PROPAGATION_DELAY" "0.00 MIL,195.00 MIL"
					( Parent
						( matchGroupRef "@baseboard_fab2_lib.baseboard_fab2(sch_1):\MG_DQ-DQS_NEAR_DIMM_NG_M_A_BYTE1\" )
					)
					( Units "uMatchProp" "ns" 1.000000)
					( Status sCSetFlattened )
					( Origin gBackEnd )
				)
				( attribute "RELATIVE_PROPAGATION_DELAY_SCOPE" "G"
					( Parent
						( matchGroupRef "@baseboard_fab2_lib.baseboard_fab2(sch_1):\MG_DQ_NEAR_DIMM_NG_M_A_BYTE1\" )
					)
					( Status sCSetFlattened )
					( Origin gBackEnd )
				)
				( attribute "RELATIVE_PROPAGATION_DELAY" "-50.00 MIL,50.00 MIL"
					( Parent
						( matchGroupRef "@baseboard_fab2_lib.baseboard_fab2(sch_1):\MG_DQ_NEAR_DIMM_NG_M_A_BYTE1\" )
					)
					( Units "uMatchProp" "ns" 1.000000)
					( Status sCSetFlattened )
					( Origin gBackEnd )
				)
			)
			( pinPair "@baseboard_fab2_lib.baseboard_fab2(sch_1):\PP5322\"
				( pinRef "@baseboard_fab2_lib.baseboard_fab2(sch_1):page23_i172:DDR0_DQ(9)" )
				( pinRef "@baseboard_fab2_lib.baseboard_fab2(sch_1):page43_i1:DQ(8)" )
				( attribute "RELATIVE_PROPAGATION_DELAY_SCOPE" "G"
					( Parent
						( matchGroupRef "@baseboard_fab2_lib.baseboard_fab2(sch_1):\MG_DQ-DQS_FAR_DIMM_NG_M_A_BYTE1\" )
					)
					( Status sCSetFlattened )
					( Origin gBackEnd )
				)
				( attribute "RELATIVE_PROPAGATION_DELAY" "0.00 MIL,195.00 MIL"
					( Parent
						( matchGroupRef "@baseboard_fab2_lib.baseboard_fab2(sch_1):\MG_DQ-DQS_FAR_DIMM_NG_M_A_BYTE1\" )
					)
					( Units "uMatchProp" "ns" 1.000000)
					( Status sCSetFlattened )
					( Origin gBackEnd )
				)
				( attribute "RELATIVE_PROPAGATION_DELAY_SCOPE" "G"
					( Parent
						( matchGroupRef "@baseboard_fab2_lib.baseboard_fab2(sch_1):\MG_DQ_FAR_DIMM_NG_M_A_BYTE1\" )
					)
					( Status sCSetFlattened )
					( Origin gBackEnd )
				)
				( attribute "RELATIVE_PROPAGATION_DELAY" "-50.00 MIL,50.00 MIL"
					( Parent
						( matchGroupRef "@baseboard_fab2_lib.baseboard_fab2(sch_1):\MG_DQ_FAR_DIMM_NG_M_A_BYTE1\" )
					)
					( Units "uMatchProp" "ns" 1.000000)
					( Status sCSetFlattened )
					( Origin gBackEnd )
				)
			)
			( pinPair "@baseboard_fab2_lib.baseboard_fab2(sch_1):\PP5324\"
				( pinRef "@baseboard_fab2_lib.baseboard_fab2(sch_1):page23_i172:DDR0_DQ(9)" )
				( pinRef "@baseboard_fab2_lib.baseboard_fab2(sch_1):page44_i13:DQ(9)" )
				( attribute "RELATIVE_PROPAGATION_DELAY_SCOPE" "G"
					( Parent
						( matchGroupRef "@baseboard_fab2_lib.baseboard_fab2(sch_1):\MG_DQ-DQS_NEAR_DIMM_NG_M_A_BYTE1\" )
					)
					( Status sCSetFlattened )
					( Origin gBackEnd )
				)
				( attribute "RELATIVE_PROPAGATION_DELAY" "0.00 MIL,195.00 MIL"
					( Parent
						( matchGroupRef "@baseboard_fab2_lib.baseboard_fab2(sch_1):\MG_DQ-DQS_NEAR_DIMM_NG_M_A_BYTE1\" )
					)
					( Units "uMatchProp" "ns" 1.000000)
					( Status sCSetFlattened )
					( Origin gBackEnd )
				)
				( attribute "RELATIVE_PROPAGATION_DELAY_SCOPE" "G"
					( Parent
						( matchGroupRef "@baseboard_fab2_lib.baseboard_fab2(sch_1):\MG_DQ_NEAR_DIMM_NG_M_A_BYTE1\" )
					)
					( Status sCSetFlattened )
					( Origin gBackEnd )
				)
				( attribute "RELATIVE_PROPAGATION_DELAY" "-50.00 MIL,50.00 MIL"
					( Parent
						( matchGroupRef "@baseboard_fab2_lib.baseboard_fab2(sch_1):\MG_DQ_NEAR_DIMM_NG_M_A_BYTE1\" )
					)
					( Units "uMatchProp" "ns" 1.000000)
					( Status sCSetFlattened )
					( Origin gBackEnd )
				)
			)
			( pinPair "@baseboard_fab2_lib.baseboard_fab2(sch_1):\PP5325\"
				( pinRef "@baseboard_fab2_lib.baseboard_fab2(sch_1):page23_i172:DDR0_DQ(10)" )
				( pinRef "@baseboard_fab2_lib.baseboard_fab2(sch_1):page43_i1:DQ(11)" )
				( attribute "RELATIVE_PROPAGATION_DELAY_SCOPE" "G"
					( Parent
						( matchGroupRef "@baseboard_fab2_lib.baseboard_fab2(sch_1):\MG_DQ-DQS_FAR_DIMM_NG_M_A_BYTE1\" )
					)
					( Status sCSetFlattened )
					( Origin gBackEnd )
				)
				( attribute "RELATIVE_PROPAGATION_DELAY" "0.00 MIL,195.00 MIL"
					( Parent
						( matchGroupRef "@baseboard_fab2_lib.baseboard_fab2(sch_1):\MG_DQ-DQS_FAR_DIMM_NG_M_A_BYTE1\" )
					)
					( Units "uMatchProp" "ns" 1.000000)
					( Status sCSetFlattened )
					( Origin gBackEnd )
				)
				( attribute "RELATIVE_PROPAGATION_DELAY_SCOPE" "G"
					( Parent
						( matchGroupRef "@baseboard_fab2_lib.baseboard_fab2(sch_1):\MG_DQ_FAR_DIMM_NG_M_A_BYTE1\" )
					)
					( Status sCSetFlattened )
					( Origin gBackEnd )
				)
				( attribute "RELATIVE_PROPAGATION_DELAY" "-50.00 MIL,50.00 MIL"
					( Parent
						( matchGroupRef "@baseboard_fab2_lib.baseboard_fab2(sch_1):\MG_DQ_FAR_DIMM_NG_M_A_BYTE1\" )
					)
					( Units "uMatchProp" "ns" 1.000000)
					( Status sCSetFlattened )
					( Origin gBackEnd )
				)
			)
			( pinPair "@baseboard_fab2_lib.baseboard_fab2(sch_1):\PP5327\"
				( pinRef "@baseboard_fab2_lib.baseboard_fab2(sch_1):page23_i172:DDR0_DQ(10)" )
				( pinRef "@baseboard_fab2_lib.baseboard_fab2(sch_1):page44_i13:DQ(10)" )
				( attribute "RELATIVE_PROPAGATION_DELAY_SCOPE" "G"
					( Parent
						( matchGroupRef "@baseboard_fab2_lib.baseboard_fab2(sch_1):\MG_DQ-DQS_NEAR_DIMM_NG_M_A_BYTE1\" )
					)
					( Status sCSetFlattened )
					( Origin gBackEnd )
				)
				( attribute "RELATIVE_PROPAGATION_DELAY" "0.00 MIL,195.00 MIL"
					( Parent
						( matchGroupRef "@baseboard_fab2_lib.baseboard_fab2(sch_1):\MG_DQ-DQS_NEAR_DIMM_NG_M_A_BYTE1\" )
					)
					( Units "uMatchProp" "ns" 1.000000)
					( Status sCSetFlattened )
					( Origin gBackEnd )
				)
				( attribute "RELATIVE_PROPAGATION_DELAY_SCOPE" "G"
					( Parent
						( matchGroupRef "@baseboard_fab2_lib.baseboard_fab2(sch_1):\MG_DQ_NEAR_DIMM_NG_M_A_BYTE1\" )
					)
					( Status sCSetFlattened )
					( Origin gBackEnd )
				)
				( attribute "RELATIVE_PROPAGATION_DELAY" "-50.00 MIL,50.00 MIL"
					( Parent
						( matchGroupRef "@baseboard_fab2_lib.baseboard_fab2(sch_1):\MG_DQ_NEAR_DIMM_NG_M_A_BYTE1\" )
					)
					( Units "uMatchProp" "ns" 1.000000)
					( Status sCSetFlattened )
					( Origin gBackEnd )
				)
			)
			( pinPair "@baseboard_fab2_lib.baseboard_fab2(sch_1):\PP5328\"
				( pinRef "@baseboard_fab2_lib.baseboard_fab2(sch_1):page23_i172:DDR0_DQ(11)" )
				( pinRef "@baseboard_fab2_lib.baseboard_fab2(sch_1):page43_i1:DQ(10)" )
				( attribute "RELATIVE_PROPAGATION_DELAY_SCOPE" "G"
					( Parent
						( matchGroupRef "@baseboard_fab2_lib.baseboard_fab2(sch_1):\MG_DQ-DQS_FAR_DIMM_NG_M_A_BYTE1\" )
					)
					( Status sCSetFlattened )
					( Origin gBackEnd )
				)
				( attribute "RELATIVE_PROPAGATION_DELAY" "0.00 MIL,195.00 MIL"
					( Parent
						( matchGroupRef "@baseboard_fab2_lib.baseboard_fab2(sch_1):\MG_DQ-DQS_FAR_DIMM_NG_M_A_BYTE1\" )
					)
					( Units "uMatchProp" "ns" 1.000000)
					( Status sCSetFlattened )
					( Origin gBackEnd )
				)
				( attribute "RELATIVE_PROPAGATION_DELAY_SCOPE" "G"
					( Parent
						( matchGroupRef "@baseboard_fab2_lib.baseboard_fab2(sch_1):\MG_DQ_FAR_DIMM_NG_M_A_BYTE1\" )
					)
					( Status sCSetFlattened )
					( Origin gBackEnd )
				)
				( attribute "RELATIVE_PROPAGATION_DELAY" "-50.00 MIL,50.00 MIL"
					( Parent
						( matchGroupRef "@baseboard_fab2_lib.baseboard_fab2(sch_1):\MG_DQ_FAR_DIMM_NG_M_A_BYTE1\" )
					)
					( Units "uMatchProp" "ns" 1.000000)
					( Status sCSetFlattened )
					( Origin gBackEnd )
				)
			)
			( pinPair "@baseboard_fab2_lib.baseboard_fab2(sch_1):\PP5330\"
				( pinRef "@baseboard_fab2_lib.baseboard_fab2(sch_1):page23_i172:DDR0_DQ(11)" )
				( pinRef "@baseboard_fab2_lib.baseboard_fab2(sch_1):page44_i13:DQ(11)" )
				( attribute "RELATIVE_PROPAGATION_DELAY_SCOPE" "G"
					( Parent
						( matchGroupRef "@baseboard_fab2_lib.baseboard_fab2(sch_1):\MG_DQ-DQS_NEAR_DIMM_NG_M_A_BYTE1\" )
					)
					( Status sCSetFlattened )
					( Origin gBackEnd )
				)
				( attribute "RELATIVE_PROPAGATION_DELAY" "0.00 MIL,195.00 MIL"
					( Parent
						( matchGroupRef "@baseboard_fab2_lib.baseboard_fab2(sch_1):\MG_DQ-DQS_NEAR_DIMM_NG_M_A_BYTE1\" )
					)
					( Units "uMatchProp" "ns" 1.000000)
					( Status sCSetFlattened )
					( Origin gBackEnd )
				)
				( attribute "RELATIVE_PROPAGATION_DELAY_SCOPE" "G"
					( Parent
						( matchGroupRef "@baseboard_fab2_lib.baseboard_fab2(sch_1):\MG_DQ_NEAR_DIMM_NG_M_A_BYTE1\" )
					)
					( Status sCSetFlattened )
					( Origin gBackEnd )
				)
				( attribute "RELATIVE_PROPAGATION_DELAY" "-50.00 MIL,50.00 MIL"
					( Parent
						( matchGroupRef "@baseboard_fab2_lib.baseboard_fab2(sch_1):\MG_DQ_NEAR_DIMM_NG_M_A_BYTE1\" )
					)
					( Units "uMatchProp" "ns" 1.000000)
					( Status sCSetFlattened )
					( Origin gBackEnd )
				)
			)
			( pinPair "@baseboard_fab2_lib.baseboard_fab2(sch_1):\PP5331\"
				( pinRef "@baseboard_fab2_lib.baseboard_fab2(sch_1):page23_i172:DDR0_DQ(12)" )
				( pinRef "@baseboard_fab2_lib.baseboard_fab2(sch_1):page43_i1:DQ(13)" )
				( attribute "RELATIVE_PROPAGATION_DELAY_SCOPE" "G"
					( Parent
						( matchGroupRef "@baseboard_fab2_lib.baseboard_fab2(sch_1):\MG_DQ-DQS_FAR_DIMM_NG_M_A_BYTE1\" )
					)
					( Status sCSetFlattened )
					( Origin gBackEnd )
				)
				( attribute "RELATIVE_PROPAGATION_DELAY" "0.00 MIL,195.00 MIL"
					( Parent
						( matchGroupRef "@baseboard_fab2_lib.baseboard_fab2(sch_1):\MG_DQ-DQS_FAR_DIMM_NG_M_A_BYTE1\" )
					)
					( Units "uMatchProp" "ns" 1.000000)
					( Status sCSetFlattened )
					( Origin gBackEnd )
				)
				( attribute "RELATIVE_PROPAGATION_DELAY_SCOPE" "G"
					( Parent
						( matchGroupRef "@baseboard_fab2_lib.baseboard_fab2(sch_1):\MG_DQ_FAR_DIMM_NG_M_A_BYTE1\" )
					)
					( Status sCSetFlattened )
					( Origin gBackEnd )
				)
				( attribute "RELATIVE_PROPAGATION_DELAY" "-50.00 MIL,50.00 MIL"
					( Parent
						( matchGroupRef "@baseboard_fab2_lib.baseboard_fab2(sch_1):\MG_DQ_FAR_DIMM_NG_M_A_BYTE1\" )
					)
					( Units "uMatchProp" "ns" 1.000000)
					( Status sCSetFlattened )
					( Origin gBackEnd )
				)
			)
			( pinPair "@baseboard_fab2_lib.baseboard_fab2(sch_1):\PP5333\"
				( pinRef "@baseboard_fab2_lib.baseboard_fab2(sch_1):page23_i172:DDR0_DQ(12)" )
				( pinRef "@baseboard_fab2_lib.baseboard_fab2(sch_1):page44_i13:DQ(12)" )
				( attribute "RELATIVE_PROPAGATION_DELAY_SCOPE" "G"
					( Parent
						( matchGroupRef "@baseboard_fab2_lib.baseboard_fab2(sch_1):\MG_DQ-DQS_NEAR_DIMM_NG_M_A_BYTE1\" )
					)
					( Status sCSetFlattened )
					( Origin gBackEnd )
				)
				( attribute "RELATIVE_PROPAGATION_DELAY" "0.00 MIL,195.00 MIL"
					( Parent
						( matchGroupRef "@baseboard_fab2_lib.baseboard_fab2(sch_1):\MG_DQ-DQS_NEAR_DIMM_NG_M_A_BYTE1\" )
					)
					( Units "uMatchProp" "ns" 1.000000)
					( Status sCSetFlattened )
					( Origin gBackEnd )
				)
				( attribute "RELATIVE_PROPAGATION_DELAY_SCOPE" "G"
					( Parent
						( matchGroupRef "@baseboard_fab2_lib.baseboard_fab2(sch_1):\MG_DQ_NEAR_DIMM_NG_M_A_BYTE1\" )
					)
					( Status sCSetFlattened )
					( Origin gBackEnd )
				)
				( attribute "RELATIVE_PROPAGATION_DELAY" "-50.00 MIL,50.00 MIL"
					( Parent
						( matchGroupRef "@baseboard_fab2_lib.baseboard_fab2(sch_1):\MG_DQ_NEAR_DIMM_NG_M_A_BYTE1\" )
					)
					( Units "uMatchProp" "ns" 1.000000)
					( Status sCSetFlattened )
					( Origin gBackEnd )
				)
			)
			( pinPair "@baseboard_fab2_lib.baseboard_fab2(sch_1):\PP5334\"
				( pinRef "@baseboard_fab2_lib.baseboard_fab2(sch_1):page23_i172:DDR0_DQ(13)" )
				( pinRef "@baseboard_fab2_lib.baseboard_fab2(sch_1):page43_i1:DQ(12)" )
				( attribute "RELATIVE_PROPAGATION_DELAY_SCOPE" "G"
					( Parent
						( matchGroupRef "@baseboard_fab2_lib.baseboard_fab2(sch_1):\MG_DQ-DQS_FAR_DIMM_NG_M_A_BYTE1\" )
					)
					( Status sCSetFlattened )
					( Origin gBackEnd )
				)
				( attribute "RELATIVE_PROPAGATION_DELAY" "0.00 MIL,195.00 MIL"
					( Parent
						( matchGroupRef "@baseboard_fab2_lib.baseboard_fab2(sch_1):\MG_DQ-DQS_FAR_DIMM_NG_M_A_BYTE1\" )
					)
					( Units "uMatchProp" "ns" 1.000000)
					( Status sCSetFlattened )
					( Origin gBackEnd )
				)
				( attribute "RELATIVE_PROPAGATION_DELAY_SCOPE" "G"
					( Parent
						( matchGroupRef "@baseboard_fab2_lib.baseboard_fab2(sch_1):\MG_DQ_FAR_DIMM_NG_M_A_BYTE1\" )
					)
					( Status sCSetFlattened )
					( Origin gBackEnd )
				)
				( attribute "RELATIVE_PROPAGATION_DELAY" "-50.00 MIL,50.00 MIL"
					( Parent
						( matchGroupRef "@baseboard_fab2_lib.baseboard_fab2(sch_1):\MG_DQ_FAR_DIMM_NG_M_A_BYTE1\" )
					)
					( Units "uMatchProp" "ns" 1.000000)
					( Status sCSetFlattened )
					( Origin gBackEnd )
				)
			)
			( pinPair "@baseboard_fab2_lib.baseboard_fab2(sch_1):\PP5336\"
				( pinRef "@baseboard_fab2_lib.baseboard_fab2(sch_1):page23_i172:DDR0_DQ(13)" )
				( pinRef "@baseboard_fab2_lib.baseboard_fab2(sch_1):page44_i13:DQ(13)" )
				( attribute "RELATIVE_PROPAGATION_DELAY_SCOPE" "G"
					( Parent
						( matchGroupRef "@baseboard_fab2_lib.baseboard_fab2(sch_1):\MG_DQ-DQS_NEAR_DIMM_NG_M_A_BYTE1\" )
					)
					( Status sCSetFlattened )
					( Origin gBackEnd )
				)
				( attribute "RELATIVE_PROPAGATION_DELAY" "0.00 MIL,195.00 MIL"
					( Parent
						( matchGroupRef "@baseboard_fab2_lib.baseboard_fab2(sch_1):\MG_DQ-DQS_NEAR_DIMM_NG_M_A_BYTE1\" )
					)
					( Units "uMatchProp" "ns" 1.000000)
					( Status sCSetFlattened )
					( Origin gBackEnd )
				)
				( attribute "RELATIVE_PROPAGATION_DELAY_SCOPE" "G"
					( Parent
						( matchGroupRef "@baseboard_fab2_lib.baseboard_fab2(sch_1):\MG_DQ_NEAR_DIMM_NG_M_A_BYTE1\" )
					)
					( Status sCSetFlattened )
					( Origin gBackEnd )
				)
				( attribute "RELATIVE_PROPAGATION_DELAY" "-50.00 MIL,50.00 MIL"
					( Parent
						( matchGroupRef "@baseboard_fab2_lib.baseboard_fab2(sch_1):\MG_DQ_NEAR_DIMM_NG_M_A_BYTE1\" )
					)
					( Units "uMatchProp" "ns" 1.000000)
					( Status sCSetFlattened )
					( Origin gBackEnd )
				)
			)
			( pinPair "@baseboard_fab2_lib.baseboard_fab2(sch_1):\PP5337\"
				( pinRef "@baseboard_fab2_lib.baseboard_fab2(sch_1):page23_i172:DDR0_DQ(14)" )
				( pinRef "@baseboard_fab2_lib.baseboard_fab2(sch_1):page43_i1:DQ(15)" )
				( attribute "RELATIVE_PROPAGATION_DELAY_SCOPE" "G"
					( Parent
						( matchGroupRef "@baseboard_fab2_lib.baseboard_fab2(sch_1):\MG_DQ-DQS_FAR_DIMM_NG_M_A_BYTE1\" )
					)
					( Status sCSetFlattened )
					( Origin gBackEnd )
				)
				( attribute "RELATIVE_PROPAGATION_DELAY" "0.00 MIL,195.00 MIL"
					( Parent
						( matchGroupRef "@baseboard_fab2_lib.baseboard_fab2(sch_1):\MG_DQ-DQS_FAR_DIMM_NG_M_A_BYTE1\" )
					)
					( Units "uMatchProp" "ns" 1.000000)
					( Status sCSetFlattened )
					( Origin gBackEnd )
				)
				( attribute "RELATIVE_PROPAGATION_DELAY_SCOPE" "G"
					( Parent
						( matchGroupRef "@baseboard_fab2_lib.baseboard_fab2(sch_1):\MG_DQ_FAR_DIMM_NG_M_A_BYTE1\" )
					)
					( Status sCSetFlattened )
					( Origin gBackEnd )
				)
				( attribute "RELATIVE_PROPAGATION_DELAY" "-50.00 MIL,50.00 MIL"
					( Parent
						( matchGroupRef "@baseboard_fab2_lib.baseboard_fab2(sch_1):\MG_DQ_FAR_DIMM_NG_M_A_BYTE1\" )
					)
					( Units "uMatchProp" "ns" 1.000000)
					( Status sCSetFlattened )
					( Origin gBackEnd )
				)
			)
			( pinPair "@baseboard_fab2_lib.baseboard_fab2(sch_1):\PP5339\"
				( pinRef "@baseboard_fab2_lib.baseboard_fab2(sch_1):page23_i172:DDR0_DQ(14)" )
				( pinRef "@baseboard_fab2_lib.baseboard_fab2(sch_1):page44_i13:DQ(14)" )
				( attribute "RELATIVE_PROPAGATION_DELAY_SCOPE" "G"
					( Parent
						( matchGroupRef "@baseboard_fab2_lib.baseboard_fab2(sch_1):\MG_DQ-DQS_NEAR_DIMM_NG_M_A_BYTE1\" )
					)
					( Status sCSetFlattened )
					( Origin gBackEnd )
				)
				( attribute "RELATIVE_PROPAGATION_DELAY" "0.00 MIL,195.00 MIL"
					( Parent
						( matchGroupRef "@baseboard_fab2_lib.baseboard_fab2(sch_1):\MG_DQ-DQS_NEAR_DIMM_NG_M_A_BYTE1\" )
					)
					( Units "uMatchProp" "ns" 1.000000)
					( Status sCSetFlattened )
					( Origin gBackEnd )
				)
				( attribute "RELATIVE_PROPAGATION_DELAY_SCOPE" "G"
					( Parent
						( matchGroupRef "@baseboard_fab2_lib.baseboard_fab2(sch_1):\MG_DQ_NEAR_DIMM_NG_M_A_BYTE1\" )
					)
					( Status sCSetFlattened )
					( Origin gBackEnd )
				)
				( attribute "RELATIVE_PROPAGATION_DELAY" "-50.00 MIL,50.00 MIL"
					( Parent
						( matchGroupRef "@baseboard_fab2_lib.baseboard_fab2(sch_1):\MG_DQ_NEAR_DIMM_NG_M_A_BYTE1\" )
					)
					( Units "uMatchProp" "ns" 1.000000)
					( Status sCSetFlattened )
					( Origin gBackEnd )
				)
			)
			( pinPair "@baseboard_fab2_lib.baseboard_fab2(sch_1):\PP5340\"
				( pinRef "@baseboard_fab2_lib.baseboard_fab2(sch_1):page23_i172:DDR0_DQ(15)" )
				( pinRef "@baseboard_fab2_lib.baseboard_fab2(sch_1):page43_i1:DQ(14)" )
				( attribute "RELATIVE_PROPAGATION_DELAY_SCOPE" "G"
					( Parent
						( matchGroupRef "@baseboard_fab2_lib.baseboard_fab2(sch_1):\MG_DQ-DQS_FAR_DIMM_NG_M_A_BYTE1\" )
					)
					( Status sCSetFlattened )
					( Origin gBackEnd )
				)
				( attribute "RELATIVE_PROPAGATION_DELAY" "0.00 MIL,195.00 MIL"
					( Parent
						( matchGroupRef "@baseboard_fab2_lib.baseboard_fab2(sch_1):\MG_DQ-DQS_FAR_DIMM_NG_M_A_BYTE1\" )
					)
					( Units "uMatchProp" "ns" 1.000000)
					( Status sCSetFlattened )
					( Origin gBackEnd )
				)
				( attribute "RELATIVE_PROPAGATION_DELAY_SCOPE" "G"
					( Parent
						( matchGroupRef "@baseboard_fab2_lib.baseboard_fab2(sch_1):\MG_DQ_FAR_DIMM_NG_M_A_BYTE1\" )
					)
					( Status sCSetFlattened )
					( Origin gBackEnd )
				)
				( attribute "RELATIVE_PROPAGATION_DELAY" "-50.00 MIL,50.00 MIL"
					( Parent
						( matchGroupRef "@baseboard_fab2_lib.baseboard_fab2(sch_1):\MG_DQ_FAR_DIMM_NG_M_A_BYTE1\" )
					)
					( Units "uMatchProp" "ns" 1.000000)
					( Status sCSetFlattened )
					( Origin gBackEnd )
				)
			)
			( pinPair "@baseboard_fab2_lib.baseboard_fab2(sch_1):\PP5342\"
				( pinRef "@baseboard_fab2_lib.baseboard_fab2(sch_1):page23_i172:DDR0_DQ(15)" )
				( pinRef "@baseboard_fab2_lib.baseboard_fab2(sch_1):page44_i13:DQ(15)" )
				( attribute "RELATIVE_PROPAGATION_DELAY_SCOPE" "G"
					( Parent
						( matchGroupRef "@baseboard_fab2_lib.baseboard_fab2(sch_1):\MG_DQ-DQS_NEAR_DIMM_NG_M_A_BYTE1\" )
					)
					( Status sCSetFlattened )
					( Origin gBackEnd )
				)
				( attribute "RELATIVE_PROPAGATION_DELAY" "0.00 MIL,195.00 MIL"
					( Parent
						( matchGroupRef "@baseboard_fab2_lib.baseboard_fab2(sch_1):\MG_DQ-DQS_NEAR_DIMM_NG_M_A_BYTE1\" )
					)
					( Units "uMatchProp" "ns" 1.000000)
					( Status sCSetFlattened )
					( Origin gBackEnd )
				)
				( attribute "RELATIVE_PROPAGATION_DELAY_SCOPE" "G"
					( Parent
						( matchGroupRef "@baseboard_fab2_lib.baseboard_fab2(sch_1):\MG_DQ_NEAR_DIMM_NG_M_A_BYTE1\" )
					)
					( Status sCSetFlattened )
					( Origin gBackEnd )
				)
				( attribute "RELATIVE_PROPAGATION_DELAY" "-50.00 MIL,50.00 MIL"
					( Parent
						( matchGroupRef "@baseboard_fab2_lib.baseboard_fab2(sch_1):\MG_DQ_NEAR_DIMM_NG_M_A_BYTE1\" )
					)
					( Units "uMatchProp" "ns" 1.000000)
					( Status sCSetFlattened )
					( Origin gBackEnd )
				)
			)
			( pinPair "@baseboard_fab2_lib.baseboard_fab2(sch_1):\PP5295\"
				( pinRef "@baseboard_fab2_lib.baseboard_fab2(sch_1):page23_i172:DDR0_DQ(16)" )
				( pinRef "@baseboard_fab2_lib.baseboard_fab2(sch_1):page43_i1:DQ(17)" )
				( attribute "RELATIVE_PROPAGATION_DELAY_SCOPE" "G"
					( Parent
						( matchGroupRef "@baseboard_fab2_lib.baseboard_fab2(sch_1):\MG_DQ-DQS_FAR_DIMM_NG_M_A_BYTE2\" )
					)
					( Status sCSetFlattened )
					( Origin gBackEnd )
				)
				( attribute "RELATIVE_PROPAGATION_DELAY" "0.00 MIL,195.00 MIL"
					( Parent
						( matchGroupRef "@baseboard_fab2_lib.baseboard_fab2(sch_1):\MG_DQ-DQS_FAR_DIMM_NG_M_A_BYTE2\" )
					)
					( Units "uMatchProp" "ns" 1.000000)
					( Status sCSetFlattened )
					( Origin gBackEnd )
				)
				( attribute "RELATIVE_PROPAGATION_DELAY_SCOPE" "G"
					( Parent
						( matchGroupRef "@baseboard_fab2_lib.baseboard_fab2(sch_1):\MG_DQ_FAR_DIMM_NG_M_A_BYTE2\" )
					)
					( Status sCSetFlattened )
					( Origin gBackEnd )
				)
				( attribute "RELATIVE_PROPAGATION_DELAY" "-50.00 MIL,50.00 MIL"
					( Parent
						( matchGroupRef "@baseboard_fab2_lib.baseboard_fab2(sch_1):\MG_DQ_FAR_DIMM_NG_M_A_BYTE2\" )
					)
					( Units "uMatchProp" "ns" 1.000000)
					( Status sCSetFlattened )
					( Origin gBackEnd )
				)
			)
			( pinPair "@baseboard_fab2_lib.baseboard_fab2(sch_1):\PP5297\"
				( pinRef "@baseboard_fab2_lib.baseboard_fab2(sch_1):page23_i172:DDR0_DQ(16)" )
				( pinRef "@baseboard_fab2_lib.baseboard_fab2(sch_1):page44_i13:DQ(16)" )
				( attribute "RELATIVE_PROPAGATION_DELAY_SCOPE" "G"
					( Parent
						( matchGroupRef "@baseboard_fab2_lib.baseboard_fab2(sch_1):\MG_DQ-DQS_NEAR_DIMM_NG_M_A_BYTE2\" )
					)
					( Status sCSetFlattened )
					( Origin gBackEnd )
				)
				( attribute "RELATIVE_PROPAGATION_DELAY" "0.00 MIL,195.00 MIL"
					( Parent
						( matchGroupRef "@baseboard_fab2_lib.baseboard_fab2(sch_1):\MG_DQ-DQS_NEAR_DIMM_NG_M_A_BYTE2\" )
					)
					( Units "uMatchProp" "ns" 1.000000)
					( Status sCSetFlattened )
					( Origin gBackEnd )
				)
				( attribute "RELATIVE_PROPAGATION_DELAY_SCOPE" "G"
					( Parent
						( matchGroupRef "@baseboard_fab2_lib.baseboard_fab2(sch_1):\MG_DQ_NEAR_DIMM_NG_M_A_BYTE2\" )
					)
					( Status sCSetFlattened )
					( Origin gBackEnd )
				)
				( attribute "RELATIVE_PROPAGATION_DELAY" "-50.00 MIL,50.00 MIL"
					( Parent
						( matchGroupRef "@baseboard_fab2_lib.baseboard_fab2(sch_1):\MG_DQ_NEAR_DIMM_NG_M_A_BYTE2\" )
					)
					( Units "uMatchProp" "ns" 1.000000)
					( Status sCSetFlattened )
					( Origin gBackEnd )
				)
			)
			( pinPair "@baseboard_fab2_lib.baseboard_fab2(sch_1):\PP5298\"
				( pinRef "@baseboard_fab2_lib.baseboard_fab2(sch_1):page23_i172:DDR0_DQ(17)" )
				( pinRef "@baseboard_fab2_lib.baseboard_fab2(sch_1):page43_i1:DQ(16)" )
				( attribute "RELATIVE_PROPAGATION_DELAY_SCOPE" "G"
					( Parent
						( matchGroupRef "@baseboard_fab2_lib.baseboard_fab2(sch_1):\MG_DQ-DQS_FAR_DIMM_NG_M_A_BYTE2\" )
					)
					( Status sCSetFlattened )
					( Origin gBackEnd )
				)
				( attribute "RELATIVE_PROPAGATION_DELAY" "0.00 MIL,195.00 MIL"
					( Parent
						( matchGroupRef "@baseboard_fab2_lib.baseboard_fab2(sch_1):\MG_DQ-DQS_FAR_DIMM_NG_M_A_BYTE2\" )
					)
					( Units "uMatchProp" "ns" 1.000000)
					( Status sCSetFlattened )
					( Origin gBackEnd )
				)
				( attribute "RELATIVE_PROPAGATION_DELAY_SCOPE" "G"
					( Parent
						( matchGroupRef "@baseboard_fab2_lib.baseboard_fab2(sch_1):\MG_DQ_FAR_DIMM_NG_M_A_BYTE2\" )
					)
					( Status sCSetFlattened )
					( Origin gBackEnd )
				)
				( attribute "RELATIVE_PROPAGATION_DELAY" "-50.00 MIL,50.00 MIL"
					( Parent
						( matchGroupRef "@baseboard_fab2_lib.baseboard_fab2(sch_1):\MG_DQ_FAR_DIMM_NG_M_A_BYTE2\" )
					)
					( Units "uMatchProp" "ns" 1.000000)
					( Status sCSetFlattened )
					( Origin gBackEnd )
				)
			)
			( pinPair "@baseboard_fab2_lib.baseboard_fab2(sch_1):\PP5300\"
				( pinRef "@baseboard_fab2_lib.baseboard_fab2(sch_1):page23_i172:DDR0_DQ(17)" )
				( pinRef "@baseboard_fab2_lib.baseboard_fab2(sch_1):page44_i13:DQ(17)" )
				( attribute "RELATIVE_PROPAGATION_DELAY_SCOPE" "G"
					( Parent
						( matchGroupRef "@baseboard_fab2_lib.baseboard_fab2(sch_1):\MG_DQ-DQS_NEAR_DIMM_NG_M_A_BYTE2\" )
					)
					( Status sCSetFlattened )
					( Origin gBackEnd )
				)
				( attribute "RELATIVE_PROPAGATION_DELAY" "0.00 MIL,195.00 MIL"
					( Parent
						( matchGroupRef "@baseboard_fab2_lib.baseboard_fab2(sch_1):\MG_DQ-DQS_NEAR_DIMM_NG_M_A_BYTE2\" )
					)
					( Units "uMatchProp" "ns" 1.000000)
					( Status sCSetFlattened )
					( Origin gBackEnd )
				)
				( attribute "RELATIVE_PROPAGATION_DELAY_SCOPE" "G"
					( Parent
						( matchGroupRef "@baseboard_fab2_lib.baseboard_fab2(sch_1):\MG_DQ_NEAR_DIMM_NG_M_A_BYTE2\" )
					)
					( Status sCSetFlattened )
					( Origin gBackEnd )
				)
				( attribute "RELATIVE_PROPAGATION_DELAY" "-50.00 MIL,50.00 MIL"
					( Parent
						( matchGroupRef "@baseboard_fab2_lib.baseboard_fab2(sch_1):\MG_DQ_NEAR_DIMM_NG_M_A_BYTE2\" )
					)
					( Units "uMatchProp" "ns" 1.000000)
					( Status sCSetFlattened )
					( Origin gBackEnd )
				)
			)
			( pinPair "@baseboard_fab2_lib.baseboard_fab2(sch_1):\PP5301\"
				( pinRef "@baseboard_fab2_lib.baseboard_fab2(sch_1):page23_i172:DDR0_DQ(18)" )
				( pinRef "@baseboard_fab2_lib.baseboard_fab2(sch_1):page43_i1:DQ(19)" )
				( attribute "RELATIVE_PROPAGATION_DELAY_SCOPE" "G"
					( Parent
						( matchGroupRef "@baseboard_fab2_lib.baseboard_fab2(sch_1):\MG_DQ-DQS_FAR_DIMM_NG_M_A_BYTE2\" )
					)
					( Status sCSetFlattened )
					( Origin gBackEnd )
				)
				( attribute "RELATIVE_PROPAGATION_DELAY" "0.00 MIL,195.00 MIL"
					( Parent
						( matchGroupRef "@baseboard_fab2_lib.baseboard_fab2(sch_1):\MG_DQ-DQS_FAR_DIMM_NG_M_A_BYTE2\" )
					)
					( Units "uMatchProp" "ns" 1.000000)
					( Status sCSetFlattened )
					( Origin gBackEnd )
				)
				( attribute "RELATIVE_PROPAGATION_DELAY_SCOPE" "G"
					( Parent
						( matchGroupRef "@baseboard_fab2_lib.baseboard_fab2(sch_1):\MG_DQ_FAR_DIMM_NG_M_A_BYTE2\" )
					)
					( Status sCSetFlattened )
					( Origin gBackEnd )
				)
				( attribute "RELATIVE_PROPAGATION_DELAY" "-50.00 MIL,50.00 MIL"
					( Parent
						( matchGroupRef "@baseboard_fab2_lib.baseboard_fab2(sch_1):\MG_DQ_FAR_DIMM_NG_M_A_BYTE2\" )
					)
					( Units "uMatchProp" "ns" 1.000000)
					( Status sCSetFlattened )
					( Origin gBackEnd )
				)
			)
			( pinPair "@baseboard_fab2_lib.baseboard_fab2(sch_1):\PP5303\"
				( pinRef "@baseboard_fab2_lib.baseboard_fab2(sch_1):page23_i172:DDR0_DQ(18)" )
				( pinRef "@baseboard_fab2_lib.baseboard_fab2(sch_1):page44_i13:DQ(18)" )
				( attribute "RELATIVE_PROPAGATION_DELAY_SCOPE" "G"
					( Parent
						( matchGroupRef "@baseboard_fab2_lib.baseboard_fab2(sch_1):\MG_DQ-DQS_NEAR_DIMM_NG_M_A_BYTE2\" )
					)
					( Status sCSetFlattened )
					( Origin gBackEnd )
				)
				( attribute "RELATIVE_PROPAGATION_DELAY" "0.00 MIL,195.00 MIL"
					( Parent
						( matchGroupRef "@baseboard_fab2_lib.baseboard_fab2(sch_1):\MG_DQ-DQS_NEAR_DIMM_NG_M_A_BYTE2\" )
					)
					( Units "uMatchProp" "ns" 1.000000)
					( Status sCSetFlattened )
					( Origin gBackEnd )
				)
				( attribute "RELATIVE_PROPAGATION_DELAY_SCOPE" "G"
					( Parent
						( matchGroupRef "@baseboard_fab2_lib.baseboard_fab2(sch_1):\MG_DQ_NEAR_DIMM_NG_M_A_BYTE2\" )
					)
					( Status sCSetFlattened )
					( Origin gBackEnd )
				)
				( attribute "RELATIVE_PROPAGATION_DELAY" "-50.00 MIL,50.00 MIL"
					( Parent
						( matchGroupRef "@baseboard_fab2_lib.baseboard_fab2(sch_1):\MG_DQ_NEAR_DIMM_NG_M_A_BYTE2\" )
					)
					( Units "uMatchProp" "ns" 1.000000)
					( Status sCSetFlattened )
					( Origin gBackEnd )
				)
			)
			( pinPair "@baseboard_fab2_lib.baseboard_fab2(sch_1):\PP5304\"
				( pinRef "@baseboard_fab2_lib.baseboard_fab2(sch_1):page23_i172:DDR0_DQ(19)" )
				( pinRef "@baseboard_fab2_lib.baseboard_fab2(sch_1):page43_i1:DQ(18)" )
				( attribute "RELATIVE_PROPAGATION_DELAY_SCOPE" "G"
					( Parent
						( matchGroupRef "@baseboard_fab2_lib.baseboard_fab2(sch_1):\MG_DQ-DQS_FAR_DIMM_NG_M_A_BYTE2\" )
					)
					( Status sCSetFlattened )
					( Origin gBackEnd )
				)
				( attribute "RELATIVE_PROPAGATION_DELAY" "0.00 MIL,195.00 MIL"
					( Parent
						( matchGroupRef "@baseboard_fab2_lib.baseboard_fab2(sch_1):\MG_DQ-DQS_FAR_DIMM_NG_M_A_BYTE2\" )
					)
					( Units "uMatchProp" "ns" 1.000000)
					( Status sCSetFlattened )
					( Origin gBackEnd )
				)
				( attribute "RELATIVE_PROPAGATION_DELAY_SCOPE" "G"
					( Parent
						( matchGroupRef "@baseboard_fab2_lib.baseboard_fab2(sch_1):\MG_DQ_FAR_DIMM_NG_M_A_BYTE2\" )
					)
					( Status sCSetFlattened )
					( Origin gBackEnd )
				)
				( attribute "RELATIVE_PROPAGATION_DELAY" "-50.00 MIL,50.00 MIL"
					( Parent
						( matchGroupRef "@baseboard_fab2_lib.baseboard_fab2(sch_1):\MG_DQ_FAR_DIMM_NG_M_A_BYTE2\" )
					)
					( Units "uMatchProp" "ns" 1.000000)
					( Status sCSetFlattened )
					( Origin gBackEnd )
				)
			)
			( pinPair "@baseboard_fab2_lib.baseboard_fab2(sch_1):\PP5306\"
				( pinRef "@baseboard_fab2_lib.baseboard_fab2(sch_1):page23_i172:DDR0_DQ(19)" )
				( pinRef "@baseboard_fab2_lib.baseboard_fab2(sch_1):page44_i13:DQ(19)" )
				( attribute "RELATIVE_PROPAGATION_DELAY_SCOPE" "G"
					( Parent
						( matchGroupRef "@baseboard_fab2_lib.baseboard_fab2(sch_1):\MG_DQ-DQS_NEAR_DIMM_NG_M_A_BYTE2\" )
					)
					( Status sCSetFlattened )
					( Origin gBackEnd )
				)
				( attribute "RELATIVE_PROPAGATION_DELAY" "0.00 MIL,195.00 MIL"
					( Parent
						( matchGroupRef "@baseboard_fab2_lib.baseboard_fab2(sch_1):\MG_DQ-DQS_NEAR_DIMM_NG_M_A_BYTE2\" )
					)
					( Units "uMatchProp" "ns" 1.000000)
					( Status sCSetFlattened )
					( Origin gBackEnd )
				)
				( attribute "RELATIVE_PROPAGATION_DELAY_SCOPE" "G"
					( Parent
						( matchGroupRef "@baseboard_fab2_lib.baseboard_fab2(sch_1):\MG_DQ_NEAR_DIMM_NG_M_A_BYTE2\" )
					)
					( Status sCSetFlattened )
					( Origin gBackEnd )
				)
				( attribute "RELATIVE_PROPAGATION_DELAY" "-50.00 MIL,50.00 MIL"
					( Parent
						( matchGroupRef "@baseboard_fab2_lib.baseboard_fab2(sch_1):\MG_DQ_NEAR_DIMM_NG_M_A_BYTE2\" )
					)
					( Units "uMatchProp" "ns" 1.000000)
					( Status sCSetFlattened )
					( Origin gBackEnd )
				)
			)
			( pinPair "@baseboard_fab2_lib.baseboard_fab2(sch_1):\PP5307\"
				( pinRef "@baseboard_fab2_lib.baseboard_fab2(sch_1):page23_i172:DDR0_DQ(20)" )
				( pinRef "@baseboard_fab2_lib.baseboard_fab2(sch_1):page43_i1:DQ(21)" )
				( attribute "RELATIVE_PROPAGATION_DELAY_SCOPE" "G"
					( Parent
						( matchGroupRef "@baseboard_fab2_lib.baseboard_fab2(sch_1):\MG_DQ-DQS_FAR_DIMM_NG_M_A_BYTE2\" )
					)
					( Status sCSetFlattened )
					( Origin gBackEnd )
				)
				( attribute "RELATIVE_PROPAGATION_DELAY" "0.00 MIL,195.00 MIL"
					( Parent
						( matchGroupRef "@baseboard_fab2_lib.baseboard_fab2(sch_1):\MG_DQ-DQS_FAR_DIMM_NG_M_A_BYTE2\" )
					)
					( Units "uMatchProp" "ns" 1.000000)
					( Status sCSetFlattened )
					( Origin gBackEnd )
				)
				( attribute "RELATIVE_PROPAGATION_DELAY_SCOPE" "G"
					( Parent
						( matchGroupRef "@baseboard_fab2_lib.baseboard_fab2(sch_1):\MG_DQ_FAR_DIMM_NG_M_A_BYTE2\" )
					)
					( Status sCSetFlattened )
					( Origin gBackEnd )
				)
				( attribute "RELATIVE_PROPAGATION_DELAY" "-50.00 MIL,50.00 MIL"
					( Parent
						( matchGroupRef "@baseboard_fab2_lib.baseboard_fab2(sch_1):\MG_DQ_FAR_DIMM_NG_M_A_BYTE2\" )
					)
					( Units "uMatchProp" "ns" 1.000000)
					( Status sCSetFlattened )
					( Origin gBackEnd )
				)
			)
			( pinPair "@baseboard_fab2_lib.baseboard_fab2(sch_1):\PP5309\"
				( pinRef "@baseboard_fab2_lib.baseboard_fab2(sch_1):page23_i172:DDR0_DQ(20)" )
				( pinRef "@baseboard_fab2_lib.baseboard_fab2(sch_1):page44_i13:DQ(20)" )
				( attribute "RELATIVE_PROPAGATION_DELAY_SCOPE" "G"
					( Parent
						( matchGroupRef "@baseboard_fab2_lib.baseboard_fab2(sch_1):\MG_DQ-DQS_NEAR_DIMM_NG_M_A_BYTE2\" )
					)
					( Status sCSetFlattened )
					( Origin gBackEnd )
				)
				( attribute "RELATIVE_PROPAGATION_DELAY" "0.00 MIL,195.00 MIL"
					( Parent
						( matchGroupRef "@baseboard_fab2_lib.baseboard_fab2(sch_1):\MG_DQ-DQS_NEAR_DIMM_NG_M_A_BYTE2\" )
					)
					( Units "uMatchProp" "ns" 1.000000)
					( Status sCSetFlattened )
					( Origin gBackEnd )
				)
				( attribute "RELATIVE_PROPAGATION_DELAY_SCOPE" "G"
					( Parent
						( matchGroupRef "@baseboard_fab2_lib.baseboard_fab2(sch_1):\MG_DQ_NEAR_DIMM_NG_M_A_BYTE2\" )
					)
					( Status sCSetFlattened )
					( Origin gBackEnd )
				)
				( attribute "RELATIVE_PROPAGATION_DELAY" "-50.00 MIL,50.00 MIL"
					( Parent
						( matchGroupRef "@baseboard_fab2_lib.baseboard_fab2(sch_1):\MG_DQ_NEAR_DIMM_NG_M_A_BYTE2\" )
					)
					( Units "uMatchProp" "ns" 1.000000)
					( Status sCSetFlattened )
					( Origin gBackEnd )
				)
			)
			( pinPair "@baseboard_fab2_lib.baseboard_fab2(sch_1):\PP5310\"
				( pinRef "@baseboard_fab2_lib.baseboard_fab2(sch_1):page23_i172:DDR0_DQ(21)" )
				( pinRef "@baseboard_fab2_lib.baseboard_fab2(sch_1):page43_i1:DQ(20)" )
				( attribute "RELATIVE_PROPAGATION_DELAY_SCOPE" "G"
					( Parent
						( matchGroupRef "@baseboard_fab2_lib.baseboard_fab2(sch_1):\MG_DQ-DQS_FAR_DIMM_NG_M_A_BYTE2\" )
					)
					( Status sCSetFlattened )
					( Origin gBackEnd )
				)
				( attribute "RELATIVE_PROPAGATION_DELAY" "0.00 MIL,195.00 MIL"
					( Parent
						( matchGroupRef "@baseboard_fab2_lib.baseboard_fab2(sch_1):\MG_DQ-DQS_FAR_DIMM_NG_M_A_BYTE2\" )
					)
					( Units "uMatchProp" "ns" 1.000000)
					( Status sCSetFlattened )
					( Origin gBackEnd )
				)
				( attribute "RELATIVE_PROPAGATION_DELAY_SCOPE" "G"
					( Parent
						( matchGroupRef "@baseboard_fab2_lib.baseboard_fab2(sch_1):\MG_DQ_FAR_DIMM_NG_M_A_BYTE2\" )
					)
					( Status sCSetFlattened )
					( Origin gBackEnd )
				)
				( attribute "RELATIVE_PROPAGATION_DELAY" "-50.00 MIL,50.00 MIL"
					( Parent
						( matchGroupRef "@baseboard_fab2_lib.baseboard_fab2(sch_1):\MG_DQ_FAR_DIMM_NG_M_A_BYTE2\" )
					)
					( Units "uMatchProp" "ns" 1.000000)
					( Status sCSetFlattened )
					( Origin gBackEnd )
				)
			)
			( pinPair "@baseboard_fab2_lib.baseboard_fab2(sch_1):\PP5312\"
				( pinRef "@baseboard_fab2_lib.baseboard_fab2(sch_1):page23_i172:DDR0_DQ(21)" )
				( pinRef "@baseboard_fab2_lib.baseboard_fab2(sch_1):page44_i13:DQ(21)" )
				( attribute "RELATIVE_PROPAGATION_DELAY_SCOPE" "G"
					( Parent
						( matchGroupRef "@baseboard_fab2_lib.baseboard_fab2(sch_1):\MG_DQ-DQS_NEAR_DIMM_NG_M_A_BYTE2\" )
					)
					( Status sCSetFlattened )
					( Origin gBackEnd )
				)
				( attribute "RELATIVE_PROPAGATION_DELAY" "0.00 MIL,195.00 MIL"
					( Parent
						( matchGroupRef "@baseboard_fab2_lib.baseboard_fab2(sch_1):\MG_DQ-DQS_NEAR_DIMM_NG_M_A_BYTE2\" )
					)
					( Units "uMatchProp" "ns" 1.000000)
					( Status sCSetFlattened )
					( Origin gBackEnd )
				)
				( attribute "RELATIVE_PROPAGATION_DELAY_SCOPE" "G"
					( Parent
						( matchGroupRef "@baseboard_fab2_lib.baseboard_fab2(sch_1):\MG_DQ_NEAR_DIMM_NG_M_A_BYTE2\" )
					)
					( Status sCSetFlattened )
					( Origin gBackEnd )
				)
				( attribute "RELATIVE_PROPAGATION_DELAY" "-50.00 MIL,50.00 MIL"
					( Parent
						( matchGroupRef "@baseboard_fab2_lib.baseboard_fab2(sch_1):\MG_DQ_NEAR_DIMM_NG_M_A_BYTE2\" )
					)
					( Units "uMatchProp" "ns" 1.000000)
					( Status sCSetFlattened )
					( Origin gBackEnd )
				)
			)
			( pinPair "@baseboard_fab2_lib.baseboard_fab2(sch_1):\PP5313\"
				( pinRef "@baseboard_fab2_lib.baseboard_fab2(sch_1):page23_i172:DDR0_DQ(22)" )
				( pinRef "@baseboard_fab2_lib.baseboard_fab2(sch_1):page43_i1:DQ(23)" )
				( attribute "RELATIVE_PROPAGATION_DELAY_SCOPE" "G"
					( Parent
						( matchGroupRef "@baseboard_fab2_lib.baseboard_fab2(sch_1):\MG_DQ-DQS_FAR_DIMM_NG_M_A_BYTE2\" )
					)
					( Status sCSetFlattened )
					( Origin gBackEnd )
				)
				( attribute "RELATIVE_PROPAGATION_DELAY" "0.00 MIL,195.00 MIL"
					( Parent
						( matchGroupRef "@baseboard_fab2_lib.baseboard_fab2(sch_1):\MG_DQ-DQS_FAR_DIMM_NG_M_A_BYTE2\" )
					)
					( Units "uMatchProp" "ns" 1.000000)
					( Status sCSetFlattened )
					( Origin gBackEnd )
				)
				( attribute "RELATIVE_PROPAGATION_DELAY_SCOPE" "G"
					( Parent
						( matchGroupRef "@baseboard_fab2_lib.baseboard_fab2(sch_1):\MG_DQ_FAR_DIMM_NG_M_A_BYTE2\" )
					)
					( Status sCSetFlattened )
					( Origin gBackEnd )
				)
				( attribute "RELATIVE_PROPAGATION_DELAY" "-50.00 MIL,50.00 MIL"
					( Parent
						( matchGroupRef "@baseboard_fab2_lib.baseboard_fab2(sch_1):\MG_DQ_FAR_DIMM_NG_M_A_BYTE2\" )
					)
					( Units "uMatchProp" "ns" 1.000000)
					( Status sCSetFlattened )
					( Origin gBackEnd )
				)
			)
			( pinPair "@baseboard_fab2_lib.baseboard_fab2(sch_1):\PP5315\"
				( pinRef "@baseboard_fab2_lib.baseboard_fab2(sch_1):page23_i172:DDR0_DQ(22)" )
				( pinRef "@baseboard_fab2_lib.baseboard_fab2(sch_1):page44_i13:DQ(22)" )
				( attribute "RELATIVE_PROPAGATION_DELAY_SCOPE" "G"
					( Parent
						( matchGroupRef "@baseboard_fab2_lib.baseboard_fab2(sch_1):\MG_DQ-DQS_NEAR_DIMM_NG_M_A_BYTE2\" )
					)
					( Status sCSetFlattened )
					( Origin gBackEnd )
				)
				( attribute "RELATIVE_PROPAGATION_DELAY" "0.00 MIL,195.00 MIL"
					( Parent
						( matchGroupRef "@baseboard_fab2_lib.baseboard_fab2(sch_1):\MG_DQ-DQS_NEAR_DIMM_NG_M_A_BYTE2\" )
					)
					( Units "uMatchProp" "ns" 1.000000)
					( Status sCSetFlattened )
					( Origin gBackEnd )
				)
				( attribute "RELATIVE_PROPAGATION_DELAY_SCOPE" "G"
					( Parent
						( matchGroupRef "@baseboard_fab2_lib.baseboard_fab2(sch_1):\MG_DQ_NEAR_DIMM_NG_M_A_BYTE2\" )
					)
					( Status sCSetFlattened )
					( Origin gBackEnd )
				)
				( attribute "RELATIVE_PROPAGATION_DELAY" "-50.00 MIL,50.00 MIL"
					( Parent
						( matchGroupRef "@baseboard_fab2_lib.baseboard_fab2(sch_1):\MG_DQ_NEAR_DIMM_NG_M_A_BYTE2\" )
					)
					( Units "uMatchProp" "ns" 1.000000)
					( Status sCSetFlattened )
					( Origin gBackEnd )
				)
			)
			( pinPair "@baseboard_fab2_lib.baseboard_fab2(sch_1):\PP5316\"
				( pinRef "@baseboard_fab2_lib.baseboard_fab2(sch_1):page23_i172:DDR0_DQ(23)" )
				( pinRef "@baseboard_fab2_lib.baseboard_fab2(sch_1):page43_i1:DQ(22)" )
				( attribute "RELATIVE_PROPAGATION_DELAY_SCOPE" "G"
					( Parent
						( matchGroupRef "@baseboard_fab2_lib.baseboard_fab2(sch_1):\MG_DQ-DQS_FAR_DIMM_NG_M_A_BYTE2\" )
					)
					( Status sCSetFlattened )
					( Origin gBackEnd )
				)
				( attribute "RELATIVE_PROPAGATION_DELAY" "0.00 MIL,195.00 MIL"
					( Parent
						( matchGroupRef "@baseboard_fab2_lib.baseboard_fab2(sch_1):\MG_DQ-DQS_FAR_DIMM_NG_M_A_BYTE2\" )
					)
					( Units "uMatchProp" "ns" 1.000000)
					( Status sCSetFlattened )
					( Origin gBackEnd )
				)
				( attribute "RELATIVE_PROPAGATION_DELAY_SCOPE" "G"
					( Parent
						( matchGroupRef "@baseboard_fab2_lib.baseboard_fab2(sch_1):\MG_DQ_FAR_DIMM_NG_M_A_BYTE2\" )
					)
					( Status sCSetFlattened )
					( Origin gBackEnd )
				)
				( attribute "RELATIVE_PROPAGATION_DELAY" "-50.00 MIL,50.00 MIL"
					( Parent
						( matchGroupRef "@baseboard_fab2_lib.baseboard_fab2(sch_1):\MG_DQ_FAR_DIMM_NG_M_A_BYTE2\" )
					)
					( Units "uMatchProp" "ns" 1.000000)
					( Status sCSetFlattened )
					( Origin gBackEnd )
				)
			)
			( pinPair "@baseboard_fab2_lib.baseboard_fab2(sch_1):\PP5318\"
				( pinRef "@baseboard_fab2_lib.baseboard_fab2(sch_1):page23_i172:DDR0_DQ(23)" )
				( pinRef "@baseboard_fab2_lib.baseboard_fab2(sch_1):page44_i13:DQ(23)" )
				( attribute "RELATIVE_PROPAGATION_DELAY_SCOPE" "G"
					( Parent
						( matchGroupRef "@baseboard_fab2_lib.baseboard_fab2(sch_1):\MG_DQ-DQS_NEAR_DIMM_NG_M_A_BYTE2\" )
					)
					( Status sCSetFlattened )
					( Origin gBackEnd )
				)
				( attribute "RELATIVE_PROPAGATION_DELAY" "0.00 MIL,195.00 MIL"
					( Parent
						( matchGroupRef "@baseboard_fab2_lib.baseboard_fab2(sch_1):\MG_DQ-DQS_NEAR_DIMM_NG_M_A_BYTE2\" )
					)
					( Units "uMatchProp" "ns" 1.000000)
					( Status sCSetFlattened )
					( Origin gBackEnd )
				)
				( attribute "RELATIVE_PROPAGATION_DELAY_SCOPE" "G"
					( Parent
						( matchGroupRef "@baseboard_fab2_lib.baseboard_fab2(sch_1):\MG_DQ_NEAR_DIMM_NG_M_A_BYTE2\" )
					)
					( Status sCSetFlattened )
					( Origin gBackEnd )
				)
				( attribute "RELATIVE_PROPAGATION_DELAY" "-50.00 MIL,50.00 MIL"
					( Parent
						( matchGroupRef "@baseboard_fab2_lib.baseboard_fab2(sch_1):\MG_DQ_NEAR_DIMM_NG_M_A_BYTE2\" )
					)
					( Units "uMatchProp" "ns" 1.000000)
					( Status sCSetFlattened )
					( Origin gBackEnd )
				)
			)
			( pinPair "@baseboard_fab2_lib.baseboard_fab2(sch_1):\PP5271\"
				( pinRef "@baseboard_fab2_lib.baseboard_fab2(sch_1):page23_i172:DDR0_DQ(24)" )
				( pinRef "@baseboard_fab2_lib.baseboard_fab2(sch_1):page43_i1:DQ(25)" )
				( attribute "RELATIVE_PROPAGATION_DELAY_SCOPE" "G"
					( Parent
						( matchGroupRef "@baseboard_fab2_lib.baseboard_fab2(sch_1):\MG_DQ-DQS_FAR_DIMM_NG_M_A_BYTE3\" )
					)
					( Status sCSetFlattened )
					( Origin gBackEnd )
				)
				( attribute "RELATIVE_PROPAGATION_DELAY" "0.00 MIL,195.00 MIL"
					( Parent
						( matchGroupRef "@baseboard_fab2_lib.baseboard_fab2(sch_1):\MG_DQ-DQS_FAR_DIMM_NG_M_A_BYTE3\" )
					)
					( Units "uMatchProp" "ns" 1.000000)
					( Status sCSetFlattened )
					( Origin gBackEnd )
				)
				( attribute "RELATIVE_PROPAGATION_DELAY_SCOPE" "G"
					( Parent
						( matchGroupRef "@baseboard_fab2_lib.baseboard_fab2(sch_1):\MG_DQ_FAR_DIMM_NG_M_A_BYTE3\" )
					)
					( Status sCSetFlattened )
					( Origin gBackEnd )
				)
				( attribute "RELATIVE_PROPAGATION_DELAY" "-50.00 MIL,50.00 MIL"
					( Parent
						( matchGroupRef "@baseboard_fab2_lib.baseboard_fab2(sch_1):\MG_DQ_FAR_DIMM_NG_M_A_BYTE3\" )
					)
					( Units "uMatchProp" "ns" 1.000000)
					( Status sCSetFlattened )
					( Origin gBackEnd )
				)
			)
			( pinPair "@baseboard_fab2_lib.baseboard_fab2(sch_1):\PP5273\"
				( pinRef "@baseboard_fab2_lib.baseboard_fab2(sch_1):page23_i172:DDR0_DQ(24)" )
				( pinRef "@baseboard_fab2_lib.baseboard_fab2(sch_1):page44_i13:DQ(24)" )
				( attribute "RELATIVE_PROPAGATION_DELAY_SCOPE" "G"
					( Parent
						( matchGroupRef "@baseboard_fab2_lib.baseboard_fab2(sch_1):\MG_DQ-DQS_NEAR_DIMM_NG_M_A_BYTE3\" )
					)
					( Status sCSetFlattened )
					( Origin gBackEnd )
				)
				( attribute "RELATIVE_PROPAGATION_DELAY" "0.00 MIL,195.00 MIL"
					( Parent
						( matchGroupRef "@baseboard_fab2_lib.baseboard_fab2(sch_1):\MG_DQ-DQS_NEAR_DIMM_NG_M_A_BYTE3\" )
					)
					( Units "uMatchProp" "ns" 1.000000)
					( Status sCSetFlattened )
					( Origin gBackEnd )
				)
				( attribute "RELATIVE_PROPAGATION_DELAY_SCOPE" "G"
					( Parent
						( matchGroupRef "@baseboard_fab2_lib.baseboard_fab2(sch_1):\MG_DQ_NEAR_DIMM_NG_M_A_BYTE3\" )
					)
					( Status sCSetFlattened )
					( Origin gBackEnd )
				)
				( attribute "RELATIVE_PROPAGATION_DELAY" "-50.00 MIL,50.00 MIL"
					( Parent
						( matchGroupRef "@baseboard_fab2_lib.baseboard_fab2(sch_1):\MG_DQ_NEAR_DIMM_NG_M_A_BYTE3\" )
					)
					( Units "uMatchProp" "ns" 1.000000)
					( Status sCSetFlattened )
					( Origin gBackEnd )
				)
			)
			( pinPair "@baseboard_fab2_lib.baseboard_fab2(sch_1):\PP5274\"
				( pinRef "@baseboard_fab2_lib.baseboard_fab2(sch_1):page23_i172:DDR0_DQ(25)" )
				( pinRef "@baseboard_fab2_lib.baseboard_fab2(sch_1):page43_i1:DQ(24)" )
				( attribute "RELATIVE_PROPAGATION_DELAY_SCOPE" "G"
					( Parent
						( matchGroupRef "@baseboard_fab2_lib.baseboard_fab2(sch_1):\MG_DQ-DQS_FAR_DIMM_NG_M_A_BYTE3\" )
					)
					( Status sCSetFlattened )
					( Origin gBackEnd )
				)
				( attribute "RELATIVE_PROPAGATION_DELAY" "0.00 MIL,195.00 MIL"
					( Parent
						( matchGroupRef "@baseboard_fab2_lib.baseboard_fab2(sch_1):\MG_DQ-DQS_FAR_DIMM_NG_M_A_BYTE3\" )
					)
					( Units "uMatchProp" "ns" 1.000000)
					( Status sCSetFlattened )
					( Origin gBackEnd )
				)
				( attribute "RELATIVE_PROPAGATION_DELAY_SCOPE" "G"
					( Parent
						( matchGroupRef "@baseboard_fab2_lib.baseboard_fab2(sch_1):\MG_DQ_FAR_DIMM_NG_M_A_BYTE3\" )
					)
					( Status sCSetFlattened )
					( Origin gBackEnd )
				)
				( attribute "RELATIVE_PROPAGATION_DELAY" "-50.00 MIL,50.00 MIL"
					( Parent
						( matchGroupRef "@baseboard_fab2_lib.baseboard_fab2(sch_1):\MG_DQ_FAR_DIMM_NG_M_A_BYTE3\" )
					)
					( Units "uMatchProp" "ns" 1.000000)
					( Status sCSetFlattened )
					( Origin gBackEnd )
				)
			)
			( pinPair "@baseboard_fab2_lib.baseboard_fab2(sch_1):\PP5276\"
				( pinRef "@baseboard_fab2_lib.baseboard_fab2(sch_1):page23_i172:DDR0_DQ(25)" )
				( pinRef "@baseboard_fab2_lib.baseboard_fab2(sch_1):page44_i13:DQ(25)" )
				( attribute "RELATIVE_PROPAGATION_DELAY_SCOPE" "G"
					( Parent
						( matchGroupRef "@baseboard_fab2_lib.baseboard_fab2(sch_1):\MG_DQ-DQS_NEAR_DIMM_NG_M_A_BYTE3\" )
					)
					( Status sCSetFlattened )
					( Origin gBackEnd )
				)
				( attribute "RELATIVE_PROPAGATION_DELAY" "0.00 MIL,195.00 MIL"
					( Parent
						( matchGroupRef "@baseboard_fab2_lib.baseboard_fab2(sch_1):\MG_DQ-DQS_NEAR_DIMM_NG_M_A_BYTE3\" )
					)
					( Units "uMatchProp" "ns" 1.000000)
					( Status sCSetFlattened )
					( Origin gBackEnd )
				)
				( attribute "RELATIVE_PROPAGATION_DELAY_SCOPE" "G"
					( Parent
						( matchGroupRef "@baseboard_fab2_lib.baseboard_fab2(sch_1):\MG_DQ_NEAR_DIMM_NG_M_A_BYTE3\" )
					)
					( Status sCSetFlattened )
					( Origin gBackEnd )
				)
				( attribute "RELATIVE_PROPAGATION_DELAY" "-50.00 MIL,50.00 MIL"
					( Parent
						( matchGroupRef "@baseboard_fab2_lib.baseboard_fab2(sch_1):\MG_DQ_NEAR_DIMM_NG_M_A_BYTE3\" )
					)
					( Units "uMatchProp" "ns" 1.000000)
					( Status sCSetFlattened )
					( Origin gBackEnd )
				)
			)
			( pinPair "@baseboard_fab2_lib.baseboard_fab2(sch_1):\PP5277\"
				( pinRef "@baseboard_fab2_lib.baseboard_fab2(sch_1):page23_i172:DDR0_DQ(26)" )
				( pinRef "@baseboard_fab2_lib.baseboard_fab2(sch_1):page43_i1:DQ(27)" )
				( attribute "RELATIVE_PROPAGATION_DELAY_SCOPE" "G"
					( Parent
						( matchGroupRef "@baseboard_fab2_lib.baseboard_fab2(sch_1):\MG_DQ-DQS_FAR_DIMM_NG_M_A_BYTE3\" )
					)
					( Status sCSetFlattened )
					( Origin gBackEnd )
				)
				( attribute "RELATIVE_PROPAGATION_DELAY" "0.00 MIL,195.00 MIL"
					( Parent
						( matchGroupRef "@baseboard_fab2_lib.baseboard_fab2(sch_1):\MG_DQ-DQS_FAR_DIMM_NG_M_A_BYTE3\" )
					)
					( Units "uMatchProp" "ns" 1.000000)
					( Status sCSetFlattened )
					( Origin gBackEnd )
				)
				( attribute "RELATIVE_PROPAGATION_DELAY_SCOPE" "G"
					( Parent
						( matchGroupRef "@baseboard_fab2_lib.baseboard_fab2(sch_1):\MG_DQ_FAR_DIMM_NG_M_A_BYTE3\" )
					)
					( Status sCSetFlattened )
					( Origin gBackEnd )
				)
				( attribute "RELATIVE_PROPAGATION_DELAY" "-50.00 MIL,50.00 MIL"
					( Parent
						( matchGroupRef "@baseboard_fab2_lib.baseboard_fab2(sch_1):\MG_DQ_FAR_DIMM_NG_M_A_BYTE3\" )
					)
					( Units "uMatchProp" "ns" 1.000000)
					( Status sCSetFlattened )
					( Origin gBackEnd )
				)
			)
			( pinPair "@baseboard_fab2_lib.baseboard_fab2(sch_1):\PP5279\"
				( pinRef "@baseboard_fab2_lib.baseboard_fab2(sch_1):page23_i172:DDR0_DQ(26)" )
				( pinRef "@baseboard_fab2_lib.baseboard_fab2(sch_1):page44_i13:DQ(26)" )
				( attribute "RELATIVE_PROPAGATION_DELAY_SCOPE" "G"
					( Parent
						( matchGroupRef "@baseboard_fab2_lib.baseboard_fab2(sch_1):\MG_DQ-DQS_NEAR_DIMM_NG_M_A_BYTE3\" )
					)
					( Status sCSetFlattened )
					( Origin gBackEnd )
				)
				( attribute "RELATIVE_PROPAGATION_DELAY" "0.00 MIL,195.00 MIL"
					( Parent
						( matchGroupRef "@baseboard_fab2_lib.baseboard_fab2(sch_1):\MG_DQ-DQS_NEAR_DIMM_NG_M_A_BYTE3\" )
					)
					( Units "uMatchProp" "ns" 1.000000)
					( Status sCSetFlattened )
					( Origin gBackEnd )
				)
				( attribute "RELATIVE_PROPAGATION_DELAY_SCOPE" "G"
					( Parent
						( matchGroupRef "@baseboard_fab2_lib.baseboard_fab2(sch_1):\MG_DQ_NEAR_DIMM_NG_M_A_BYTE3\" )
					)
					( Status sCSetFlattened )
					( Origin gBackEnd )
				)
				( attribute "RELATIVE_PROPAGATION_DELAY" "-50.00 MIL,50.00 MIL"
					( Parent
						( matchGroupRef "@baseboard_fab2_lib.baseboard_fab2(sch_1):\MG_DQ_NEAR_DIMM_NG_M_A_BYTE3\" )
					)
					( Units "uMatchProp" "ns" 1.000000)
					( Status sCSetFlattened )
					( Origin gBackEnd )
				)
			)
			( pinPair "@baseboard_fab2_lib.baseboard_fab2(sch_1):\PP5280\"
				( pinRef "@baseboard_fab2_lib.baseboard_fab2(sch_1):page23_i172:DDR0_DQ(27)" )
				( pinRef "@baseboard_fab2_lib.baseboard_fab2(sch_1):page43_i1:DQ(26)" )
				( attribute "RELATIVE_PROPAGATION_DELAY_SCOPE" "G"
					( Parent
						( matchGroupRef "@baseboard_fab2_lib.baseboard_fab2(sch_1):\MG_DQ-DQS_FAR_DIMM_NG_M_A_BYTE3\" )
					)
					( Status sCSetFlattened )
					( Origin gBackEnd )
				)
				( attribute "RELATIVE_PROPAGATION_DELAY" "0.00 MIL,195.00 MIL"
					( Parent
						( matchGroupRef "@baseboard_fab2_lib.baseboard_fab2(sch_1):\MG_DQ-DQS_FAR_DIMM_NG_M_A_BYTE3\" )
					)
					( Units "uMatchProp" "ns" 1.000000)
					( Status sCSetFlattened )
					( Origin gBackEnd )
				)
				( attribute "RELATIVE_PROPAGATION_DELAY_SCOPE" "G"
					( Parent
						( matchGroupRef "@baseboard_fab2_lib.baseboard_fab2(sch_1):\MG_DQ_FAR_DIMM_NG_M_A_BYTE3\" )
					)
					( Status sCSetFlattened )
					( Origin gBackEnd )
				)
				( attribute "RELATIVE_PROPAGATION_DELAY" "-50.00 MIL,50.00 MIL"
					( Parent
						( matchGroupRef "@baseboard_fab2_lib.baseboard_fab2(sch_1):\MG_DQ_FAR_DIMM_NG_M_A_BYTE3\" )
					)
					( Units "uMatchProp" "ns" 1.000000)
					( Status sCSetFlattened )
					( Origin gBackEnd )
				)
			)
			( pinPair "@baseboard_fab2_lib.baseboard_fab2(sch_1):\PP5282\"
				( pinRef "@baseboard_fab2_lib.baseboard_fab2(sch_1):page23_i172:DDR0_DQ(27)" )
				( pinRef "@baseboard_fab2_lib.baseboard_fab2(sch_1):page44_i13:DQ(27)" )
				( attribute "RELATIVE_PROPAGATION_DELAY_SCOPE" "G"
					( Parent
						( matchGroupRef "@baseboard_fab2_lib.baseboard_fab2(sch_1):\MG_DQ-DQS_NEAR_DIMM_NG_M_A_BYTE3\" )
					)
					( Status sCSetFlattened )
					( Origin gBackEnd )
				)
				( attribute "RELATIVE_PROPAGATION_DELAY" "0.00 MIL,195.00 MIL"
					( Parent
						( matchGroupRef "@baseboard_fab2_lib.baseboard_fab2(sch_1):\MG_DQ-DQS_NEAR_DIMM_NG_M_A_BYTE3\" )
					)
					( Units "uMatchProp" "ns" 1.000000)
					( Status sCSetFlattened )
					( Origin gBackEnd )
				)
				( attribute "RELATIVE_PROPAGATION_DELAY_SCOPE" "G"
					( Parent
						( matchGroupRef "@baseboard_fab2_lib.baseboard_fab2(sch_1):\MG_DQ_NEAR_DIMM_NG_M_A_BYTE3\" )
					)
					( Status sCSetFlattened )
					( Origin gBackEnd )
				)
				( attribute "RELATIVE_PROPAGATION_DELAY" "-50.00 MIL,50.00 MIL"
					( Parent
						( matchGroupRef "@baseboard_fab2_lib.baseboard_fab2(sch_1):\MG_DQ_NEAR_DIMM_NG_M_A_BYTE3\" )
					)
					( Units "uMatchProp" "ns" 1.000000)
					( Status sCSetFlattened )
					( Origin gBackEnd )
				)
			)
			( pinPair "@baseboard_fab2_lib.baseboard_fab2(sch_1):\PP5283\"
				( pinRef "@baseboard_fab2_lib.baseboard_fab2(sch_1):page23_i172:DDR0_DQ(28)" )
				( pinRef "@baseboard_fab2_lib.baseboard_fab2(sch_1):page43_i1:DQ(29)" )
				( attribute "RELATIVE_PROPAGATION_DELAY_SCOPE" "G"
					( Parent
						( matchGroupRef "@baseboard_fab2_lib.baseboard_fab2(sch_1):\MG_DQ-DQS_FAR_DIMM_NG_M_A_BYTE3\" )
					)
					( Status sCSetFlattened )
					( Origin gBackEnd )
				)
				( attribute "RELATIVE_PROPAGATION_DELAY" "0.00 MIL,195.00 MIL"
					( Parent
						( matchGroupRef "@baseboard_fab2_lib.baseboard_fab2(sch_1):\MG_DQ-DQS_FAR_DIMM_NG_M_A_BYTE3\" )
					)
					( Units "uMatchProp" "ns" 1.000000)
					( Status sCSetFlattened )
					( Origin gBackEnd )
				)
				( attribute "RELATIVE_PROPAGATION_DELAY_SCOPE" "G"
					( Parent
						( matchGroupRef "@baseboard_fab2_lib.baseboard_fab2(sch_1):\MG_DQ_FAR_DIMM_NG_M_A_BYTE3\" )
					)
					( Status sCSetFlattened )
					( Origin gBackEnd )
				)
				( attribute "RELATIVE_PROPAGATION_DELAY" "-50.00 MIL,50.00 MIL"
					( Parent
						( matchGroupRef "@baseboard_fab2_lib.baseboard_fab2(sch_1):\MG_DQ_FAR_DIMM_NG_M_A_BYTE3\" )
					)
					( Units "uMatchProp" "ns" 1.000000)
					( Status sCSetFlattened )
					( Origin gBackEnd )
				)
			)
			( pinPair "@baseboard_fab2_lib.baseboard_fab2(sch_1):\PP5285\"
				( pinRef "@baseboard_fab2_lib.baseboard_fab2(sch_1):page23_i172:DDR0_DQ(28)" )
				( pinRef "@baseboard_fab2_lib.baseboard_fab2(sch_1):page44_i13:DQ(28)" )
				( attribute "RELATIVE_PROPAGATION_DELAY_SCOPE" "G"
					( Parent
						( matchGroupRef "@baseboard_fab2_lib.baseboard_fab2(sch_1):\MG_DQ-DQS_NEAR_DIMM_NG_M_A_BYTE3\" )
					)
					( Status sCSetFlattened )
					( Origin gBackEnd )
				)
				( attribute "RELATIVE_PROPAGATION_DELAY" "0.00 MIL,195.00 MIL"
					( Parent
						( matchGroupRef "@baseboard_fab2_lib.baseboard_fab2(sch_1):\MG_DQ-DQS_NEAR_DIMM_NG_M_A_BYTE3\" )
					)
					( Units "uMatchProp" "ns" 1.000000)
					( Status sCSetFlattened )
					( Origin gBackEnd )
				)
				( attribute "RELATIVE_PROPAGATION_DELAY_SCOPE" "G"
					( Parent
						( matchGroupRef "@baseboard_fab2_lib.baseboard_fab2(sch_1):\MG_DQ_NEAR_DIMM_NG_M_A_BYTE3\" )
					)
					( Status sCSetFlattened )
					( Origin gBackEnd )
				)
				( attribute "RELATIVE_PROPAGATION_DELAY" "-50.00 MIL,50.00 MIL"
					( Parent
						( matchGroupRef "@baseboard_fab2_lib.baseboard_fab2(sch_1):\MG_DQ_NEAR_DIMM_NG_M_A_BYTE3\" )
					)
					( Units "uMatchProp" "ns" 1.000000)
					( Status sCSetFlattened )
					( Origin gBackEnd )
				)
			)
			( pinPair "@baseboard_fab2_lib.baseboard_fab2(sch_1):\PP5286\"
				( pinRef "@baseboard_fab2_lib.baseboard_fab2(sch_1):page23_i172:DDR0_DQ(29)" )
				( pinRef "@baseboard_fab2_lib.baseboard_fab2(sch_1):page43_i1:DQ(28)" )
				( attribute "RELATIVE_PROPAGATION_DELAY_SCOPE" "G"
					( Parent
						( matchGroupRef "@baseboard_fab2_lib.baseboard_fab2(sch_1):\MG_DQ-DQS_FAR_DIMM_NG_M_A_BYTE3\" )
					)
					( Status sCSetFlattened )
					( Origin gBackEnd )
				)
				( attribute "RELATIVE_PROPAGATION_DELAY" "0.00 MIL,195.00 MIL"
					( Parent
						( matchGroupRef "@baseboard_fab2_lib.baseboard_fab2(sch_1):\MG_DQ-DQS_FAR_DIMM_NG_M_A_BYTE3\" )
					)
					( Units "uMatchProp" "ns" 1.000000)
					( Status sCSetFlattened )
					( Origin gBackEnd )
				)
				( attribute "RELATIVE_PROPAGATION_DELAY_SCOPE" "G"
					( Parent
						( matchGroupRef "@baseboard_fab2_lib.baseboard_fab2(sch_1):\MG_DQ_FAR_DIMM_NG_M_A_BYTE3\" )
					)
					( Status sCSetFlattened )
					( Origin gBackEnd )
				)
				( attribute "RELATIVE_PROPAGATION_DELAY" "-50.00 MIL,50.00 MIL"
					( Parent
						( matchGroupRef "@baseboard_fab2_lib.baseboard_fab2(sch_1):\MG_DQ_FAR_DIMM_NG_M_A_BYTE3\" )
					)
					( Units "uMatchProp" "ns" 1.000000)
					( Status sCSetFlattened )
					( Origin gBackEnd )
				)
			)
			( pinPair "@baseboard_fab2_lib.baseboard_fab2(sch_1):\PP5288\"
				( pinRef "@baseboard_fab2_lib.baseboard_fab2(sch_1):page23_i172:DDR0_DQ(29)" )
				( pinRef "@baseboard_fab2_lib.baseboard_fab2(sch_1):page44_i13:DQ(29)" )
				( attribute "RELATIVE_PROPAGATION_DELAY_SCOPE" "G"
					( Parent
						( matchGroupRef "@baseboard_fab2_lib.baseboard_fab2(sch_1):\MG_DQ-DQS_NEAR_DIMM_NG_M_A_BYTE3\" )
					)
					( Status sCSetFlattened )
					( Origin gBackEnd )
				)
				( attribute "RELATIVE_PROPAGATION_DELAY" "0.00 MIL,195.00 MIL"
					( Parent
						( matchGroupRef "@baseboard_fab2_lib.baseboard_fab2(sch_1):\MG_DQ-DQS_NEAR_DIMM_NG_M_A_BYTE3\" )
					)
					( Units "uMatchProp" "ns" 1.000000)
					( Status sCSetFlattened )
					( Origin gBackEnd )
				)
				( attribute "RELATIVE_PROPAGATION_DELAY_SCOPE" "G"
					( Parent
						( matchGroupRef "@baseboard_fab2_lib.baseboard_fab2(sch_1):\MG_DQ_NEAR_DIMM_NG_M_A_BYTE3\" )
					)
					( Status sCSetFlattened )
					( Origin gBackEnd )
				)
				( attribute "RELATIVE_PROPAGATION_DELAY" "-50.00 MIL,50.00 MIL"
					( Parent
						( matchGroupRef "@baseboard_fab2_lib.baseboard_fab2(sch_1):\MG_DQ_NEAR_DIMM_NG_M_A_BYTE3\" )
					)
					( Units "uMatchProp" "ns" 1.000000)
					( Status sCSetFlattened )
					( Origin gBackEnd )
				)
			)
			( pinPair "@baseboard_fab2_lib.baseboard_fab2(sch_1):\PP5289\"
				( pinRef "@baseboard_fab2_lib.baseboard_fab2(sch_1):page23_i172:DDR0_DQ(30)" )
				( pinRef "@baseboard_fab2_lib.baseboard_fab2(sch_1):page43_i1:DQ(31)" )
				( attribute "RELATIVE_PROPAGATION_DELAY_SCOPE" "G"
					( Parent
						( matchGroupRef "@baseboard_fab2_lib.baseboard_fab2(sch_1):\MG_DQ-DQS_FAR_DIMM_NG_M_A_BYTE3\" )
					)
					( Status sCSetFlattened )
					( Origin gBackEnd )
				)
				( attribute "RELATIVE_PROPAGATION_DELAY" "0.00 MIL,195.00 MIL"
					( Parent
						( matchGroupRef "@baseboard_fab2_lib.baseboard_fab2(sch_1):\MG_DQ-DQS_FAR_DIMM_NG_M_A_BYTE3\" )
					)
					( Units "uMatchProp" "ns" 1.000000)
					( Status sCSetFlattened )
					( Origin gBackEnd )
				)
				( attribute "RELATIVE_PROPAGATION_DELAY_SCOPE" "G"
					( Parent
						( matchGroupRef "@baseboard_fab2_lib.baseboard_fab2(sch_1):\MG_DQ_FAR_DIMM_NG_M_A_BYTE3\" )
					)
					( Status sCSetFlattened )
					( Origin gBackEnd )
				)
				( attribute "RELATIVE_PROPAGATION_DELAY" "-50.00 MIL,50.00 MIL"
					( Parent
						( matchGroupRef "@baseboard_fab2_lib.baseboard_fab2(sch_1):\MG_DQ_FAR_DIMM_NG_M_A_BYTE3\" )
					)
					( Units "uMatchProp" "ns" 1.000000)
					( Status sCSetFlattened )
					( Origin gBackEnd )
				)
			)
			( pinPair "@baseboard_fab2_lib.baseboard_fab2(sch_1):\PP5291\"
				( pinRef "@baseboard_fab2_lib.baseboard_fab2(sch_1):page23_i172:DDR0_DQ(30)" )
				( pinRef "@baseboard_fab2_lib.baseboard_fab2(sch_1):page44_i13:DQ(30)" )
				( attribute "RELATIVE_PROPAGATION_DELAY_SCOPE" "G"
					( Parent
						( matchGroupRef "@baseboard_fab2_lib.baseboard_fab2(sch_1):\MG_DQ-DQS_NEAR_DIMM_NG_M_A_BYTE3\" )
					)
					( Status sCSetFlattened )
					( Origin gBackEnd )
				)
				( attribute "RELATIVE_PROPAGATION_DELAY" "0.00 MIL,195.00 MIL"
					( Parent
						( matchGroupRef "@baseboard_fab2_lib.baseboard_fab2(sch_1):\MG_DQ-DQS_NEAR_DIMM_NG_M_A_BYTE3\" )
					)
					( Units "uMatchProp" "ns" 1.000000)
					( Status sCSetFlattened )
					( Origin gBackEnd )
				)
				( attribute "RELATIVE_PROPAGATION_DELAY_SCOPE" "G"
					( Parent
						( matchGroupRef "@baseboard_fab2_lib.baseboard_fab2(sch_1):\MG_DQ_NEAR_DIMM_NG_M_A_BYTE3\" )
					)
					( Status sCSetFlattened )
					( Origin gBackEnd )
				)
				( attribute "RELATIVE_PROPAGATION_DELAY" "-50.00 MIL,50.00 MIL"
					( Parent
						( matchGroupRef "@baseboard_fab2_lib.baseboard_fab2(sch_1):\MG_DQ_NEAR_DIMM_NG_M_A_BYTE3\" )
					)
					( Units "uMatchProp" "ns" 1.000000)
					( Status sCSetFlattened )
					( Origin gBackEnd )
				)
			)
			( pinPair "@baseboard_fab2_lib.baseboard_fab2(sch_1):\PP5292\"
				( pinRef "@baseboard_fab2_lib.baseboard_fab2(sch_1):page23_i172:DDR0_DQ(31)" )
				( pinRef "@baseboard_fab2_lib.baseboard_fab2(sch_1):page43_i1:DQ(30)" )
				( attribute "RELATIVE_PROPAGATION_DELAY_SCOPE" "G"
					( Parent
						( matchGroupRef "@baseboard_fab2_lib.baseboard_fab2(sch_1):\MG_DQ-DQS_FAR_DIMM_NG_M_A_BYTE3\" )
					)
					( Status sCSetFlattened )
					( Origin gBackEnd )
				)
				( attribute "RELATIVE_PROPAGATION_DELAY" "0.00 MIL,195.00 MIL"
					( Parent
						( matchGroupRef "@baseboard_fab2_lib.baseboard_fab2(sch_1):\MG_DQ-DQS_FAR_DIMM_NG_M_A_BYTE3\" )
					)
					( Units "uMatchProp" "ns" 1.000000)
					( Status sCSetFlattened )
					( Origin gBackEnd )
				)
				( attribute "RELATIVE_PROPAGATION_DELAY_SCOPE" "G"
					( Parent
						( matchGroupRef "@baseboard_fab2_lib.baseboard_fab2(sch_1):\MG_DQ_FAR_DIMM_NG_M_A_BYTE3\" )
					)
					( Status sCSetFlattened )
					( Origin gBackEnd )
				)
				( attribute "RELATIVE_PROPAGATION_DELAY" "-50.00 MIL,50.00 MIL"
					( Parent
						( matchGroupRef "@baseboard_fab2_lib.baseboard_fab2(sch_1):\MG_DQ_FAR_DIMM_NG_M_A_BYTE3\" )
					)
					( Units "uMatchProp" "ns" 1.000000)
					( Status sCSetFlattened )
					( Origin gBackEnd )
				)
			)
			( pinPair "@baseboard_fab2_lib.baseboard_fab2(sch_1):\PP5294\"
				( pinRef "@baseboard_fab2_lib.baseboard_fab2(sch_1):page23_i172:DDR0_DQ(31)" )
				( pinRef "@baseboard_fab2_lib.baseboard_fab2(sch_1):page44_i13:DQ(31)" )
				( attribute "RELATIVE_PROPAGATION_DELAY_SCOPE" "G"
					( Parent
						( matchGroupRef "@baseboard_fab2_lib.baseboard_fab2(sch_1):\MG_DQ-DQS_NEAR_DIMM_NG_M_A_BYTE3\" )
					)
					( Status sCSetFlattened )
					( Origin gBackEnd )
				)
				( attribute "RELATIVE_PROPAGATION_DELAY" "0.00 MIL,195.00 MIL"
					( Parent
						( matchGroupRef "@baseboard_fab2_lib.baseboard_fab2(sch_1):\MG_DQ-DQS_NEAR_DIMM_NG_M_A_BYTE3\" )
					)
					( Units "uMatchProp" "ns" 1.000000)
					( Status sCSetFlattened )
					( Origin gBackEnd )
				)
				( attribute "RELATIVE_PROPAGATION_DELAY_SCOPE" "G"
					( Parent
						( matchGroupRef "@baseboard_fab2_lib.baseboard_fab2(sch_1):\MG_DQ_NEAR_DIMM_NG_M_A_BYTE3\" )
					)
					( Status sCSetFlattened )
					( Origin gBackEnd )
				)
				( attribute "RELATIVE_PROPAGATION_DELAY" "-50.00 MIL,50.00 MIL"
					( Parent
						( matchGroupRef "@baseboard_fab2_lib.baseboard_fab2(sch_1):\MG_DQ_NEAR_DIMM_NG_M_A_BYTE3\" )
					)
					( Units "uMatchProp" "ns" 1.000000)
					( Status sCSetFlattened )
					( Origin gBackEnd )
				)
			)
			( pinPair "@baseboard_fab2_lib.baseboard_fab2(sch_1):\PP5247\"
				( pinRef "@baseboard_fab2_lib.baseboard_fab2(sch_1):page23_i172:DDR0_DQ(32)" )
				( pinRef "@baseboard_fab2_lib.baseboard_fab2(sch_1):page43_i1:DQ(33)" )
				( attribute "RELATIVE_PROPAGATION_DELAY_SCOPE" "G"
					( Parent
						( matchGroupRef "@baseboard_fab2_lib.baseboard_fab2(sch_1):\MG_DQ-DQS_FAR_DIMM_NG_M_A_BYTE4\" )
					)
					( Status sCSetFlattened )
					( Origin gBackEnd )
				)
				( attribute "RELATIVE_PROPAGATION_DELAY" "0.00 MIL,195.00 MIL"
					( Parent
						( matchGroupRef "@baseboard_fab2_lib.baseboard_fab2(sch_1):\MG_DQ-DQS_FAR_DIMM_NG_M_A_BYTE4\" )
					)
					( Units "uMatchProp" "ns" 1.000000)
					( Status sCSetFlattened )
					( Origin gBackEnd )
				)
				( attribute "RELATIVE_PROPAGATION_DELAY_SCOPE" "G"
					( Parent
						( matchGroupRef "@baseboard_fab2_lib.baseboard_fab2(sch_1):\MG_DQ_FAR_DIMM_NG_M_A_BYTE4\" )
					)
					( Status sCSetFlattened )
					( Origin gBackEnd )
				)
				( attribute "RELATIVE_PROPAGATION_DELAY" "-50.00 MIL,50.00 MIL"
					( Parent
						( matchGroupRef "@baseboard_fab2_lib.baseboard_fab2(sch_1):\MG_DQ_FAR_DIMM_NG_M_A_BYTE4\" )
					)
					( Units "uMatchProp" "ns" 1.000000)
					( Status sCSetFlattened )
					( Origin gBackEnd )
				)
			)
			( pinPair "@baseboard_fab2_lib.baseboard_fab2(sch_1):\PP5249\"
				( pinRef "@baseboard_fab2_lib.baseboard_fab2(sch_1):page23_i172:DDR0_DQ(32)" )
				( pinRef "@baseboard_fab2_lib.baseboard_fab2(sch_1):page44_i13:DQ(32)" )
				( attribute "RELATIVE_PROPAGATION_DELAY_SCOPE" "G"
					( Parent
						( matchGroupRef "@baseboard_fab2_lib.baseboard_fab2(sch_1):\MG_DQ-DQS_NEAR_DIMM_NG_M_A_BYTE4\" )
					)
					( Status sCSetFlattened )
					( Origin gBackEnd )
				)
				( attribute "RELATIVE_PROPAGATION_DELAY" "0.00 MIL,195.00 MIL"
					( Parent
						( matchGroupRef "@baseboard_fab2_lib.baseboard_fab2(sch_1):\MG_DQ-DQS_NEAR_DIMM_NG_M_A_BYTE4\" )
					)
					( Units "uMatchProp" "ns" 1.000000)
					( Status sCSetFlattened )
					( Origin gBackEnd )
				)
				( attribute "RELATIVE_PROPAGATION_DELAY_SCOPE" "G"
					( Parent
						( matchGroupRef "@baseboard_fab2_lib.baseboard_fab2(sch_1):\MG_DQ_NEAR_DIMM_NG_M_A_BYTE4\" )
					)
					( Status sCSetFlattened )
					( Origin gBackEnd )
				)
				( attribute "RELATIVE_PROPAGATION_DELAY" "-50.00 MIL,50.00 MIL"
					( Parent
						( matchGroupRef "@baseboard_fab2_lib.baseboard_fab2(sch_1):\MG_DQ_NEAR_DIMM_NG_M_A_BYTE4\" )
					)
					( Units "uMatchProp" "ns" 1.000000)
					( Status sCSetFlattened )
					( Origin gBackEnd )
				)
			)
			( pinPair "@baseboard_fab2_lib.baseboard_fab2(sch_1):\PP5250\"
				( pinRef "@baseboard_fab2_lib.baseboard_fab2(sch_1):page23_i172:DDR0_DQ(33)" )
				( pinRef "@baseboard_fab2_lib.baseboard_fab2(sch_1):page43_i1:DQ(32)" )
				( attribute "RELATIVE_PROPAGATION_DELAY_SCOPE" "G"
					( Parent
						( matchGroupRef "@baseboard_fab2_lib.baseboard_fab2(sch_1):\MG_DQ-DQS_FAR_DIMM_NG_M_A_BYTE4\" )
					)
					( Status sCSetFlattened )
					( Origin gBackEnd )
				)
				( attribute "RELATIVE_PROPAGATION_DELAY" "0.00 MIL,195.00 MIL"
					( Parent
						( matchGroupRef "@baseboard_fab2_lib.baseboard_fab2(sch_1):\MG_DQ-DQS_FAR_DIMM_NG_M_A_BYTE4\" )
					)
					( Units "uMatchProp" "ns" 1.000000)
					( Status sCSetFlattened )
					( Origin gBackEnd )
				)
				( attribute "RELATIVE_PROPAGATION_DELAY_SCOPE" "G"
					( Parent
						( matchGroupRef "@baseboard_fab2_lib.baseboard_fab2(sch_1):\MG_DQ_FAR_DIMM_NG_M_A_BYTE4\" )
					)
					( Status sCSetFlattened )
					( Origin gBackEnd )
				)
				( attribute "RELATIVE_PROPAGATION_DELAY" "-50.00 MIL,50.00 MIL"
					( Parent
						( matchGroupRef "@baseboard_fab2_lib.baseboard_fab2(sch_1):\MG_DQ_FAR_DIMM_NG_M_A_BYTE4\" )
					)
					( Units "uMatchProp" "ns" 1.000000)
					( Status sCSetFlattened )
					( Origin gBackEnd )
				)
			)
			( pinPair "@baseboard_fab2_lib.baseboard_fab2(sch_1):\PP5252\"
				( pinRef "@baseboard_fab2_lib.baseboard_fab2(sch_1):page23_i172:DDR0_DQ(33)" )
				( pinRef "@baseboard_fab2_lib.baseboard_fab2(sch_1):page44_i13:DQ(33)" )
				( attribute "RELATIVE_PROPAGATION_DELAY_SCOPE" "G"
					( Parent
						( matchGroupRef "@baseboard_fab2_lib.baseboard_fab2(sch_1):\MG_DQ-DQS_NEAR_DIMM_NG_M_A_BYTE4\" )
					)
					( Status sCSetFlattened )
					( Origin gBackEnd )
				)
				( attribute "RELATIVE_PROPAGATION_DELAY" "0.00 MIL,195.00 MIL"
					( Parent
						( matchGroupRef "@baseboard_fab2_lib.baseboard_fab2(sch_1):\MG_DQ-DQS_NEAR_DIMM_NG_M_A_BYTE4\" )
					)
					( Units "uMatchProp" "ns" 1.000000)
					( Status sCSetFlattened )
					( Origin gBackEnd )
				)
				( attribute "RELATIVE_PROPAGATION_DELAY_SCOPE" "G"
					( Parent
						( matchGroupRef "@baseboard_fab2_lib.baseboard_fab2(sch_1):\MG_DQ_NEAR_DIMM_NG_M_A_BYTE4\" )
					)
					( Status sCSetFlattened )
					( Origin gBackEnd )
				)
				( attribute "RELATIVE_PROPAGATION_DELAY" "-50.00 MIL,50.00 MIL"
					( Parent
						( matchGroupRef "@baseboard_fab2_lib.baseboard_fab2(sch_1):\MG_DQ_NEAR_DIMM_NG_M_A_BYTE4\" )
					)
					( Units "uMatchProp" "ns" 1.000000)
					( Status sCSetFlattened )
					( Origin gBackEnd )
				)
			)
			( pinPair "@baseboard_fab2_lib.baseboard_fab2(sch_1):\PP5253\"
				( pinRef "@baseboard_fab2_lib.baseboard_fab2(sch_1):page23_i172:DDR0_DQ(34)" )
				( pinRef "@baseboard_fab2_lib.baseboard_fab2(sch_1):page43_i1:DQ(35)" )
				( attribute "RELATIVE_PROPAGATION_DELAY_SCOPE" "G"
					( Parent
						( matchGroupRef "@baseboard_fab2_lib.baseboard_fab2(sch_1):\MG_DQ-DQS_FAR_DIMM_NG_M_A_BYTE4\" )
					)
					( Status sCSetFlattened )
					( Origin gBackEnd )
				)
				( attribute "RELATIVE_PROPAGATION_DELAY" "0.00 MIL,195.00 MIL"
					( Parent
						( matchGroupRef "@baseboard_fab2_lib.baseboard_fab2(sch_1):\MG_DQ-DQS_FAR_DIMM_NG_M_A_BYTE4\" )
					)
					( Units "uMatchProp" "ns" 1.000000)
					( Status sCSetFlattened )
					( Origin gBackEnd )
				)
				( attribute "RELATIVE_PROPAGATION_DELAY_SCOPE" "G"
					( Parent
						( matchGroupRef "@baseboard_fab2_lib.baseboard_fab2(sch_1):\MG_DQ_FAR_DIMM_NG_M_A_BYTE4\" )
					)
					( Status sCSetFlattened )
					( Origin gBackEnd )
				)
				( attribute "RELATIVE_PROPAGATION_DELAY" "-50.00 MIL,50.00 MIL"
					( Parent
						( matchGroupRef "@baseboard_fab2_lib.baseboard_fab2(sch_1):\MG_DQ_FAR_DIMM_NG_M_A_BYTE4\" )
					)
					( Units "uMatchProp" "ns" 1.000000)
					( Status sCSetFlattened )
					( Origin gBackEnd )
				)
			)
			( pinPair "@baseboard_fab2_lib.baseboard_fab2(sch_1):\PP5255\"
				( pinRef "@baseboard_fab2_lib.baseboard_fab2(sch_1):page23_i172:DDR0_DQ(34)" )
				( pinRef "@baseboard_fab2_lib.baseboard_fab2(sch_1):page44_i13:DQ(34)" )
				( attribute "RELATIVE_PROPAGATION_DELAY_SCOPE" "G"
					( Parent
						( matchGroupRef "@baseboard_fab2_lib.baseboard_fab2(sch_1):\MG_DQ-DQS_NEAR_DIMM_NG_M_A_BYTE4\" )
					)
					( Status sCSetFlattened )
					( Origin gBackEnd )
				)
				( attribute "RELATIVE_PROPAGATION_DELAY" "0.00 MIL,195.00 MIL"
					( Parent
						( matchGroupRef "@baseboard_fab2_lib.baseboard_fab2(sch_1):\MG_DQ-DQS_NEAR_DIMM_NG_M_A_BYTE4\" )
					)
					( Units "uMatchProp" "ns" 1.000000)
					( Status sCSetFlattened )
					( Origin gBackEnd )
				)
				( attribute "RELATIVE_PROPAGATION_DELAY_SCOPE" "G"
					( Parent
						( matchGroupRef "@baseboard_fab2_lib.baseboard_fab2(sch_1):\MG_DQ_NEAR_DIMM_NG_M_A_BYTE4\" )
					)
					( Status sCSetFlattened )
					( Origin gBackEnd )
				)
				( attribute "RELATIVE_PROPAGATION_DELAY" "-50.00 MIL,50.00 MIL"
					( Parent
						( matchGroupRef "@baseboard_fab2_lib.baseboard_fab2(sch_1):\MG_DQ_NEAR_DIMM_NG_M_A_BYTE4\" )
					)
					( Units "uMatchProp" "ns" 1.000000)
					( Status sCSetFlattened )
					( Origin gBackEnd )
				)
			)
			( pinPair "@baseboard_fab2_lib.baseboard_fab2(sch_1):\PP5256\"
				( pinRef "@baseboard_fab2_lib.baseboard_fab2(sch_1):page23_i172:DDR0_DQ(35)" )
				( pinRef "@baseboard_fab2_lib.baseboard_fab2(sch_1):page43_i1:DQ(34)" )
				( attribute "RELATIVE_PROPAGATION_DELAY_SCOPE" "G"
					( Parent
						( matchGroupRef "@baseboard_fab2_lib.baseboard_fab2(sch_1):\MG_DQ-DQS_FAR_DIMM_NG_M_A_BYTE4\" )
					)
					( Status sCSetFlattened )
					( Origin gBackEnd )
				)
				( attribute "RELATIVE_PROPAGATION_DELAY" "0.00 MIL,195.00 MIL"
					( Parent
						( matchGroupRef "@baseboard_fab2_lib.baseboard_fab2(sch_1):\MG_DQ-DQS_FAR_DIMM_NG_M_A_BYTE4\" )
					)
					( Units "uMatchProp" "ns" 1.000000)
					( Status sCSetFlattened )
					( Origin gBackEnd )
				)
				( attribute "RELATIVE_PROPAGATION_DELAY_SCOPE" "G"
					( Parent
						( matchGroupRef "@baseboard_fab2_lib.baseboard_fab2(sch_1):\MG_DQ_FAR_DIMM_NG_M_A_BYTE4\" )
					)
					( Status sCSetFlattened )
					( Origin gBackEnd )
				)
				( attribute "RELATIVE_PROPAGATION_DELAY" "-50.00 MIL,50.00 MIL"
					( Parent
						( matchGroupRef "@baseboard_fab2_lib.baseboard_fab2(sch_1):\MG_DQ_FAR_DIMM_NG_M_A_BYTE4\" )
					)
					( Units "uMatchProp" "ns" 1.000000)
					( Status sCSetFlattened )
					( Origin gBackEnd )
				)
			)
			( pinPair "@baseboard_fab2_lib.baseboard_fab2(sch_1):\PP5258\"
				( pinRef "@baseboard_fab2_lib.baseboard_fab2(sch_1):page23_i172:DDR0_DQ(35)" )
				( pinRef "@baseboard_fab2_lib.baseboard_fab2(sch_1):page44_i13:DQ(35)" )
				( attribute "RELATIVE_PROPAGATION_DELAY_SCOPE" "G"
					( Parent
						( matchGroupRef "@baseboard_fab2_lib.baseboard_fab2(sch_1):\MG_DQ-DQS_NEAR_DIMM_NG_M_A_BYTE4\" )
					)
					( Status sCSetFlattened )
					( Origin gBackEnd )
				)
				( attribute "RELATIVE_PROPAGATION_DELAY" "0.00 MIL,195.00 MIL"
					( Parent
						( matchGroupRef "@baseboard_fab2_lib.baseboard_fab2(sch_1):\MG_DQ-DQS_NEAR_DIMM_NG_M_A_BYTE4\" )
					)
					( Units "uMatchProp" "ns" 1.000000)
					( Status sCSetFlattened )
					( Origin gBackEnd )
				)
				( attribute "RELATIVE_PROPAGATION_DELAY_SCOPE" "G"
					( Parent
						( matchGroupRef "@baseboard_fab2_lib.baseboard_fab2(sch_1):\MG_DQ_NEAR_DIMM_NG_M_A_BYTE4\" )
					)
					( Status sCSetFlattened )
					( Origin gBackEnd )
				)
				( attribute "RELATIVE_PROPAGATION_DELAY" "-50.00 MIL,50.00 MIL"
					( Parent
						( matchGroupRef "@baseboard_fab2_lib.baseboard_fab2(sch_1):\MG_DQ_NEAR_DIMM_NG_M_A_BYTE4\" )
					)
					( Units "uMatchProp" "ns" 1.000000)
					( Status sCSetFlattened )
					( Origin gBackEnd )
				)
			)
			( pinPair "@baseboard_fab2_lib.baseboard_fab2(sch_1):\PP5259\"
				( pinRef "@baseboard_fab2_lib.baseboard_fab2(sch_1):page23_i172:DDR0_DQ(36)" )
				( pinRef "@baseboard_fab2_lib.baseboard_fab2(sch_1):page43_i1:DQ(37)" )
				( attribute "RELATIVE_PROPAGATION_DELAY_SCOPE" "G"
					( Parent
						( matchGroupRef "@baseboard_fab2_lib.baseboard_fab2(sch_1):\MG_DQ-DQS_FAR_DIMM_NG_M_A_BYTE4\" )
					)
					( Status sCSetFlattened )
					( Origin gBackEnd )
				)
				( attribute "RELATIVE_PROPAGATION_DELAY" "0.00 MIL,195.00 MIL"
					( Parent
						( matchGroupRef "@baseboard_fab2_lib.baseboard_fab2(sch_1):\MG_DQ-DQS_FAR_DIMM_NG_M_A_BYTE4\" )
					)
					( Units "uMatchProp" "ns" 1.000000)
					( Status sCSetFlattened )
					( Origin gBackEnd )
				)
				( attribute "RELATIVE_PROPAGATION_DELAY_SCOPE" "G"
					( Parent
						( matchGroupRef "@baseboard_fab2_lib.baseboard_fab2(sch_1):\MG_DQ_FAR_DIMM_NG_M_A_BYTE4\" )
					)
					( Status sCSetFlattened )
					( Origin gBackEnd )
				)
				( attribute "RELATIVE_PROPAGATION_DELAY" "-50.00 MIL,50.00 MIL"
					( Parent
						( matchGroupRef "@baseboard_fab2_lib.baseboard_fab2(sch_1):\MG_DQ_FAR_DIMM_NG_M_A_BYTE4\" )
					)
					( Units "uMatchProp" "ns" 1.000000)
					( Status sCSetFlattened )
					( Origin gBackEnd )
				)
			)
			( pinPair "@baseboard_fab2_lib.baseboard_fab2(sch_1):\PP5261\"
				( pinRef "@baseboard_fab2_lib.baseboard_fab2(sch_1):page23_i172:DDR0_DQ(36)" )
				( pinRef "@baseboard_fab2_lib.baseboard_fab2(sch_1):page44_i13:DQ(36)" )
				( attribute "RELATIVE_PROPAGATION_DELAY_SCOPE" "G"
					( Parent
						( matchGroupRef "@baseboard_fab2_lib.baseboard_fab2(sch_1):\MG_DQ-DQS_NEAR_DIMM_NG_M_A_BYTE4\" )
					)
					( Status sCSetFlattened )
					( Origin gBackEnd )
				)
				( attribute "RELATIVE_PROPAGATION_DELAY" "0.00 MIL,195.00 MIL"
					( Parent
						( matchGroupRef "@baseboard_fab2_lib.baseboard_fab2(sch_1):\MG_DQ-DQS_NEAR_DIMM_NG_M_A_BYTE4\" )
					)
					( Units "uMatchProp" "ns" 1.000000)
					( Status sCSetFlattened )
					( Origin gBackEnd )
				)
				( attribute "RELATIVE_PROPAGATION_DELAY_SCOPE" "G"
					( Parent
						( matchGroupRef "@baseboard_fab2_lib.baseboard_fab2(sch_1):\MG_DQ_NEAR_DIMM_NG_M_A_BYTE4\" )
					)
					( Status sCSetFlattened )
					( Origin gBackEnd )
				)
				( attribute "RELATIVE_PROPAGATION_DELAY" "-50.00 MIL,50.00 MIL"
					( Parent
						( matchGroupRef "@baseboard_fab2_lib.baseboard_fab2(sch_1):\MG_DQ_NEAR_DIMM_NG_M_A_BYTE4\" )
					)
					( Units "uMatchProp" "ns" 1.000000)
					( Status sCSetFlattened )
					( Origin gBackEnd )
				)
			)
			( pinPair "@baseboard_fab2_lib.baseboard_fab2(sch_1):\PP5262\"
				( pinRef "@baseboard_fab2_lib.baseboard_fab2(sch_1):page23_i172:DDR0_DQ(37)" )
				( pinRef "@baseboard_fab2_lib.baseboard_fab2(sch_1):page43_i1:DQ(36)" )
				( attribute "RELATIVE_PROPAGATION_DELAY_SCOPE" "G"
					( Parent
						( matchGroupRef "@baseboard_fab2_lib.baseboard_fab2(sch_1):\MG_DQ-DQS_FAR_DIMM_NG_M_A_BYTE4\" )
					)
					( Status sCSetFlattened )
					( Origin gBackEnd )
				)
				( attribute "RELATIVE_PROPAGATION_DELAY" "0.00 MIL,195.00 MIL"
					( Parent
						( matchGroupRef "@baseboard_fab2_lib.baseboard_fab2(sch_1):\MG_DQ-DQS_FAR_DIMM_NG_M_A_BYTE4\" )
					)
					( Units "uMatchProp" "ns" 1.000000)
					( Status sCSetFlattened )
					( Origin gBackEnd )
				)
				( attribute "RELATIVE_PROPAGATION_DELAY_SCOPE" "G"
					( Parent
						( matchGroupRef "@baseboard_fab2_lib.baseboard_fab2(sch_1):\MG_DQ_FAR_DIMM_NG_M_A_BYTE4\" )
					)
					( Status sCSetFlattened )
					( Origin gBackEnd )
				)
				( attribute "RELATIVE_PROPAGATION_DELAY" "-50.00 MIL,50.00 MIL"
					( Parent
						( matchGroupRef "@baseboard_fab2_lib.baseboard_fab2(sch_1):\MG_DQ_FAR_DIMM_NG_M_A_BYTE4\" )
					)
					( Units "uMatchProp" "ns" 1.000000)
					( Status sCSetFlattened )
					( Origin gBackEnd )
				)
			)
			( pinPair "@baseboard_fab2_lib.baseboard_fab2(sch_1):\PP5264\"
				( pinRef "@baseboard_fab2_lib.baseboard_fab2(sch_1):page23_i172:DDR0_DQ(37)" )
				( pinRef "@baseboard_fab2_lib.baseboard_fab2(sch_1):page44_i13:DQ(37)" )
				( attribute "RELATIVE_PROPAGATION_DELAY_SCOPE" "G"
					( Parent
						( matchGroupRef "@baseboard_fab2_lib.baseboard_fab2(sch_1):\MG_DQ-DQS_NEAR_DIMM_NG_M_A_BYTE4\" )
					)
					( Status sCSetFlattened )
					( Origin gBackEnd )
				)
				( attribute "RELATIVE_PROPAGATION_DELAY" "0.00 MIL,195.00 MIL"
					( Parent
						( matchGroupRef "@baseboard_fab2_lib.baseboard_fab2(sch_1):\MG_DQ-DQS_NEAR_DIMM_NG_M_A_BYTE4\" )
					)
					( Units "uMatchProp" "ns" 1.000000)
					( Status sCSetFlattened )
					( Origin gBackEnd )
				)
				( attribute "RELATIVE_PROPAGATION_DELAY_SCOPE" "G"
					( Parent
						( matchGroupRef "@baseboard_fab2_lib.baseboard_fab2(sch_1):\MG_DQ_NEAR_DIMM_NG_M_A_BYTE4\" )
					)
					( Status sCSetFlattened )
					( Origin gBackEnd )
				)
				( attribute "RELATIVE_PROPAGATION_DELAY" "-50.00 MIL,50.00 MIL"
					( Parent
						( matchGroupRef "@baseboard_fab2_lib.baseboard_fab2(sch_1):\MG_DQ_NEAR_DIMM_NG_M_A_BYTE4\" )
					)
					( Units "uMatchProp" "ns" 1.000000)
					( Status sCSetFlattened )
					( Origin gBackEnd )
				)
			)
			( pinPair "@baseboard_fab2_lib.baseboard_fab2(sch_1):\PP5265\"
				( pinRef "@baseboard_fab2_lib.baseboard_fab2(sch_1):page23_i172:DDR0_DQ(38)" )
				( pinRef "@baseboard_fab2_lib.baseboard_fab2(sch_1):page43_i1:DQ(39)" )
				( attribute "RELATIVE_PROPAGATION_DELAY_SCOPE" "G"
					( Parent
						( matchGroupRef "@baseboard_fab2_lib.baseboard_fab2(sch_1):\MG_DQ-DQS_FAR_DIMM_NG_M_A_BYTE4\" )
					)
					( Status sCSetFlattened )
					( Origin gBackEnd )
				)
				( attribute "RELATIVE_PROPAGATION_DELAY" "0.00 MIL,195.00 MIL"
					( Parent
						( matchGroupRef "@baseboard_fab2_lib.baseboard_fab2(sch_1):\MG_DQ-DQS_FAR_DIMM_NG_M_A_BYTE4\" )
					)
					( Units "uMatchProp" "ns" 1.000000)
					( Status sCSetFlattened )
					( Origin gBackEnd )
				)
				( attribute "RELATIVE_PROPAGATION_DELAY_SCOPE" "G"
					( Parent
						( matchGroupRef "@baseboard_fab2_lib.baseboard_fab2(sch_1):\MG_DQ_FAR_DIMM_NG_M_A_BYTE4\" )
					)
					( Status sCSetFlattened )
					( Origin gBackEnd )
				)
				( attribute "RELATIVE_PROPAGATION_DELAY" "-50.00 MIL,50.00 MIL"
					( Parent
						( matchGroupRef "@baseboard_fab2_lib.baseboard_fab2(sch_1):\MG_DQ_FAR_DIMM_NG_M_A_BYTE4\" )
					)
					( Units "uMatchProp" "ns" 1.000000)
					( Status sCSetFlattened )
					( Origin gBackEnd )
				)
			)
			( pinPair "@baseboard_fab2_lib.baseboard_fab2(sch_1):\PP5267\"
				( pinRef "@baseboard_fab2_lib.baseboard_fab2(sch_1):page23_i172:DDR0_DQ(38)" )
				( pinRef "@baseboard_fab2_lib.baseboard_fab2(sch_1):page44_i13:DQ(38)" )
				( attribute "RELATIVE_PROPAGATION_DELAY_SCOPE" "G"
					( Parent
						( matchGroupRef "@baseboard_fab2_lib.baseboard_fab2(sch_1):\MG_DQ-DQS_NEAR_DIMM_NG_M_A_BYTE4\" )
					)
					( Status sCSetFlattened )
					( Origin gBackEnd )
				)
				( attribute "RELATIVE_PROPAGATION_DELAY" "0.00 MIL,195.00 MIL"
					( Parent
						( matchGroupRef "@baseboard_fab2_lib.baseboard_fab2(sch_1):\MG_DQ-DQS_NEAR_DIMM_NG_M_A_BYTE4\" )
					)
					( Units "uMatchProp" "ns" 1.000000)
					( Status sCSetFlattened )
					( Origin gBackEnd )
				)
				( attribute "RELATIVE_PROPAGATION_DELAY_SCOPE" "G"
					( Parent
						( matchGroupRef "@baseboard_fab2_lib.baseboard_fab2(sch_1):\MG_DQ_NEAR_DIMM_NG_M_A_BYTE4\" )
					)
					( Status sCSetFlattened )
					( Origin gBackEnd )
				)
				( attribute "RELATIVE_PROPAGATION_DELAY" "-50.00 MIL,50.00 MIL"
					( Parent
						( matchGroupRef "@baseboard_fab2_lib.baseboard_fab2(sch_1):\MG_DQ_NEAR_DIMM_NG_M_A_BYTE4\" )
					)
					( Units "uMatchProp" "ns" 1.000000)
					( Status sCSetFlattened )
					( Origin gBackEnd )
				)
			)
			( pinPair "@baseboard_fab2_lib.baseboard_fab2(sch_1):\PP5268\"
				( pinRef "@baseboard_fab2_lib.baseboard_fab2(sch_1):page23_i172:DDR0_DQ(39)" )
				( pinRef "@baseboard_fab2_lib.baseboard_fab2(sch_1):page43_i1:DQ(38)" )
				( attribute "RELATIVE_PROPAGATION_DELAY_SCOPE" "G"
					( Parent
						( matchGroupRef "@baseboard_fab2_lib.baseboard_fab2(sch_1):\MG_DQ-DQS_FAR_DIMM_NG_M_A_BYTE4\" )
					)
					( Status sCSetFlattened )
					( Origin gBackEnd )
				)
				( attribute "RELATIVE_PROPAGATION_DELAY" "0.00 MIL,195.00 MIL"
					( Parent
						( matchGroupRef "@baseboard_fab2_lib.baseboard_fab2(sch_1):\MG_DQ-DQS_FAR_DIMM_NG_M_A_BYTE4\" )
					)
					( Units "uMatchProp" "ns" 1.000000)
					( Status sCSetFlattened )
					( Origin gBackEnd )
				)
				( attribute "RELATIVE_PROPAGATION_DELAY_SCOPE" "G"
					( Parent
						( matchGroupRef "@baseboard_fab2_lib.baseboard_fab2(sch_1):\MG_DQ_FAR_DIMM_NG_M_A_BYTE4\" )
					)
					( Status sCSetFlattened )
					( Origin gBackEnd )
				)
				( attribute "RELATIVE_PROPAGATION_DELAY" "-50.00 MIL,50.00 MIL"
					( Parent
						( matchGroupRef "@baseboard_fab2_lib.baseboard_fab2(sch_1):\MG_DQ_FAR_DIMM_NG_M_A_BYTE4\" )
					)
					( Units "uMatchProp" "ns" 1.000000)
					( Status sCSetFlattened )
					( Origin gBackEnd )
				)
			)
			( pinPair "@baseboard_fab2_lib.baseboard_fab2(sch_1):\PP5270\"
				( pinRef "@baseboard_fab2_lib.baseboard_fab2(sch_1):page23_i172:DDR0_DQ(39)" )
				( pinRef "@baseboard_fab2_lib.baseboard_fab2(sch_1):page44_i13:DQ(39)" )
				( attribute "RELATIVE_PROPAGATION_DELAY_SCOPE" "G"
					( Parent
						( matchGroupRef "@baseboard_fab2_lib.baseboard_fab2(sch_1):\MG_DQ-DQS_NEAR_DIMM_NG_M_A_BYTE4\" )
					)
					( Status sCSetFlattened )
					( Origin gBackEnd )
				)
				( attribute "RELATIVE_PROPAGATION_DELAY" "0.00 MIL,195.00 MIL"
					( Parent
						( matchGroupRef "@baseboard_fab2_lib.baseboard_fab2(sch_1):\MG_DQ-DQS_NEAR_DIMM_NG_M_A_BYTE4\" )
					)
					( Units "uMatchProp" "ns" 1.000000)
					( Status sCSetFlattened )
					( Origin gBackEnd )
				)
				( attribute "RELATIVE_PROPAGATION_DELAY_SCOPE" "G"
					( Parent
						( matchGroupRef "@baseboard_fab2_lib.baseboard_fab2(sch_1):\MG_DQ_NEAR_DIMM_NG_M_A_BYTE4\" )
					)
					( Status sCSetFlattened )
					( Origin gBackEnd )
				)
				( attribute "RELATIVE_PROPAGATION_DELAY" "-50.00 MIL,50.00 MIL"
					( Parent
						( matchGroupRef "@baseboard_fab2_lib.baseboard_fab2(sch_1):\MG_DQ_NEAR_DIMM_NG_M_A_BYTE4\" )
					)
					( Units "uMatchProp" "ns" 1.000000)
					( Status sCSetFlattened )
					( Origin gBackEnd )
				)
			)
			( pinPair "@baseboard_fab2_lib.baseboard_fab2(sch_1):\PP5223\"
				( pinRef "@baseboard_fab2_lib.baseboard_fab2(sch_1):page23_i172:DDR0_DQ(40)" )
				( pinRef "@baseboard_fab2_lib.baseboard_fab2(sch_1):page43_i1:DQ(41)" )
				( attribute "RELATIVE_PROPAGATION_DELAY_SCOPE" "G"
					( Parent
						( matchGroupRef "@baseboard_fab2_lib.baseboard_fab2(sch_1):\MG_DQ-DQS_FAR_DIMM_NG_M_A_BYTE5\" )
					)
					( Status sCSetFlattened )
					( Origin gBackEnd )
				)
				( attribute "RELATIVE_PROPAGATION_DELAY" "0.00 MIL,195.00 MIL"
					( Parent
						( matchGroupRef "@baseboard_fab2_lib.baseboard_fab2(sch_1):\MG_DQ-DQS_FAR_DIMM_NG_M_A_BYTE5\" )
					)
					( Units "uMatchProp" "ns" 1.000000)
					( Status sCSetFlattened )
					( Origin gBackEnd )
				)
				( attribute "RELATIVE_PROPAGATION_DELAY_SCOPE" "G"
					( Parent
						( matchGroupRef "@crescent_city_bb_fab1_lib.crescent_city_bb_fab1(sch_1):\MG_DQ_FAR_DIMM_NG_M_A_BYTE5\" )
					)
					( Status sCSetFlattened )
					( Origin gBackEnd )
				)
				( attribute "RELATIVE_PROPAGATION_DELAY" "-50.00 MIL,50.00 MIL"
					( Parent
						( matchGroupRef "@crescent_city_bb_fab1_lib.crescent_city_bb_fab1(sch_1):\MG_DQ_FAR_DIMM_NG_M_A_BYTE5\" )
					)
					( Units "uMatchProp" "ns" 1.000000)
					( Status sCSetFlattened )
					( Origin gBackEnd )
				)
			)
			( pinPair "@baseboard_fab2_lib.baseboard_fab2(sch_1):\PP5225\"
				( pinRef "@baseboard_fab2_lib.baseboard_fab2(sch_1):page23_i172:DDR0_DQ(40)" )
				( pinRef "@baseboard_fab2_lib.baseboard_fab2(sch_1):page44_i13:DQ(40)" )
				( attribute "RELATIVE_PROPAGATION_DELAY_SCOPE" "G"
					( Parent
						( matchGroupRef "@baseboard_fab2_lib.baseboard_fab2(sch_1):\MG_DQ-DQS_NEAR_DIMM_NG_M_A_BYTE5\" )
					)
					( Status sCSetFlattened )
					( Origin gBackEnd )
				)
				( attribute "RELATIVE_PROPAGATION_DELAY" "0.00 MIL,195.00 MIL"
					( Parent
						( matchGroupRef "@baseboard_fab2_lib.baseboard_fab2(sch_1):\MG_DQ-DQS_NEAR_DIMM_NG_M_A_BYTE5\" )
					)
					( Units "uMatchProp" "ns" 1.000000)
					( Status sCSetFlattened )
					( Origin gBackEnd )
				)
				( attribute "RELATIVE_PROPAGATION_DELAY_SCOPE" "G"
					( Parent
						( matchGroupRef "@crescent_city_bb_fab1_lib.crescent_city_bb_fab1(sch_1):\MG_DQ_NEAR_DIMM_NG_M_A_BYTE5\" )
					)
					( Status sCSetFlattened )
					( Origin gBackEnd )
				)
				( attribute "RELATIVE_PROPAGATION_DELAY" "-50.00 MIL,50.00 MIL"
					( Parent
						( matchGroupRef "@crescent_city_bb_fab1_lib.crescent_city_bb_fab1(sch_1):\MG_DQ_NEAR_DIMM_NG_M_A_BYTE5\" )
					)
					( Units "uMatchProp" "ns" 1.000000)
					( Status sCSetFlattened )
					( Origin gBackEnd )
				)
			)
			( pinPair "@baseboard_fab2_lib.baseboard_fab2(sch_1):\PP5226\"
				( pinRef "@baseboard_fab2_lib.baseboard_fab2(sch_1):page23_i172:DDR0_DQ(41)" )
				( pinRef "@baseboard_fab2_lib.baseboard_fab2(sch_1):page43_i1:DQ(40)" )
				( attribute "RELATIVE_PROPAGATION_DELAY_SCOPE" "G"
					( Parent
						( matchGroupRef "@baseboard_fab2_lib.baseboard_fab2(sch_1):\MG_DQ-DQS_FAR_DIMM_NG_M_A_BYTE5\" )
					)
					( Status sCSetFlattened )
					( Origin gBackEnd )
				)
				( attribute "RELATIVE_PROPAGATION_DELAY" "0.00 MIL,195.00 MIL"
					( Parent
						( matchGroupRef "@baseboard_fab2_lib.baseboard_fab2(sch_1):\MG_DQ-DQS_FAR_DIMM_NG_M_A_BYTE5\" )
					)
					( Units "uMatchProp" "ns" 1.000000)
					( Status sCSetFlattened )
					( Origin gBackEnd )
				)
				( attribute "RELATIVE_PROPAGATION_DELAY_SCOPE" "G"
					( Parent
						( matchGroupRef "@crescent_city_bb_fab1_lib.crescent_city_bb_fab1(sch_1):\MG_DQ_FAR_DIMM_NG_M_A_BYTE5\" )
					)
					( Status sCSetFlattened )
					( Origin gBackEnd )
				)
				( attribute "RELATIVE_PROPAGATION_DELAY" "-50.00 MIL,50.00 MIL"
					( Parent
						( matchGroupRef "@crescent_city_bb_fab1_lib.crescent_city_bb_fab1(sch_1):\MG_DQ_FAR_DIMM_NG_M_A_BYTE5\" )
					)
					( Units "uMatchProp" "ns" 1.000000)
					( Status sCSetFlattened )
					( Origin gBackEnd )
				)
			)
			( pinPair "@baseboard_fab2_lib.baseboard_fab2(sch_1):\PP5228\"
				( pinRef "@baseboard_fab2_lib.baseboard_fab2(sch_1):page23_i172:DDR0_DQ(41)" )
				( pinRef "@baseboard_fab2_lib.baseboard_fab2(sch_1):page44_i13:DQ(41)" )
				( attribute "RELATIVE_PROPAGATION_DELAY_SCOPE" "G"
					( Parent
						( matchGroupRef "@baseboard_fab2_lib.baseboard_fab2(sch_1):\MG_DQ-DQS_NEAR_DIMM_NG_M_A_BYTE5\" )
					)
					( Status sCSetFlattened )
					( Origin gBackEnd )
				)
				( attribute "RELATIVE_PROPAGATION_DELAY" "0.00 MIL,195.00 MIL"
					( Parent
						( matchGroupRef "@baseboard_fab2_lib.baseboard_fab2(sch_1):\MG_DQ-DQS_NEAR_DIMM_NG_M_A_BYTE5\" )
					)
					( Units "uMatchProp" "ns" 1.000000)
					( Status sCSetFlattened )
					( Origin gBackEnd )
				)
				( attribute "RELATIVE_PROPAGATION_DELAY_SCOPE" "G"
					( Parent
						( matchGroupRef "@crescent_city_bb_fab1_lib.crescent_city_bb_fab1(sch_1):\MG_DQ_NEAR_DIMM_NG_M_A_BYTE5\" )
					)
					( Status sCSetFlattened )
					( Origin gBackEnd )
				)
				( attribute "RELATIVE_PROPAGATION_DELAY" "-50.00 MIL,50.00 MIL"
					( Parent
						( matchGroupRef "@crescent_city_bb_fab1_lib.crescent_city_bb_fab1(sch_1):\MG_DQ_NEAR_DIMM_NG_M_A_BYTE5\" )
					)
					( Units "uMatchProp" "ns" 1.000000)
					( Status sCSetFlattened )
					( Origin gBackEnd )
				)
			)
			( pinPair "@baseboard_fab2_lib.baseboard_fab2(sch_1):\PP5229\"
				( pinRef "@baseboard_fab2_lib.baseboard_fab2(sch_1):page23_i172:DDR0_DQ(42)" )
				( pinRef "@baseboard_fab2_lib.baseboard_fab2(sch_1):page43_i1:DQ(43)" )
				( attribute "RELATIVE_PROPAGATION_DELAY_SCOPE" "G"
					( Parent
						( matchGroupRef "@baseboard_fab2_lib.baseboard_fab2(sch_1):\MG_DQ-DQS_FAR_DIMM_NG_M_A_BYTE5\" )
					)
					( Status sCSetFlattened )
					( Origin gBackEnd )
				)
				( attribute "RELATIVE_PROPAGATION_DELAY" "0.00 MIL,195.00 MIL"
					( Parent
						( matchGroupRef "@baseboard_fab2_lib.baseboard_fab2(sch_1):\MG_DQ-DQS_FAR_DIMM_NG_M_A_BYTE5\" )
					)
					( Units "uMatchProp" "ns" 1.000000)
					( Status sCSetFlattened )
					( Origin gBackEnd )
				)
				( attribute "RELATIVE_PROPAGATION_DELAY_SCOPE" "G"
					( Parent
						( matchGroupRef "@crescent_city_bb_fab1_lib.crescent_city_bb_fab1(sch_1):\MG_DQ_FAR_DIMM_NG_M_A_BYTE5\" )
					)
					( Status sCSetFlattened )
					( Origin gBackEnd )
				)
				( attribute "RELATIVE_PROPAGATION_DELAY" "-50.00 MIL,50.00 MIL"
					( Parent
						( matchGroupRef "@crescent_city_bb_fab1_lib.crescent_city_bb_fab1(sch_1):\MG_DQ_FAR_DIMM_NG_M_A_BYTE5\" )
					)
					( Units "uMatchProp" "ns" 1.000000)
					( Status sCSetFlattened )
					( Origin gBackEnd )
				)
			)
			( pinPair "@baseboard_fab2_lib.baseboard_fab2(sch_1):\PP5231\"
				( pinRef "@baseboard_fab2_lib.baseboard_fab2(sch_1):page23_i172:DDR0_DQ(42)" )
				( pinRef "@baseboard_fab2_lib.baseboard_fab2(sch_1):page44_i13:DQ(42)" )
				( attribute "RELATIVE_PROPAGATION_DELAY_SCOPE" "G"
					( Parent
						( matchGroupRef "@baseboard_fab2_lib.baseboard_fab2(sch_1):\MG_DQ-DQS_NEAR_DIMM_NG_M_A_BYTE5\" )
					)
					( Status sCSetFlattened )
					( Origin gBackEnd )
				)
				( attribute "RELATIVE_PROPAGATION_DELAY" "0.00 MIL,195.00 MIL"
					( Parent
						( matchGroupRef "@baseboard_fab2_lib.baseboard_fab2(sch_1):\MG_DQ-DQS_NEAR_DIMM_NG_M_A_BYTE5\" )
					)
					( Units "uMatchProp" "ns" 1.000000)
					( Status sCSetFlattened )
					( Origin gBackEnd )
				)
				( attribute "RELATIVE_PROPAGATION_DELAY_SCOPE" "G"
					( Parent
						( matchGroupRef "@crescent_city_bb_fab1_lib.crescent_city_bb_fab1(sch_1):\MG_DQ_NEAR_DIMM_NG_M_A_BYTE5\" )
					)
					( Status sCSetFlattened )
					( Origin gBackEnd )
				)
				( attribute "RELATIVE_PROPAGATION_DELAY" "-50.00 MIL,50.00 MIL"
					( Parent
						( matchGroupRef "@crescent_city_bb_fab1_lib.crescent_city_bb_fab1(sch_1):\MG_DQ_NEAR_DIMM_NG_M_A_BYTE5\" )
					)
					( Units "uMatchProp" "ns" 1.000000)
					( Status sCSetFlattened )
					( Origin gBackEnd )
				)
			)
			( pinPair "@baseboard_fab2_lib.baseboard_fab2(sch_1):\PP5232\"
				( pinRef "@baseboard_fab2_lib.baseboard_fab2(sch_1):page23_i172:DDR0_DQ(43)" )
				( pinRef "@baseboard_fab2_lib.baseboard_fab2(sch_1):page43_i1:DQ(42)" )
				( attribute "RELATIVE_PROPAGATION_DELAY_SCOPE" "G"
					( Parent
						( matchGroupRef "@baseboard_fab2_lib.baseboard_fab2(sch_1):\MG_DQ-DQS_FAR_DIMM_NG_M_A_BYTE5\" )
					)
					( Status sCSetFlattened )
					( Origin gBackEnd )
				)
				( attribute "RELATIVE_PROPAGATION_DELAY" "0.00 MIL,195.00 MIL"
					( Parent
						( matchGroupRef "@baseboard_fab2_lib.baseboard_fab2(sch_1):\MG_DQ-DQS_FAR_DIMM_NG_M_A_BYTE5\" )
					)
					( Units "uMatchProp" "ns" 1.000000)
					( Status sCSetFlattened )
					( Origin gBackEnd )
				)
				( attribute "RELATIVE_PROPAGATION_DELAY_SCOPE" "G"
					( Parent
						( matchGroupRef "@crescent_city_bb_fab1_lib.crescent_city_bb_fab1(sch_1):\MG_DQ_FAR_DIMM_NG_M_A_BYTE5\" )
					)
					( Status sCSetFlattened )
					( Origin gBackEnd )
				)
				( attribute "RELATIVE_PROPAGATION_DELAY" "-50.00 MIL,50.00 MIL"
					( Parent
						( matchGroupRef "@crescent_city_bb_fab1_lib.crescent_city_bb_fab1(sch_1):\MG_DQ_FAR_DIMM_NG_M_A_BYTE5\" )
					)
					( Units "uMatchProp" "ns" 1.000000)
					( Status sCSetFlattened )
					( Origin gBackEnd )
				)
			)
			( pinPair "@baseboard_fab2_lib.baseboard_fab2(sch_1):\PP5234\"
				( pinRef "@baseboard_fab2_lib.baseboard_fab2(sch_1):page23_i172:DDR0_DQ(43)" )
				( pinRef "@baseboard_fab2_lib.baseboard_fab2(sch_1):page44_i13:DQ(43)" )
				( attribute "RELATIVE_PROPAGATION_DELAY_SCOPE" "G"
					( Parent
						( matchGroupRef "@baseboard_fab2_lib.baseboard_fab2(sch_1):\MG_DQ-DQS_NEAR_DIMM_NG_M_A_BYTE5\" )
					)
					( Status sCSetFlattened )
					( Origin gBackEnd )
				)
				( attribute "RELATIVE_PROPAGATION_DELAY" "0.00 MIL,195.00 MIL"
					( Parent
						( matchGroupRef "@baseboard_fab2_lib.baseboard_fab2(sch_1):\MG_DQ-DQS_NEAR_DIMM_NG_M_A_BYTE5\" )
					)
					( Units "uMatchProp" "ns" 1.000000)
					( Status sCSetFlattened )
					( Origin gBackEnd )
				)
				( attribute "RELATIVE_PROPAGATION_DELAY_SCOPE" "G"
					( Parent
						( matchGroupRef "@crescent_city_bb_fab1_lib.crescent_city_bb_fab1(sch_1):\MG_DQ_NEAR_DIMM_NG_M_A_BYTE5\" )
					)
					( Status sCSetFlattened )
					( Origin gBackEnd )
				)
				( attribute "RELATIVE_PROPAGATION_DELAY" "-50.00 MIL,50.00 MIL"
					( Parent
						( matchGroupRef "@crescent_city_bb_fab1_lib.crescent_city_bb_fab1(sch_1):\MG_DQ_NEAR_DIMM_NG_M_A_BYTE5\" )
					)
					( Units "uMatchProp" "ns" 1.000000)
					( Status sCSetFlattened )
					( Origin gBackEnd )
				)
			)
			( pinPair "@baseboard_fab2_lib.baseboard_fab2(sch_1):\PP5235\"
				( pinRef "@baseboard_fab2_lib.baseboard_fab2(sch_1):page23_i172:DDR0_DQ(44)" )
				( pinRef "@baseboard_fab2_lib.baseboard_fab2(sch_1):page43_i1:DQ(45)" )
				( attribute "RELATIVE_PROPAGATION_DELAY_SCOPE" "G"
					( Parent
						( matchGroupRef "@baseboard_fab2_lib.baseboard_fab2(sch_1):\MG_DQ-DQS_FAR_DIMM_NG_M_A_BYTE5\" )
					)
					( Status sCSetFlattened )
					( Origin gBackEnd )
				)
				( attribute "RELATIVE_PROPAGATION_DELAY" "0.00 MIL,195.00 MIL"
					( Parent
						( matchGroupRef "@baseboard_fab2_lib.baseboard_fab2(sch_1):\MG_DQ-DQS_FAR_DIMM_NG_M_A_BYTE5\" )
					)
					( Units "uMatchProp" "ns" 1.000000)
					( Status sCSetFlattened )
					( Origin gBackEnd )
				)
				( attribute "RELATIVE_PROPAGATION_DELAY_SCOPE" "G"
					( Parent
						( matchGroupRef "@crescent_city_bb_fab1_lib.crescent_city_bb_fab1(sch_1):\MG_DQ_FAR_DIMM_NG_M_A_BYTE5\" )
					)
					( Status sCSetFlattened )
					( Origin gBackEnd )
				)
				( attribute "RELATIVE_PROPAGATION_DELAY" "-50.00 MIL,50.00 MIL"
					( Parent
						( matchGroupRef "@crescent_city_bb_fab1_lib.crescent_city_bb_fab1(sch_1):\MG_DQ_FAR_DIMM_NG_M_A_BYTE5\" )
					)
					( Units "uMatchProp" "ns" 1.000000)
					( Status sCSetFlattened )
					( Origin gBackEnd )
				)
			)
			( pinPair "@baseboard_fab2_lib.baseboard_fab2(sch_1):\PP5237\"
				( pinRef "@baseboard_fab2_lib.baseboard_fab2(sch_1):page23_i172:DDR0_DQ(44)" )
				( pinRef "@baseboard_fab2_lib.baseboard_fab2(sch_1):page44_i13:DQ(44)" )
				( attribute "RELATIVE_PROPAGATION_DELAY_SCOPE" "G"
					( Parent
						( matchGroupRef "@baseboard_fab2_lib.baseboard_fab2(sch_1):\MG_DQ-DQS_NEAR_DIMM_NG_M_A_BYTE5\" )
					)
					( Status sCSetFlattened )
					( Origin gBackEnd )
				)
				( attribute "RELATIVE_PROPAGATION_DELAY" "0.00 MIL,195.00 MIL"
					( Parent
						( matchGroupRef "@baseboard_fab2_lib.baseboard_fab2(sch_1):\MG_DQ-DQS_NEAR_DIMM_NG_M_A_BYTE5\" )
					)
					( Units "uMatchProp" "ns" 1.000000)
					( Status sCSetFlattened )
					( Origin gBackEnd )
				)
				( attribute "RELATIVE_PROPAGATION_DELAY_SCOPE" "G"
					( Parent
						( matchGroupRef "@crescent_city_bb_fab1_lib.crescent_city_bb_fab1(sch_1):\MG_DQ_NEAR_DIMM_NG_M_A_BYTE5\" )
					)
					( Status sCSetFlattened )
					( Origin gBackEnd )
				)
				( attribute "RELATIVE_PROPAGATION_DELAY" "-50.00 MIL,50.00 MIL"
					( Parent
						( matchGroupRef "@crescent_city_bb_fab1_lib.crescent_city_bb_fab1(sch_1):\MG_DQ_NEAR_DIMM_NG_M_A_BYTE5\" )
					)
					( Units "uMatchProp" "ns" 1.000000)
					( Status sCSetFlattened )
					( Origin gBackEnd )
				)
			)
			( pinPair "@baseboard_fab2_lib.baseboard_fab2(sch_1):\PP5238\"
				( pinRef "@baseboard_fab2_lib.baseboard_fab2(sch_1):page23_i172:DDR0_DQ(45)" )
				( pinRef "@baseboard_fab2_lib.baseboard_fab2(sch_1):page43_i1:DQ(44)" )
				( attribute "RELATIVE_PROPAGATION_DELAY_SCOPE" "G"
					( Parent
						( matchGroupRef "@baseboard_fab2_lib.baseboard_fab2(sch_1):\MG_DQ-DQS_FAR_DIMM_NG_M_A_BYTE5\" )
					)
					( Status sCSetFlattened )
					( Origin gBackEnd )
				)
				( attribute "RELATIVE_PROPAGATION_DELAY" "0.00 MIL,195.00 MIL"
					( Parent
						( matchGroupRef "@baseboard_fab2_lib.baseboard_fab2(sch_1):\MG_DQ-DQS_FAR_DIMM_NG_M_A_BYTE5\" )
					)
					( Units "uMatchProp" "ns" 1.000000)
					( Status sCSetFlattened )
					( Origin gBackEnd )
				)
				( attribute "RELATIVE_PROPAGATION_DELAY_SCOPE" "G"
					( Parent
						( matchGroupRef "@crescent_city_bb_fab1_lib.crescent_city_bb_fab1(sch_1):\MG_DQ_FAR_DIMM_NG_M_A_BYTE5\" )
					)
					( Status sCSetFlattened )
					( Origin gBackEnd )
				)
				( attribute "RELATIVE_PROPAGATION_DELAY" "-50.00 MIL,50.00 MIL"
					( Parent
						( matchGroupRef "@crescent_city_bb_fab1_lib.crescent_city_bb_fab1(sch_1):\MG_DQ_FAR_DIMM_NG_M_A_BYTE5\" )
					)
					( Units "uMatchProp" "ns" 1.000000)
					( Status sCSetFlattened )
					( Origin gBackEnd )
				)
			)
			( pinPair "@baseboard_fab2_lib.baseboard_fab2(sch_1):\PP5240\"
				( pinRef "@baseboard_fab2_lib.baseboard_fab2(sch_1):page23_i172:DDR0_DQ(45)" )
				( pinRef "@baseboard_fab2_lib.baseboard_fab2(sch_1):page44_i13:DQ(45)" )
				( attribute "RELATIVE_PROPAGATION_DELAY_SCOPE" "G"
					( Parent
						( matchGroupRef "@baseboard_fab2_lib.baseboard_fab2(sch_1):\MG_DQ-DQS_NEAR_DIMM_NG_M_A_BYTE5\" )
					)
					( Status sCSetFlattened )
					( Origin gBackEnd )
				)
				( attribute "RELATIVE_PROPAGATION_DELAY" "0.00 MIL,195.00 MIL"
					( Parent
						( matchGroupRef "@baseboard_fab2_lib.baseboard_fab2(sch_1):\MG_DQ-DQS_NEAR_DIMM_NG_M_A_BYTE5\" )
					)
					( Units "uMatchProp" "ns" 1.000000)
					( Status sCSetFlattened )
					( Origin gBackEnd )
				)
				( attribute "RELATIVE_PROPAGATION_DELAY_SCOPE" "G"
					( Parent
						( matchGroupRef "@crescent_city_bb_fab1_lib.crescent_city_bb_fab1(sch_1):\MG_DQ_NEAR_DIMM_NG_M_A_BYTE5\" )
					)
					( Status sCSetFlattened )
					( Origin gBackEnd )
				)
				( attribute "RELATIVE_PROPAGATION_DELAY" "-50.00 MIL,50.00 MIL"
					( Parent
						( matchGroupRef "@crescent_city_bb_fab1_lib.crescent_city_bb_fab1(sch_1):\MG_DQ_NEAR_DIMM_NG_M_A_BYTE5\" )
					)
					( Units "uMatchProp" "ns" 1.000000)
					( Status sCSetFlattened )
					( Origin gBackEnd )
				)
			)
			( pinPair "@baseboard_fab2_lib.baseboard_fab2(sch_1):\PP5241\"
				( pinRef "@baseboard_fab2_lib.baseboard_fab2(sch_1):page23_i172:DDR0_DQ(46)" )
				( pinRef "@baseboard_fab2_lib.baseboard_fab2(sch_1):page43_i1:DQ(47)" )
				( attribute "RELATIVE_PROPAGATION_DELAY_SCOPE" "G"
					( Parent
						( matchGroupRef "@baseboard_fab2_lib.baseboard_fab2(sch_1):\MG_DQ-DQS_FAR_DIMM_NG_M_A_BYTE5\" )
					)
					( Status sCSetFlattened )
					( Origin gBackEnd )
				)
				( attribute "RELATIVE_PROPAGATION_DELAY" "0.00 MIL,195.00 MIL"
					( Parent
						( matchGroupRef "@baseboard_fab2_lib.baseboard_fab2(sch_1):\MG_DQ-DQS_FAR_DIMM_NG_M_A_BYTE5\" )
					)
					( Units "uMatchProp" "ns" 1.000000)
					( Status sCSetFlattened )
					( Origin gBackEnd )
				)
				( attribute "RELATIVE_PROPAGATION_DELAY_SCOPE" "G"
					( Parent
						( matchGroupRef "@crescent_city_bb_fab1_lib.crescent_city_bb_fab1(sch_1):\MG_DQ_FAR_DIMM_NG_M_A_BYTE5\" )
					)
					( Status sCSetFlattened )
					( Origin gBackEnd )
				)
				( attribute "RELATIVE_PROPAGATION_DELAY" "-50.00 MIL,50.00 MIL"
					( Parent
						( matchGroupRef "@crescent_city_bb_fab1_lib.crescent_city_bb_fab1(sch_1):\MG_DQ_FAR_DIMM_NG_M_A_BYTE5\" )
					)
					( Units "uMatchProp" "ns" 1.000000)
					( Status sCSetFlattened )
					( Origin gBackEnd )
				)
			)
			( pinPair "@baseboard_fab2_lib.baseboard_fab2(sch_1):\PP5243\"
				( pinRef "@baseboard_fab2_lib.baseboard_fab2(sch_1):page23_i172:DDR0_DQ(46)" )
				( pinRef "@baseboard_fab2_lib.baseboard_fab2(sch_1):page44_i13:DQ(46)" )
				( attribute "RELATIVE_PROPAGATION_DELAY_SCOPE" "G"
					( Parent
						( matchGroupRef "@baseboard_fab2_lib.baseboard_fab2(sch_1):\MG_DQ-DQS_NEAR_DIMM_NG_M_A_BYTE5\" )
					)
					( Status sCSetFlattened )
					( Origin gBackEnd )
				)
				( attribute "RELATIVE_PROPAGATION_DELAY" "0.00 MIL,195.00 MIL"
					( Parent
						( matchGroupRef "@baseboard_fab2_lib.baseboard_fab2(sch_1):\MG_DQ-DQS_NEAR_DIMM_NG_M_A_BYTE5\" )
					)
					( Units "uMatchProp" "ns" 1.000000)
					( Status sCSetFlattened )
					( Origin gBackEnd )
				)
				( attribute "RELATIVE_PROPAGATION_DELAY_SCOPE" "G"
					( Parent
						( matchGroupRef "@crescent_city_bb_fab1_lib.crescent_city_bb_fab1(sch_1):\MG_DQ_NEAR_DIMM_NG_M_A_BYTE5\" )
					)
					( Status sCSetFlattened )
					( Origin gBackEnd )
				)
				( attribute "RELATIVE_PROPAGATION_DELAY" "-50.00 MIL,50.00 MIL"
					( Parent
						( matchGroupRef "@crescent_city_bb_fab1_lib.crescent_city_bb_fab1(sch_1):\MG_DQ_NEAR_DIMM_NG_M_A_BYTE5\" )
					)
					( Units "uMatchProp" "ns" 1.000000)
					( Status sCSetFlattened )
					( Origin gBackEnd )
				)
			)
			( pinPair "@baseboard_fab2_lib.baseboard_fab2(sch_1):\PP5244\"
				( pinRef "@baseboard_fab2_lib.baseboard_fab2(sch_1):page23_i172:DDR0_DQ(47)" )
				( pinRef "@baseboard_fab2_lib.baseboard_fab2(sch_1):page43_i1:DQ(46)" )
				( attribute "RELATIVE_PROPAGATION_DELAY_SCOPE" "G"
					( Parent
						( matchGroupRef "@baseboard_fab2_lib.baseboard_fab2(sch_1):\MG_DQ-DQS_FAR_DIMM_NG_M_A_BYTE5\" )
					)
					( Status sCSetFlattened )
					( Origin gBackEnd )
				)
				( attribute "RELATIVE_PROPAGATION_DELAY" "0.00 MIL,195.00 MIL"
					( Parent
						( matchGroupRef "@baseboard_fab2_lib.baseboard_fab2(sch_1):\MG_DQ-DQS_FAR_DIMM_NG_M_A_BYTE5\" )
					)
					( Units "uMatchProp" "ns" 1.000000)
					( Status sCSetFlattened )
					( Origin gBackEnd )
				)
				( attribute "RELATIVE_PROPAGATION_DELAY_SCOPE" "G"
					( Parent
						( matchGroupRef "@crescent_city_bb_fab1_lib.crescent_city_bb_fab1(sch_1):\MG_DQ_FAR_DIMM_NG_M_A_BYTE5\" )
					)
					( Origin gBackEnd )
				)
				( attribute "RELATIVE_PROPAGATION_DELAY" "TARGET,TARGET"
					( Parent
						( matchGroupRef "@crescent_city_bb_fab1_lib.crescent_city_bb_fab1(sch_1):\MG_DQ_FAR_DIMM_NG_M_A_BYTE5\" )
					)
					( Units "uMatchProp" "ns" 1.000000)
					( Origin gBackEnd )
				)
			)
			( pinPair "@baseboard_fab2_lib.baseboard_fab2(sch_1):\PP5246\"
				( pinRef "@baseboard_fab2_lib.baseboard_fab2(sch_1):page23_i172:DDR0_DQ(47)" )
				( pinRef "@baseboard_fab2_lib.baseboard_fab2(sch_1):page44_i13:DQ(47)" )
				( attribute "RELATIVE_PROPAGATION_DELAY_SCOPE" "G"
					( Parent
						( matchGroupRef "@baseboard_fab2_lib.baseboard_fab2(sch_1):\MG_DQ-DQS_NEAR_DIMM_NG_M_A_BYTE5\" )
					)
					( Status sCSetFlattened )
					( Origin gBackEnd )
				)
				( attribute "RELATIVE_PROPAGATION_DELAY" "0.00 MIL,195.00 MIL"
					( Parent
						( matchGroupRef "@baseboard_fab2_lib.baseboard_fab2(sch_1):\MG_DQ-DQS_NEAR_DIMM_NG_M_A_BYTE5\" )
					)
					( Units "uMatchProp" "ns" 1.000000)
					( Status sCSetFlattened )
					( Origin gBackEnd )
				)
				( attribute "RELATIVE_PROPAGATION_DELAY_SCOPE" "G"
					( Parent
						( matchGroupRef "@crescent_city_bb_fab1_lib.crescent_city_bb_fab1(sch_1):\MG_DQ_NEAR_DIMM_NG_M_A_BYTE5\" )
					)
					( Origin gBackEnd )
				)
				( attribute "RELATIVE_PROPAGATION_DELAY" "TARGET,TARGET"
					( Parent
						( matchGroupRef "@crescent_city_bb_fab1_lib.crescent_city_bb_fab1(sch_1):\MG_DQ_NEAR_DIMM_NG_M_A_BYTE5\" )
					)
					( Units "uMatchProp" "ns" 1.000000)
					( Origin gBackEnd )
				)
			)
			( pinPair "@baseboard_fab2_lib.baseboard_fab2(sch_1):\PP5199\"
				( pinRef "@baseboard_fab2_lib.baseboard_fab2(sch_1):page23_i172:DDR0_DQ(48)" )
				( pinRef "@baseboard_fab2_lib.baseboard_fab2(sch_1):page43_i1:DQ(49)" )
				( attribute "RELATIVE_PROPAGATION_DELAY_SCOPE" "G"
					( Parent
						( matchGroupRef "@baseboard_fab2_lib.baseboard_fab2(sch_1):\MG_DQ-DQS_FAR_DIMM_NG_M_A_BYTE6\" )
					)
					( Status sCSetFlattened )
					( Origin gBackEnd )
				)
				( attribute "RELATIVE_PROPAGATION_DELAY" "0.00 MIL,195.00 MIL"
					( Parent
						( matchGroupRef "@baseboard_fab2_lib.baseboard_fab2(sch_1):\MG_DQ-DQS_FAR_DIMM_NG_M_A_BYTE6\" )
					)
					( Units "uMatchProp" "ns" 1.000000)
					( Status sCSetFlattened )
					( Origin gBackEnd )
				)
				( attribute "RELATIVE_PROPAGATION_DELAY_SCOPE" "G"
					( Parent
						( matchGroupRef "@baseboard_fab2_lib.baseboard_fab2(sch_1):\MG_DQ_FAR_DIMM_NG_M_A_BYTE6\" )
					)
					( Status sCSetFlattened )
					( Origin gBackEnd )
				)
				( attribute "RELATIVE_PROPAGATION_DELAY" "-50.00 MIL,50.00 MIL"
					( Parent
						( matchGroupRef "@baseboard_fab2_lib.baseboard_fab2(sch_1):\MG_DQ_FAR_DIMM_NG_M_A_BYTE6\" )
					)
					( Units "uMatchProp" "ns" 1.000000)
					( Status sCSetFlattened )
					( Origin gBackEnd )
				)
			)
			( pinPair "@baseboard_fab2_lib.baseboard_fab2(sch_1):\PP5201\"
				( pinRef "@baseboard_fab2_lib.baseboard_fab2(sch_1):page23_i172:DDR0_DQ(48)" )
				( pinRef "@baseboard_fab2_lib.baseboard_fab2(sch_1):page44_i13:DQ(48)" )
				( attribute "RELATIVE_PROPAGATION_DELAY_SCOPE" "G"
					( Parent
						( matchGroupRef "@baseboard_fab2_lib.baseboard_fab2(sch_1):\MG_DQ-DQS_NEAR_DIMM_NG_M_A_BYTE6\" )
					)
					( Status sCSetFlattened )
					( Origin gBackEnd )
				)
				( attribute "RELATIVE_PROPAGATION_DELAY" "0.00 MIL,195.00 MIL"
					( Parent
						( matchGroupRef "@baseboard_fab2_lib.baseboard_fab2(sch_1):\MG_DQ-DQS_NEAR_DIMM_NG_M_A_BYTE6\" )
					)
					( Units "uMatchProp" "ns" 1.000000)
					( Status sCSetFlattened )
					( Origin gBackEnd )
				)
				( attribute "RELATIVE_PROPAGATION_DELAY_SCOPE" "G"
					( Parent
						( matchGroupRef "@baseboard_fab2_lib.baseboard_fab2(sch_1):\MG_DQ_NEAR_DIMM_NG_M_A_BYTE6\" )
					)
					( Status sCSetFlattened )
					( Origin gBackEnd )
				)
				( attribute "RELATIVE_PROPAGATION_DELAY" "-50.00 MIL,50.00 MIL"
					( Parent
						( matchGroupRef "@baseboard_fab2_lib.baseboard_fab2(sch_1):\MG_DQ_NEAR_DIMM_NG_M_A_BYTE6\" )
					)
					( Units "uMatchProp" "ns" 1.000000)
					( Status sCSetFlattened )
					( Origin gBackEnd )
				)
			)
			( pinPair "@baseboard_fab2_lib.baseboard_fab2(sch_1):\PP5202\"
				( pinRef "@baseboard_fab2_lib.baseboard_fab2(sch_1):page23_i172:DDR0_DQ(49)" )
				( pinRef "@baseboard_fab2_lib.baseboard_fab2(sch_1):page43_i1:DQ(48)" )
				( attribute "RELATIVE_PROPAGATION_DELAY_SCOPE" "G"
					( Parent
						( matchGroupRef "@baseboard_fab2_lib.baseboard_fab2(sch_1):\MG_DQ-DQS_FAR_DIMM_NG_M_A_BYTE6\" )
					)
					( Status sCSetFlattened )
					( Origin gBackEnd )
				)
				( attribute "RELATIVE_PROPAGATION_DELAY" "0.00 MIL,195.00 MIL"
					( Parent
						( matchGroupRef "@baseboard_fab2_lib.baseboard_fab2(sch_1):\MG_DQ-DQS_FAR_DIMM_NG_M_A_BYTE6\" )
					)
					( Units "uMatchProp" "ns" 1.000000)
					( Status sCSetFlattened )
					( Origin gBackEnd )
				)
				( attribute "RELATIVE_PROPAGATION_DELAY_SCOPE" "G"
					( Parent
						( matchGroupRef "@baseboard_fab2_lib.baseboard_fab2(sch_1):\MG_DQ_FAR_DIMM_NG_M_A_BYTE6\" )
					)
					( Status sCSetFlattened )
					( Origin gBackEnd )
				)
				( attribute "RELATIVE_PROPAGATION_DELAY" "-50.00 MIL,50.00 MIL"
					( Parent
						( matchGroupRef "@baseboard_fab2_lib.baseboard_fab2(sch_1):\MG_DQ_FAR_DIMM_NG_M_A_BYTE6\" )
					)
					( Units "uMatchProp" "ns" 1.000000)
					( Status sCSetFlattened )
					( Origin gBackEnd )
				)
			)
			( pinPair "@baseboard_fab2_lib.baseboard_fab2(sch_1):\PP5204\"
				( pinRef "@baseboard_fab2_lib.baseboard_fab2(sch_1):page23_i172:DDR0_DQ(49)" )
				( pinRef "@baseboard_fab2_lib.baseboard_fab2(sch_1):page44_i13:DQ(49)" )
				( attribute "RELATIVE_PROPAGATION_DELAY_SCOPE" "G"
					( Parent
						( matchGroupRef "@baseboard_fab2_lib.baseboard_fab2(sch_1):\MG_DQ-DQS_NEAR_DIMM_NG_M_A_BYTE6\" )
					)
					( Status sCSetFlattened )
					( Origin gBackEnd )
				)
				( attribute "RELATIVE_PROPAGATION_DELAY" "0.00 MIL,195.00 MIL"
					( Parent
						( matchGroupRef "@baseboard_fab2_lib.baseboard_fab2(sch_1):\MG_DQ-DQS_NEAR_DIMM_NG_M_A_BYTE6\" )
					)
					( Units "uMatchProp" "ns" 1.000000)
					( Status sCSetFlattened )
					( Origin gBackEnd )
				)
				( attribute "RELATIVE_PROPAGATION_DELAY_SCOPE" "G"
					( Parent
						( matchGroupRef "@baseboard_fab2_lib.baseboard_fab2(sch_1):\MG_DQ_NEAR_DIMM_NG_M_A_BYTE6\" )
					)
					( Status sCSetFlattened )
					( Origin gBackEnd )
				)
				( attribute "RELATIVE_PROPAGATION_DELAY" "-50.00 MIL,50.00 MIL"
					( Parent
						( matchGroupRef "@baseboard_fab2_lib.baseboard_fab2(sch_1):\MG_DQ_NEAR_DIMM_NG_M_A_BYTE6\" )
					)
					( Units "uMatchProp" "ns" 1.000000)
					( Status sCSetFlattened )
					( Origin gBackEnd )
				)
			)
			( pinPair "@baseboard_fab2_lib.baseboard_fab2(sch_1):\PP5205\"
				( pinRef "@baseboard_fab2_lib.baseboard_fab2(sch_1):page23_i172:DDR0_DQ(50)" )
				( pinRef "@baseboard_fab2_lib.baseboard_fab2(sch_1):page43_i1:DQ(51)" )
				( attribute "RELATIVE_PROPAGATION_DELAY_SCOPE" "G"
					( Parent
						( matchGroupRef "@baseboard_fab2_lib.baseboard_fab2(sch_1):\MG_DQ-DQS_FAR_DIMM_NG_M_A_BYTE6\" )
					)
					( Status sCSetFlattened )
					( Origin gBackEnd )
				)
				( attribute "RELATIVE_PROPAGATION_DELAY" "0.00 MIL,195.00 MIL"
					( Parent
						( matchGroupRef "@baseboard_fab2_lib.baseboard_fab2(sch_1):\MG_DQ-DQS_FAR_DIMM_NG_M_A_BYTE6\" )
					)
					( Units "uMatchProp" "ns" 1.000000)
					( Status sCSetFlattened )
					( Origin gBackEnd )
				)
				( attribute "RELATIVE_PROPAGATION_DELAY_SCOPE" "G"
					( Parent
						( matchGroupRef "@baseboard_fab2_lib.baseboard_fab2(sch_1):\MG_DQ_FAR_DIMM_NG_M_A_BYTE6\" )
					)
					( Status sCSetFlattened )
					( Origin gBackEnd )
				)
				( attribute "RELATIVE_PROPAGATION_DELAY" "-50.00 MIL,50.00 MIL"
					( Parent
						( matchGroupRef "@baseboard_fab2_lib.baseboard_fab2(sch_1):\MG_DQ_FAR_DIMM_NG_M_A_BYTE6\" )
					)
					( Units "uMatchProp" "ns" 1.000000)
					( Status sCSetFlattened )
					( Origin gBackEnd )
				)
			)
			( pinPair "@baseboard_fab2_lib.baseboard_fab2(sch_1):\PP5207\"
				( pinRef "@baseboard_fab2_lib.baseboard_fab2(sch_1):page23_i172:DDR0_DQ(50)" )
				( pinRef "@baseboard_fab2_lib.baseboard_fab2(sch_1):page44_i13:DQ(50)" )
				( attribute "RELATIVE_PROPAGATION_DELAY_SCOPE" "G"
					( Parent
						( matchGroupRef "@baseboard_fab2_lib.baseboard_fab2(sch_1):\MG_DQ-DQS_NEAR_DIMM_NG_M_A_BYTE6\" )
					)
					( Status sCSetFlattened )
					( Origin gBackEnd )
				)
				( attribute "RELATIVE_PROPAGATION_DELAY" "0.00 MIL,195.00 MIL"
					( Parent
						( matchGroupRef "@baseboard_fab2_lib.baseboard_fab2(sch_1):\MG_DQ-DQS_NEAR_DIMM_NG_M_A_BYTE6\" )
					)
					( Units "uMatchProp" "ns" 1.000000)
					( Status sCSetFlattened )
					( Origin gBackEnd )
				)
				( attribute "RELATIVE_PROPAGATION_DELAY_SCOPE" "G"
					( Parent
						( matchGroupRef "@baseboard_fab2_lib.baseboard_fab2(sch_1):\MG_DQ_NEAR_DIMM_NG_M_A_BYTE6\" )
					)
					( Status sCSetFlattened )
					( Origin gBackEnd )
				)
				( attribute "RELATIVE_PROPAGATION_DELAY" "-50.00 MIL,50.00 MIL"
					( Parent
						( matchGroupRef "@baseboard_fab2_lib.baseboard_fab2(sch_1):\MG_DQ_NEAR_DIMM_NG_M_A_BYTE6\" )
					)
					( Units "uMatchProp" "ns" 1.000000)
					( Status sCSetFlattened )
					( Origin gBackEnd )
				)
			)
			( pinPair "@baseboard_fab2_lib.baseboard_fab2(sch_1):\PP5208\"
				( pinRef "@baseboard_fab2_lib.baseboard_fab2(sch_1):page23_i172:DDR0_DQ(51)" )
				( pinRef "@baseboard_fab2_lib.baseboard_fab2(sch_1):page43_i1:DQ(50)" )
				( attribute "RELATIVE_PROPAGATION_DELAY_SCOPE" "G"
					( Parent
						( matchGroupRef "@baseboard_fab2_lib.baseboard_fab2(sch_1):\MG_DQ-DQS_FAR_DIMM_NG_M_A_BYTE6\" )
					)
					( Status sCSetFlattened )
					( Origin gBackEnd )
				)
				( attribute "RELATIVE_PROPAGATION_DELAY" "0.00 MIL,195.00 MIL"
					( Parent
						( matchGroupRef "@baseboard_fab2_lib.baseboard_fab2(sch_1):\MG_DQ-DQS_FAR_DIMM_NG_M_A_BYTE6\" )
					)
					( Units "uMatchProp" "ns" 1.000000)
					( Status sCSetFlattened )
					( Origin gBackEnd )
				)
				( attribute "RELATIVE_PROPAGATION_DELAY_SCOPE" "G"
					( Parent
						( matchGroupRef "@baseboard_fab2_lib.baseboard_fab2(sch_1):\MG_DQ_FAR_DIMM_NG_M_A_BYTE6\" )
					)
					( Status sCSetFlattened )
					( Origin gBackEnd )
				)
				( attribute "RELATIVE_PROPAGATION_DELAY" "-50.00 MIL,50.00 MIL"
					( Parent
						( matchGroupRef "@baseboard_fab2_lib.baseboard_fab2(sch_1):\MG_DQ_FAR_DIMM_NG_M_A_BYTE6\" )
					)
					( Units "uMatchProp" "ns" 1.000000)
					( Status sCSetFlattened )
					( Origin gBackEnd )
				)
			)
			( pinPair "@baseboard_fab2_lib.baseboard_fab2(sch_1):\PP5210\"
				( pinRef "@baseboard_fab2_lib.baseboard_fab2(sch_1):page23_i172:DDR0_DQ(51)" )
				( pinRef "@baseboard_fab2_lib.baseboard_fab2(sch_1):page44_i13:DQ(51)" )
				( attribute "RELATIVE_PROPAGATION_DELAY_SCOPE" "G"
					( Parent
						( matchGroupRef "@baseboard_fab2_lib.baseboard_fab2(sch_1):\MG_DQ-DQS_NEAR_DIMM_NG_M_A_BYTE6\" )
					)
					( Status sCSetFlattened )
					( Origin gBackEnd )
				)
				( attribute "RELATIVE_PROPAGATION_DELAY" "0.00 MIL,195.00 MIL"
					( Parent
						( matchGroupRef "@baseboard_fab2_lib.baseboard_fab2(sch_1):\MG_DQ-DQS_NEAR_DIMM_NG_M_A_BYTE6\" )
					)
					( Units "uMatchProp" "ns" 1.000000)
					( Status sCSetFlattened )
					( Origin gBackEnd )
				)
				( attribute "RELATIVE_PROPAGATION_DELAY_SCOPE" "G"
					( Parent
						( matchGroupRef "@baseboard_fab2_lib.baseboard_fab2(sch_1):\MG_DQ_NEAR_DIMM_NG_M_A_BYTE6\" )
					)
					( Status sCSetFlattened )
					( Origin gBackEnd )
				)
				( attribute "RELATIVE_PROPAGATION_DELAY" "-50.00 MIL,50.00 MIL"
					( Parent
						( matchGroupRef "@baseboard_fab2_lib.baseboard_fab2(sch_1):\MG_DQ_NEAR_DIMM_NG_M_A_BYTE6\" )
					)
					( Units "uMatchProp" "ns" 1.000000)
					( Status sCSetFlattened )
					( Origin gBackEnd )
				)
			)
			( pinPair "@baseboard_fab2_lib.baseboard_fab2(sch_1):\PP5211\"
				( pinRef "@baseboard_fab2_lib.baseboard_fab2(sch_1):page23_i172:DDR0_DQ(52)" )
				( pinRef "@baseboard_fab2_lib.baseboard_fab2(sch_1):page43_i1:DQ(53)" )
				( attribute "RELATIVE_PROPAGATION_DELAY_SCOPE" "G"
					( Parent
						( matchGroupRef "@baseboard_fab2_lib.baseboard_fab2(sch_1):\MG_DQ-DQS_FAR_DIMM_NG_M_A_BYTE6\" )
					)
					( Status sCSetFlattened )
					( Origin gBackEnd )
				)
				( attribute "RELATIVE_PROPAGATION_DELAY" "0.00 MIL,195.00 MIL"
					( Parent
						( matchGroupRef "@baseboard_fab2_lib.baseboard_fab2(sch_1):\MG_DQ-DQS_FAR_DIMM_NG_M_A_BYTE6\" )
					)
					( Units "uMatchProp" "ns" 1.000000)
					( Status sCSetFlattened )
					( Origin gBackEnd )
				)
				( attribute "RELATIVE_PROPAGATION_DELAY_SCOPE" "G"
					( Parent
						( matchGroupRef "@baseboard_fab2_lib.baseboard_fab2(sch_1):\MG_DQ_FAR_DIMM_NG_M_A_BYTE6\" )
					)
					( Status sCSetFlattened )
					( Origin gBackEnd )
				)
				( attribute "RELATIVE_PROPAGATION_DELAY" "-50.00 MIL,50.00 MIL"
					( Parent
						( matchGroupRef "@baseboard_fab2_lib.baseboard_fab2(sch_1):\MG_DQ_FAR_DIMM_NG_M_A_BYTE6\" )
					)
					( Units "uMatchProp" "ns" 1.000000)
					( Status sCSetFlattened )
					( Origin gBackEnd )
				)
			)
			( pinPair "@baseboard_fab2_lib.baseboard_fab2(sch_1):\PP5213\"
				( pinRef "@baseboard_fab2_lib.baseboard_fab2(sch_1):page23_i172:DDR0_DQ(52)" )
				( pinRef "@baseboard_fab2_lib.baseboard_fab2(sch_1):page44_i13:DQ(52)" )
				( attribute "RELATIVE_PROPAGATION_DELAY_SCOPE" "G"
					( Parent
						( matchGroupRef "@baseboard_fab2_lib.baseboard_fab2(sch_1):\MG_DQ-DQS_NEAR_DIMM_NG_M_A_BYTE6\" )
					)
					( Status sCSetFlattened )
					( Origin gBackEnd )
				)
				( attribute "RELATIVE_PROPAGATION_DELAY" "0.00 MIL,195.00 MIL"
					( Parent
						( matchGroupRef "@baseboard_fab2_lib.baseboard_fab2(sch_1):\MG_DQ-DQS_NEAR_DIMM_NG_M_A_BYTE6\" )
					)
					( Units "uMatchProp" "ns" 1.000000)
					( Status sCSetFlattened )
					( Origin gBackEnd )
				)
				( attribute "RELATIVE_PROPAGATION_DELAY_SCOPE" "G"
					( Parent
						( matchGroupRef "@baseboard_fab2_lib.baseboard_fab2(sch_1):\MG_DQ_NEAR_DIMM_NG_M_A_BYTE6\" )
					)
					( Status sCSetFlattened )
					( Origin gBackEnd )
				)
				( attribute "RELATIVE_PROPAGATION_DELAY" "-50.00 MIL,50.00 MIL"
					( Parent
						( matchGroupRef "@baseboard_fab2_lib.baseboard_fab2(sch_1):\MG_DQ_NEAR_DIMM_NG_M_A_BYTE6\" )
					)
					( Units "uMatchProp" "ns" 1.000000)
					( Status sCSetFlattened )
					( Origin gBackEnd )
				)
			)
			( pinPair "@baseboard_fab2_lib.baseboard_fab2(sch_1):\PP5214\"
				( pinRef "@baseboard_fab2_lib.baseboard_fab2(sch_1):page23_i172:DDR0_DQ(53)" )
				( pinRef "@baseboard_fab2_lib.baseboard_fab2(sch_1):page43_i1:DQ(52)" )
				( attribute "RELATIVE_PROPAGATION_DELAY_SCOPE" "G"
					( Parent
						( matchGroupRef "@baseboard_fab2_lib.baseboard_fab2(sch_1):\MG_DQ-DQS_FAR_DIMM_NG_M_A_BYTE6\" )
					)
					( Status sCSetFlattened )
					( Origin gBackEnd )
				)
				( attribute "RELATIVE_PROPAGATION_DELAY" "0.00 MIL,195.00 MIL"
					( Parent
						( matchGroupRef "@baseboard_fab2_lib.baseboard_fab2(sch_1):\MG_DQ-DQS_FAR_DIMM_NG_M_A_BYTE6\" )
					)
					( Units "uMatchProp" "ns" 1.000000)
					( Status sCSetFlattened )
					( Origin gBackEnd )
				)
				( attribute "RELATIVE_PROPAGATION_DELAY_SCOPE" "G"
					( Parent
						( matchGroupRef "@baseboard_fab2_lib.baseboard_fab2(sch_1):\MG_DQ_FAR_DIMM_NG_M_A_BYTE6\" )
					)
					( Status sCSetFlattened )
					( Origin gBackEnd )
				)
				( attribute "RELATIVE_PROPAGATION_DELAY" "-50.00 MIL,50.00 MIL"
					( Parent
						( matchGroupRef "@baseboard_fab2_lib.baseboard_fab2(sch_1):\MG_DQ_FAR_DIMM_NG_M_A_BYTE6\" )
					)
					( Units "uMatchProp" "ns" 1.000000)
					( Status sCSetFlattened )
					( Origin gBackEnd )
				)
			)
			( pinPair "@baseboard_fab2_lib.baseboard_fab2(sch_1):\PP5216\"
				( pinRef "@baseboard_fab2_lib.baseboard_fab2(sch_1):page23_i172:DDR0_DQ(53)" )
				( pinRef "@baseboard_fab2_lib.baseboard_fab2(sch_1):page44_i13:DQ(53)" )
				( attribute "RELATIVE_PROPAGATION_DELAY_SCOPE" "G"
					( Parent
						( matchGroupRef "@baseboard_fab2_lib.baseboard_fab2(sch_1):\MG_DQ-DQS_NEAR_DIMM_NG_M_A_BYTE6\" )
					)
					( Status sCSetFlattened )
					( Origin gBackEnd )
				)
				( attribute "RELATIVE_PROPAGATION_DELAY" "0.00 MIL,195.00 MIL"
					( Parent
						( matchGroupRef "@baseboard_fab2_lib.baseboard_fab2(sch_1):\MG_DQ-DQS_NEAR_DIMM_NG_M_A_BYTE6\" )
					)
					( Units "uMatchProp" "ns" 1.000000)
					( Status sCSetFlattened )
					( Origin gBackEnd )
				)
				( attribute "RELATIVE_PROPAGATION_DELAY_SCOPE" "G"
					( Parent
						( matchGroupRef "@baseboard_fab2_lib.baseboard_fab2(sch_1):\MG_DQ_NEAR_DIMM_NG_M_A_BYTE6\" )
					)
					( Status sCSetFlattened )
					( Origin gBackEnd )
				)
				( attribute "RELATIVE_PROPAGATION_DELAY" "-50.00 MIL,50.00 MIL"
					( Parent
						( matchGroupRef "@baseboard_fab2_lib.baseboard_fab2(sch_1):\MG_DQ_NEAR_DIMM_NG_M_A_BYTE6\" )
					)
					( Units "uMatchProp" "ns" 1.000000)
					( Status sCSetFlattened )
					( Origin gBackEnd )
				)
			)
			( pinPair "@baseboard_fab2_lib.baseboard_fab2(sch_1):\PP5217\"
				( pinRef "@baseboard_fab2_lib.baseboard_fab2(sch_1):page23_i172:DDR0_DQ(54)" )
				( pinRef "@baseboard_fab2_lib.baseboard_fab2(sch_1):page43_i1:DQ(55)" )
				( attribute "RELATIVE_PROPAGATION_DELAY_SCOPE" "G"
					( Parent
						( matchGroupRef "@baseboard_fab2_lib.baseboard_fab2(sch_1):\MG_DQ-DQS_FAR_DIMM_NG_M_A_BYTE6\" )
					)
					( Status sCSetFlattened )
					( Origin gBackEnd )
				)
				( attribute "RELATIVE_PROPAGATION_DELAY" "0.00 MIL,195.00 MIL"
					( Parent
						( matchGroupRef "@baseboard_fab2_lib.baseboard_fab2(sch_1):\MG_DQ-DQS_FAR_DIMM_NG_M_A_BYTE6\" )
					)
					( Units "uMatchProp" "ns" 1.000000)
					( Status sCSetFlattened )
					( Origin gBackEnd )
				)
				( attribute "RELATIVE_PROPAGATION_DELAY_SCOPE" "G"
					( Parent
						( matchGroupRef "@baseboard_fab2_lib.baseboard_fab2(sch_1):\MG_DQ_FAR_DIMM_NG_M_A_BYTE6\" )
					)
					( Status sCSetFlattened )
					( Origin gBackEnd )
				)
				( attribute "RELATIVE_PROPAGATION_DELAY" "-50.00 MIL,50.00 MIL"
					( Parent
						( matchGroupRef "@baseboard_fab2_lib.baseboard_fab2(sch_1):\MG_DQ_FAR_DIMM_NG_M_A_BYTE6\" )
					)
					( Units "uMatchProp" "ns" 1.000000)
					( Status sCSetFlattened )
					( Origin gBackEnd )
				)
			)
			( pinPair "@baseboard_fab2_lib.baseboard_fab2(sch_1):\PP5219\"
				( pinRef "@baseboard_fab2_lib.baseboard_fab2(sch_1):page23_i172:DDR0_DQ(54)" )
				( pinRef "@baseboard_fab2_lib.baseboard_fab2(sch_1):page44_i13:DQ(54)" )
				( attribute "RELATIVE_PROPAGATION_DELAY_SCOPE" "G"
					( Parent
						( matchGroupRef "@baseboard_fab2_lib.baseboard_fab2(sch_1):\MG_DQ-DQS_NEAR_DIMM_NG_M_A_BYTE6\" )
					)
					( Status sCSetFlattened )
					( Origin gBackEnd )
				)
				( attribute "RELATIVE_PROPAGATION_DELAY" "0.00 MIL,195.00 MIL"
					( Parent
						( matchGroupRef "@baseboard_fab2_lib.baseboard_fab2(sch_1):\MG_DQ-DQS_NEAR_DIMM_NG_M_A_BYTE6\" )
					)
					( Units "uMatchProp" "ns" 1.000000)
					( Status sCSetFlattened )
					( Origin gBackEnd )
				)
				( attribute "RELATIVE_PROPAGATION_DELAY_SCOPE" "G"
					( Parent
						( matchGroupRef "@baseboard_fab2_lib.baseboard_fab2(sch_1):\MG_DQ_NEAR_DIMM_NG_M_A_BYTE6\" )
					)
					( Status sCSetFlattened )
					( Origin gBackEnd )
				)
				( attribute "RELATIVE_PROPAGATION_DELAY" "-50.00 MIL,50.00 MIL"
					( Parent
						( matchGroupRef "@baseboard_fab2_lib.baseboard_fab2(sch_1):\MG_DQ_NEAR_DIMM_NG_M_A_BYTE6\" )
					)
					( Units "uMatchProp" "ns" 1.000000)
					( Status sCSetFlattened )
					( Origin gBackEnd )
				)
			)
			( pinPair "@baseboard_fab2_lib.baseboard_fab2(sch_1):\PP5220\"
				( pinRef "@baseboard_fab2_lib.baseboard_fab2(sch_1):page23_i172:DDR0_DQ(55)" )
				( pinRef "@baseboard_fab2_lib.baseboard_fab2(sch_1):page43_i1:DQ(54)" )
				( attribute "RELATIVE_PROPAGATION_DELAY_SCOPE" "G"
					( Parent
						( matchGroupRef "@baseboard_fab2_lib.baseboard_fab2(sch_1):\MG_DQ-DQS_FAR_DIMM_NG_M_A_BYTE6\" )
					)
					( Status sCSetFlattened )
					( Origin gBackEnd )
				)
				( attribute "RELATIVE_PROPAGATION_DELAY" "0.00 MIL,195.00 MIL"
					( Parent
						( matchGroupRef "@baseboard_fab2_lib.baseboard_fab2(sch_1):\MG_DQ-DQS_FAR_DIMM_NG_M_A_BYTE6\" )
					)
					( Units "uMatchProp" "ns" 1.000000)
					( Status sCSetFlattened )
					( Origin gBackEnd )
				)
				( attribute "RELATIVE_PROPAGATION_DELAY_SCOPE" "G"
					( Parent
						( matchGroupRef "@baseboard_fab2_lib.baseboard_fab2(sch_1):\MG_DQ_FAR_DIMM_NG_M_A_BYTE6\" )
					)
					( Status sCSetFlattened )
					( Origin gBackEnd )
				)
				( attribute "RELATIVE_PROPAGATION_DELAY" "-50.00 MIL,50.00 MIL"
					( Parent
						( matchGroupRef "@baseboard_fab2_lib.baseboard_fab2(sch_1):\MG_DQ_FAR_DIMM_NG_M_A_BYTE6\" )
					)
					( Units "uMatchProp" "ns" 1.000000)
					( Status sCSetFlattened )
					( Origin gBackEnd )
				)
			)
			( pinPair "@baseboard_fab2_lib.baseboard_fab2(sch_1):\PP5222\"
				( pinRef "@baseboard_fab2_lib.baseboard_fab2(sch_1):page23_i172:DDR0_DQ(55)" )
				( pinRef "@baseboard_fab2_lib.baseboard_fab2(sch_1):page44_i13:DQ(55)" )
				( attribute "RELATIVE_PROPAGATION_DELAY_SCOPE" "G"
					( Parent
						( matchGroupRef "@baseboard_fab2_lib.baseboard_fab2(sch_1):\MG_DQ-DQS_NEAR_DIMM_NG_M_A_BYTE6\" )
					)
					( Status sCSetFlattened )
					( Origin gBackEnd )
				)
				( attribute "RELATIVE_PROPAGATION_DELAY" "0.00 MIL,195.00 MIL"
					( Parent
						( matchGroupRef "@baseboard_fab2_lib.baseboard_fab2(sch_1):\MG_DQ-DQS_NEAR_DIMM_NG_M_A_BYTE6\" )
					)
					( Units "uMatchProp" "ns" 1.000000)
					( Status sCSetFlattened )
					( Origin gBackEnd )
				)
				( attribute "RELATIVE_PROPAGATION_DELAY_SCOPE" "G"
					( Parent
						( matchGroupRef "@baseboard_fab2_lib.baseboard_fab2(sch_1):\MG_DQ_NEAR_DIMM_NG_M_A_BYTE6\" )
					)
					( Status sCSetFlattened )
					( Origin gBackEnd )
				)
				( attribute "RELATIVE_PROPAGATION_DELAY" "-50.00 MIL,50.00 MIL"
					( Parent
						( matchGroupRef "@baseboard_fab2_lib.baseboard_fab2(sch_1):\MG_DQ_NEAR_DIMM_NG_M_A_BYTE6\" )
					)
					( Units "uMatchProp" "ns" 1.000000)
					( Status sCSetFlattened )
					( Origin gBackEnd )
				)
			)
			( pinPair "@baseboard_fab2_lib.baseboard_fab2(sch_1):\PP5163\"
				( pinRef "@baseboard_fab2_lib.baseboard_fab2(sch_1):page23_i172:DDR0_DQ(56)" )
				( pinRef "@baseboard_fab2_lib.baseboard_fab2(sch_1):page43_i1:DQ(57)" )
				( attribute "RELATIVE_PROPAGATION_DELAY_SCOPE" "G"
					( Parent
						( matchGroupRef "@baseboard_fab2_lib.baseboard_fab2(sch_1):\MG_DQ-DQS_FAR_DIMM_NG_M_A_BYTE7\" )
					)
					( Status sCSetFlattened )
					( Origin gBackEnd )
				)
				( attribute "RELATIVE_PROPAGATION_DELAY" "0.00 MIL,195.00 MIL"
					( Parent
						( matchGroupRef "@baseboard_fab2_lib.baseboard_fab2(sch_1):\MG_DQ-DQS_FAR_DIMM_NG_M_A_BYTE7\" )
					)
					( Units "uMatchProp" "ns" 1.000000)
					( Status sCSetFlattened )
					( Origin gBackEnd )
				)
				( attribute "RELATIVE_PROPAGATION_DELAY_SCOPE" "G"
					( Parent
						( matchGroupRef "@baseboard_fab2_lib.baseboard_fab2(sch_1):\MG_DQ_FAR_DIMM_NG_M_A_BYTE7\" )
					)
					( Status sCSetFlattened )
					( Origin gBackEnd )
				)
				( attribute "RELATIVE_PROPAGATION_DELAY" "-50.00 MIL,50.00 MIL"
					( Parent
						( matchGroupRef "@baseboard_fab2_lib.baseboard_fab2(sch_1):\MG_DQ_FAR_DIMM_NG_M_A_BYTE7\" )
					)
					( Units "uMatchProp" "ns" 1.000000)
					( Status sCSetFlattened )
					( Origin gBackEnd )
				)
			)
			( pinPair "@baseboard_fab2_lib.baseboard_fab2(sch_1):\PP5165\"
				( pinRef "@baseboard_fab2_lib.baseboard_fab2(sch_1):page23_i172:DDR0_DQ(56)" )
				( pinRef "@baseboard_fab2_lib.baseboard_fab2(sch_1):page44_i13:DQ(56)" )
				( attribute "RELATIVE_PROPAGATION_DELAY_SCOPE" "G"
					( Parent
						( matchGroupRef "@baseboard_fab2_lib.baseboard_fab2(sch_1):\MG_DQ-DQS_NEAR_DIMM_NG_M_A_BYTE7\" )
					)
					( Status sCSetFlattened )
					( Origin gBackEnd )
				)
				( attribute "RELATIVE_PROPAGATION_DELAY" "0.00 MIL,195.00 MIL"
					( Parent
						( matchGroupRef "@baseboard_fab2_lib.baseboard_fab2(sch_1):\MG_DQ-DQS_NEAR_DIMM_NG_M_A_BYTE7\" )
					)
					( Units "uMatchProp" "ns" 1.000000)
					( Status sCSetFlattened )
					( Origin gBackEnd )
				)
				( attribute "RELATIVE_PROPAGATION_DELAY_SCOPE" "G"
					( Parent
						( matchGroupRef "@baseboard_fab2_lib.baseboard_fab2(sch_1):\MG_DQ_NEAR_DIMM_NG_M_A_BYTE7\" )
					)
					( Status sCSetFlattened )
					( Origin gBackEnd )
				)
				( attribute "RELATIVE_PROPAGATION_DELAY" "-50.00 MIL,50.00 MIL"
					( Parent
						( matchGroupRef "@baseboard_fab2_lib.baseboard_fab2(sch_1):\MG_DQ_NEAR_DIMM_NG_M_A_BYTE7\" )
					)
					( Units "uMatchProp" "ns" 1.000000)
					( Status sCSetFlattened )
					( Origin gBackEnd )
				)
			)
			( pinPair "@baseboard_fab2_lib.baseboard_fab2(sch_1):\PP5166\"
				( pinRef "@baseboard_fab2_lib.baseboard_fab2(sch_1):page23_i172:DDR0_DQ(57)" )
				( pinRef "@baseboard_fab2_lib.baseboard_fab2(sch_1):page43_i1:DQ(56)" )
				( attribute "RELATIVE_PROPAGATION_DELAY_SCOPE" "G"
					( Parent
						( matchGroupRef "@baseboard_fab2_lib.baseboard_fab2(sch_1):\MG_DQ-DQS_FAR_DIMM_NG_M_A_BYTE7\" )
					)
					( Status sCSetFlattened )
					( Origin gBackEnd )
				)
				( attribute "RELATIVE_PROPAGATION_DELAY" "0.00 MIL,195.00 MIL"
					( Parent
						( matchGroupRef "@baseboard_fab2_lib.baseboard_fab2(sch_1):\MG_DQ-DQS_FAR_DIMM_NG_M_A_BYTE7\" )
					)
					( Units "uMatchProp" "ns" 1.000000)
					( Status sCSetFlattened )
					( Origin gBackEnd )
				)
				( attribute "RELATIVE_PROPAGATION_DELAY_SCOPE" "G"
					( Parent
						( matchGroupRef "@baseboard_fab2_lib.baseboard_fab2(sch_1):\MG_DQ_FAR_DIMM_NG_M_A_BYTE7\" )
					)
					( Status sCSetFlattened )
					( Origin gBackEnd )
				)
				( attribute "RELATIVE_PROPAGATION_DELAY" "-50.00 MIL,50.00 MIL"
					( Parent
						( matchGroupRef "@baseboard_fab2_lib.baseboard_fab2(sch_1):\MG_DQ_FAR_DIMM_NG_M_A_BYTE7\" )
					)
					( Units "uMatchProp" "ns" 1.000000)
					( Status sCSetFlattened )
					( Origin gBackEnd )
				)
			)
			( pinPair "@baseboard_fab2_lib.baseboard_fab2(sch_1):\PP5168\"
				( pinRef "@baseboard_fab2_lib.baseboard_fab2(sch_1):page23_i172:DDR0_DQ(57)" )
				( pinRef "@baseboard_fab2_lib.baseboard_fab2(sch_1):page44_i13:DQ(57)" )
				( attribute "RELATIVE_PROPAGATION_DELAY_SCOPE" "G"
					( Parent
						( matchGroupRef "@baseboard_fab2_lib.baseboard_fab2(sch_1):\MG_DQ-DQS_NEAR_DIMM_NG_M_A_BYTE7\" )
					)
					( Status sCSetFlattened )
					( Origin gBackEnd )
				)
				( attribute "RELATIVE_PROPAGATION_DELAY" "0.00 MIL,195.00 MIL"
					( Parent
						( matchGroupRef "@baseboard_fab2_lib.baseboard_fab2(sch_1):\MG_DQ-DQS_NEAR_DIMM_NG_M_A_BYTE7\" )
					)
					( Units "uMatchProp" "ns" 1.000000)
					( Status sCSetFlattened )
					( Origin gBackEnd )
				)
				( attribute "RELATIVE_PROPAGATION_DELAY_SCOPE" "G"
					( Parent
						( matchGroupRef "@baseboard_fab2_lib.baseboard_fab2(sch_1):\MG_DQ_NEAR_DIMM_NG_M_A_BYTE7\" )
					)
					( Status sCSetFlattened )
					( Origin gBackEnd )
				)
				( attribute "RELATIVE_PROPAGATION_DELAY" "-50.00 MIL,50.00 MIL"
					( Parent
						( matchGroupRef "@baseboard_fab2_lib.baseboard_fab2(sch_1):\MG_DQ_NEAR_DIMM_NG_M_A_BYTE7\" )
					)
					( Units "uMatchProp" "ns" 1.000000)
					( Status sCSetFlattened )
					( Origin gBackEnd )
				)
			)
			( pinPair "@baseboard_fab2_lib.baseboard_fab2(sch_1):\PP5169\"
				( pinRef "@baseboard_fab2_lib.baseboard_fab2(sch_1):page23_i172:DDR0_DQ(58)" )
				( pinRef "@baseboard_fab2_lib.baseboard_fab2(sch_1):page43_i1:DQ(59)" )
				( attribute "RELATIVE_PROPAGATION_DELAY_SCOPE" "G"
					( Parent
						( matchGroupRef "@baseboard_fab2_lib.baseboard_fab2(sch_1):\MG_DQ-DQS_FAR_DIMM_NG_M_A_BYTE7\" )
					)
					( Status sCSetFlattened )
					( Origin gBackEnd )
				)
				( attribute "RELATIVE_PROPAGATION_DELAY" "0.00 MIL,195.00 MIL"
					( Parent
						( matchGroupRef "@baseboard_fab2_lib.baseboard_fab2(sch_1):\MG_DQ-DQS_FAR_DIMM_NG_M_A_BYTE7\" )
					)
					( Units "uMatchProp" "ns" 1.000000)
					( Status sCSetFlattened )
					( Origin gBackEnd )
				)
				( attribute "RELATIVE_PROPAGATION_DELAY_SCOPE" "G"
					( Parent
						( matchGroupRef "@baseboard_fab2_lib.baseboard_fab2(sch_1):\MG_DQ_FAR_DIMM_NG_M_A_BYTE7\" )
					)
					( Status sCSetFlattened )
					( Origin gBackEnd )
				)
				( attribute "RELATIVE_PROPAGATION_DELAY" "-50.00 MIL,50.00 MIL"
					( Parent
						( matchGroupRef "@baseboard_fab2_lib.baseboard_fab2(sch_1):\MG_DQ_FAR_DIMM_NG_M_A_BYTE7\" )
					)
					( Units "uMatchProp" "ns" 1.000000)
					( Status sCSetFlattened )
					( Origin gBackEnd )
				)
			)
			( pinPair "@baseboard_fab2_lib.baseboard_fab2(sch_1):\PP5171\"
				( pinRef "@baseboard_fab2_lib.baseboard_fab2(sch_1):page23_i172:DDR0_DQ(58)" )
				( pinRef "@baseboard_fab2_lib.baseboard_fab2(sch_1):page44_i13:DQ(58)" )
				( attribute "RELATIVE_PROPAGATION_DELAY_SCOPE" "G"
					( Parent
						( matchGroupRef "@baseboard_fab2_lib.baseboard_fab2(sch_1):\MG_DQ-DQS_NEAR_DIMM_NG_M_A_BYTE7\" )
					)
					( Status sCSetFlattened )
					( Origin gBackEnd )
				)
				( attribute "RELATIVE_PROPAGATION_DELAY" "0.00 MIL,195.00 MIL"
					( Parent
						( matchGroupRef "@baseboard_fab2_lib.baseboard_fab2(sch_1):\MG_DQ-DQS_NEAR_DIMM_NG_M_A_BYTE7\" )
					)
					( Units "uMatchProp" "ns" 1.000000)
					( Status sCSetFlattened )
					( Origin gBackEnd )
				)
				( attribute "RELATIVE_PROPAGATION_DELAY_SCOPE" "G"
					( Parent
						( matchGroupRef "@baseboard_fab2_lib.baseboard_fab2(sch_1):\MG_DQ_NEAR_DIMM_NG_M_A_BYTE7\" )
					)
					( Status sCSetFlattened )
					( Origin gBackEnd )
				)
				( attribute "RELATIVE_PROPAGATION_DELAY" "-50.00 MIL,50.00 MIL"
					( Parent
						( matchGroupRef "@baseboard_fab2_lib.baseboard_fab2(sch_1):\MG_DQ_NEAR_DIMM_NG_M_A_BYTE7\" )
					)
					( Units "uMatchProp" "ns" 1.000000)
					( Status sCSetFlattened )
					( Origin gBackEnd )
				)
			)
			( pinPair "@baseboard_fab2_lib.baseboard_fab2(sch_1):\PP5172\"
				( pinRef "@baseboard_fab2_lib.baseboard_fab2(sch_1):page23_i172:DDR0_DQ(59)" )
				( pinRef "@baseboard_fab2_lib.baseboard_fab2(sch_1):page43_i1:DQ(58)" )
				( attribute "RELATIVE_PROPAGATION_DELAY_SCOPE" "G"
					( Parent
						( matchGroupRef "@baseboard_fab2_lib.baseboard_fab2(sch_1):\MG_DQ-DQS_FAR_DIMM_NG_M_A_BYTE7\" )
					)
					( Status sCSetFlattened )
					( Origin gBackEnd )
				)
				( attribute "RELATIVE_PROPAGATION_DELAY" "0.00 MIL,195.00 MIL"
					( Parent
						( matchGroupRef "@baseboard_fab2_lib.baseboard_fab2(sch_1):\MG_DQ-DQS_FAR_DIMM_NG_M_A_BYTE7\" )
					)
					( Units "uMatchProp" "ns" 1.000000)
					( Status sCSetFlattened )
					( Origin gBackEnd )
				)
				( attribute "RELATIVE_PROPAGATION_DELAY_SCOPE" "G"
					( Parent
						( matchGroupRef "@baseboard_fab2_lib.baseboard_fab2(sch_1):\MG_DQ_FAR_DIMM_NG_M_A_BYTE7\" )
					)
					( Status sCSetFlattened )
					( Origin gBackEnd )
				)
				( attribute "RELATIVE_PROPAGATION_DELAY" "-50.00 MIL,50.00 MIL"
					( Parent
						( matchGroupRef "@baseboard_fab2_lib.baseboard_fab2(sch_1):\MG_DQ_FAR_DIMM_NG_M_A_BYTE7\" )
					)
					( Units "uMatchProp" "ns" 1.000000)
					( Status sCSetFlattened )
					( Origin gBackEnd )
				)
			)
			( pinPair "@baseboard_fab2_lib.baseboard_fab2(sch_1):\PP5174\"
				( pinRef "@baseboard_fab2_lib.baseboard_fab2(sch_1):page23_i172:DDR0_DQ(59)" )
				( pinRef "@baseboard_fab2_lib.baseboard_fab2(sch_1):page44_i13:DQ(59)" )
				( attribute "RELATIVE_PROPAGATION_DELAY_SCOPE" "G"
					( Parent
						( matchGroupRef "@baseboard_fab2_lib.baseboard_fab2(sch_1):\MG_DQ-DQS_NEAR_DIMM_NG_M_A_BYTE7\" )
					)
					( Status sCSetFlattened )
					( Origin gBackEnd )
				)
				( attribute "RELATIVE_PROPAGATION_DELAY" "0.00 MIL,195.00 MIL"
					( Parent
						( matchGroupRef "@baseboard_fab2_lib.baseboard_fab2(sch_1):\MG_DQ-DQS_NEAR_DIMM_NG_M_A_BYTE7\" )
					)
					( Units "uMatchProp" "ns" 1.000000)
					( Status sCSetFlattened )
					( Origin gBackEnd )
				)
				( attribute "RELATIVE_PROPAGATION_DELAY_SCOPE" "G"
					( Parent
						( matchGroupRef "@baseboard_fab2_lib.baseboard_fab2(sch_1):\MG_DQ_NEAR_DIMM_NG_M_A_BYTE7\" )
					)
					( Status sCSetFlattened )
					( Origin gBackEnd )
				)
				( attribute "RELATIVE_PROPAGATION_DELAY" "-50.00 MIL,50.00 MIL"
					( Parent
						( matchGroupRef "@baseboard_fab2_lib.baseboard_fab2(sch_1):\MG_DQ_NEAR_DIMM_NG_M_A_BYTE7\" )
					)
					( Units "uMatchProp" "ns" 1.000000)
					( Status sCSetFlattened )
					( Origin gBackEnd )
				)
			)
			( pinPair "@baseboard_fab2_lib.baseboard_fab2(sch_1):\PP5175\"
				( pinRef "@baseboard_fab2_lib.baseboard_fab2(sch_1):page23_i172:DDR0_DQ(60)" )
				( pinRef "@baseboard_fab2_lib.baseboard_fab2(sch_1):page43_i1:DQ(61)" )
				( attribute "RELATIVE_PROPAGATION_DELAY_SCOPE" "G"
					( Parent
						( matchGroupRef "@baseboard_fab2_lib.baseboard_fab2(sch_1):\MG_DQ-DQS_FAR_DIMM_NG_M_A_BYTE7\" )
					)
					( Status sCSetFlattened )
					( Origin gBackEnd )
				)
				( attribute "RELATIVE_PROPAGATION_DELAY" "0.00 MIL,195.00 MIL"
					( Parent
						( matchGroupRef "@baseboard_fab2_lib.baseboard_fab2(sch_1):\MG_DQ-DQS_FAR_DIMM_NG_M_A_BYTE7\" )
					)
					( Units "uMatchProp" "ns" 1.000000)
					( Status sCSetFlattened )
					( Origin gBackEnd )
				)
				( attribute "RELATIVE_PROPAGATION_DELAY_SCOPE" "G"
					( Parent
						( matchGroupRef "@baseboard_fab2_lib.baseboard_fab2(sch_1):\MG_DQ_FAR_DIMM_NG_M_A_BYTE7\" )
					)
					( Status sCSetFlattened )
					( Origin gBackEnd )
				)
				( attribute "RELATIVE_PROPAGATION_DELAY" "-50.00 MIL,50.00 MIL"
					( Parent
						( matchGroupRef "@baseboard_fab2_lib.baseboard_fab2(sch_1):\MG_DQ_FAR_DIMM_NG_M_A_BYTE7\" )
					)
					( Units "uMatchProp" "ns" 1.000000)
					( Status sCSetFlattened )
					( Origin gBackEnd )
				)
			)
			( pinPair "@baseboard_fab2_lib.baseboard_fab2(sch_1):\PP5177\"
				( pinRef "@baseboard_fab2_lib.baseboard_fab2(sch_1):page23_i172:DDR0_DQ(60)" )
				( pinRef "@baseboard_fab2_lib.baseboard_fab2(sch_1):page44_i13:DQ(60)" )
				( attribute "RELATIVE_PROPAGATION_DELAY_SCOPE" "G"
					( Parent
						( matchGroupRef "@baseboard_fab2_lib.baseboard_fab2(sch_1):\MG_DQ-DQS_NEAR_DIMM_NG_M_A_BYTE7\" )
					)
					( Status sCSetFlattened )
					( Origin gBackEnd )
				)
				( attribute "RELATIVE_PROPAGATION_DELAY" "0.00 MIL,195.00 MIL"
					( Parent
						( matchGroupRef "@baseboard_fab2_lib.baseboard_fab2(sch_1):\MG_DQ-DQS_NEAR_DIMM_NG_M_A_BYTE7\" )
					)
					( Units "uMatchProp" "ns" 1.000000)
					( Status sCSetFlattened )
					( Origin gBackEnd )
				)
				( attribute "RELATIVE_PROPAGATION_DELAY_SCOPE" "G"
					( Parent
						( matchGroupRef "@baseboard_fab2_lib.baseboard_fab2(sch_1):\MG_DQ_NEAR_DIMM_NG_M_A_BYTE7\" )
					)
					( Status sCSetFlattened )
					( Origin gBackEnd )
				)
				( attribute "RELATIVE_PROPAGATION_DELAY" "-50.00 MIL,50.00 MIL"
					( Parent
						( matchGroupRef "@baseboard_fab2_lib.baseboard_fab2(sch_1):\MG_DQ_NEAR_DIMM_NG_M_A_BYTE7\" )
					)
					( Units "uMatchProp" "ns" 1.000000)
					( Status sCSetFlattened )
					( Origin gBackEnd )
				)
			)
			( pinPair "@baseboard_fab2_lib.baseboard_fab2(sch_1):\PP5178\"
				( pinRef "@baseboard_fab2_lib.baseboard_fab2(sch_1):page23_i172:DDR0_DQ(61)" )
				( pinRef "@baseboard_fab2_lib.baseboard_fab2(sch_1):page43_i1:DQ(60)" )
				( attribute "RELATIVE_PROPAGATION_DELAY_SCOPE" "G"
					( Parent
						( matchGroupRef "@baseboard_fab2_lib.baseboard_fab2(sch_1):\MG_DQ-DQS_FAR_DIMM_NG_M_A_BYTE7\" )
					)
					( Status sCSetFlattened )
					( Origin gBackEnd )
				)
				( attribute "RELATIVE_PROPAGATION_DELAY" "0.00 MIL,195.00 MIL"
					( Parent
						( matchGroupRef "@baseboard_fab2_lib.baseboard_fab2(sch_1):\MG_DQ-DQS_FAR_DIMM_NG_M_A_BYTE7\" )
					)
					( Units "uMatchProp" "ns" 1.000000)
					( Status sCSetFlattened )
					( Origin gBackEnd )
				)
				( attribute "RELATIVE_PROPAGATION_DELAY_SCOPE" "G"
					( Parent
						( matchGroupRef "@baseboard_fab2_lib.baseboard_fab2(sch_1):\MG_DQ_FAR_DIMM_NG_M_A_BYTE7\" )
					)
					( Status sCSetFlattened )
					( Origin gBackEnd )
				)
				( attribute "RELATIVE_PROPAGATION_DELAY" "-50.00 MIL,50.00 MIL"
					( Parent
						( matchGroupRef "@baseboard_fab2_lib.baseboard_fab2(sch_1):\MG_DQ_FAR_DIMM_NG_M_A_BYTE7\" )
					)
					( Units "uMatchProp" "ns" 1.000000)
					( Status sCSetFlattened )
					( Origin gBackEnd )
				)
			)
			( pinPair "@baseboard_fab2_lib.baseboard_fab2(sch_1):\PP5180\"
				( pinRef "@baseboard_fab2_lib.baseboard_fab2(sch_1):page23_i172:DDR0_DQ(61)" )
				( pinRef "@baseboard_fab2_lib.baseboard_fab2(sch_1):page44_i13:DQ(61)" )
				( attribute "RELATIVE_PROPAGATION_DELAY_SCOPE" "G"
					( Parent
						( matchGroupRef "@baseboard_fab2_lib.baseboard_fab2(sch_1):\MG_DQ-DQS_NEAR_DIMM_NG_M_A_BYTE7\" )
					)
					( Status sCSetFlattened )
					( Origin gBackEnd )
				)
				( attribute "RELATIVE_PROPAGATION_DELAY" "0.00 MIL,195.00 MIL"
					( Parent
						( matchGroupRef "@baseboard_fab2_lib.baseboard_fab2(sch_1):\MG_DQ-DQS_NEAR_DIMM_NG_M_A_BYTE7\" )
					)
					( Units "uMatchProp" "ns" 1.000000)
					( Status sCSetFlattened )
					( Origin gBackEnd )
				)
				( attribute "RELATIVE_PROPAGATION_DELAY_SCOPE" "G"
					( Parent
						( matchGroupRef "@baseboard_fab2_lib.baseboard_fab2(sch_1):\MG_DQ_NEAR_DIMM_NG_M_A_BYTE7\" )
					)
					( Status sCSetFlattened )
					( Origin gBackEnd )
				)
				( attribute "RELATIVE_PROPAGATION_DELAY" "-50.00 MIL,50.00 MIL"
					( Parent
						( matchGroupRef "@baseboard_fab2_lib.baseboard_fab2(sch_1):\MG_DQ_NEAR_DIMM_NG_M_A_BYTE7\" )
					)
					( Units "uMatchProp" "ns" 1.000000)
					( Status sCSetFlattened )
					( Origin gBackEnd )
				)
			)
			( pinPair "@baseboard_fab2_lib.baseboard_fab2(sch_1):\PP5181\"
				( pinRef "@baseboard_fab2_lib.baseboard_fab2(sch_1):page23_i172:DDR0_DQ(62)" )
				( pinRef "@baseboard_fab2_lib.baseboard_fab2(sch_1):page43_i1:DQ(63)" )
				( attribute "RELATIVE_PROPAGATION_DELAY_SCOPE" "G"
					( Parent
						( matchGroupRef "@baseboard_fab2_lib.baseboard_fab2(sch_1):\MG_DQ-DQS_FAR_DIMM_NG_M_A_BYTE7\" )
					)
					( Status sCSetFlattened )
					( Origin gBackEnd )
				)
				( attribute "RELATIVE_PROPAGATION_DELAY" "0.00 MIL,195.00 MIL"
					( Parent
						( matchGroupRef "@baseboard_fab2_lib.baseboard_fab2(sch_1):\MG_DQ-DQS_FAR_DIMM_NG_M_A_BYTE7\" )
					)
					( Units "uMatchProp" "ns" 1.000000)
					( Status sCSetFlattened )
					( Origin gBackEnd )
				)
				( attribute "RELATIVE_PROPAGATION_DELAY_SCOPE" "G"
					( Parent
						( matchGroupRef "@baseboard_fab2_lib.baseboard_fab2(sch_1):\MG_DQ_FAR_DIMM_NG_M_A_BYTE7\" )
					)
					( Status sCSetFlattened )
					( Origin gBackEnd )
				)
				( attribute "RELATIVE_PROPAGATION_DELAY" "-50.00 MIL,50.00 MIL"
					( Parent
						( matchGroupRef "@baseboard_fab2_lib.baseboard_fab2(sch_1):\MG_DQ_FAR_DIMM_NG_M_A_BYTE7\" )
					)
					( Units "uMatchProp" "ns" 1.000000)
					( Status sCSetFlattened )
					( Origin gBackEnd )
				)
			)
			( pinPair "@baseboard_fab2_lib.baseboard_fab2(sch_1):\PP5183\"
				( pinRef "@baseboard_fab2_lib.baseboard_fab2(sch_1):page23_i172:DDR0_DQ(62)" )
				( pinRef "@baseboard_fab2_lib.baseboard_fab2(sch_1):page44_i13:DQ(62)" )
				( attribute "RELATIVE_PROPAGATION_DELAY_SCOPE" "G"
					( Parent
						( matchGroupRef "@baseboard_fab2_lib.baseboard_fab2(sch_1):\MG_DQ-DQS_NEAR_DIMM_NG_M_A_BYTE7\" )
					)
					( Status sCSetFlattened )
					( Origin gBackEnd )
				)
				( attribute "RELATIVE_PROPAGATION_DELAY" "0.00 MIL,195.00 MIL"
					( Parent
						( matchGroupRef "@baseboard_fab2_lib.baseboard_fab2(sch_1):\MG_DQ-DQS_NEAR_DIMM_NG_M_A_BYTE7\" )
					)
					( Units "uMatchProp" "ns" 1.000000)
					( Status sCSetFlattened )
					( Origin gBackEnd )
				)
				( attribute "RELATIVE_PROPAGATION_DELAY_SCOPE" "G"
					( Parent
						( matchGroupRef "@baseboard_fab2_lib.baseboard_fab2(sch_1):\MG_DQ_NEAR_DIMM_NG_M_A_BYTE7\" )
					)
					( Status sCSetFlattened )
					( Origin gBackEnd )
				)
				( attribute "RELATIVE_PROPAGATION_DELAY" "-50.00 MIL,50.00 MIL"
					( Parent
						( matchGroupRef "@baseboard_fab2_lib.baseboard_fab2(sch_1):\MG_DQ_NEAR_DIMM_NG_M_A_BYTE7\" )
					)
					( Units "uMatchProp" "ns" 1.000000)
					( Status sCSetFlattened )
					( Origin gBackEnd )
				)
			)
			( pinPair "@baseboard_fab2_lib.baseboard_fab2(sch_1):\PP5184\"
				( pinRef "@baseboard_fab2_lib.baseboard_fab2(sch_1):page23_i172:DDR0_DQ(63)" )
				( pinRef "@baseboard_fab2_lib.baseboard_fab2(sch_1):page43_i1:DQ(62)" )
				( attribute "RELATIVE_PROPAGATION_DELAY_SCOPE" "G"
					( Parent
						( matchGroupRef "@baseboard_fab2_lib.baseboard_fab2(sch_1):\MG_DQ-DQS_FAR_DIMM_NG_M_A_BYTE7\" )
					)
					( Status sCSetFlattened )
					( Origin gBackEnd )
				)
				( attribute "RELATIVE_PROPAGATION_DELAY" "0.00 MIL,195.00 MIL"
					( Parent
						( matchGroupRef "@baseboard_fab2_lib.baseboard_fab2(sch_1):\MG_DQ-DQS_FAR_DIMM_NG_M_A_BYTE7\" )
					)
					( Units "uMatchProp" "ns" 1.000000)
					( Status sCSetFlattened )
					( Origin gBackEnd )
				)
				( attribute "RELATIVE_PROPAGATION_DELAY_SCOPE" "G"
					( Parent
						( matchGroupRef "@baseboard_fab2_lib.baseboard_fab2(sch_1):\MG_DQ_FAR_DIMM_NG_M_A_BYTE7\" )
					)
					( Status sCSetFlattened )
					( Origin gBackEnd )
				)
				( attribute "RELATIVE_PROPAGATION_DELAY" "-50.00 MIL,50.00 MIL"
					( Parent
						( matchGroupRef "@baseboard_fab2_lib.baseboard_fab2(sch_1):\MG_DQ_FAR_DIMM_NG_M_A_BYTE7\" )
					)
					( Units "uMatchProp" "ns" 1.000000)
					( Status sCSetFlattened )
					( Origin gBackEnd )
				)
			)
			( pinPair "@baseboard_fab2_lib.baseboard_fab2(sch_1):\PP5186\"
				( pinRef "@baseboard_fab2_lib.baseboard_fab2(sch_1):page23_i172:DDR0_DQ(63)" )
				( pinRef "@baseboard_fab2_lib.baseboard_fab2(sch_1):page44_i13:DQ(63)" )
				( attribute "RELATIVE_PROPAGATION_DELAY_SCOPE" "G"
					( Parent
						( matchGroupRef "@baseboard_fab2_lib.baseboard_fab2(sch_1):\MG_DQ-DQS_NEAR_DIMM_NG_M_A_BYTE7\" )
					)
					( Status sCSetFlattened )
					( Origin gBackEnd )
				)
				( attribute "RELATIVE_PROPAGATION_DELAY" "0.00 MIL,195.00 MIL"
					( Parent
						( matchGroupRef "@baseboard_fab2_lib.baseboard_fab2(sch_1):\MG_DQ-DQS_NEAR_DIMM_NG_M_A_BYTE7\" )
					)
					( Units "uMatchProp" "ns" 1.000000)
					( Status sCSetFlattened )
					( Origin gBackEnd )
				)
				( attribute "RELATIVE_PROPAGATION_DELAY_SCOPE" "G"
					( Parent
						( matchGroupRef "@baseboard_fab2_lib.baseboard_fab2(sch_1):\MG_DQ_NEAR_DIMM_NG_M_A_BYTE7\" )
					)
					( Status sCSetFlattened )
					( Origin gBackEnd )
				)
				( attribute "RELATIVE_PROPAGATION_DELAY" "-50.00 MIL,50.00 MIL"
					( Parent
						( matchGroupRef "@baseboard_fab2_lib.baseboard_fab2(sch_1):\MG_DQ_NEAR_DIMM_NG_M_A_BYTE7\" )
					)
					( Units "uMatchProp" "ns" 1.000000)
					( Status sCSetFlattened )
					( Origin gBackEnd )
				)
			)
			( pinPair "@baseboard_fab2_lib.baseboard_fab2(sch_1):\PP2923\"
				( pinRef "@baseboard_fab2_lib.baseboard_fab2(sch_1):page57_i172:DDR0_DQ(0)" )
				( pinRef "@baseboard_fab2_lib.baseboard_fab2(sch_1):page77_i111:DQ(1)" )
				( attribute "RELATIVE_PROPAGATION_DELAY_SCOPE" "G"
					( Parent
						( matchGroupRef "@baseboard_fab2_lib.baseboard_fab2(sch_1):\MG_DQ-DQS_FAR_DIMM_NG_M_G_BYTE0\" )
					)
					( Status sCSetFlattened )
					( Origin gBackEnd )
				)
				( attribute "RELATIVE_PROPAGATION_DELAY" "0.00 MIL,195.00 MIL"
					( Parent
						( matchGroupRef "@baseboard_fab2_lib.baseboard_fab2(sch_1):\MG_DQ-DQS_FAR_DIMM_NG_M_G_BYTE0\" )
					)
					( Units "uMatchProp" "ns" 1.000000)
					( Status sCSetFlattened )
					( Origin gBackEnd )
				)
				( attribute "RELATIVE_PROPAGATION_DELAY_SCOPE" "G"
					( Parent
						( matchGroupRef "@baseboard_fab2_lib.baseboard_fab2(sch_1):\MG_DQ_FAR_DIMM_NG_M_G_BYTE0\" )
					)
					( Status sCSetFlattened )
					( Origin gBackEnd )
				)
				( attribute "RELATIVE_PROPAGATION_DELAY" "-50.00 MIL,50.00 MIL"
					( Parent
						( matchGroupRef "@baseboard_fab2_lib.baseboard_fab2(sch_1):\MG_DQ_FAR_DIMM_NG_M_G_BYTE0\" )
					)
					( Units "uMatchProp" "ns" 1.000000)
					( Status sCSetFlattened )
					( Origin gBackEnd )
				)
			)
			( pinPair "@baseboard_fab2_lib.baseboard_fab2(sch_1):\PP2924\"
				( pinRef "@baseboard_fab2_lib.baseboard_fab2(sch_1):page78_i13:DQ(0)" )
				( pinRef "@baseboard_fab2_lib.baseboard_fab2(sch_1):page57_i172:DDR0_DQ(0)" )
				( attribute "RELATIVE_PROPAGATION_DELAY_SCOPE" "G"
					( Parent
						( matchGroupRef "@baseboard_fab2_lib.baseboard_fab2(sch_1):\MG_DQ-DQS_NEAR_DIMM_NG_M_G_BYTE0\" )
					)
					( Status sCSetFlattened )
					( Origin gBackEnd )
				)
				( attribute "RELATIVE_PROPAGATION_DELAY" "0.00 MIL,195.00 MIL"
					( Parent
						( matchGroupRef "@baseboard_fab2_lib.baseboard_fab2(sch_1):\MG_DQ-DQS_NEAR_DIMM_NG_M_G_BYTE0\" )
					)
					( Units "uMatchProp" "ns" 1.000000)
					( Status sCSetFlattened )
					( Origin gBackEnd )
				)
				( attribute "RELATIVE_PROPAGATION_DELAY_SCOPE" "G"
					( Parent
						( matchGroupRef "@baseboard_fab2_lib.baseboard_fab2(sch_1):\MG_DQ_NEAR_DIMM_NG_M_G_BYTE0\" )
					)
					( Status sCSetFlattened )
					( Origin gBackEnd )
				)
				( attribute "RELATIVE_PROPAGATION_DELAY" "-50.00 MIL,50.00 MIL"
					( Parent
						( matchGroupRef "@baseboard_fab2_lib.baseboard_fab2(sch_1):\MG_DQ_NEAR_DIMM_NG_M_G_BYTE0\" )
					)
					( Units "uMatchProp" "ns" 1.000000)
					( Status sCSetFlattened )
					( Origin gBackEnd )
				)
			)
			( pinPair "@baseboard_fab2_lib.baseboard_fab2(sch_1):\PP2926\"
				( pinRef "@baseboard_fab2_lib.baseboard_fab2(sch_1):page57_i172:DDR0_DQ(1)" )
				( pinRef "@baseboard_fab2_lib.baseboard_fab2(sch_1):page77_i111:DQ(0)" )
				( attribute "RELATIVE_PROPAGATION_DELAY_SCOPE" "G"
					( Parent
						( matchGroupRef "@baseboard_fab2_lib.baseboard_fab2(sch_1):\MG_DQ-DQS_FAR_DIMM_NG_M_G_BYTE0\" )
					)
					( Status sCSetFlattened )
					( Origin gBackEnd )
				)
				( attribute "RELATIVE_PROPAGATION_DELAY" "0.00 MIL,195.00 MIL"
					( Parent
						( matchGroupRef "@baseboard_fab2_lib.baseboard_fab2(sch_1):\MG_DQ-DQS_FAR_DIMM_NG_M_G_BYTE0\" )
					)
					( Units "uMatchProp" "ns" 1.000000)
					( Status sCSetFlattened )
					( Origin gBackEnd )
				)
				( attribute "RELATIVE_PROPAGATION_DELAY_SCOPE" "G"
					( Parent
						( matchGroupRef "@baseboard_fab2_lib.baseboard_fab2(sch_1):\MG_DQ_FAR_DIMM_NG_M_G_BYTE0\" )
					)
					( Status sCSetFlattened )
					( Origin gBackEnd )
				)
				( attribute "RELATIVE_PROPAGATION_DELAY" "-50.00 MIL,50.00 MIL"
					( Parent
						( matchGroupRef "@baseboard_fab2_lib.baseboard_fab2(sch_1):\MG_DQ_FAR_DIMM_NG_M_G_BYTE0\" )
					)
					( Units "uMatchProp" "ns" 1.000000)
					( Status sCSetFlattened )
					( Origin gBackEnd )
				)
			)
			( pinPair "@baseboard_fab2_lib.baseboard_fab2(sch_1):\PP2927\"
				( pinRef "@baseboard_fab2_lib.baseboard_fab2(sch_1):page78_i13:DQ(1)" )
				( pinRef "@baseboard_fab2_lib.baseboard_fab2(sch_1):page57_i172:DDR0_DQ(1)" )
				( attribute "RELATIVE_PROPAGATION_DELAY_SCOPE" "G"
					( Parent
						( matchGroupRef "@baseboard_fab2_lib.baseboard_fab2(sch_1):\MG_DQ-DQS_NEAR_DIMM_NG_M_G_BYTE0\" )
					)
					( Status sCSetFlattened )
					( Origin gBackEnd )
				)
				( attribute "RELATIVE_PROPAGATION_DELAY" "0.00 MIL,195.00 MIL"
					( Parent
						( matchGroupRef "@baseboard_fab2_lib.baseboard_fab2(sch_1):\MG_DQ-DQS_NEAR_DIMM_NG_M_G_BYTE0\" )
					)
					( Units "uMatchProp" "ns" 1.000000)
					( Status sCSetFlattened )
					( Origin gBackEnd )
				)
				( attribute "RELATIVE_PROPAGATION_DELAY_SCOPE" "G"
					( Parent
						( matchGroupRef "@baseboard_fab2_lib.baseboard_fab2(sch_1):\MG_DQ_NEAR_DIMM_NG_M_G_BYTE0\" )
					)
					( Status sCSetFlattened )
					( Origin gBackEnd )
				)
				( attribute "RELATIVE_PROPAGATION_DELAY" "-50.00 MIL,50.00 MIL"
					( Parent
						( matchGroupRef "@baseboard_fab2_lib.baseboard_fab2(sch_1):\MG_DQ_NEAR_DIMM_NG_M_G_BYTE0\" )
					)
					( Units "uMatchProp" "ns" 1.000000)
					( Status sCSetFlattened )
					( Origin gBackEnd )
				)
			)
			( pinPair "@baseboard_fab2_lib.baseboard_fab2(sch_1):\PP2929\"
				( pinRef "@baseboard_fab2_lib.baseboard_fab2(sch_1):page57_i172:DDR0_DQ(2)" )
				( pinRef "@baseboard_fab2_lib.baseboard_fab2(sch_1):page77_i111:DQ(3)" )
				( attribute "RELATIVE_PROPAGATION_DELAY_SCOPE" "G"
					( Parent
						( matchGroupRef "@baseboard_fab2_lib.baseboard_fab2(sch_1):\MG_DQ-DQS_FAR_DIMM_NG_M_G_BYTE0\" )
					)
					( Status sCSetFlattened )
					( Origin gBackEnd )
				)
				( attribute "RELATIVE_PROPAGATION_DELAY" "0.00 MIL,195.00 MIL"
					( Parent
						( matchGroupRef "@baseboard_fab2_lib.baseboard_fab2(sch_1):\MG_DQ-DQS_FAR_DIMM_NG_M_G_BYTE0\" )
					)
					( Units "uMatchProp" "ns" 1.000000)
					( Status sCSetFlattened )
					( Origin gBackEnd )
				)
				( attribute "RELATIVE_PROPAGATION_DELAY_SCOPE" "G"
					( Parent
						( matchGroupRef "@baseboard_fab2_lib.baseboard_fab2(sch_1):\MG_DQ_FAR_DIMM_NG_M_G_BYTE0\" )
					)
					( Status sCSetFlattened )
					( Origin gBackEnd )
				)
				( attribute "RELATIVE_PROPAGATION_DELAY" "-50.00 MIL,50.00 MIL"
					( Parent
						( matchGroupRef "@baseboard_fab2_lib.baseboard_fab2(sch_1):\MG_DQ_FAR_DIMM_NG_M_G_BYTE0\" )
					)
					( Units "uMatchProp" "ns" 1.000000)
					( Status sCSetFlattened )
					( Origin gBackEnd )
				)
			)
			( pinPair "@baseboard_fab2_lib.baseboard_fab2(sch_1):\PP2930\"
				( pinRef "@baseboard_fab2_lib.baseboard_fab2(sch_1):page57_i172:DDR0_DQ(2)" )
				( pinRef "@baseboard_fab2_lib.baseboard_fab2(sch_1):page78_i13:DQ(2)" )
				( attribute "RELATIVE_PROPAGATION_DELAY_SCOPE" "G"
					( Parent
						( matchGroupRef "@baseboard_fab2_lib.baseboard_fab2(sch_1):\MG_DQ-DQS_NEAR_DIMM_NG_M_G_BYTE0\" )
					)
					( Status sCSetFlattened )
					( Origin gBackEnd )
				)
				( attribute "RELATIVE_PROPAGATION_DELAY" "0.00 MIL,195.00 MIL"
					( Parent
						( matchGroupRef "@baseboard_fab2_lib.baseboard_fab2(sch_1):\MG_DQ-DQS_NEAR_DIMM_NG_M_G_BYTE0\" )
					)
					( Units "uMatchProp" "ns" 1.000000)
					( Status sCSetFlattened )
					( Origin gBackEnd )
				)
				( attribute "RELATIVE_PROPAGATION_DELAY_SCOPE" "G"
					( Parent
						( matchGroupRef "@baseboard_fab2_lib.baseboard_fab2(sch_1):\MG_DQ_NEAR_DIMM_NG_M_G_BYTE0\" )
					)
					( Status sCSetFlattened )
					( Origin gBackEnd )
				)
				( attribute "RELATIVE_PROPAGATION_DELAY" "-50.00 MIL,50.00 MIL"
					( Parent
						( matchGroupRef "@baseboard_fab2_lib.baseboard_fab2(sch_1):\MG_DQ_NEAR_DIMM_NG_M_G_BYTE0\" )
					)
					( Units "uMatchProp" "ns" 1.000000)
					( Status sCSetFlattened )
					( Origin gBackEnd )
				)
			)
			( pinPair "@baseboard_fab2_lib.baseboard_fab2(sch_1):\PP2932\"
				( pinRef "@baseboard_fab2_lib.baseboard_fab2(sch_1):page57_i172:DDR0_DQ(3)" )
				( pinRef "@baseboard_fab2_lib.baseboard_fab2(sch_1):page77_i111:DQ(2)" )
				( attribute "RELATIVE_PROPAGATION_DELAY_SCOPE" "G"
					( Parent
						( matchGroupRef "@baseboard_fab2_lib.baseboard_fab2(sch_1):\MG_DQ-DQS_FAR_DIMM_NG_M_G_BYTE0\" )
					)
					( Status sCSetFlattened )
					( Origin gBackEnd )
				)
				( attribute "RELATIVE_PROPAGATION_DELAY" "0.00 MIL,195.00 MIL"
					( Parent
						( matchGroupRef "@baseboard_fab2_lib.baseboard_fab2(sch_1):\MG_DQ-DQS_FAR_DIMM_NG_M_G_BYTE0\" )
					)
					( Units "uMatchProp" "ns" 1.000000)
					( Status sCSetFlattened )
					( Origin gBackEnd )
				)
				( attribute "RELATIVE_PROPAGATION_DELAY_SCOPE" "G"
					( Parent
						( matchGroupRef "@baseboard_fab2_lib.baseboard_fab2(sch_1):\MG_DQ_FAR_DIMM_NG_M_G_BYTE0\" )
					)
					( Status sCSetFlattened )
					( Origin gBackEnd )
				)
				( attribute "RELATIVE_PROPAGATION_DELAY" "-50.00 MIL,50.00 MIL"
					( Parent
						( matchGroupRef "@baseboard_fab2_lib.baseboard_fab2(sch_1):\MG_DQ_FAR_DIMM_NG_M_G_BYTE0\" )
					)
					( Units "uMatchProp" "ns" 1.000000)
					( Status sCSetFlattened )
					( Origin gBackEnd )
				)
			)
			( pinPair "@baseboard_fab2_lib.baseboard_fab2(sch_1):\PP2933\"
				( pinRef "@baseboard_fab2_lib.baseboard_fab2(sch_1):page78_i13:DQ(3)" )
				( pinRef "@baseboard_fab2_lib.baseboard_fab2(sch_1):page57_i172:DDR0_DQ(3)" )
				( attribute "RELATIVE_PROPAGATION_DELAY_SCOPE" "G"
					( Parent
						( matchGroupRef "@baseboard_fab2_lib.baseboard_fab2(sch_1):\MG_DQ-DQS_NEAR_DIMM_NG_M_G_BYTE0\" )
					)
					( Status sCSetFlattened )
					( Origin gBackEnd )
				)
				( attribute "RELATIVE_PROPAGATION_DELAY" "0.00 MIL,195.00 MIL"
					( Parent
						( matchGroupRef "@baseboard_fab2_lib.baseboard_fab2(sch_1):\MG_DQ-DQS_NEAR_DIMM_NG_M_G_BYTE0\" )
					)
					( Units "uMatchProp" "ns" 1.000000)
					( Status sCSetFlattened )
					( Origin gBackEnd )
				)
				( attribute "RELATIVE_PROPAGATION_DELAY_SCOPE" "G"
					( Parent
						( matchGroupRef "@baseboard_fab2_lib.baseboard_fab2(sch_1):\MG_DQ_NEAR_DIMM_NG_M_G_BYTE0\" )
					)
					( Status sCSetFlattened )
					( Origin gBackEnd )
				)
				( attribute "RELATIVE_PROPAGATION_DELAY" "-50.00 MIL,50.00 MIL"
					( Parent
						( matchGroupRef "@baseboard_fab2_lib.baseboard_fab2(sch_1):\MG_DQ_NEAR_DIMM_NG_M_G_BYTE0\" )
					)
					( Units "uMatchProp" "ns" 1.000000)
					( Status sCSetFlattened )
					( Origin gBackEnd )
				)
			)
			( pinPair "@baseboard_fab2_lib.baseboard_fab2(sch_1):\PP2935\"
				( pinRef "@baseboard_fab2_lib.baseboard_fab2(sch_1):page57_i172:DDR0_DQ(4)" )
				( pinRef "@baseboard_fab2_lib.baseboard_fab2(sch_1):page77_i111:DQ(5)" )
				( attribute "RELATIVE_PROPAGATION_DELAY_SCOPE" "G"
					( Parent
						( matchGroupRef "@baseboard_fab2_lib.baseboard_fab2(sch_1):\MG_DQ-DQS_FAR_DIMM_NG_M_G_BYTE0\" )
					)
					( Status sCSetFlattened )
					( Origin gBackEnd )
				)
				( attribute "RELATIVE_PROPAGATION_DELAY" "0.00 MIL,195.00 MIL"
					( Parent
						( matchGroupRef "@baseboard_fab2_lib.baseboard_fab2(sch_1):\MG_DQ-DQS_FAR_DIMM_NG_M_G_BYTE0\" )
					)
					( Units "uMatchProp" "ns" 1.000000)
					( Status sCSetFlattened )
					( Origin gBackEnd )
				)
				( attribute "RELATIVE_PROPAGATION_DELAY_SCOPE" "G"
					( Parent
						( matchGroupRef "@baseboard_fab2_lib.baseboard_fab2(sch_1):\MG_DQ_FAR_DIMM_NG_M_G_BYTE0\" )
					)
					( Status sCSetFlattened )
					( Origin gBackEnd )
				)
				( attribute "RELATIVE_PROPAGATION_DELAY" "-50.00 MIL,50.00 MIL"
					( Parent
						( matchGroupRef "@baseboard_fab2_lib.baseboard_fab2(sch_1):\MG_DQ_FAR_DIMM_NG_M_G_BYTE0\" )
					)
					( Units "uMatchProp" "ns" 1.000000)
					( Status sCSetFlattened )
					( Origin gBackEnd )
				)
			)
			( pinPair "@baseboard_fab2_lib.baseboard_fab2(sch_1):\PP2936\"
				( pinRef "@baseboard_fab2_lib.baseboard_fab2(sch_1):page78_i13:DQ(4)" )
				( pinRef "@baseboard_fab2_lib.baseboard_fab2(sch_1):page57_i172:DDR0_DQ(4)" )
				( attribute "RELATIVE_PROPAGATION_DELAY_SCOPE" "G"
					( Parent
						( matchGroupRef "@baseboard_fab2_lib.baseboard_fab2(sch_1):\MG_DQ-DQS_NEAR_DIMM_NG_M_G_BYTE0\" )
					)
					( Status sCSetFlattened )
					( Origin gBackEnd )
				)
				( attribute "RELATIVE_PROPAGATION_DELAY" "0.00 MIL,195.00 MIL"
					( Parent
						( matchGroupRef "@baseboard_fab2_lib.baseboard_fab2(sch_1):\MG_DQ-DQS_NEAR_DIMM_NG_M_G_BYTE0\" )
					)
					( Units "uMatchProp" "ns" 1.000000)
					( Status sCSetFlattened )
					( Origin gBackEnd )
				)
				( attribute "RELATIVE_PROPAGATION_DELAY_SCOPE" "G"
					( Parent
						( matchGroupRef "@baseboard_fab2_lib.baseboard_fab2(sch_1):\MG_DQ_NEAR_DIMM_NG_M_G_BYTE0\" )
					)
					( Status sCSetFlattened )
					( Origin gBackEnd )
				)
				( attribute "RELATIVE_PROPAGATION_DELAY" "-50.00 MIL,50.00 MIL"
					( Parent
						( matchGroupRef "@baseboard_fab2_lib.baseboard_fab2(sch_1):\MG_DQ_NEAR_DIMM_NG_M_G_BYTE0\" )
					)
					( Units "uMatchProp" "ns" 1.000000)
					( Status sCSetFlattened )
					( Origin gBackEnd )
				)
			)
			( pinPair "@baseboard_fab2_lib.baseboard_fab2(sch_1):\PP2938\"
				( pinRef "@baseboard_fab2_lib.baseboard_fab2(sch_1):page57_i172:DDR0_DQ(5)" )
				( pinRef "@baseboard_fab2_lib.baseboard_fab2(sch_1):page77_i111:DQ(4)" )
				( attribute "RELATIVE_PROPAGATION_DELAY_SCOPE" "G"
					( Parent
						( matchGroupRef "@baseboard_fab2_lib.baseboard_fab2(sch_1):\MG_DQ-DQS_FAR_DIMM_NG_M_G_BYTE0\" )
					)
					( Status sCSetFlattened )
					( Origin gBackEnd )
				)
				( attribute "RELATIVE_PROPAGATION_DELAY" "0.00 MIL,195.00 MIL"
					( Parent
						( matchGroupRef "@baseboard_fab2_lib.baseboard_fab2(sch_1):\MG_DQ-DQS_FAR_DIMM_NG_M_G_BYTE0\" )
					)
					( Units "uMatchProp" "ns" 1.000000)
					( Status sCSetFlattened )
					( Origin gBackEnd )
				)
				( attribute "RELATIVE_PROPAGATION_DELAY_SCOPE" "G"
					( Parent
						( matchGroupRef "@baseboard_fab2_lib.baseboard_fab2(sch_1):\MG_DQ_FAR_DIMM_NG_M_G_BYTE0\" )
					)
					( Status sCSetFlattened )
					( Origin gBackEnd )
				)
				( attribute "RELATIVE_PROPAGATION_DELAY" "-50.00 MIL,50.00 MIL"
					( Parent
						( matchGroupRef "@baseboard_fab2_lib.baseboard_fab2(sch_1):\MG_DQ_FAR_DIMM_NG_M_G_BYTE0\" )
					)
					( Units "uMatchProp" "ns" 1.000000)
					( Status sCSetFlattened )
					( Origin gBackEnd )
				)
			)
			( pinPair "@baseboard_fab2_lib.baseboard_fab2(sch_1):\PP2939\"
				( pinRef "@baseboard_fab2_lib.baseboard_fab2(sch_1):page57_i172:DDR0_DQ(5)" )
				( pinRef "@baseboard_fab2_lib.baseboard_fab2(sch_1):page78_i13:DQ(5)" )
				( attribute "RELATIVE_PROPAGATION_DELAY_SCOPE" "G"
					( Parent
						( matchGroupRef "@baseboard_fab2_lib.baseboard_fab2(sch_1):\MG_DQ-DQS_NEAR_DIMM_NG_M_G_BYTE0\" )
					)
					( Status sCSetFlattened )
					( Origin gBackEnd )
				)
				( attribute "RELATIVE_PROPAGATION_DELAY" "0.00 MIL,195.00 MIL"
					( Parent
						( matchGroupRef "@baseboard_fab2_lib.baseboard_fab2(sch_1):\MG_DQ-DQS_NEAR_DIMM_NG_M_G_BYTE0\" )
					)
					( Units "uMatchProp" "ns" 1.000000)
					( Status sCSetFlattened )
					( Origin gBackEnd )
				)
				( attribute "RELATIVE_PROPAGATION_DELAY_SCOPE" "G"
					( Parent
						( matchGroupRef "@baseboard_fab2_lib.baseboard_fab2(sch_1):\MG_DQ_NEAR_DIMM_NG_M_G_BYTE0\" )
					)
					( Status sCSetFlattened )
					( Origin gBackEnd )
				)
				( attribute "RELATIVE_PROPAGATION_DELAY" "-50.00 MIL,50.00 MIL"
					( Parent
						( matchGroupRef "@baseboard_fab2_lib.baseboard_fab2(sch_1):\MG_DQ_NEAR_DIMM_NG_M_G_BYTE0\" )
					)
					( Units "uMatchProp" "ns" 1.000000)
					( Status sCSetFlattened )
					( Origin gBackEnd )
				)
			)
			( pinPair "@baseboard_fab2_lib.baseboard_fab2(sch_1):\PP2941\"
				( pinRef "@baseboard_fab2_lib.baseboard_fab2(sch_1):page57_i172:DDR0_DQ(6)" )
				( pinRef "@baseboard_fab2_lib.baseboard_fab2(sch_1):page77_i111:DQ(7)" )
				( attribute "RELATIVE_PROPAGATION_DELAY_SCOPE" "G"
					( Parent
						( matchGroupRef "@baseboard_fab2_lib.baseboard_fab2(sch_1):\MG_DQ-DQS_FAR_DIMM_NG_M_G_BYTE0\" )
					)
					( Status sCSetFlattened )
					( Origin gBackEnd )
				)
				( attribute "RELATIVE_PROPAGATION_DELAY" "0.00 MIL,195.00 MIL"
					( Parent
						( matchGroupRef "@baseboard_fab2_lib.baseboard_fab2(sch_1):\MG_DQ-DQS_FAR_DIMM_NG_M_G_BYTE0\" )
					)
					( Units "uMatchProp" "ns" 1.000000)
					( Status sCSetFlattened )
					( Origin gBackEnd )
				)
				( attribute "RELATIVE_PROPAGATION_DELAY_SCOPE" "G"
					( Parent
						( matchGroupRef "@baseboard_fab2_lib.baseboard_fab2(sch_1):\MG_DQ_FAR_DIMM_NG_M_G_BYTE0\" )
					)
					( Status sCSetFlattened )
					( Origin gBackEnd )
				)
				( attribute "RELATIVE_PROPAGATION_DELAY" "-50.00 MIL,50.00 MIL"
					( Parent
						( matchGroupRef "@baseboard_fab2_lib.baseboard_fab2(sch_1):\MG_DQ_FAR_DIMM_NG_M_G_BYTE0\" )
					)
					( Units "uMatchProp" "ns" 1.000000)
					( Status sCSetFlattened )
					( Origin gBackEnd )
				)
			)
			( pinPair "@baseboard_fab2_lib.baseboard_fab2(sch_1):\PP2942\"
				( pinRef "@baseboard_fab2_lib.baseboard_fab2(sch_1):page78_i13:DQ(6)" )
				( pinRef "@baseboard_fab2_lib.baseboard_fab2(sch_1):page57_i172:DDR0_DQ(6)" )
				( attribute "RELATIVE_PROPAGATION_DELAY_SCOPE" "G"
					( Parent
						( matchGroupRef "@baseboard_fab2_lib.baseboard_fab2(sch_1):\MG_DQ-DQS_NEAR_DIMM_NG_M_G_BYTE0\" )
					)
					( Status sCSetFlattened )
					( Origin gBackEnd )
				)
				( attribute "RELATIVE_PROPAGATION_DELAY" "0.00 MIL,195.00 MIL"
					( Parent
						( matchGroupRef "@baseboard_fab2_lib.baseboard_fab2(sch_1):\MG_DQ-DQS_NEAR_DIMM_NG_M_G_BYTE0\" )
					)
					( Units "uMatchProp" "ns" 1.000000)
					( Status sCSetFlattened )
					( Origin gBackEnd )
				)
				( attribute "RELATIVE_PROPAGATION_DELAY_SCOPE" "G"
					( Parent
						( matchGroupRef "@baseboard_fab2_lib.baseboard_fab2(sch_1):\MG_DQ_NEAR_DIMM_NG_M_G_BYTE0\" )
					)
					( Status sCSetFlattened )
					( Origin gBackEnd )
				)
				( attribute "RELATIVE_PROPAGATION_DELAY" "-50.00 MIL,50.00 MIL"
					( Parent
						( matchGroupRef "@baseboard_fab2_lib.baseboard_fab2(sch_1):\MG_DQ_NEAR_DIMM_NG_M_G_BYTE0\" )
					)
					( Units "uMatchProp" "ns" 1.000000)
					( Status sCSetFlattened )
					( Origin gBackEnd )
				)
			)
			( pinPair "@baseboard_fab2_lib.baseboard_fab2(sch_1):\PP2944\"
				( pinRef "@baseboard_fab2_lib.baseboard_fab2(sch_1):page57_i172:DDR0_DQ(7)" )
				( pinRef "@baseboard_fab2_lib.baseboard_fab2(sch_1):page77_i111:DQ(6)" )
				( attribute "RELATIVE_PROPAGATION_DELAY_SCOPE" "G"
					( Parent
						( matchGroupRef "@baseboard_fab2_lib.baseboard_fab2(sch_1):\MG_DQ-DQS_FAR_DIMM_NG_M_G_BYTE0\" )
					)
					( Status sCSetFlattened )
					( Origin gBackEnd )
				)
				( attribute "RELATIVE_PROPAGATION_DELAY" "0.00 MIL,195.00 MIL"
					( Parent
						( matchGroupRef "@baseboard_fab2_lib.baseboard_fab2(sch_1):\MG_DQ-DQS_FAR_DIMM_NG_M_G_BYTE0\" )
					)
					( Units "uMatchProp" "ns" 1.000000)
					( Status sCSetFlattened )
					( Origin gBackEnd )
				)
				( attribute "RELATIVE_PROPAGATION_DELAY_SCOPE" "G"
					( Parent
						( matchGroupRef "@baseboard_fab2_lib.baseboard_fab2(sch_1):\MG_DQ_FAR_DIMM_NG_M_G_BYTE0\" )
					)
					( Status sCSetFlattened )
					( Origin gBackEnd )
				)
				( attribute "RELATIVE_PROPAGATION_DELAY" "-50.00 MIL,50.00 MIL"
					( Parent
						( matchGroupRef "@baseboard_fab2_lib.baseboard_fab2(sch_1):\MG_DQ_FAR_DIMM_NG_M_G_BYTE0\" )
					)
					( Units "uMatchProp" "ns" 1.000000)
					( Status sCSetFlattened )
					( Origin gBackEnd )
				)
			)
			( pinPair "@baseboard_fab2_lib.baseboard_fab2(sch_1):\PP2945\"
				( pinRef "@baseboard_fab2_lib.baseboard_fab2(sch_1):page57_i172:DDR0_DQ(7)" )
				( pinRef "@baseboard_fab2_lib.baseboard_fab2(sch_1):page78_i13:DQ(7)" )
				( attribute "RELATIVE_PROPAGATION_DELAY_SCOPE" "G"
					( Parent
						( matchGroupRef "@baseboard_fab2_lib.baseboard_fab2(sch_1):\MG_DQ-DQS_NEAR_DIMM_NG_M_G_BYTE0\" )
					)
					( Status sCSetFlattened )
					( Origin gBackEnd )
				)
				( attribute "RELATIVE_PROPAGATION_DELAY" "0.00 MIL,195.00 MIL"
					( Parent
						( matchGroupRef "@baseboard_fab2_lib.baseboard_fab2(sch_1):\MG_DQ-DQS_NEAR_DIMM_NG_M_G_BYTE0\" )
					)
					( Units "uMatchProp" "ns" 1.000000)
					( Status sCSetFlattened )
					( Origin gBackEnd )
				)
				( attribute "RELATIVE_PROPAGATION_DELAY_SCOPE" "G"
					( Parent
						( matchGroupRef "@baseboard_fab2_lib.baseboard_fab2(sch_1):\MG_DQ_NEAR_DIMM_NG_M_G_BYTE0\" )
					)
					( Status sCSetFlattened )
					( Origin gBackEnd )
				)
				( attribute "RELATIVE_PROPAGATION_DELAY" "-50.00 MIL,50.00 MIL"
					( Parent
						( matchGroupRef "@baseboard_fab2_lib.baseboard_fab2(sch_1):\MG_DQ_NEAR_DIMM_NG_M_G_BYTE0\" )
					)
					( Units "uMatchProp" "ns" 1.000000)
					( Status sCSetFlattened )
					( Origin gBackEnd )
				)
			)
			( pinPair "@baseboard_fab2_lib.baseboard_fab2(sch_1):\PP2899\"
				( pinRef "@baseboard_fab2_lib.baseboard_fab2(sch_1):page57_i172:DDR0_DQ(8)" )
				( pinRef "@baseboard_fab2_lib.baseboard_fab2(sch_1):page77_i111:DQ(9)" )
				( attribute "RELATIVE_PROPAGATION_DELAY_SCOPE" "G"
					( Parent
						( matchGroupRef "@baseboard_fab2_lib.baseboard_fab2(sch_1):\MG_DQ-DQS_FAR_DIMM_NG_M_G_BYTE1\" )
					)
					( Status sCSetFlattened )
					( Origin gBackEnd )
				)
				( attribute "RELATIVE_PROPAGATION_DELAY" "0.00 MIL,195.00 MIL"
					( Parent
						( matchGroupRef "@baseboard_fab2_lib.baseboard_fab2(sch_1):\MG_DQ-DQS_FAR_DIMM_NG_M_G_BYTE1\" )
					)
					( Units "uMatchProp" "ns" 1.000000)
					( Status sCSetFlattened )
					( Origin gBackEnd )
				)
				( attribute "RELATIVE_PROPAGATION_DELAY_SCOPE" "G"
					( Parent
						( matchGroupRef "@baseboard_fab2_lib.baseboard_fab2(sch_1):\MG_DQ_FAR_DIMM_NG_M_G_BYTE1\" )
					)
					( Status sCSetFlattened )
					( Origin gBackEnd )
				)
				( attribute "RELATIVE_PROPAGATION_DELAY" "-50.00 MIL,50.00 MIL"
					( Parent
						( matchGroupRef "@baseboard_fab2_lib.baseboard_fab2(sch_1):\MG_DQ_FAR_DIMM_NG_M_G_BYTE1\" )
					)
					( Units "uMatchProp" "ns" 1.000000)
					( Status sCSetFlattened )
					( Origin gBackEnd )
				)
			)
			( pinPair "@baseboard_fab2_lib.baseboard_fab2(sch_1):\PP2900\"
				( pinRef "@baseboard_fab2_lib.baseboard_fab2(sch_1):page78_i13:DQ(8)" )
				( pinRef "@baseboard_fab2_lib.baseboard_fab2(sch_1):page57_i172:DDR0_DQ(8)" )
				( attribute "RELATIVE_PROPAGATION_DELAY_SCOPE" "G"
					( Parent
						( matchGroupRef "@baseboard_fab2_lib.baseboard_fab2(sch_1):\MG_DQ-DQS_NEAR_DIMM_NG_M_G_BYTE1\" )
					)
					( Status sCSetFlattened )
					( Origin gBackEnd )
				)
				( attribute "RELATIVE_PROPAGATION_DELAY" "0.00 MIL,195.00 MIL"
					( Parent
						( matchGroupRef "@baseboard_fab2_lib.baseboard_fab2(sch_1):\MG_DQ-DQS_NEAR_DIMM_NG_M_G_BYTE1\" )
					)
					( Units "uMatchProp" "ns" 1.000000)
					( Status sCSetFlattened )
					( Origin gBackEnd )
				)
				( attribute "RELATIVE_PROPAGATION_DELAY_SCOPE" "G"
					( Parent
						( matchGroupRef "@baseboard_fab2_lib.baseboard_fab2(sch_1):\MG_DQ_NEAR_DIMM_NG_M_G_BYTE1\" )
					)
					( Status sCSetFlattened )
					( Origin gBackEnd )
				)
				( attribute "RELATIVE_PROPAGATION_DELAY" "-50.00 MIL,50.00 MIL"
					( Parent
						( matchGroupRef "@baseboard_fab2_lib.baseboard_fab2(sch_1):\MG_DQ_NEAR_DIMM_NG_M_G_BYTE1\" )
					)
					( Units "uMatchProp" "ns" 1.000000)
					( Status sCSetFlattened )
					( Origin gBackEnd )
				)
			)
			( pinPair "@baseboard_fab2_lib.baseboard_fab2(sch_1):\PP2902\"
				( pinRef "@baseboard_fab2_lib.baseboard_fab2(sch_1):page57_i172:DDR0_DQ(9)" )
				( pinRef "@baseboard_fab2_lib.baseboard_fab2(sch_1):page77_i111:DQ(8)" )
				( attribute "RELATIVE_PROPAGATION_DELAY_SCOPE" "G"
					( Parent
						( matchGroupRef "@baseboard_fab2_lib.baseboard_fab2(sch_1):\MG_DQ-DQS_FAR_DIMM_NG_M_G_BYTE1\" )
					)
					( Status sCSetFlattened )
					( Origin gBackEnd )
				)
				( attribute "RELATIVE_PROPAGATION_DELAY" "0.00 MIL,195.00 MIL"
					( Parent
						( matchGroupRef "@baseboard_fab2_lib.baseboard_fab2(sch_1):\MG_DQ-DQS_FAR_DIMM_NG_M_G_BYTE1\" )
					)
					( Units "uMatchProp" "ns" 1.000000)
					( Status sCSetFlattened )
					( Origin gBackEnd )
				)
				( attribute "RELATIVE_PROPAGATION_DELAY_SCOPE" "G"
					( Parent
						( matchGroupRef "@baseboard_fab2_lib.baseboard_fab2(sch_1):\MG_DQ_FAR_DIMM_NG_M_G_BYTE1\" )
					)
					( Status sCSetFlattened )
					( Origin gBackEnd )
				)
				( attribute "RELATIVE_PROPAGATION_DELAY" "-50.00 MIL,50.00 MIL"
					( Parent
						( matchGroupRef "@baseboard_fab2_lib.baseboard_fab2(sch_1):\MG_DQ_FAR_DIMM_NG_M_G_BYTE1\" )
					)
					( Units "uMatchProp" "ns" 1.000000)
					( Status sCSetFlattened )
					( Origin gBackEnd )
				)
			)
			( pinPair "@baseboard_fab2_lib.baseboard_fab2(sch_1):\PP2903\"
				( pinRef "@baseboard_fab2_lib.baseboard_fab2(sch_1):page78_i13:DQ(9)" )
				( pinRef "@baseboard_fab2_lib.baseboard_fab2(sch_1):page57_i172:DDR0_DQ(9)" )
				( attribute "RELATIVE_PROPAGATION_DELAY_SCOPE" "G"
					( Parent
						( matchGroupRef "@baseboard_fab2_lib.baseboard_fab2(sch_1):\MG_DQ-DQS_NEAR_DIMM_NG_M_G_BYTE1\" )
					)
					( Status sCSetFlattened )
					( Origin gBackEnd )
				)
				( attribute "RELATIVE_PROPAGATION_DELAY" "0.00 MIL,195.00 MIL"
					( Parent
						( matchGroupRef "@baseboard_fab2_lib.baseboard_fab2(sch_1):\MG_DQ-DQS_NEAR_DIMM_NG_M_G_BYTE1\" )
					)
					( Units "uMatchProp" "ns" 1.000000)
					( Status sCSetFlattened )
					( Origin gBackEnd )
				)
				( attribute "RELATIVE_PROPAGATION_DELAY_SCOPE" "G"
					( Parent
						( matchGroupRef "@baseboard_fab2_lib.baseboard_fab2(sch_1):\MG_DQ_NEAR_DIMM_NG_M_G_BYTE1\" )
					)
					( Status sCSetFlattened )
					( Origin gBackEnd )
				)
				( attribute "RELATIVE_PROPAGATION_DELAY" "-50.00 MIL,50.00 MIL"
					( Parent
						( matchGroupRef "@baseboard_fab2_lib.baseboard_fab2(sch_1):\MG_DQ_NEAR_DIMM_NG_M_G_BYTE1\" )
					)
					( Units "uMatchProp" "ns" 1.000000)
					( Status sCSetFlattened )
					( Origin gBackEnd )
				)
			)
			( pinPair "@baseboard_fab2_lib.baseboard_fab2(sch_1):\PP2908\"
				( pinRef "@baseboard_fab2_lib.baseboard_fab2(sch_1):page57_i172:DDR0_DQ(11)" )
				( pinRef "@baseboard_fab2_lib.baseboard_fab2(sch_1):page77_i111:DQ(10)" )
				( attribute "RELATIVE_PROPAGATION_DELAY_SCOPE" "G"
					( Parent
						( matchGroupRef "@baseboard_fab2_lib.baseboard_fab2(sch_1):\MG_DQ-DQS_FAR_DIMM_NG_M_G_BYTE1\" )
					)
					( Status sCSetFlattened )
					( Origin gBackEnd )
				)
				( attribute "RELATIVE_PROPAGATION_DELAY" "0.00 MIL,195.00 MIL"
					( Parent
						( matchGroupRef "@baseboard_fab2_lib.baseboard_fab2(sch_1):\MG_DQ-DQS_FAR_DIMM_NG_M_G_BYTE1\" )
					)
					( Units "uMatchProp" "ns" 1.000000)
					( Status sCSetFlattened )
					( Origin gBackEnd )
				)
				( attribute "RELATIVE_PROPAGATION_DELAY_SCOPE" "G"
					( Parent
						( matchGroupRef "@baseboard_fab2_lib.baseboard_fab2(sch_1):\MG_DQ_FAR_DIMM_NG_M_G_BYTE1\" )
					)
					( Status sCSetFlattened )
					( Origin gBackEnd )
				)
				( attribute "RELATIVE_PROPAGATION_DELAY" "-50.00 MIL,50.00 MIL"
					( Parent
						( matchGroupRef "@baseboard_fab2_lib.baseboard_fab2(sch_1):\MG_DQ_FAR_DIMM_NG_M_G_BYTE1\" )
					)
					( Units "uMatchProp" "ns" 1.000000)
					( Status sCSetFlattened )
					( Origin gBackEnd )
				)
			)
			( pinPair "@baseboard_fab2_lib.baseboard_fab2(sch_1):\PP2909\"
				( pinRef "@baseboard_fab2_lib.baseboard_fab2(sch_1):page78_i13:DQ(11)" )
				( pinRef "@baseboard_fab2_lib.baseboard_fab2(sch_1):page57_i172:DDR0_DQ(11)" )
				( attribute "RELATIVE_PROPAGATION_DELAY_SCOPE" "G"
					( Parent
						( matchGroupRef "@baseboard_fab2_lib.baseboard_fab2(sch_1):\MG_DQ-DQS_NEAR_DIMM_NG_M_G_BYTE1\" )
					)
					( Status sCSetFlattened )
					( Origin gBackEnd )
				)
				( attribute "RELATIVE_PROPAGATION_DELAY" "0.00 MIL,195.00 MIL"
					( Parent
						( matchGroupRef "@baseboard_fab2_lib.baseboard_fab2(sch_1):\MG_DQ-DQS_NEAR_DIMM_NG_M_G_BYTE1\" )
					)
					( Units "uMatchProp" "ns" 1.000000)
					( Status sCSetFlattened )
					( Origin gBackEnd )
				)
				( attribute "RELATIVE_PROPAGATION_DELAY_SCOPE" "G"
					( Parent
						( matchGroupRef "@baseboard_fab2_lib.baseboard_fab2(sch_1):\MG_DQ_NEAR_DIMM_NG_M_G_BYTE1\" )
					)
					( Status sCSetFlattened )
					( Origin gBackEnd )
				)
				( attribute "RELATIVE_PROPAGATION_DELAY" "-50.00 MIL,50.00 MIL"
					( Parent
						( matchGroupRef "@baseboard_fab2_lib.baseboard_fab2(sch_1):\MG_DQ_NEAR_DIMM_NG_M_G_BYTE1\" )
					)
					( Units "uMatchProp" "ns" 1.000000)
					( Status sCSetFlattened )
					( Origin gBackEnd )
				)
			)
			( pinPair "@baseboard_fab2_lib.baseboard_fab2(sch_1):\PP2911\"
				( pinRef "@baseboard_fab2_lib.baseboard_fab2(sch_1):page57_i172:DDR0_DQ(12)" )
				( pinRef "@baseboard_fab2_lib.baseboard_fab2(sch_1):page77_i111:DQ(13)" )
				( attribute "RELATIVE_PROPAGATION_DELAY_SCOPE" "G"
					( Parent
						( matchGroupRef "@baseboard_fab2_lib.baseboard_fab2(sch_1):\MG_DQ-DQS_FAR_DIMM_NG_M_G_BYTE1\" )
					)
					( Status sCSetFlattened )
					( Origin gBackEnd )
				)
				( attribute "RELATIVE_PROPAGATION_DELAY" "0.00 MIL,195.00 MIL"
					( Parent
						( matchGroupRef "@baseboard_fab2_lib.baseboard_fab2(sch_1):\MG_DQ-DQS_FAR_DIMM_NG_M_G_BYTE1\" )
					)
					( Units "uMatchProp" "ns" 1.000000)
					( Status sCSetFlattened )
					( Origin gBackEnd )
				)
				( attribute "RELATIVE_PROPAGATION_DELAY_SCOPE" "G"
					( Parent
						( matchGroupRef "@baseboard_fab2_lib.baseboard_fab2(sch_1):\MG_DQ_FAR_DIMM_NG_M_G_BYTE1\" )
					)
					( Status sCSetFlattened )
					( Origin gBackEnd )
				)
				( attribute "RELATIVE_PROPAGATION_DELAY" "-50.00 MIL,50.00 MIL"
					( Parent
						( matchGroupRef "@baseboard_fab2_lib.baseboard_fab2(sch_1):\MG_DQ_FAR_DIMM_NG_M_G_BYTE1\" )
					)
					( Units "uMatchProp" "ns" 1.000000)
					( Status sCSetFlattened )
					( Origin gBackEnd )
				)
			)
			( pinPair "@baseboard_fab2_lib.baseboard_fab2(sch_1):\PP2912\"
				( pinRef "@baseboard_fab2_lib.baseboard_fab2(sch_1):page78_i13:DQ(12)" )
				( pinRef "@baseboard_fab2_lib.baseboard_fab2(sch_1):page57_i172:DDR0_DQ(12)" )
				( attribute "RELATIVE_PROPAGATION_DELAY_SCOPE" "G"
					( Parent
						( matchGroupRef "@baseboard_fab2_lib.baseboard_fab2(sch_1):\MG_DQ-DQS_NEAR_DIMM_NG_M_G_BYTE1\" )
					)
					( Status sCSetFlattened )
					( Origin gBackEnd )
				)
				( attribute "RELATIVE_PROPAGATION_DELAY" "0.00 MIL,195.00 MIL"
					( Parent
						( matchGroupRef "@baseboard_fab2_lib.baseboard_fab2(sch_1):\MG_DQ-DQS_NEAR_DIMM_NG_M_G_BYTE1\" )
					)
					( Units "uMatchProp" "ns" 1.000000)
					( Status sCSetFlattened )
					( Origin gBackEnd )
				)
				( attribute "RELATIVE_PROPAGATION_DELAY_SCOPE" "G"
					( Parent
						( matchGroupRef "@baseboard_fab2_lib.baseboard_fab2(sch_1):\MG_DQ_NEAR_DIMM_NG_M_G_BYTE1\" )
					)
					( Status sCSetFlattened )
					( Origin gBackEnd )
				)
				( attribute "RELATIVE_PROPAGATION_DELAY" "-50.00 MIL,50.00 MIL"
					( Parent
						( matchGroupRef "@baseboard_fab2_lib.baseboard_fab2(sch_1):\MG_DQ_NEAR_DIMM_NG_M_G_BYTE1\" )
					)
					( Units "uMatchProp" "ns" 1.000000)
					( Status sCSetFlattened )
					( Origin gBackEnd )
				)
			)
			( pinPair "@baseboard_fab2_lib.baseboard_fab2(sch_1):\PP2914\"
				( pinRef "@baseboard_fab2_lib.baseboard_fab2(sch_1):page57_i172:DDR0_DQ(13)" )
				( pinRef "@baseboard_fab2_lib.baseboard_fab2(sch_1):page77_i111:DQ(12)" )
				( attribute "RELATIVE_PROPAGATION_DELAY_SCOPE" "G"
					( Parent
						( matchGroupRef "@baseboard_fab2_lib.baseboard_fab2(sch_1):\MG_DQ-DQS_FAR_DIMM_NG_M_G_BYTE1\" )
					)
					( Status sCSetFlattened )
					( Origin gBackEnd )
				)
				( attribute "RELATIVE_PROPAGATION_DELAY" "0.00 MIL,195.00 MIL"
					( Parent
						( matchGroupRef "@baseboard_fab2_lib.baseboard_fab2(sch_1):\MG_DQ-DQS_FAR_DIMM_NG_M_G_BYTE1\" )
					)
					( Units "uMatchProp" "ns" 1.000000)
					( Status sCSetFlattened )
					( Origin gBackEnd )
				)
				( attribute "RELATIVE_PROPAGATION_DELAY_SCOPE" "G"
					( Parent
						( matchGroupRef "@baseboard_fab2_lib.baseboard_fab2(sch_1):\MG_DQ_FAR_DIMM_NG_M_G_BYTE1\" )
					)
					( Status sCSetFlattened )
					( Origin gBackEnd )
				)
				( attribute "RELATIVE_PROPAGATION_DELAY" "-50.00 MIL,50.00 MIL"
					( Parent
						( matchGroupRef "@baseboard_fab2_lib.baseboard_fab2(sch_1):\MG_DQ_FAR_DIMM_NG_M_G_BYTE1\" )
					)
					( Units "uMatchProp" "ns" 1.000000)
					( Status sCSetFlattened )
					( Origin gBackEnd )
				)
			)
			( pinPair "@baseboard_fab2_lib.baseboard_fab2(sch_1):\PP2915\"
				( pinRef "@baseboard_fab2_lib.baseboard_fab2(sch_1):page78_i13:DQ(13)" )
				( pinRef "@baseboard_fab2_lib.baseboard_fab2(sch_1):page57_i172:DDR0_DQ(13)" )
				( attribute "RELATIVE_PROPAGATION_DELAY_SCOPE" "G"
					( Parent
						( matchGroupRef "@baseboard_fab2_lib.baseboard_fab2(sch_1):\MG_DQ-DQS_NEAR_DIMM_NG_M_G_BYTE1\" )
					)
					( Status sCSetFlattened )
					( Origin gBackEnd )
				)
				( attribute "RELATIVE_PROPAGATION_DELAY" "0.00 MIL,195.00 MIL"
					( Parent
						( matchGroupRef "@baseboard_fab2_lib.baseboard_fab2(sch_1):\MG_DQ-DQS_NEAR_DIMM_NG_M_G_BYTE1\" )
					)
					( Units "uMatchProp" "ns" 1.000000)
					( Status sCSetFlattened )
					( Origin gBackEnd )
				)
				( attribute "RELATIVE_PROPAGATION_DELAY_SCOPE" "G"
					( Parent
						( matchGroupRef "@baseboard_fab2_lib.baseboard_fab2(sch_1):\MG_DQ_NEAR_DIMM_NG_M_G_BYTE1\" )
					)
					( Status sCSetFlattened )
					( Origin gBackEnd )
				)
				( attribute "RELATIVE_PROPAGATION_DELAY" "-50.00 MIL,50.00 MIL"
					( Parent
						( matchGroupRef "@baseboard_fab2_lib.baseboard_fab2(sch_1):\MG_DQ_NEAR_DIMM_NG_M_G_BYTE1\" )
					)
					( Units "uMatchProp" "ns" 1.000000)
					( Status sCSetFlattened )
					( Origin gBackEnd )
				)
			)
			( pinPair "@baseboard_fab2_lib.baseboard_fab2(sch_1):\PP2917\"
				( pinRef "@baseboard_fab2_lib.baseboard_fab2(sch_1):page57_i172:DDR0_DQ(14)" )
				( pinRef "@baseboard_fab2_lib.baseboard_fab2(sch_1):page77_i111:DQ(15)" )
				( attribute "RELATIVE_PROPAGATION_DELAY_SCOPE" "G"
					( Parent
						( matchGroupRef "@baseboard_fab2_lib.baseboard_fab2(sch_1):\MG_DQ-DQS_FAR_DIMM_NG_M_G_BYTE1\" )
					)
					( Status sCSetFlattened )
					( Origin gBackEnd )
				)
				( attribute "RELATIVE_PROPAGATION_DELAY" "0.00 MIL,195.00 MIL"
					( Parent
						( matchGroupRef "@baseboard_fab2_lib.baseboard_fab2(sch_1):\MG_DQ-DQS_FAR_DIMM_NG_M_G_BYTE1\" )
					)
					( Units "uMatchProp" "ns" 1.000000)
					( Status sCSetFlattened )
					( Origin gBackEnd )
				)
				( attribute "RELATIVE_PROPAGATION_DELAY_SCOPE" "G"
					( Parent
						( matchGroupRef "@baseboard_fab2_lib.baseboard_fab2(sch_1):\MG_DQ_FAR_DIMM_NG_M_G_BYTE1\" )
					)
					( Status sCSetFlattened )
					( Origin gBackEnd )
				)
				( attribute "RELATIVE_PROPAGATION_DELAY" "-50.00 MIL,50.00 MIL"
					( Parent
						( matchGroupRef "@baseboard_fab2_lib.baseboard_fab2(sch_1):\MG_DQ_FAR_DIMM_NG_M_G_BYTE1\" )
					)
					( Units "uMatchProp" "ns" 1.000000)
					( Status sCSetFlattened )
					( Origin gBackEnd )
				)
			)
			( pinPair "@baseboard_fab2_lib.baseboard_fab2(sch_1):\PP2918\"
				( pinRef "@baseboard_fab2_lib.baseboard_fab2(sch_1):page78_i13:DQ(14)" )
				( pinRef "@baseboard_fab2_lib.baseboard_fab2(sch_1):page57_i172:DDR0_DQ(14)" )
				( attribute "RELATIVE_PROPAGATION_DELAY_SCOPE" "G"
					( Parent
						( matchGroupRef "@baseboard_fab2_lib.baseboard_fab2(sch_1):\MG_DQ-DQS_NEAR_DIMM_NG_M_G_BYTE1\" )
					)
					( Status sCSetFlattened )
					( Origin gBackEnd )
				)
				( attribute "RELATIVE_PROPAGATION_DELAY" "0.00 MIL,195.00 MIL"
					( Parent
						( matchGroupRef "@baseboard_fab2_lib.baseboard_fab2(sch_1):\MG_DQ-DQS_NEAR_DIMM_NG_M_G_BYTE1\" )
					)
					( Units "uMatchProp" "ns" 1.000000)
					( Status sCSetFlattened )
					( Origin gBackEnd )
				)
				( attribute "RELATIVE_PROPAGATION_DELAY_SCOPE" "G"
					( Parent
						( matchGroupRef "@baseboard_fab2_lib.baseboard_fab2(sch_1):\MG_DQ_NEAR_DIMM_NG_M_G_BYTE1\" )
					)
					( Status sCSetFlattened )
					( Origin gBackEnd )
				)
				( attribute "RELATIVE_PROPAGATION_DELAY" "-50.00 MIL,50.00 MIL"
					( Parent
						( matchGroupRef "@baseboard_fab2_lib.baseboard_fab2(sch_1):\MG_DQ_NEAR_DIMM_NG_M_G_BYTE1\" )
					)
					( Units "uMatchProp" "ns" 1.000000)
					( Status sCSetFlattened )
					( Origin gBackEnd )
				)
			)
			( pinPair "@baseboard_fab2_lib.baseboard_fab2(sch_1):\PP2920\"
				( pinRef "@baseboard_fab2_lib.baseboard_fab2(sch_1):page57_i172:DDR0_DQ(15)" )
				( pinRef "@baseboard_fab2_lib.baseboard_fab2(sch_1):page77_i111:DQ(14)" )
				( attribute "RELATIVE_PROPAGATION_DELAY_SCOPE" "G"
					( Parent
						( matchGroupRef "@baseboard_fab2_lib.baseboard_fab2(sch_1):\MG_DQ-DQS_FAR_DIMM_NG_M_G_BYTE1\" )
					)
					( Status sCSetFlattened )
					( Origin gBackEnd )
				)
				( attribute "RELATIVE_PROPAGATION_DELAY" "0.00 MIL,195.00 MIL"
					( Parent
						( matchGroupRef "@baseboard_fab2_lib.baseboard_fab2(sch_1):\MG_DQ-DQS_FAR_DIMM_NG_M_G_BYTE1\" )
					)
					( Units "uMatchProp" "ns" 1.000000)
					( Status sCSetFlattened )
					( Origin gBackEnd )
				)
				( attribute "RELATIVE_PROPAGATION_DELAY_SCOPE" "G"
					( Parent
						( matchGroupRef "@baseboard_fab2_lib.baseboard_fab2(sch_1):\MG_DQ_FAR_DIMM_NG_M_G_BYTE1\" )
					)
					( Status sCSetFlattened )
					( Origin gBackEnd )
				)
				( attribute "RELATIVE_PROPAGATION_DELAY" "-50.00 MIL,50.00 MIL"
					( Parent
						( matchGroupRef "@baseboard_fab2_lib.baseboard_fab2(sch_1):\MG_DQ_FAR_DIMM_NG_M_G_BYTE1\" )
					)
					( Units "uMatchProp" "ns" 1.000000)
					( Status sCSetFlattened )
					( Origin gBackEnd )
				)
			)
			( pinPair "@baseboard_fab2_lib.baseboard_fab2(sch_1):\PP2921\"
				( pinRef "@baseboard_fab2_lib.baseboard_fab2(sch_1):page78_i13:DQ(15)" )
				( pinRef "@baseboard_fab2_lib.baseboard_fab2(sch_1):page57_i172:DDR0_DQ(15)" )
				( attribute "RELATIVE_PROPAGATION_DELAY_SCOPE" "G"
					( Parent
						( matchGroupRef "@baseboard_fab2_lib.baseboard_fab2(sch_1):\MG_DQ-DQS_NEAR_DIMM_NG_M_G_BYTE1\" )
					)
					( Status sCSetFlattened )
					( Origin gBackEnd )
				)
				( attribute "RELATIVE_PROPAGATION_DELAY" "0.00 MIL,195.00 MIL"
					( Parent
						( matchGroupRef "@baseboard_fab2_lib.baseboard_fab2(sch_1):\MG_DQ-DQS_NEAR_DIMM_NG_M_G_BYTE1\" )
					)
					( Units "uMatchProp" "ns" 1.000000)
					( Status sCSetFlattened )
					( Origin gBackEnd )
				)
				( attribute "RELATIVE_PROPAGATION_DELAY_SCOPE" "G"
					( Parent
						( matchGroupRef "@baseboard_fab2_lib.baseboard_fab2(sch_1):\MG_DQ_NEAR_DIMM_NG_M_G_BYTE1\" )
					)
					( Status sCSetFlattened )
					( Origin gBackEnd )
				)
				( attribute "RELATIVE_PROPAGATION_DELAY" "-50.00 MIL,50.00 MIL"
					( Parent
						( matchGroupRef "@baseboard_fab2_lib.baseboard_fab2(sch_1):\MG_DQ_NEAR_DIMM_NG_M_G_BYTE1\" )
					)
					( Units "uMatchProp" "ns" 1.000000)
					( Status sCSetFlattened )
					( Origin gBackEnd )
				)
			)
			( pinPair "@baseboard_fab2_lib.baseboard_fab2(sch_1):\PP2875\"
				( pinRef "@baseboard_fab2_lib.baseboard_fab2(sch_1):page57_i172:DDR0_DQ(16)" )
				( pinRef "@baseboard_fab2_lib.baseboard_fab2(sch_1):page77_i111:DQ(17)" )
				( attribute "RELATIVE_PROPAGATION_DELAY_SCOPE" "G"
					( Parent
						( matchGroupRef "@baseboard_fab2_lib.baseboard_fab2(sch_1):\MG_DQ-DQS_FAR_DIMM_NG_M_G_BYTE2\" )
					)
					( Status sCSetFlattened )
					( Origin gBackEnd )
				)
				( attribute "RELATIVE_PROPAGATION_DELAY" "0.00 MIL,195.00 MIL"
					( Parent
						( matchGroupRef "@baseboard_fab2_lib.baseboard_fab2(sch_1):\MG_DQ-DQS_FAR_DIMM_NG_M_G_BYTE2\" )
					)
					( Units "uMatchProp" "ns" 1.000000)
					( Status sCSetFlattened )
					( Origin gBackEnd )
				)
				( attribute "RELATIVE_PROPAGATION_DELAY_SCOPE" "G"
					( Parent
						( matchGroupRef "@baseboard_fab2_lib.baseboard_fab2(sch_1):\MG_DQ_FAR_DIMM_NG_M_G_BYTE2\" )
					)
					( Status sCSetFlattened )
					( Origin gBackEnd )
				)
				( attribute "RELATIVE_PROPAGATION_DELAY" "-50.00 MIL,50.00 MIL"
					( Parent
						( matchGroupRef "@baseboard_fab2_lib.baseboard_fab2(sch_1):\MG_DQ_FAR_DIMM_NG_M_G_BYTE2\" )
					)
					( Units "uMatchProp" "ns" 1.000000)
					( Status sCSetFlattened )
					( Origin gBackEnd )
				)
			)
			( pinPair "@baseboard_fab2_lib.baseboard_fab2(sch_1):\PP2876\"
				( pinRef "@baseboard_fab2_lib.baseboard_fab2(sch_1):page78_i13:DQ(16)" )
				( pinRef "@baseboard_fab2_lib.baseboard_fab2(sch_1):page57_i172:DDR0_DQ(16)" )
				( attribute "RELATIVE_PROPAGATION_DELAY_SCOPE" "G"
					( Parent
						( matchGroupRef "@baseboard_fab2_lib.baseboard_fab2(sch_1):\MG_DQ-DQS_NEAR_DIMM_NG_M_G_BYTE2\" )
					)
					( Status sCSetFlattened )
					( Origin gBackEnd )
				)
				( attribute "RELATIVE_PROPAGATION_DELAY" "0.00 MIL,195.00 MIL"
					( Parent
						( matchGroupRef "@baseboard_fab2_lib.baseboard_fab2(sch_1):\MG_DQ-DQS_NEAR_DIMM_NG_M_G_BYTE2\" )
					)
					( Units "uMatchProp" "ns" 1.000000)
					( Status sCSetFlattened )
					( Origin gBackEnd )
				)
				( attribute "RELATIVE_PROPAGATION_DELAY_SCOPE" "G"
					( Parent
						( matchGroupRef "@baseboard_fab2_lib.baseboard_fab2(sch_1):\MG_DQ_NEAR_DIMM_NG_M_G_BYTE2\" )
					)
					( Status sCSetFlattened )
					( Origin gBackEnd )
				)
				( attribute "RELATIVE_PROPAGATION_DELAY" "-50.00 MIL,50.00 MIL"
					( Parent
						( matchGroupRef "@baseboard_fab2_lib.baseboard_fab2(sch_1):\MG_DQ_NEAR_DIMM_NG_M_G_BYTE2\" )
					)
					( Units "uMatchProp" "ns" 1.000000)
					( Status sCSetFlattened )
					( Origin gBackEnd )
				)
			)
			( pinPair "@baseboard_fab2_lib.baseboard_fab2(sch_1):\PP2878\"
				( pinRef "@baseboard_fab2_lib.baseboard_fab2(sch_1):page57_i172:DDR0_DQ(17)" )
				( pinRef "@baseboard_fab2_lib.baseboard_fab2(sch_1):page77_i111:DQ(16)" )
				( attribute "RELATIVE_PROPAGATION_DELAY_SCOPE" "G"
					( Parent
						( matchGroupRef "@baseboard_fab2_lib.baseboard_fab2(sch_1):\MG_DQ-DQS_FAR_DIMM_NG_M_G_BYTE2\" )
					)
					( Status sCSetFlattened )
					( Origin gBackEnd )
				)
				( attribute "RELATIVE_PROPAGATION_DELAY" "0.00 MIL,195.00 MIL"
					( Parent
						( matchGroupRef "@baseboard_fab2_lib.baseboard_fab2(sch_1):\MG_DQ-DQS_FAR_DIMM_NG_M_G_BYTE2\" )
					)
					( Units "uMatchProp" "ns" 1.000000)
					( Status sCSetFlattened )
					( Origin gBackEnd )
				)
				( attribute "RELATIVE_PROPAGATION_DELAY_SCOPE" "G"
					( Parent
						( matchGroupRef "@baseboard_fab2_lib.baseboard_fab2(sch_1):\MG_DQ_FAR_DIMM_NG_M_G_BYTE2\" )
					)
					( Status sCSetFlattened )
					( Origin gBackEnd )
				)
				( attribute "RELATIVE_PROPAGATION_DELAY" "-50.00 MIL,50.00 MIL"
					( Parent
						( matchGroupRef "@baseboard_fab2_lib.baseboard_fab2(sch_1):\MG_DQ_FAR_DIMM_NG_M_G_BYTE2\" )
					)
					( Units "uMatchProp" "ns" 1.000000)
					( Status sCSetFlattened )
					( Origin gBackEnd )
				)
			)
			( pinPair "@baseboard_fab2_lib.baseboard_fab2(sch_1):\PP2879\"
				( pinRef "@baseboard_fab2_lib.baseboard_fab2(sch_1):page78_i13:DQ(17)" )
				( pinRef "@baseboard_fab2_lib.baseboard_fab2(sch_1):page57_i172:DDR0_DQ(17)" )
				( attribute "RELATIVE_PROPAGATION_DELAY_SCOPE" "G"
					( Parent
						( matchGroupRef "@baseboard_fab2_lib.baseboard_fab2(sch_1):\MG_DQ-DQS_NEAR_DIMM_NG_M_G_BYTE2\" )
					)
					( Status sCSetFlattened )
					( Origin gBackEnd )
				)
				( attribute "RELATIVE_PROPAGATION_DELAY" "0.00 MIL,195.00 MIL"
					( Parent
						( matchGroupRef "@baseboard_fab2_lib.baseboard_fab2(sch_1):\MG_DQ-DQS_NEAR_DIMM_NG_M_G_BYTE2\" )
					)
					( Units "uMatchProp" "ns" 1.000000)
					( Status sCSetFlattened )
					( Origin gBackEnd )
				)
				( attribute "RELATIVE_PROPAGATION_DELAY_SCOPE" "G"
					( Parent
						( matchGroupRef "@baseboard_fab2_lib.baseboard_fab2(sch_1):\MG_DQ_NEAR_DIMM_NG_M_G_BYTE2\" )
					)
					( Status sCSetFlattened )
					( Origin gBackEnd )
				)
				( attribute "RELATIVE_PROPAGATION_DELAY" "-50.00 MIL,50.00 MIL"
					( Parent
						( matchGroupRef "@baseboard_fab2_lib.baseboard_fab2(sch_1):\MG_DQ_NEAR_DIMM_NG_M_G_BYTE2\" )
					)
					( Units "uMatchProp" "ns" 1.000000)
					( Status sCSetFlattened )
					( Origin gBackEnd )
				)
			)
			( pinPair "@baseboard_fab2_lib.baseboard_fab2(sch_1):\PP2881\"
				( pinRef "@baseboard_fab2_lib.baseboard_fab2(sch_1):page57_i172:DDR0_DQ(18)" )
				( pinRef "@baseboard_fab2_lib.baseboard_fab2(sch_1):page77_i111:DQ(19)" )
				( attribute "RELATIVE_PROPAGATION_DELAY_SCOPE" "G"
					( Parent
						( matchGroupRef "@baseboard_fab2_lib.baseboard_fab2(sch_1):\MG_DQ-DQS_FAR_DIMM_NG_M_G_BYTE2\" )
					)
					( Status sCSetFlattened )
					( Origin gBackEnd )
				)
				( attribute "RELATIVE_PROPAGATION_DELAY" "0.00 MIL,195.00 MIL"
					( Parent
						( matchGroupRef "@baseboard_fab2_lib.baseboard_fab2(sch_1):\MG_DQ-DQS_FAR_DIMM_NG_M_G_BYTE2\" )
					)
					( Units "uMatchProp" "ns" 1.000000)
					( Status sCSetFlattened )
					( Origin gBackEnd )
				)
				( attribute "RELATIVE_PROPAGATION_DELAY_SCOPE" "G"
					( Parent
						( matchGroupRef "@baseboard_fab2_lib.baseboard_fab2(sch_1):\MG_DQ_FAR_DIMM_NG_M_G_BYTE2\" )
					)
					( Status sCSetFlattened )
					( Origin gBackEnd )
				)
				( attribute "RELATIVE_PROPAGATION_DELAY" "-50.00 MIL,50.00 MIL"
					( Parent
						( matchGroupRef "@baseboard_fab2_lib.baseboard_fab2(sch_1):\MG_DQ_FAR_DIMM_NG_M_G_BYTE2\" )
					)
					( Units "uMatchProp" "ns" 1.000000)
					( Status sCSetFlattened )
					( Origin gBackEnd )
				)
			)
			( pinPair "@baseboard_fab2_lib.baseboard_fab2(sch_1):\PP2882\"
				( pinRef "@baseboard_fab2_lib.baseboard_fab2(sch_1):page78_i13:DQ(18)" )
				( pinRef "@baseboard_fab2_lib.baseboard_fab2(sch_1):page57_i172:DDR0_DQ(18)" )
				( attribute "RELATIVE_PROPAGATION_DELAY_SCOPE" "G"
					( Parent
						( matchGroupRef "@baseboard_fab2_lib.baseboard_fab2(sch_1):\MG_DQ-DQS_NEAR_DIMM_NG_M_G_BYTE2\" )
					)
					( Status sCSetFlattened )
					( Origin gBackEnd )
				)
				( attribute "RELATIVE_PROPAGATION_DELAY" "0.00 MIL,195.00 MIL"
					( Parent
						( matchGroupRef "@baseboard_fab2_lib.baseboard_fab2(sch_1):\MG_DQ-DQS_NEAR_DIMM_NG_M_G_BYTE2\" )
					)
					( Units "uMatchProp" "ns" 1.000000)
					( Status sCSetFlattened )
					( Origin gBackEnd )
				)
				( attribute "RELATIVE_PROPAGATION_DELAY_SCOPE" "G"
					( Parent
						( matchGroupRef "@baseboard_fab2_lib.baseboard_fab2(sch_1):\MG_DQ_NEAR_DIMM_NG_M_G_BYTE2\" )
					)
					( Status sCSetFlattened )
					( Origin gBackEnd )
				)
				( attribute "RELATIVE_PROPAGATION_DELAY" "-50.00 MIL,50.00 MIL"
					( Parent
						( matchGroupRef "@baseboard_fab2_lib.baseboard_fab2(sch_1):\MG_DQ_NEAR_DIMM_NG_M_G_BYTE2\" )
					)
					( Units "uMatchProp" "ns" 1.000000)
					( Status sCSetFlattened )
					( Origin gBackEnd )
				)
			)
			( pinPair "@baseboard_fab2_lib.baseboard_fab2(sch_1):\PP2884\"
				( pinRef "@baseboard_fab2_lib.baseboard_fab2(sch_1):page57_i172:DDR0_DQ(19)" )
				( pinRef "@baseboard_fab2_lib.baseboard_fab2(sch_1):page77_i111:DQ(18)" )
				( attribute "RELATIVE_PROPAGATION_DELAY_SCOPE" "G"
					( Parent
						( matchGroupRef "@baseboard_fab2_lib.baseboard_fab2(sch_1):\MG_DQ-DQS_FAR_DIMM_NG_M_G_BYTE2\" )
					)
					( Status sCSetFlattened )
					( Origin gBackEnd )
				)
				( attribute "RELATIVE_PROPAGATION_DELAY" "0.00 MIL,195.00 MIL"
					( Parent
						( matchGroupRef "@baseboard_fab2_lib.baseboard_fab2(sch_1):\MG_DQ-DQS_FAR_DIMM_NG_M_G_BYTE2\" )
					)
					( Units "uMatchProp" "ns" 1.000000)
					( Status sCSetFlattened )
					( Origin gBackEnd )
				)
				( attribute "RELATIVE_PROPAGATION_DELAY_SCOPE" "G"
					( Parent
						( matchGroupRef "@baseboard_fab2_lib.baseboard_fab2(sch_1):\MG_DQ_FAR_DIMM_NG_M_G_BYTE2\" )
					)
					( Status sCSetFlattened )
					( Origin gBackEnd )
				)
				( attribute "RELATIVE_PROPAGATION_DELAY" "-50.00 MIL,50.00 MIL"
					( Parent
						( matchGroupRef "@baseboard_fab2_lib.baseboard_fab2(sch_1):\MG_DQ_FAR_DIMM_NG_M_G_BYTE2\" )
					)
					( Units "uMatchProp" "ns" 1.000000)
					( Status sCSetFlattened )
					( Origin gBackEnd )
				)
			)
			( pinPair "@baseboard_fab2_lib.baseboard_fab2(sch_1):\PP2885\"
				( pinRef "@baseboard_fab2_lib.baseboard_fab2(sch_1):page57_i172:DDR0_DQ(19)" )
				( pinRef "@baseboard_fab2_lib.baseboard_fab2(sch_1):page78_i13:DQ(19)" )
				( attribute "RELATIVE_PROPAGATION_DELAY_SCOPE" "G"
					( Parent
						( matchGroupRef "@baseboard_fab2_lib.baseboard_fab2(sch_1):\MG_DQ-DQS_NEAR_DIMM_NG_M_G_BYTE2\" )
					)
					( Status sCSetFlattened )
					( Origin gBackEnd )
				)
				( attribute "RELATIVE_PROPAGATION_DELAY" "0.00 MIL,195.00 MIL"
					( Parent
						( matchGroupRef "@baseboard_fab2_lib.baseboard_fab2(sch_1):\MG_DQ-DQS_NEAR_DIMM_NG_M_G_BYTE2\" )
					)
					( Units "uMatchProp" "ns" 1.000000)
					( Status sCSetFlattened )
					( Origin gBackEnd )
				)
				( attribute "RELATIVE_PROPAGATION_DELAY_SCOPE" "G"
					( Parent
						( matchGroupRef "@baseboard_fab2_lib.baseboard_fab2(sch_1):\MG_DQ_NEAR_DIMM_NG_M_G_BYTE2\" )
					)
					( Status sCSetFlattened )
					( Origin gBackEnd )
				)
				( attribute "RELATIVE_PROPAGATION_DELAY" "-50.00 MIL,50.00 MIL"
					( Parent
						( matchGroupRef "@baseboard_fab2_lib.baseboard_fab2(sch_1):\MG_DQ_NEAR_DIMM_NG_M_G_BYTE2\" )
					)
					( Units "uMatchProp" "ns" 1.000000)
					( Status sCSetFlattened )
					( Origin gBackEnd )
				)
			)
			( pinPair "@baseboard_fab2_lib.baseboard_fab2(sch_1):\PP2887\"
				( pinRef "@baseboard_fab2_lib.baseboard_fab2(sch_1):page57_i172:DDR0_DQ(20)" )
				( pinRef "@baseboard_fab2_lib.baseboard_fab2(sch_1):page77_i111:DQ(21)" )
				( attribute "RELATIVE_PROPAGATION_DELAY_SCOPE" "G"
					( Parent
						( matchGroupRef "@baseboard_fab2_lib.baseboard_fab2(sch_1):\MG_DQ-DQS_FAR_DIMM_NG_M_G_BYTE2\" )
					)
					( Status sCSetFlattened )
					( Origin gBackEnd )
				)
				( attribute "RELATIVE_PROPAGATION_DELAY" "0.00 MIL,195.00 MIL"
					( Parent
						( matchGroupRef "@baseboard_fab2_lib.baseboard_fab2(sch_1):\MG_DQ-DQS_FAR_DIMM_NG_M_G_BYTE2\" )
					)
					( Units "uMatchProp" "ns" 1.000000)
					( Status sCSetFlattened )
					( Origin gBackEnd )
				)
				( attribute "RELATIVE_PROPAGATION_DELAY_SCOPE" "G"
					( Parent
						( matchGroupRef "@baseboard_fab2_lib.baseboard_fab2(sch_1):\MG_DQ_FAR_DIMM_NG_M_G_BYTE2\" )
					)
					( Status sCSetFlattened )
					( Origin gBackEnd )
				)
				( attribute "RELATIVE_PROPAGATION_DELAY" "-50.00 MIL,50.00 MIL"
					( Parent
						( matchGroupRef "@baseboard_fab2_lib.baseboard_fab2(sch_1):\MG_DQ_FAR_DIMM_NG_M_G_BYTE2\" )
					)
					( Units "uMatchProp" "ns" 1.000000)
					( Status sCSetFlattened )
					( Origin gBackEnd )
				)
			)
			( pinPair "@baseboard_fab2_lib.baseboard_fab2(sch_1):\PP2888\"
				( pinRef "@baseboard_fab2_lib.baseboard_fab2(sch_1):page78_i13:DQ(20)" )
				( pinRef "@baseboard_fab2_lib.baseboard_fab2(sch_1):page57_i172:DDR0_DQ(20)" )
				( attribute "RELATIVE_PROPAGATION_DELAY_SCOPE" "G"
					( Parent
						( matchGroupRef "@baseboard_fab2_lib.baseboard_fab2(sch_1):\MG_DQ-DQS_NEAR_DIMM_NG_M_G_BYTE2\" )
					)
					( Status sCSetFlattened )
					( Origin gBackEnd )
				)
				( attribute "RELATIVE_PROPAGATION_DELAY" "0.00 MIL,195.00 MIL"
					( Parent
						( matchGroupRef "@baseboard_fab2_lib.baseboard_fab2(sch_1):\MG_DQ-DQS_NEAR_DIMM_NG_M_G_BYTE2\" )
					)
					( Units "uMatchProp" "ns" 1.000000)
					( Status sCSetFlattened )
					( Origin gBackEnd )
				)
				( attribute "RELATIVE_PROPAGATION_DELAY_SCOPE" "G"
					( Parent
						( matchGroupRef "@baseboard_fab2_lib.baseboard_fab2(sch_1):\MG_DQ_NEAR_DIMM_NG_M_G_BYTE2\" )
					)
					( Status sCSetFlattened )
					( Origin gBackEnd )
				)
				( attribute "RELATIVE_PROPAGATION_DELAY" "-50.00 MIL,50.00 MIL"
					( Parent
						( matchGroupRef "@baseboard_fab2_lib.baseboard_fab2(sch_1):\MG_DQ_NEAR_DIMM_NG_M_G_BYTE2\" )
					)
					( Units "uMatchProp" "ns" 1.000000)
					( Status sCSetFlattened )
					( Origin gBackEnd )
				)
			)
			( pinPair "@baseboard_fab2_lib.baseboard_fab2(sch_1):\PP2890\"
				( pinRef "@baseboard_fab2_lib.baseboard_fab2(sch_1):page57_i172:DDR0_DQ(21)" )
				( pinRef "@baseboard_fab2_lib.baseboard_fab2(sch_1):page77_i111:DQ(20)" )
				( attribute "RELATIVE_PROPAGATION_DELAY_SCOPE" "G"
					( Parent
						( matchGroupRef "@baseboard_fab2_lib.baseboard_fab2(sch_1):\MG_DQ-DQS_FAR_DIMM_NG_M_G_BYTE2\" )
					)
					( Status sCSetFlattened )
					( Origin gBackEnd )
				)
				( attribute "RELATIVE_PROPAGATION_DELAY" "0.00 MIL,195.00 MIL"
					( Parent
						( matchGroupRef "@baseboard_fab2_lib.baseboard_fab2(sch_1):\MG_DQ-DQS_FAR_DIMM_NG_M_G_BYTE2\" )
					)
					( Units "uMatchProp" "ns" 1.000000)
					( Status sCSetFlattened )
					( Origin gBackEnd )
				)
				( attribute "RELATIVE_PROPAGATION_DELAY_SCOPE" "G"
					( Parent
						( matchGroupRef "@baseboard_fab2_lib.baseboard_fab2(sch_1):\MG_DQ_FAR_DIMM_NG_M_G_BYTE2\" )
					)
					( Status sCSetFlattened )
					( Origin gBackEnd )
				)
				( attribute "RELATIVE_PROPAGATION_DELAY" "-50.00 MIL,50.00 MIL"
					( Parent
						( matchGroupRef "@baseboard_fab2_lib.baseboard_fab2(sch_1):\MG_DQ_FAR_DIMM_NG_M_G_BYTE2\" )
					)
					( Units "uMatchProp" "ns" 1.000000)
					( Status sCSetFlattened )
					( Origin gBackEnd )
				)
			)
			( pinPair "@baseboard_fab2_lib.baseboard_fab2(sch_1):\PP2891\"
				( pinRef "@baseboard_fab2_lib.baseboard_fab2(sch_1):page78_i13:DQ(21)" )
				( pinRef "@baseboard_fab2_lib.baseboard_fab2(sch_1):page57_i172:DDR0_DQ(21)" )
				( attribute "RELATIVE_PROPAGATION_DELAY_SCOPE" "G"
					( Parent
						( matchGroupRef "@baseboard_fab2_lib.baseboard_fab2(sch_1):\MG_DQ-DQS_NEAR_DIMM_NG_M_G_BYTE2\" )
					)
					( Status sCSetFlattened )
					( Origin gBackEnd )
				)
				( attribute "RELATIVE_PROPAGATION_DELAY" "0.00 MIL,195.00 MIL"
					( Parent
						( matchGroupRef "@baseboard_fab2_lib.baseboard_fab2(sch_1):\MG_DQ-DQS_NEAR_DIMM_NG_M_G_BYTE2\" )
					)
					( Units "uMatchProp" "ns" 1.000000)
					( Status sCSetFlattened )
					( Origin gBackEnd )
				)
				( attribute "RELATIVE_PROPAGATION_DELAY_SCOPE" "G"
					( Parent
						( matchGroupRef "@baseboard_fab2_lib.baseboard_fab2(sch_1):\MG_DQ_NEAR_DIMM_NG_M_G_BYTE2\" )
					)
					( Status sCSetFlattened )
					( Origin gBackEnd )
				)
				( attribute "RELATIVE_PROPAGATION_DELAY" "-50.00 MIL,50.00 MIL"
					( Parent
						( matchGroupRef "@baseboard_fab2_lib.baseboard_fab2(sch_1):\MG_DQ_NEAR_DIMM_NG_M_G_BYTE2\" )
					)
					( Units "uMatchProp" "ns" 1.000000)
					( Status sCSetFlattened )
					( Origin gBackEnd )
				)
			)
			( pinPair "@baseboard_fab2_lib.baseboard_fab2(sch_1):\PP2893\"
				( pinRef "@baseboard_fab2_lib.baseboard_fab2(sch_1):page57_i172:DDR0_DQ(22)" )
				( pinRef "@baseboard_fab2_lib.baseboard_fab2(sch_1):page77_i111:DQ(23)" )
				( attribute "RELATIVE_PROPAGATION_DELAY_SCOPE" "G"
					( Parent
						( matchGroupRef "@baseboard_fab2_lib.baseboard_fab2(sch_1):\MG_DQ-DQS_FAR_DIMM_NG_M_G_BYTE2\" )
					)
					( Status sCSetFlattened )
					( Origin gBackEnd )
				)
				( attribute "RELATIVE_PROPAGATION_DELAY" "0.00 MIL,195.00 MIL"
					( Parent
						( matchGroupRef "@baseboard_fab2_lib.baseboard_fab2(sch_1):\MG_DQ-DQS_FAR_DIMM_NG_M_G_BYTE2\" )
					)
					( Units "uMatchProp" "ns" 1.000000)
					( Status sCSetFlattened )
					( Origin gBackEnd )
				)
				( attribute "RELATIVE_PROPAGATION_DELAY_SCOPE" "G"
					( Parent
						( matchGroupRef "@baseboard_fab2_lib.baseboard_fab2(sch_1):\MG_DQ_FAR_DIMM_NG_M_G_BYTE2\" )
					)
					( Status sCSetFlattened )
					( Origin gBackEnd )
				)
				( attribute "RELATIVE_PROPAGATION_DELAY" "-50.00 MIL,50.00 MIL"
					( Parent
						( matchGroupRef "@baseboard_fab2_lib.baseboard_fab2(sch_1):\MG_DQ_FAR_DIMM_NG_M_G_BYTE2\" )
					)
					( Units "uMatchProp" "ns" 1.000000)
					( Status sCSetFlattened )
					( Origin gBackEnd )
				)
			)
			( pinPair "@baseboard_fab2_lib.baseboard_fab2(sch_1):\PP2894\"
				( pinRef "@baseboard_fab2_lib.baseboard_fab2(sch_1):page78_i13:DQ(22)" )
				( pinRef "@baseboard_fab2_lib.baseboard_fab2(sch_1):page57_i172:DDR0_DQ(22)" )
				( attribute "RELATIVE_PROPAGATION_DELAY_SCOPE" "G"
					( Parent
						( matchGroupRef "@baseboard_fab2_lib.baseboard_fab2(sch_1):\MG_DQ-DQS_NEAR_DIMM_NG_M_G_BYTE2\" )
					)
					( Status sCSetFlattened )
					( Origin gBackEnd )
				)
				( attribute "RELATIVE_PROPAGATION_DELAY" "0.00 MIL,195.00 MIL"
					( Parent
						( matchGroupRef "@baseboard_fab2_lib.baseboard_fab2(sch_1):\MG_DQ-DQS_NEAR_DIMM_NG_M_G_BYTE2\" )
					)
					( Units "uMatchProp" "ns" 1.000000)
					( Status sCSetFlattened )
					( Origin gBackEnd )
				)
				( attribute "RELATIVE_PROPAGATION_DELAY_SCOPE" "G"
					( Parent
						( matchGroupRef "@baseboard_fab2_lib.baseboard_fab2(sch_1):\MG_DQ_NEAR_DIMM_NG_M_G_BYTE2\" )
					)
					( Status sCSetFlattened )
					( Origin gBackEnd )
				)
				( attribute "RELATIVE_PROPAGATION_DELAY" "-50.00 MIL,50.00 MIL"
					( Parent
						( matchGroupRef "@baseboard_fab2_lib.baseboard_fab2(sch_1):\MG_DQ_NEAR_DIMM_NG_M_G_BYTE2\" )
					)
					( Units "uMatchProp" "ns" 1.000000)
					( Status sCSetFlattened )
					( Origin gBackEnd )
				)
			)
			( pinPair "@baseboard_fab2_lib.baseboard_fab2(sch_1):\PP2896\"
				( pinRef "@baseboard_fab2_lib.baseboard_fab2(sch_1):page57_i172:DDR0_DQ(23)" )
				( pinRef "@baseboard_fab2_lib.baseboard_fab2(sch_1):page77_i111:DQ(22)" )
				( attribute "RELATIVE_PROPAGATION_DELAY_SCOPE" "G"
					( Parent
						( matchGroupRef "@baseboard_fab2_lib.baseboard_fab2(sch_1):\MG_DQ-DQS_FAR_DIMM_NG_M_G_BYTE2\" )
					)
					( Status sCSetFlattened )
					( Origin gBackEnd )
				)
				( attribute "RELATIVE_PROPAGATION_DELAY" "0.00 MIL,195.00 MIL"
					( Parent
						( matchGroupRef "@baseboard_fab2_lib.baseboard_fab2(sch_1):\MG_DQ-DQS_FAR_DIMM_NG_M_G_BYTE2\" )
					)
					( Units "uMatchProp" "ns" 1.000000)
					( Status sCSetFlattened )
					( Origin gBackEnd )
				)
				( attribute "RELATIVE_PROPAGATION_DELAY_SCOPE" "G"
					( Parent
						( matchGroupRef "@baseboard_fab2_lib.baseboard_fab2(sch_1):\MG_DQ_FAR_DIMM_NG_M_G_BYTE2\" )
					)
					( Status sCSetFlattened )
					( Origin gBackEnd )
				)
				( attribute "RELATIVE_PROPAGATION_DELAY" "-50.00 MIL,50.00 MIL"
					( Parent
						( matchGroupRef "@baseboard_fab2_lib.baseboard_fab2(sch_1):\MG_DQ_FAR_DIMM_NG_M_G_BYTE2\" )
					)
					( Units "uMatchProp" "ns" 1.000000)
					( Status sCSetFlattened )
					( Origin gBackEnd )
				)
			)
			( pinPair "@baseboard_fab2_lib.baseboard_fab2(sch_1):\PP2897\"
				( pinRef "@baseboard_fab2_lib.baseboard_fab2(sch_1):page78_i13:DQ(23)" )
				( pinRef "@baseboard_fab2_lib.baseboard_fab2(sch_1):page57_i172:DDR0_DQ(23)" )
				( attribute "RELATIVE_PROPAGATION_DELAY_SCOPE" "G"
					( Parent
						( matchGroupRef "@baseboard_fab2_lib.baseboard_fab2(sch_1):\MG_DQ-DQS_NEAR_DIMM_NG_M_G_BYTE2\" )
					)
					( Status sCSetFlattened )
					( Origin gBackEnd )
				)
				( attribute "RELATIVE_PROPAGATION_DELAY" "0.00 MIL,195.00 MIL"
					( Parent
						( matchGroupRef "@baseboard_fab2_lib.baseboard_fab2(sch_1):\MG_DQ-DQS_NEAR_DIMM_NG_M_G_BYTE2\" )
					)
					( Units "uMatchProp" "ns" 1.000000)
					( Status sCSetFlattened )
					( Origin gBackEnd )
				)
				( attribute "RELATIVE_PROPAGATION_DELAY_SCOPE" "G"
					( Parent
						( matchGroupRef "@baseboard_fab2_lib.baseboard_fab2(sch_1):\MG_DQ_NEAR_DIMM_NG_M_G_BYTE2\" )
					)
					( Status sCSetFlattened )
					( Origin gBackEnd )
				)
				( attribute "RELATIVE_PROPAGATION_DELAY" "-50.00 MIL,50.00 MIL"
					( Parent
						( matchGroupRef "@baseboard_fab2_lib.baseboard_fab2(sch_1):\MG_DQ_NEAR_DIMM_NG_M_G_BYTE2\" )
					)
					( Units "uMatchProp" "ns" 1.000000)
					( Status sCSetFlattened )
					( Origin gBackEnd )
				)
			)
			( pinPair "@baseboard_fab2_lib.baseboard_fab2(sch_1):\PP2851\"
				( pinRef "@baseboard_fab2_lib.baseboard_fab2(sch_1):page57_i172:DDR0_DQ(24)" )
				( pinRef "@baseboard_fab2_lib.baseboard_fab2(sch_1):page77_i111:DQ(25)" )
				( attribute "RELATIVE_PROPAGATION_DELAY_SCOPE" "G"
					( Parent
						( matchGroupRef "@baseboard_fab2_lib.baseboard_fab2(sch_1):\MG_DQ-DQS_FAR_DIMM_NG_M_G_BYTE3\" )
					)
					( Status sCSetFlattened )
					( Origin gBackEnd )
				)
				( attribute "RELATIVE_PROPAGATION_DELAY" "0.00 MIL,195.00 MIL"
					( Parent
						( matchGroupRef "@baseboard_fab2_lib.baseboard_fab2(sch_1):\MG_DQ-DQS_FAR_DIMM_NG_M_G_BYTE3\" )
					)
					( Units "uMatchProp" "ns" 1.000000)
					( Status sCSetFlattened )
					( Origin gBackEnd )
				)
				( attribute "RELATIVE_PROPAGATION_DELAY_SCOPE" "G"
					( Parent
						( matchGroupRef "@baseboard_fab2_lib.baseboard_fab2(sch_1):\MG_DQ_FAR_DIMM_NG_M_G_BYTE3\" )
					)
					( Status sCSetFlattened )
					( Origin gBackEnd )
				)
				( attribute "RELATIVE_PROPAGATION_DELAY" "-50.00 MIL,50.00 MIL"
					( Parent
						( matchGroupRef "@baseboard_fab2_lib.baseboard_fab2(sch_1):\MG_DQ_FAR_DIMM_NG_M_G_BYTE3\" )
					)
					( Units "uMatchProp" "ns" 1.000000)
					( Status sCSetFlattened )
					( Origin gBackEnd )
				)
			)
			( pinPair "@baseboard_fab2_lib.baseboard_fab2(sch_1):\PP2852\"
				( pinRef "@baseboard_fab2_lib.baseboard_fab2(sch_1):page78_i13:DQ(24)" )
				( pinRef "@baseboard_fab2_lib.baseboard_fab2(sch_1):page57_i172:DDR0_DQ(24)" )
				( attribute "RELATIVE_PROPAGATION_DELAY_SCOPE" "G"
					( Parent
						( matchGroupRef "@baseboard_fab2_lib.baseboard_fab2(sch_1):\MG_DQ-DQS_NEAR_DIMM_NG_M_G_BYTE3\" )
					)
					( Status sCSetFlattened )
					( Origin gBackEnd )
				)
				( attribute "RELATIVE_PROPAGATION_DELAY" "0.00 MIL,195.00 MIL"
					( Parent
						( matchGroupRef "@baseboard_fab2_lib.baseboard_fab2(sch_1):\MG_DQ-DQS_NEAR_DIMM_NG_M_G_BYTE3\" )
					)
					( Units "uMatchProp" "ns" 1.000000)
					( Status sCSetFlattened )
					( Origin gBackEnd )
				)
				( attribute "RELATIVE_PROPAGATION_DELAY_SCOPE" "G"
					( Parent
						( matchGroupRef "@baseboard_fab2_lib.baseboard_fab2(sch_1):\MG_DQ_NEAR_DIMM_NG_M_G_BYTE3\" )
					)
					( Status sCSetFlattened )
					( Origin gBackEnd )
				)
				( attribute "RELATIVE_PROPAGATION_DELAY" "-50.00 MIL,50.00 MIL"
					( Parent
						( matchGroupRef "@baseboard_fab2_lib.baseboard_fab2(sch_1):\MG_DQ_NEAR_DIMM_NG_M_G_BYTE3\" )
					)
					( Units "uMatchProp" "ns" 1.000000)
					( Status sCSetFlattened )
					( Origin gBackEnd )
				)
			)
			( pinPair "@baseboard_fab2_lib.baseboard_fab2(sch_1):\PP2854\"
				( pinRef "@baseboard_fab2_lib.baseboard_fab2(sch_1):page57_i172:DDR0_DQ(25)" )
				( pinRef "@baseboard_fab2_lib.baseboard_fab2(sch_1):page77_i111:DQ(24)" )
				( attribute "RELATIVE_PROPAGATION_DELAY_SCOPE" "G"
					( Parent
						( matchGroupRef "@baseboard_fab2_lib.baseboard_fab2(sch_1):\MG_DQ-DQS_FAR_DIMM_NG_M_G_BYTE3\" )
					)
					( Status sCSetFlattened )
					( Origin gBackEnd )
				)
				( attribute "RELATIVE_PROPAGATION_DELAY" "0.00 MIL,195.00 MIL"
					( Parent
						( matchGroupRef "@baseboard_fab2_lib.baseboard_fab2(sch_1):\MG_DQ-DQS_FAR_DIMM_NG_M_G_BYTE3\" )
					)
					( Units "uMatchProp" "ns" 1.000000)
					( Status sCSetFlattened )
					( Origin gBackEnd )
				)
				( attribute "RELATIVE_PROPAGATION_DELAY_SCOPE" "G"
					( Parent
						( matchGroupRef "@baseboard_fab2_lib.baseboard_fab2(sch_1):\MG_DQ_FAR_DIMM_NG_M_G_BYTE3\" )
					)
					( Status sCSetFlattened )
					( Origin gBackEnd )
				)
				( attribute "RELATIVE_PROPAGATION_DELAY" "-50.00 MIL,50.00 MIL"
					( Parent
						( matchGroupRef "@baseboard_fab2_lib.baseboard_fab2(sch_1):\MG_DQ_FAR_DIMM_NG_M_G_BYTE3\" )
					)
					( Units "uMatchProp" "ns" 1.000000)
					( Status sCSetFlattened )
					( Origin gBackEnd )
				)
			)
			( pinPair "@baseboard_fab2_lib.baseboard_fab2(sch_1):\PP2855\"
				( pinRef "@baseboard_fab2_lib.baseboard_fab2(sch_1):page78_i13:DQ(25)" )
				( pinRef "@baseboard_fab2_lib.baseboard_fab2(sch_1):page57_i172:DDR0_DQ(25)" )
				( attribute "RELATIVE_PROPAGATION_DELAY_SCOPE" "G"
					( Parent
						( matchGroupRef "@baseboard_fab2_lib.baseboard_fab2(sch_1):\MG_DQ-DQS_NEAR_DIMM_NG_M_G_BYTE3\" )
					)
					( Status sCSetFlattened )
					( Origin gBackEnd )
				)
				( attribute "RELATIVE_PROPAGATION_DELAY" "0.00 MIL,195.00 MIL"
					( Parent
						( matchGroupRef "@baseboard_fab2_lib.baseboard_fab2(sch_1):\MG_DQ-DQS_NEAR_DIMM_NG_M_G_BYTE3\" )
					)
					( Units "uMatchProp" "ns" 1.000000)
					( Status sCSetFlattened )
					( Origin gBackEnd )
				)
				( attribute "RELATIVE_PROPAGATION_DELAY_SCOPE" "G"
					( Parent
						( matchGroupRef "@baseboard_fab2_lib.baseboard_fab2(sch_1):\MG_DQ_NEAR_DIMM_NG_M_G_BYTE3\" )
					)
					( Status sCSetFlattened )
					( Origin gBackEnd )
				)
				( attribute "RELATIVE_PROPAGATION_DELAY" "-50.00 MIL,50.00 MIL"
					( Parent
						( matchGroupRef "@baseboard_fab2_lib.baseboard_fab2(sch_1):\MG_DQ_NEAR_DIMM_NG_M_G_BYTE3\" )
					)
					( Units "uMatchProp" "ns" 1.000000)
					( Status sCSetFlattened )
					( Origin gBackEnd )
				)
			)
			( pinPair "@baseboard_fab2_lib.baseboard_fab2(sch_1):\PP2857\"
				( pinRef "@baseboard_fab2_lib.baseboard_fab2(sch_1):page57_i172:DDR0_DQ(26)" )
				( pinRef "@baseboard_fab2_lib.baseboard_fab2(sch_1):page77_i111:DQ(27)" )
				( attribute "RELATIVE_PROPAGATION_DELAY_SCOPE" "G"
					( Parent
						( matchGroupRef "@baseboard_fab2_lib.baseboard_fab2(sch_1):\MG_DQ-DQS_FAR_DIMM_NG_M_G_BYTE3\" )
					)
					( Status sCSetFlattened )
					( Origin gBackEnd )
				)
				( attribute "RELATIVE_PROPAGATION_DELAY" "0.00 MIL,195.00 MIL"
					( Parent
						( matchGroupRef "@baseboard_fab2_lib.baseboard_fab2(sch_1):\MG_DQ-DQS_FAR_DIMM_NG_M_G_BYTE3\" )
					)
					( Units "uMatchProp" "ns" 1.000000)
					( Status sCSetFlattened )
					( Origin gBackEnd )
				)
				( attribute "RELATIVE_PROPAGATION_DELAY_SCOPE" "G"
					( Parent
						( matchGroupRef "@baseboard_fab2_lib.baseboard_fab2(sch_1):\MG_DQ_FAR_DIMM_NG_M_G_BYTE3\" )
					)
					( Status sCSetFlattened )
					( Origin gBackEnd )
				)
				( attribute "RELATIVE_PROPAGATION_DELAY" "-50.00 MIL,50.00 MIL"
					( Parent
						( matchGroupRef "@baseboard_fab2_lib.baseboard_fab2(sch_1):\MG_DQ_FAR_DIMM_NG_M_G_BYTE3\" )
					)
					( Units "uMatchProp" "ns" 1.000000)
					( Status sCSetFlattened )
					( Origin gBackEnd )
				)
			)
			( pinPair "@baseboard_fab2_lib.baseboard_fab2(sch_1):\PP2858\"
				( pinRef "@baseboard_fab2_lib.baseboard_fab2(sch_1):page78_i13:DQ(26)" )
				( pinRef "@baseboard_fab2_lib.baseboard_fab2(sch_1):page57_i172:DDR0_DQ(26)" )
				( attribute "RELATIVE_PROPAGATION_DELAY_SCOPE" "G"
					( Parent
						( matchGroupRef "@baseboard_fab2_lib.baseboard_fab2(sch_1):\MG_DQ-DQS_NEAR_DIMM_NG_M_G_BYTE3\" )
					)
					( Status sCSetFlattened )
					( Origin gBackEnd )
				)
				( attribute "RELATIVE_PROPAGATION_DELAY" "0.00 MIL,195.00 MIL"
					( Parent
						( matchGroupRef "@baseboard_fab2_lib.baseboard_fab2(sch_1):\MG_DQ-DQS_NEAR_DIMM_NG_M_G_BYTE3\" )
					)
					( Units "uMatchProp" "ns" 1.000000)
					( Status sCSetFlattened )
					( Origin gBackEnd )
				)
				( attribute "RELATIVE_PROPAGATION_DELAY_SCOPE" "G"
					( Parent
						( matchGroupRef "@baseboard_fab2_lib.baseboard_fab2(sch_1):\MG_DQ_NEAR_DIMM_NG_M_G_BYTE3\" )
					)
					( Status sCSetFlattened )
					( Origin gBackEnd )
				)
				( attribute "RELATIVE_PROPAGATION_DELAY" "-50.00 MIL,50.00 MIL"
					( Parent
						( matchGroupRef "@baseboard_fab2_lib.baseboard_fab2(sch_1):\MG_DQ_NEAR_DIMM_NG_M_G_BYTE3\" )
					)
					( Units "uMatchProp" "ns" 1.000000)
					( Status sCSetFlattened )
					( Origin gBackEnd )
				)
			)
			( pinPair "@baseboard_fab2_lib.baseboard_fab2(sch_1):\PP2860\"
				( pinRef "@baseboard_fab2_lib.baseboard_fab2(sch_1):page57_i172:DDR0_DQ(27)" )
				( pinRef "@baseboard_fab2_lib.baseboard_fab2(sch_1):page77_i111:DQ(26)" )
				( attribute "RELATIVE_PROPAGATION_DELAY_SCOPE" "G"
					( Parent
						( matchGroupRef "@baseboard_fab2_lib.baseboard_fab2(sch_1):\MG_DQ-DQS_FAR_DIMM_NG_M_G_BYTE3\" )
					)
					( Status sCSetFlattened )
					( Origin gBackEnd )
				)
				( attribute "RELATIVE_PROPAGATION_DELAY" "0.00 MIL,195.00 MIL"
					( Parent
						( matchGroupRef "@baseboard_fab2_lib.baseboard_fab2(sch_1):\MG_DQ-DQS_FAR_DIMM_NG_M_G_BYTE3\" )
					)
					( Units "uMatchProp" "ns" 1.000000)
					( Status sCSetFlattened )
					( Origin gBackEnd )
				)
				( attribute "RELATIVE_PROPAGATION_DELAY_SCOPE" "G"
					( Parent
						( matchGroupRef "@baseboard_fab2_lib.baseboard_fab2(sch_1):\MG_DQ_FAR_DIMM_NG_M_G_BYTE3\" )
					)
					( Status sCSetFlattened )
					( Origin gBackEnd )
				)
				( attribute "RELATIVE_PROPAGATION_DELAY" "-50.00 MIL,50.00 MIL"
					( Parent
						( matchGroupRef "@baseboard_fab2_lib.baseboard_fab2(sch_1):\MG_DQ_FAR_DIMM_NG_M_G_BYTE3\" )
					)
					( Units "uMatchProp" "ns" 1.000000)
					( Status sCSetFlattened )
					( Origin gBackEnd )
				)
			)
			( pinPair "@baseboard_fab2_lib.baseboard_fab2(sch_1):\PP2861\"
				( pinRef "@baseboard_fab2_lib.baseboard_fab2(sch_1):page78_i13:DQ(27)" )
				( pinRef "@baseboard_fab2_lib.baseboard_fab2(sch_1):page57_i172:DDR0_DQ(27)" )
				( attribute "RELATIVE_PROPAGATION_DELAY_SCOPE" "G"
					( Parent
						( matchGroupRef "@baseboard_fab2_lib.baseboard_fab2(sch_1):\MG_DQ-DQS_NEAR_DIMM_NG_M_G_BYTE3\" )
					)
					( Status sCSetFlattened )
					( Origin gBackEnd )
				)
				( attribute "RELATIVE_PROPAGATION_DELAY" "0.00 MIL,195.00 MIL"
					( Parent
						( matchGroupRef "@baseboard_fab2_lib.baseboard_fab2(sch_1):\MG_DQ-DQS_NEAR_DIMM_NG_M_G_BYTE3\" )
					)
					( Units "uMatchProp" "ns" 1.000000)
					( Status sCSetFlattened )
					( Origin gBackEnd )
				)
				( attribute "RELATIVE_PROPAGATION_DELAY_SCOPE" "G"
					( Parent
						( matchGroupRef "@baseboard_fab2_lib.baseboard_fab2(sch_1):\MG_DQ_NEAR_DIMM_NG_M_G_BYTE3\" )
					)
					( Status sCSetFlattened )
					( Origin gBackEnd )
				)
				( attribute "RELATIVE_PROPAGATION_DELAY" "-50.00 MIL,50.00 MIL"
					( Parent
						( matchGroupRef "@baseboard_fab2_lib.baseboard_fab2(sch_1):\MG_DQ_NEAR_DIMM_NG_M_G_BYTE3\" )
					)
					( Units "uMatchProp" "ns" 1.000000)
					( Status sCSetFlattened )
					( Origin gBackEnd )
				)
			)
			( pinPair "@baseboard_fab2_lib.baseboard_fab2(sch_1):\PP2863\"
				( pinRef "@baseboard_fab2_lib.baseboard_fab2(sch_1):page57_i172:DDR0_DQ(28)" )
				( pinRef "@baseboard_fab2_lib.baseboard_fab2(sch_1):page77_i111:DQ(29)" )
				( attribute "RELATIVE_PROPAGATION_DELAY_SCOPE" "G"
					( Parent
						( matchGroupRef "@baseboard_fab2_lib.baseboard_fab2(sch_1):\MG_DQ-DQS_FAR_DIMM_NG_M_G_BYTE3\" )
					)
					( Status sCSetFlattened )
					( Origin gBackEnd )
				)
				( attribute "RELATIVE_PROPAGATION_DELAY" "0.00 MIL,195.00 MIL"
					( Parent
						( matchGroupRef "@baseboard_fab2_lib.baseboard_fab2(sch_1):\MG_DQ-DQS_FAR_DIMM_NG_M_G_BYTE3\" )
					)
					( Units "uMatchProp" "ns" 1.000000)
					( Status sCSetFlattened )
					( Origin gBackEnd )
				)
				( attribute "RELATIVE_PROPAGATION_DELAY_SCOPE" "G"
					( Parent
						( matchGroupRef "@baseboard_fab2_lib.baseboard_fab2(sch_1):\MG_DQ_FAR_DIMM_NG_M_G_BYTE3\" )
					)
					( Status sCSetFlattened )
					( Origin gBackEnd )
				)
				( attribute "RELATIVE_PROPAGATION_DELAY" "-50.00 MIL,50.00 MIL"
					( Parent
						( matchGroupRef "@baseboard_fab2_lib.baseboard_fab2(sch_1):\MG_DQ_FAR_DIMM_NG_M_G_BYTE3\" )
					)
					( Units "uMatchProp" "ns" 1.000000)
					( Status sCSetFlattened )
					( Origin gBackEnd )
				)
			)
			( pinPair "@baseboard_fab2_lib.baseboard_fab2(sch_1):\PP2864\"
				( pinRef "@baseboard_fab2_lib.baseboard_fab2(sch_1):page78_i13:DQ(28)" )
				( pinRef "@baseboard_fab2_lib.baseboard_fab2(sch_1):page57_i172:DDR0_DQ(28)" )
				( attribute "RELATIVE_PROPAGATION_DELAY_SCOPE" "G"
					( Parent
						( matchGroupRef "@baseboard_fab2_lib.baseboard_fab2(sch_1):\MG_DQ-DQS_NEAR_DIMM_NG_M_G_BYTE3\" )
					)
					( Status sCSetFlattened )
					( Origin gBackEnd )
				)
				( attribute "RELATIVE_PROPAGATION_DELAY" "0.00 MIL,195.00 MIL"
					( Parent
						( matchGroupRef "@baseboard_fab2_lib.baseboard_fab2(sch_1):\MG_DQ-DQS_NEAR_DIMM_NG_M_G_BYTE3\" )
					)
					( Units "uMatchProp" "ns" 1.000000)
					( Status sCSetFlattened )
					( Origin gBackEnd )
				)
				( attribute "RELATIVE_PROPAGATION_DELAY_SCOPE" "G"
					( Parent
						( matchGroupRef "@baseboard_fab2_lib.baseboard_fab2(sch_1):\MG_DQ_NEAR_DIMM_NG_M_G_BYTE3\" )
					)
					( Status sCSetFlattened )
					( Origin gBackEnd )
				)
				( attribute "RELATIVE_PROPAGATION_DELAY" "-50.00 MIL,50.00 MIL"
					( Parent
						( matchGroupRef "@baseboard_fab2_lib.baseboard_fab2(sch_1):\MG_DQ_NEAR_DIMM_NG_M_G_BYTE3\" )
					)
					( Units "uMatchProp" "ns" 1.000000)
					( Status sCSetFlattened )
					( Origin gBackEnd )
				)
			)
			( pinPair "@baseboard_fab2_lib.baseboard_fab2(sch_1):\PP2866\"
				( pinRef "@baseboard_fab2_lib.baseboard_fab2(sch_1):page57_i172:DDR0_DQ(29)" )
				( pinRef "@baseboard_fab2_lib.baseboard_fab2(sch_1):page77_i111:DQ(28)" )
				( attribute "RELATIVE_PROPAGATION_DELAY_SCOPE" "G"
					( Parent
						( matchGroupRef "@baseboard_fab2_lib.baseboard_fab2(sch_1):\MG_DQ-DQS_FAR_DIMM_NG_M_G_BYTE3\" )
					)
					( Status sCSetFlattened )
					( Origin gBackEnd )
				)
				( attribute "RELATIVE_PROPAGATION_DELAY" "0.00 MIL,195.00 MIL"
					( Parent
						( matchGroupRef "@baseboard_fab2_lib.baseboard_fab2(sch_1):\MG_DQ-DQS_FAR_DIMM_NG_M_G_BYTE3\" )
					)
					( Units "uMatchProp" "ns" 1.000000)
					( Status sCSetFlattened )
					( Origin gBackEnd )
				)
				( attribute "RELATIVE_PROPAGATION_DELAY_SCOPE" "G"
					( Parent
						( matchGroupRef "@baseboard_fab2_lib.baseboard_fab2(sch_1):\MG_DQ_FAR_DIMM_NG_M_G_BYTE3\" )
					)
					( Status sCSetFlattened )
					( Origin gBackEnd )
				)
				( attribute "RELATIVE_PROPAGATION_DELAY" "-50.00 MIL,50.00 MIL"
					( Parent
						( matchGroupRef "@baseboard_fab2_lib.baseboard_fab2(sch_1):\MG_DQ_FAR_DIMM_NG_M_G_BYTE3\" )
					)
					( Units "uMatchProp" "ns" 1.000000)
					( Status sCSetFlattened )
					( Origin gBackEnd )
				)
			)
			( pinPair "@baseboard_fab2_lib.baseboard_fab2(sch_1):\PP2867\"
				( pinRef "@baseboard_fab2_lib.baseboard_fab2(sch_1):page78_i13:DQ(29)" )
				( pinRef "@baseboard_fab2_lib.baseboard_fab2(sch_1):page57_i172:DDR0_DQ(29)" )
				( attribute "RELATIVE_PROPAGATION_DELAY_SCOPE" "G"
					( Parent
						( matchGroupRef "@baseboard_fab2_lib.baseboard_fab2(sch_1):\MG_DQ-DQS_NEAR_DIMM_NG_M_G_BYTE3\" )
					)
					( Status sCSetFlattened )
					( Origin gBackEnd )
				)
				( attribute "RELATIVE_PROPAGATION_DELAY" "0.00 MIL,195.00 MIL"
					( Parent
						( matchGroupRef "@baseboard_fab2_lib.baseboard_fab2(sch_1):\MG_DQ-DQS_NEAR_DIMM_NG_M_G_BYTE3\" )
					)
					( Units "uMatchProp" "ns" 1.000000)
					( Status sCSetFlattened )
					( Origin gBackEnd )
				)
				( attribute "RELATIVE_PROPAGATION_DELAY_SCOPE" "G"
					( Parent
						( matchGroupRef "@baseboard_fab2_lib.baseboard_fab2(sch_1):\MG_DQ_NEAR_DIMM_NG_M_G_BYTE3\" )
					)
					( Status sCSetFlattened )
					( Origin gBackEnd )
				)
				( attribute "RELATIVE_PROPAGATION_DELAY" "-50.00 MIL,50.00 MIL"
					( Parent
						( matchGroupRef "@baseboard_fab2_lib.baseboard_fab2(sch_1):\MG_DQ_NEAR_DIMM_NG_M_G_BYTE3\" )
					)
					( Units "uMatchProp" "ns" 1.000000)
					( Status sCSetFlattened )
					( Origin gBackEnd )
				)
			)
			( pinPair "@baseboard_fab2_lib.baseboard_fab2(sch_1):\PP2869\"
				( pinRef "@baseboard_fab2_lib.baseboard_fab2(sch_1):page57_i172:DDR0_DQ(30)" )
				( pinRef "@baseboard_fab2_lib.baseboard_fab2(sch_1):page77_i111:DQ(31)" )
				( attribute "RELATIVE_PROPAGATION_DELAY_SCOPE" "G"
					( Parent
						( matchGroupRef "@baseboard_fab2_lib.baseboard_fab2(sch_1):\MG_DQ-DQS_FAR_DIMM_NG_M_G_BYTE3\" )
					)
					( Status sCSetFlattened )
					( Origin gBackEnd )
				)
				( attribute "RELATIVE_PROPAGATION_DELAY" "0.00 MIL,195.00 MIL"
					( Parent
						( matchGroupRef "@baseboard_fab2_lib.baseboard_fab2(sch_1):\MG_DQ-DQS_FAR_DIMM_NG_M_G_BYTE3\" )
					)
					( Units "uMatchProp" "ns" 1.000000)
					( Status sCSetFlattened )
					( Origin gBackEnd )
				)
				( attribute "RELATIVE_PROPAGATION_DELAY_SCOPE" "G"
					( Parent
						( matchGroupRef "@baseboard_fab2_lib.baseboard_fab2(sch_1):\MG_DQ_FAR_DIMM_NG_M_G_BYTE3\" )
					)
					( Status sCSetFlattened )
					( Origin gBackEnd )
				)
				( attribute "RELATIVE_PROPAGATION_DELAY" "-50.00 MIL,50.00 MIL"
					( Parent
						( matchGroupRef "@baseboard_fab2_lib.baseboard_fab2(sch_1):\MG_DQ_FAR_DIMM_NG_M_G_BYTE3\" )
					)
					( Units "uMatchProp" "ns" 1.000000)
					( Status sCSetFlattened )
					( Origin gBackEnd )
				)
			)
			( pinPair "@baseboard_fab2_lib.baseboard_fab2(sch_1):\PP2870\"
				( pinRef "@baseboard_fab2_lib.baseboard_fab2(sch_1):page78_i13:DQ(30)" )
				( pinRef "@baseboard_fab2_lib.baseboard_fab2(sch_1):page57_i172:DDR0_DQ(30)" )
				( attribute "RELATIVE_PROPAGATION_DELAY_SCOPE" "G"
					( Parent
						( matchGroupRef "@baseboard_fab2_lib.baseboard_fab2(sch_1):\MG_DQ-DQS_NEAR_DIMM_NG_M_G_BYTE3\" )
					)
					( Status sCSetFlattened )
					( Origin gBackEnd )
				)
				( attribute "RELATIVE_PROPAGATION_DELAY" "0.00 MIL,195.00 MIL"
					( Parent
						( matchGroupRef "@baseboard_fab2_lib.baseboard_fab2(sch_1):\MG_DQ-DQS_NEAR_DIMM_NG_M_G_BYTE3\" )
					)
					( Units "uMatchProp" "ns" 1.000000)
					( Status sCSetFlattened )
					( Origin gBackEnd )
				)
				( attribute "RELATIVE_PROPAGATION_DELAY_SCOPE" "G"
					( Parent
						( matchGroupRef "@baseboard_fab2_lib.baseboard_fab2(sch_1):\MG_DQ_NEAR_DIMM_NG_M_G_BYTE3\" )
					)
					( Status sCSetFlattened )
					( Origin gBackEnd )
				)
				( attribute "RELATIVE_PROPAGATION_DELAY" "-50.00 MIL,50.00 MIL"
					( Parent
						( matchGroupRef "@baseboard_fab2_lib.baseboard_fab2(sch_1):\MG_DQ_NEAR_DIMM_NG_M_G_BYTE3\" )
					)
					( Units "uMatchProp" "ns" 1.000000)
					( Status sCSetFlattened )
					( Origin gBackEnd )
				)
			)
			( pinPair "@baseboard_fab2_lib.baseboard_fab2(sch_1):\PP2872\"
				( pinRef "@baseboard_fab2_lib.baseboard_fab2(sch_1):page57_i172:DDR0_DQ(31)" )
				( pinRef "@baseboard_fab2_lib.baseboard_fab2(sch_1):page77_i111:DQ(30)" )
				( attribute "RELATIVE_PROPAGATION_DELAY_SCOPE" "G"
					( Parent
						( matchGroupRef "@baseboard_fab2_lib.baseboard_fab2(sch_1):\MG_DQ-DQS_FAR_DIMM_NG_M_G_BYTE3\" )
					)
					( Status sCSetFlattened )
					( Origin gBackEnd )
				)
				( attribute "RELATIVE_PROPAGATION_DELAY" "0.00 MIL,195.00 MIL"
					( Parent
						( matchGroupRef "@baseboard_fab2_lib.baseboard_fab2(sch_1):\MG_DQ-DQS_FAR_DIMM_NG_M_G_BYTE3\" )
					)
					( Units "uMatchProp" "ns" 1.000000)
					( Status sCSetFlattened )
					( Origin gBackEnd )
				)
				( attribute "RELATIVE_PROPAGATION_DELAY_SCOPE" "G"
					( Parent
						( matchGroupRef "@baseboard_fab2_lib.baseboard_fab2(sch_1):\MG_DQ_FAR_DIMM_NG_M_G_BYTE3\" )
					)
					( Status sCSetFlattened )
					( Origin gBackEnd )
				)
				( attribute "RELATIVE_PROPAGATION_DELAY" "-50.00 MIL,50.00 MIL"
					( Parent
						( matchGroupRef "@baseboard_fab2_lib.baseboard_fab2(sch_1):\MG_DQ_FAR_DIMM_NG_M_G_BYTE3\" )
					)
					( Units "uMatchProp" "ns" 1.000000)
					( Status sCSetFlattened )
					( Origin gBackEnd )
				)
			)
			( pinPair "@baseboard_fab2_lib.baseboard_fab2(sch_1):\PP2873\"
				( pinRef "@baseboard_fab2_lib.baseboard_fab2(sch_1):page78_i13:DQ(31)" )
				( pinRef "@baseboard_fab2_lib.baseboard_fab2(sch_1):page57_i172:DDR0_DQ(31)" )
				( attribute "RELATIVE_PROPAGATION_DELAY_SCOPE" "G"
					( Parent
						( matchGroupRef "@baseboard_fab2_lib.baseboard_fab2(sch_1):\MG_DQ-DQS_NEAR_DIMM_NG_M_G_BYTE3\" )
					)
					( Status sCSetFlattened )
					( Origin gBackEnd )
				)
				( attribute "RELATIVE_PROPAGATION_DELAY" "0.00 MIL,195.00 MIL"
					( Parent
						( matchGroupRef "@baseboard_fab2_lib.baseboard_fab2(sch_1):\MG_DQ-DQS_NEAR_DIMM_NG_M_G_BYTE3\" )
					)
					( Units "uMatchProp" "ns" 1.000000)
					( Status sCSetFlattened )
					( Origin gBackEnd )
				)
				( attribute "RELATIVE_PROPAGATION_DELAY_SCOPE" "G"
					( Parent
						( matchGroupRef "@baseboard_fab2_lib.baseboard_fab2(sch_1):\MG_DQ_NEAR_DIMM_NG_M_G_BYTE3\" )
					)
					( Status sCSetFlattened )
					( Origin gBackEnd )
				)
				( attribute "RELATIVE_PROPAGATION_DELAY" "-50.00 MIL,50.00 MIL"
					( Parent
						( matchGroupRef "@baseboard_fab2_lib.baseboard_fab2(sch_1):\MG_DQ_NEAR_DIMM_NG_M_G_BYTE3\" )
					)
					( Units "uMatchProp" "ns" 1.000000)
					( Status sCSetFlattened )
					( Origin gBackEnd )
				)
			)
			( pinPair "@baseboard_fab2_lib.baseboard_fab2(sch_1):\PP2827\"
				( pinRef "@baseboard_fab2_lib.baseboard_fab2(sch_1):page57_i172:DDR0_DQ(32)" )
				( pinRef "@baseboard_fab2_lib.baseboard_fab2(sch_1):page77_i111:DQ(33)" )
				( attribute "RELATIVE_PROPAGATION_DELAY_SCOPE" "G"
					( Parent
						( matchGroupRef "@baseboard_fab2_lib.baseboard_fab2(sch_1):\MG_DQ-DQS_FAR_DIMM_NG_M_G_BYTE4\" )
					)
					( Status sCSetFlattened )
					( Origin gBackEnd )
				)
				( attribute "RELATIVE_PROPAGATION_DELAY" "0.00 MIL,195.00 MIL"
					( Parent
						( matchGroupRef "@baseboard_fab2_lib.baseboard_fab2(sch_1):\MG_DQ-DQS_FAR_DIMM_NG_M_G_BYTE4\" )
					)
					( Units "uMatchProp" "ns" 1.000000)
					( Status sCSetFlattened )
					( Origin gBackEnd )
				)
				( attribute "RELATIVE_PROPAGATION_DELAY_SCOPE" "G"
					( Parent
						( matchGroupRef "@baseboard_fab2_lib.baseboard_fab2(sch_1):\MG_DQ_FAR_DIMM_NG_M_G_BYTE4\" )
					)
					( Status sCSetFlattened )
					( Origin gBackEnd )
				)
				( attribute "RELATIVE_PROPAGATION_DELAY" "-50.00 MIL,50.00 MIL"
					( Parent
						( matchGroupRef "@baseboard_fab2_lib.baseboard_fab2(sch_1):\MG_DQ_FAR_DIMM_NG_M_G_BYTE4\" )
					)
					( Units "uMatchProp" "ns" 1.000000)
					( Status sCSetFlattened )
					( Origin gBackEnd )
				)
			)
			( pinPair "@baseboard_fab2_lib.baseboard_fab2(sch_1):\PP2829\"
				( pinRef "@baseboard_fab2_lib.baseboard_fab2(sch_1):page78_i13:DQ(32)" )
				( pinRef "@baseboard_fab2_lib.baseboard_fab2(sch_1):page57_i172:DDR0_DQ(32)" )
				( attribute "RELATIVE_PROPAGATION_DELAY_SCOPE" "G"
					( Parent
						( matchGroupRef "@baseboard_fab2_lib.baseboard_fab2(sch_1):\MG_DQ-DQS_NEAR_DIMM_NG_M_G_BYTE4\" )
					)
					( Status sCSetFlattened )
					( Origin gBackEnd )
				)
				( attribute "RELATIVE_PROPAGATION_DELAY" "0.00 MIL,195.00 MIL"
					( Parent
						( matchGroupRef "@baseboard_fab2_lib.baseboard_fab2(sch_1):\MG_DQ-DQS_NEAR_DIMM_NG_M_G_BYTE4\" )
					)
					( Units "uMatchProp" "ns" 1.000000)
					( Status sCSetFlattened )
					( Origin gBackEnd )
				)
				( attribute "RELATIVE_PROPAGATION_DELAY_SCOPE" "G"
					( Parent
						( matchGroupRef "@baseboard_fab2_lib.baseboard_fab2(sch_1):\MG_DQ_NEAR_DIMM_NG_M_G_BYTE4\" )
					)
					( Status sCSetFlattened )
					( Origin gBackEnd )
				)
				( attribute "RELATIVE_PROPAGATION_DELAY" "-50.00 MIL,50.00 MIL"
					( Parent
						( matchGroupRef "@baseboard_fab2_lib.baseboard_fab2(sch_1):\MG_DQ_NEAR_DIMM_NG_M_G_BYTE4\" )
					)
					( Units "uMatchProp" "ns" 1.000000)
					( Status sCSetFlattened )
					( Origin gBackEnd )
				)
			)
			( pinPair "@baseboard_fab2_lib.baseboard_fab2(sch_1):\PP2830\"
				( pinRef "@baseboard_fab2_lib.baseboard_fab2(sch_1):page57_i172:DDR0_DQ(33)" )
				( pinRef "@baseboard_fab2_lib.baseboard_fab2(sch_1):page77_i111:DQ(32)" )
				( attribute "RELATIVE_PROPAGATION_DELAY_SCOPE" "G"
					( Parent
						( matchGroupRef "@baseboard_fab2_lib.baseboard_fab2(sch_1):\MG_DQ-DQS_FAR_DIMM_NG_M_G_BYTE4\" )
					)
					( Status sCSetFlattened )
					( Origin gBackEnd )
				)
				( attribute "RELATIVE_PROPAGATION_DELAY" "0.00 MIL,195.00 MIL"
					( Parent
						( matchGroupRef "@baseboard_fab2_lib.baseboard_fab2(sch_1):\MG_DQ-DQS_FAR_DIMM_NG_M_G_BYTE4\" )
					)
					( Units "uMatchProp" "ns" 1.000000)
					( Status sCSetFlattened )
					( Origin gBackEnd )
				)
				( attribute "RELATIVE_PROPAGATION_DELAY_SCOPE" "G"
					( Parent
						( matchGroupRef "@baseboard_fab2_lib.baseboard_fab2(sch_1):\MG_DQ_FAR_DIMM_NG_M_G_BYTE4\" )
					)
					( Status sCSetFlattened )
					( Origin gBackEnd )
				)
				( attribute "RELATIVE_PROPAGATION_DELAY" "-50.00 MIL,50.00 MIL"
					( Parent
						( matchGroupRef "@baseboard_fab2_lib.baseboard_fab2(sch_1):\MG_DQ_FAR_DIMM_NG_M_G_BYTE4\" )
					)
					( Units "uMatchProp" "ns" 1.000000)
					( Status sCSetFlattened )
					( Origin gBackEnd )
				)
			)
			( pinPair "@baseboard_fab2_lib.baseboard_fab2(sch_1):\PP2832\"
				( pinRef "@baseboard_fab2_lib.baseboard_fab2(sch_1):page78_i13:DQ(33)" )
				( pinRef "@baseboard_fab2_lib.baseboard_fab2(sch_1):page57_i172:DDR0_DQ(33)" )
				( attribute "RELATIVE_PROPAGATION_DELAY_SCOPE" "G"
					( Parent
						( matchGroupRef "@baseboard_fab2_lib.baseboard_fab2(sch_1):\MG_DQ-DQS_NEAR_DIMM_NG_M_G_BYTE4\" )
					)
					( Status sCSetFlattened )
					( Origin gBackEnd )
				)
				( attribute "RELATIVE_PROPAGATION_DELAY" "0.00 MIL,195.00 MIL"
					( Parent
						( matchGroupRef "@baseboard_fab2_lib.baseboard_fab2(sch_1):\MG_DQ-DQS_NEAR_DIMM_NG_M_G_BYTE4\" )
					)
					( Units "uMatchProp" "ns" 1.000000)
					( Status sCSetFlattened )
					( Origin gBackEnd )
				)
				( attribute "RELATIVE_PROPAGATION_DELAY_SCOPE" "G"
					( Parent
						( matchGroupRef "@baseboard_fab2_lib.baseboard_fab2(sch_1):\MG_DQ_NEAR_DIMM_NG_M_G_BYTE4\" )
					)
					( Status sCSetFlattened )
					( Origin gBackEnd )
				)
				( attribute "RELATIVE_PROPAGATION_DELAY" "-50.00 MIL,50.00 MIL"
					( Parent
						( matchGroupRef "@baseboard_fab2_lib.baseboard_fab2(sch_1):\MG_DQ_NEAR_DIMM_NG_M_G_BYTE4\" )
					)
					( Units "uMatchProp" "ns" 1.000000)
					( Status sCSetFlattened )
					( Origin gBackEnd )
				)
			)
			( pinPair "@baseboard_fab2_lib.baseboard_fab2(sch_1):\PP2833\"
				( pinRef "@baseboard_fab2_lib.baseboard_fab2(sch_1):page57_i172:DDR0_DQ(34)" )
				( pinRef "@baseboard_fab2_lib.baseboard_fab2(sch_1):page77_i111:DQ(35)" )
				( attribute "RELATIVE_PROPAGATION_DELAY_SCOPE" "G"
					( Parent
						( matchGroupRef "@baseboard_fab2_lib.baseboard_fab2(sch_1):\MG_DQ-DQS_FAR_DIMM_NG_M_G_BYTE4\" )
					)
					( Status sCSetFlattened )
					( Origin gBackEnd )
				)
				( attribute "RELATIVE_PROPAGATION_DELAY" "0.00 MIL,195.00 MIL"
					( Parent
						( matchGroupRef "@baseboard_fab2_lib.baseboard_fab2(sch_1):\MG_DQ-DQS_FAR_DIMM_NG_M_G_BYTE4\" )
					)
					( Units "uMatchProp" "ns" 1.000000)
					( Status sCSetFlattened )
					( Origin gBackEnd )
				)
				( attribute "RELATIVE_PROPAGATION_DELAY_SCOPE" "G"
					( Parent
						( matchGroupRef "@baseboard_fab2_lib.baseboard_fab2(sch_1):\MG_DQ_FAR_DIMM_NG_M_G_BYTE4\" )
					)
					( Status sCSetFlattened )
					( Origin gBackEnd )
				)
				( attribute "RELATIVE_PROPAGATION_DELAY" "-50.00 MIL,50.00 MIL"
					( Parent
						( matchGroupRef "@baseboard_fab2_lib.baseboard_fab2(sch_1):\MG_DQ_FAR_DIMM_NG_M_G_BYTE4\" )
					)
					( Units "uMatchProp" "ns" 1.000000)
					( Status sCSetFlattened )
					( Origin gBackEnd )
				)
			)
			( pinPair "@baseboard_fab2_lib.baseboard_fab2(sch_1):\PP2835\"
				( pinRef "@baseboard_fab2_lib.baseboard_fab2(sch_1):page78_i13:DQ(34)" )
				( pinRef "@baseboard_fab2_lib.baseboard_fab2(sch_1):page57_i172:DDR0_DQ(34)" )
				( attribute "RELATIVE_PROPAGATION_DELAY_SCOPE" "G"
					( Parent
						( matchGroupRef "@baseboard_fab2_lib.baseboard_fab2(sch_1):\MG_DQ-DQS_NEAR_DIMM_NG_M_G_BYTE4\" )
					)
					( Status sCSetFlattened )
					( Origin gBackEnd )
				)
				( attribute "RELATIVE_PROPAGATION_DELAY" "0.00 MIL,195.00 MIL"
					( Parent
						( matchGroupRef "@baseboard_fab2_lib.baseboard_fab2(sch_1):\MG_DQ-DQS_NEAR_DIMM_NG_M_G_BYTE4\" )
					)
					( Units "uMatchProp" "ns" 1.000000)
					( Status sCSetFlattened )
					( Origin gBackEnd )
				)
				( attribute "RELATIVE_PROPAGATION_DELAY_SCOPE" "G"
					( Parent
						( matchGroupRef "@baseboard_fab2_lib.baseboard_fab2(sch_1):\MG_DQ_NEAR_DIMM_NG_M_G_BYTE4\" )
					)
					( Status sCSetFlattened )
					( Origin gBackEnd )
				)
				( attribute "RELATIVE_PROPAGATION_DELAY" "-50.00 MIL,50.00 MIL"
					( Parent
						( matchGroupRef "@baseboard_fab2_lib.baseboard_fab2(sch_1):\MG_DQ_NEAR_DIMM_NG_M_G_BYTE4\" )
					)
					( Units "uMatchProp" "ns" 1.000000)
					( Status sCSetFlattened )
					( Origin gBackEnd )
				)
			)
			( pinPair "@baseboard_fab2_lib.baseboard_fab2(sch_1):\PP2836\"
				( pinRef "@baseboard_fab2_lib.baseboard_fab2(sch_1):page57_i172:DDR0_DQ(35)" )
				( pinRef "@baseboard_fab2_lib.baseboard_fab2(sch_1):page77_i111:DQ(34)" )
				( attribute "RELATIVE_PROPAGATION_DELAY_SCOPE" "G"
					( Parent
						( matchGroupRef "@baseboard_fab2_lib.baseboard_fab2(sch_1):\MG_DQ-DQS_FAR_DIMM_NG_M_G_BYTE4\" )
					)
					( Status sCSetFlattened )
					( Origin gBackEnd )
				)
				( attribute "RELATIVE_PROPAGATION_DELAY" "0.00 MIL,195.00 MIL"
					( Parent
						( matchGroupRef "@baseboard_fab2_lib.baseboard_fab2(sch_1):\MG_DQ-DQS_FAR_DIMM_NG_M_G_BYTE4\" )
					)
					( Units "uMatchProp" "ns" 1.000000)
					( Status sCSetFlattened )
					( Origin gBackEnd )
				)
				( attribute "RELATIVE_PROPAGATION_DELAY_SCOPE" "G"
					( Parent
						( matchGroupRef "@baseboard_fab2_lib.baseboard_fab2(sch_1):\MG_DQ_FAR_DIMM_NG_M_G_BYTE4\" )
					)
					( Status sCSetFlattened )
					( Origin gBackEnd )
				)
				( attribute "RELATIVE_PROPAGATION_DELAY" "-50.00 MIL,50.00 MIL"
					( Parent
						( matchGroupRef "@baseboard_fab2_lib.baseboard_fab2(sch_1):\MG_DQ_FAR_DIMM_NG_M_G_BYTE4\" )
					)
					( Units "uMatchProp" "ns" 1.000000)
					( Status sCSetFlattened )
					( Origin gBackEnd )
				)
			)
			( pinPair "@baseboard_fab2_lib.baseboard_fab2(sch_1):\PP2838\"
				( pinRef "@baseboard_fab2_lib.baseboard_fab2(sch_1):page78_i13:DQ(35)" )
				( pinRef "@baseboard_fab2_lib.baseboard_fab2(sch_1):page57_i172:DDR0_DQ(35)" )
				( attribute "RELATIVE_PROPAGATION_DELAY_SCOPE" "G"
					( Parent
						( matchGroupRef "@baseboard_fab2_lib.baseboard_fab2(sch_1):\MG_DQ-DQS_NEAR_DIMM_NG_M_G_BYTE4\" )
					)
					( Status sCSetFlattened )
					( Origin gBackEnd )
				)
				( attribute "RELATIVE_PROPAGATION_DELAY" "0.00 MIL,195.00 MIL"
					( Parent
						( matchGroupRef "@baseboard_fab2_lib.baseboard_fab2(sch_1):\MG_DQ-DQS_NEAR_DIMM_NG_M_G_BYTE4\" )
					)
					( Units "uMatchProp" "ns" 1.000000)
					( Status sCSetFlattened )
					( Origin gBackEnd )
				)
				( attribute "RELATIVE_PROPAGATION_DELAY_SCOPE" "G"
					( Parent
						( matchGroupRef "@baseboard_fab2_lib.baseboard_fab2(sch_1):\MG_DQ_NEAR_DIMM_NG_M_G_BYTE4\" )
					)
					( Status sCSetFlattened )
					( Origin gBackEnd )
				)
				( attribute "RELATIVE_PROPAGATION_DELAY" "-50.00 MIL,50.00 MIL"
					( Parent
						( matchGroupRef "@baseboard_fab2_lib.baseboard_fab2(sch_1):\MG_DQ_NEAR_DIMM_NG_M_G_BYTE4\" )
					)
					( Units "uMatchProp" "ns" 1.000000)
					( Status sCSetFlattened )
					( Origin gBackEnd )
				)
			)
			( pinPair "@baseboard_fab2_lib.baseboard_fab2(sch_1):\PP2839\"
				( pinRef "@baseboard_fab2_lib.baseboard_fab2(sch_1):page57_i172:DDR0_DQ(36)" )
				( pinRef "@baseboard_fab2_lib.baseboard_fab2(sch_1):page77_i111:DQ(37)" )
				( attribute "RELATIVE_PROPAGATION_DELAY_SCOPE" "G"
					( Parent
						( matchGroupRef "@baseboard_fab2_lib.baseboard_fab2(sch_1):\MG_DQ-DQS_FAR_DIMM_NG_M_G_BYTE4\" )
					)
					( Status sCSetFlattened )
					( Origin gBackEnd )
				)
				( attribute "RELATIVE_PROPAGATION_DELAY" "0.00 MIL,195.00 MIL"
					( Parent
						( matchGroupRef "@baseboard_fab2_lib.baseboard_fab2(sch_1):\MG_DQ-DQS_FAR_DIMM_NG_M_G_BYTE4\" )
					)
					( Units "uMatchProp" "ns" 1.000000)
					( Status sCSetFlattened )
					( Origin gBackEnd )
				)
				( attribute "RELATIVE_PROPAGATION_DELAY_SCOPE" "G"
					( Parent
						( matchGroupRef "@baseboard_fab2_lib.baseboard_fab2(sch_1):\MG_DQ_FAR_DIMM_NG_M_G_BYTE4\" )
					)
					( Status sCSetFlattened )
					( Origin gBackEnd )
				)
				( attribute "RELATIVE_PROPAGATION_DELAY" "-50.00 MIL,50.00 MIL"
					( Parent
						( matchGroupRef "@baseboard_fab2_lib.baseboard_fab2(sch_1):\MG_DQ_FAR_DIMM_NG_M_G_BYTE4\" )
					)
					( Units "uMatchProp" "ns" 1.000000)
					( Status sCSetFlattened )
					( Origin gBackEnd )
				)
			)
			( pinPair "@baseboard_fab2_lib.baseboard_fab2(sch_1):\PP2841\"
				( pinRef "@baseboard_fab2_lib.baseboard_fab2(sch_1):page78_i13:DQ(36)" )
				( pinRef "@baseboard_fab2_lib.baseboard_fab2(sch_1):page57_i172:DDR0_DQ(36)" )
				( attribute "RELATIVE_PROPAGATION_DELAY_SCOPE" "G"
					( Parent
						( matchGroupRef "@baseboard_fab2_lib.baseboard_fab2(sch_1):\MG_DQ-DQS_NEAR_DIMM_NG_M_G_BYTE4\" )
					)
					( Status sCSetFlattened )
					( Origin gBackEnd )
				)
				( attribute "RELATIVE_PROPAGATION_DELAY" "0.00 MIL,195.00 MIL"
					( Parent
						( matchGroupRef "@baseboard_fab2_lib.baseboard_fab2(sch_1):\MG_DQ-DQS_NEAR_DIMM_NG_M_G_BYTE4\" )
					)
					( Units "uMatchProp" "ns" 1.000000)
					( Status sCSetFlattened )
					( Origin gBackEnd )
				)
				( attribute "RELATIVE_PROPAGATION_DELAY_SCOPE" "G"
					( Parent
						( matchGroupRef "@baseboard_fab2_lib.baseboard_fab2(sch_1):\MG_DQ_NEAR_DIMM_NG_M_G_BYTE4\" )
					)
					( Status sCSetFlattened )
					( Origin gBackEnd )
				)
				( attribute "RELATIVE_PROPAGATION_DELAY" "-50.00 MIL,50.00 MIL"
					( Parent
						( matchGroupRef "@baseboard_fab2_lib.baseboard_fab2(sch_1):\MG_DQ_NEAR_DIMM_NG_M_G_BYTE4\" )
					)
					( Units "uMatchProp" "ns" 1.000000)
					( Status sCSetFlattened )
					( Origin gBackEnd )
				)
			)
			( pinPair "@baseboard_fab2_lib.baseboard_fab2(sch_1):\PP2842\"
				( pinRef "@baseboard_fab2_lib.baseboard_fab2(sch_1):page57_i172:DDR0_DQ(37)" )
				( pinRef "@baseboard_fab2_lib.baseboard_fab2(sch_1):page77_i111:DQ(36)" )
				( attribute "RELATIVE_PROPAGATION_DELAY_SCOPE" "G"
					( Parent
						( matchGroupRef "@baseboard_fab2_lib.baseboard_fab2(sch_1):\MG_DQ-DQS_FAR_DIMM_NG_M_G_BYTE4\" )
					)
					( Status sCSetFlattened )
					( Origin gBackEnd )
				)
				( attribute "RELATIVE_PROPAGATION_DELAY" "0.00 MIL,195.00 MIL"
					( Parent
						( matchGroupRef "@baseboard_fab2_lib.baseboard_fab2(sch_1):\MG_DQ-DQS_FAR_DIMM_NG_M_G_BYTE4\" )
					)
					( Units "uMatchProp" "ns" 1.000000)
					( Status sCSetFlattened )
					( Origin gBackEnd )
				)
				( attribute "RELATIVE_PROPAGATION_DELAY_SCOPE" "G"
					( Parent
						( matchGroupRef "@baseboard_fab2_lib.baseboard_fab2(sch_1):\MG_DQ_FAR_DIMM_NG_M_G_BYTE4\" )
					)
					( Status sCSetFlattened )
					( Origin gBackEnd )
				)
				( attribute "RELATIVE_PROPAGATION_DELAY" "-50.00 MIL,50.00 MIL"
					( Parent
						( matchGroupRef "@baseboard_fab2_lib.baseboard_fab2(sch_1):\MG_DQ_FAR_DIMM_NG_M_G_BYTE4\" )
					)
					( Units "uMatchProp" "ns" 1.000000)
					( Status sCSetFlattened )
					( Origin gBackEnd )
				)
			)
			( pinPair "@baseboard_fab2_lib.baseboard_fab2(sch_1):\PP2844\"
				( pinRef "@baseboard_fab2_lib.baseboard_fab2(sch_1):page78_i13:DQ(37)" )
				( pinRef "@baseboard_fab2_lib.baseboard_fab2(sch_1):page57_i172:DDR0_DQ(37)" )
				( attribute "RELATIVE_PROPAGATION_DELAY_SCOPE" "G"
					( Parent
						( matchGroupRef "@baseboard_fab2_lib.baseboard_fab2(sch_1):\MG_DQ-DQS_NEAR_DIMM_NG_M_G_BYTE4\" )
					)
					( Status sCSetFlattened )
					( Origin gBackEnd )
				)
				( attribute "RELATIVE_PROPAGATION_DELAY" "0.00 MIL,195.00 MIL"
					( Parent
						( matchGroupRef "@baseboard_fab2_lib.baseboard_fab2(sch_1):\MG_DQ-DQS_NEAR_DIMM_NG_M_G_BYTE4\" )
					)
					( Units "uMatchProp" "ns" 1.000000)
					( Status sCSetFlattened )
					( Origin gBackEnd )
				)
				( attribute "RELATIVE_PROPAGATION_DELAY_SCOPE" "G"
					( Parent
						( matchGroupRef "@baseboard_fab2_lib.baseboard_fab2(sch_1):\MG_DQ_NEAR_DIMM_NG_M_G_BYTE4\" )
					)
					( Status sCSetFlattened )
					( Origin gBackEnd )
				)
				( attribute "RELATIVE_PROPAGATION_DELAY" "-50.00 MIL,50.00 MIL"
					( Parent
						( matchGroupRef "@baseboard_fab2_lib.baseboard_fab2(sch_1):\MG_DQ_NEAR_DIMM_NG_M_G_BYTE4\" )
					)
					( Units "uMatchProp" "ns" 1.000000)
					( Status sCSetFlattened )
					( Origin gBackEnd )
				)
			)
			( pinPair "@baseboard_fab2_lib.baseboard_fab2(sch_1):\PP2845\"
				( pinRef "@baseboard_fab2_lib.baseboard_fab2(sch_1):page57_i172:DDR0_DQ(38)" )
				( pinRef "@baseboard_fab2_lib.baseboard_fab2(sch_1):page77_i111:DQ(39)" )
				( attribute "RELATIVE_PROPAGATION_DELAY_SCOPE" "G"
					( Parent
						( matchGroupRef "@baseboard_fab2_lib.baseboard_fab2(sch_1):\MG_DQ-DQS_FAR_DIMM_NG_M_G_BYTE4\" )
					)
					( Status sCSetFlattened )
					( Origin gBackEnd )
				)
				( attribute "RELATIVE_PROPAGATION_DELAY" "0.00 MIL,195.00 MIL"
					( Parent
						( matchGroupRef "@baseboard_fab2_lib.baseboard_fab2(sch_1):\MG_DQ-DQS_FAR_DIMM_NG_M_G_BYTE4\" )
					)
					( Units "uMatchProp" "ns" 1.000000)
					( Status sCSetFlattened )
					( Origin gBackEnd )
				)
				( attribute "RELATIVE_PROPAGATION_DELAY_SCOPE" "G"
					( Parent
						( matchGroupRef "@baseboard_fab2_lib.baseboard_fab2(sch_1):\MG_DQ_FAR_DIMM_NG_M_G_BYTE4\" )
					)
					( Status sCSetFlattened )
					( Origin gBackEnd )
				)
				( attribute "RELATIVE_PROPAGATION_DELAY" "-50.00 MIL,50.00 MIL"
					( Parent
						( matchGroupRef "@baseboard_fab2_lib.baseboard_fab2(sch_1):\MG_DQ_FAR_DIMM_NG_M_G_BYTE4\" )
					)
					( Units "uMatchProp" "ns" 1.000000)
					( Status sCSetFlattened )
					( Origin gBackEnd )
				)
			)
			( pinPair "@baseboard_fab2_lib.baseboard_fab2(sch_1):\PP2847\"
				( pinRef "@baseboard_fab2_lib.baseboard_fab2(sch_1):page78_i13:DQ(38)" )
				( pinRef "@baseboard_fab2_lib.baseboard_fab2(sch_1):page57_i172:DDR0_DQ(38)" )
				( attribute "RELATIVE_PROPAGATION_DELAY_SCOPE" "G"
					( Parent
						( matchGroupRef "@baseboard_fab2_lib.baseboard_fab2(sch_1):\MG_DQ-DQS_NEAR_DIMM_NG_M_G_BYTE4\" )
					)
					( Status sCSetFlattened )
					( Origin gBackEnd )
				)
				( attribute "RELATIVE_PROPAGATION_DELAY" "0.00 MIL,195.00 MIL"
					( Parent
						( matchGroupRef "@baseboard_fab2_lib.baseboard_fab2(sch_1):\MG_DQ-DQS_NEAR_DIMM_NG_M_G_BYTE4\" )
					)
					( Units "uMatchProp" "ns" 1.000000)
					( Status sCSetFlattened )
					( Origin gBackEnd )
				)
				( attribute "RELATIVE_PROPAGATION_DELAY_SCOPE" "G"
					( Parent
						( matchGroupRef "@baseboard_fab2_lib.baseboard_fab2(sch_1):\MG_DQ_NEAR_DIMM_NG_M_G_BYTE4\" )
					)
					( Status sCSetFlattened )
					( Origin gBackEnd )
				)
				( attribute "RELATIVE_PROPAGATION_DELAY" "-50.00 MIL,50.00 MIL"
					( Parent
						( matchGroupRef "@baseboard_fab2_lib.baseboard_fab2(sch_1):\MG_DQ_NEAR_DIMM_NG_M_G_BYTE4\" )
					)
					( Units "uMatchProp" "ns" 1.000000)
					( Status sCSetFlattened )
					( Origin gBackEnd )
				)
			)
			( pinPair "@baseboard_fab2_lib.baseboard_fab2(sch_1):\PP2848\"
				( pinRef "@baseboard_fab2_lib.baseboard_fab2(sch_1):page57_i172:DDR0_DQ(39)" )
				( pinRef "@baseboard_fab2_lib.baseboard_fab2(sch_1):page77_i111:DQ(38)" )
				( attribute "RELATIVE_PROPAGATION_DELAY_SCOPE" "G"
					( Parent
						( matchGroupRef "@baseboard_fab2_lib.baseboard_fab2(sch_1):\MG_DQ-DQS_FAR_DIMM_NG_M_G_BYTE4\" )
					)
					( Status sCSetFlattened )
					( Origin gBackEnd )
				)
				( attribute "RELATIVE_PROPAGATION_DELAY" "0.00 MIL,195.00 MIL"
					( Parent
						( matchGroupRef "@baseboard_fab2_lib.baseboard_fab2(sch_1):\MG_DQ-DQS_FAR_DIMM_NG_M_G_BYTE4\" )
					)
					( Units "uMatchProp" "ns" 1.000000)
					( Status sCSetFlattened )
					( Origin gBackEnd )
				)
				( attribute "RELATIVE_PROPAGATION_DELAY_SCOPE" "G"
					( Parent
						( matchGroupRef "@baseboard_fab2_lib.baseboard_fab2(sch_1):\MG_DQ_FAR_DIMM_NG_M_G_BYTE4\" )
					)
					( Status sCSetFlattened )
					( Origin gBackEnd )
				)
				( attribute "RELATIVE_PROPAGATION_DELAY" "-50.00 MIL,50.00 MIL"
					( Parent
						( matchGroupRef "@baseboard_fab2_lib.baseboard_fab2(sch_1):\MG_DQ_FAR_DIMM_NG_M_G_BYTE4\" )
					)
					( Units "uMatchProp" "ns" 1.000000)
					( Status sCSetFlattened )
					( Origin gBackEnd )
				)
			)
			( pinPair "@baseboard_fab2_lib.baseboard_fab2(sch_1):\PP2850\"
				( pinRef "@baseboard_fab2_lib.baseboard_fab2(sch_1):page78_i13:DQ(39)" )
				( pinRef "@baseboard_fab2_lib.baseboard_fab2(sch_1):page57_i172:DDR0_DQ(39)" )
				( attribute "RELATIVE_PROPAGATION_DELAY_SCOPE" "G"
					( Parent
						( matchGroupRef "@baseboard_fab2_lib.baseboard_fab2(sch_1):\MG_DQ-DQS_NEAR_DIMM_NG_M_G_BYTE4\" )
					)
					( Status sCSetFlattened )
					( Origin gBackEnd )
				)
				( attribute "RELATIVE_PROPAGATION_DELAY" "0.00 MIL,195.00 MIL"
					( Parent
						( matchGroupRef "@baseboard_fab2_lib.baseboard_fab2(sch_1):\MG_DQ-DQS_NEAR_DIMM_NG_M_G_BYTE4\" )
					)
					( Units "uMatchProp" "ns" 1.000000)
					( Status sCSetFlattened )
					( Origin gBackEnd )
				)
				( attribute "RELATIVE_PROPAGATION_DELAY_SCOPE" "G"
					( Parent
						( matchGroupRef "@baseboard_fab2_lib.baseboard_fab2(sch_1):\MG_DQ_NEAR_DIMM_NG_M_G_BYTE4\" )
					)
					( Status sCSetFlattened )
					( Origin gBackEnd )
				)
				( attribute "RELATIVE_PROPAGATION_DELAY" "-50.00 MIL,50.00 MIL"
					( Parent
						( matchGroupRef "@baseboard_fab2_lib.baseboard_fab2(sch_1):\MG_DQ_NEAR_DIMM_NG_M_G_BYTE4\" )
					)
					( Units "uMatchProp" "ns" 1.000000)
					( Status sCSetFlattened )
					( Origin gBackEnd )
				)
			)
			( pinPair "@baseboard_fab2_lib.baseboard_fab2(sch_1):\PP2803\"
				( pinRef "@baseboard_fab2_lib.baseboard_fab2(sch_1):page57_i172:DDR0_DQ(40)" )
				( pinRef "@baseboard_fab2_lib.baseboard_fab2(sch_1):page77_i111:DQ(41)" )
				( attribute "RELATIVE_PROPAGATION_DELAY_SCOPE" "G"
					( Parent
						( matchGroupRef "@baseboard_fab2_lib.baseboard_fab2(sch_1):\MG_DQ-DQS_FAR_DIMM_NG_M_G_BYTE5\" )
					)
					( Status sCSetFlattened )
					( Origin gBackEnd )
				)
				( attribute "RELATIVE_PROPAGATION_DELAY" "0.00 MIL,195.00 MIL"
					( Parent
						( matchGroupRef "@baseboard_fab2_lib.baseboard_fab2(sch_1):\MG_DQ-DQS_FAR_DIMM_NG_M_G_BYTE5\" )
					)
					( Units "uMatchProp" "ns" 1.000000)
					( Status sCSetFlattened )
					( Origin gBackEnd )
				)
				( attribute "RELATIVE_PROPAGATION_DELAY_SCOPE" "G"
					( Parent
						( matchGroupRef "@crescent_city_bb_fab1_lib.crescent_city_bb_fab1(sch_1):\MG_DQ_FAR_DIMM_NG_M_G_BYTE5\" )
					)
					( Status sCSetFlattened )
					( Origin gBackEnd )
				)
				( attribute "RELATIVE_PROPAGATION_DELAY" "-50.00 MIL,50.00 MIL"
					( Parent
						( matchGroupRef "@crescent_city_bb_fab1_lib.crescent_city_bb_fab1(sch_1):\MG_DQ_FAR_DIMM_NG_M_G_BYTE5\" )
					)
					( Units "uMatchProp" "ns" 1.000000)
					( Status sCSetFlattened )
					( Origin gBackEnd )
				)
			)
			( pinPair "@baseboard_fab2_lib.baseboard_fab2(sch_1):\PP2805\"
				( pinRef "@baseboard_fab2_lib.baseboard_fab2(sch_1):page57_i172:DDR0_DQ(40)" )
				( pinRef "@baseboard_fab2_lib.baseboard_fab2(sch_1):page78_i13:DQ(40)" )
				( attribute "RELATIVE_PROPAGATION_DELAY_SCOPE" "G"
					( Parent
						( matchGroupRef "@baseboard_fab2_lib.baseboard_fab2(sch_1):\MG_DQ-DQS_NEAR_DIMM_NG_M_G_BYTE5\" )
					)
					( Status sCSetFlattened )
					( Origin gBackEnd )
				)
				( attribute "RELATIVE_PROPAGATION_DELAY" "0.00 MIL,195.00 MIL"
					( Parent
						( matchGroupRef "@baseboard_fab2_lib.baseboard_fab2(sch_1):\MG_DQ-DQS_NEAR_DIMM_NG_M_G_BYTE5\" )
					)
					( Units "uMatchProp" "ns" 1.000000)
					( Status sCSetFlattened )
					( Origin gBackEnd )
				)
				( attribute "RELATIVE_PROPAGATION_DELAY_SCOPE" "G"
					( Parent
						( matchGroupRef "@crescent_city_bb_fab1_lib.crescent_city_bb_fab1(sch_1):\MG_DQ_NEAR_DIMM_NG_M_G_BYTE5\" )
					)
					( Status sCSetFlattened )
					( Origin gBackEnd )
				)
				( attribute "RELATIVE_PROPAGATION_DELAY" "-50.00 MIL,50.00 MIL"
					( Parent
						( matchGroupRef "@crescent_city_bb_fab1_lib.crescent_city_bb_fab1(sch_1):\MG_DQ_NEAR_DIMM_NG_M_G_BYTE5\" )
					)
					( Units "uMatchProp" "ns" 1.000000)
					( Status sCSetFlattened )
					( Origin gBackEnd )
				)
			)
			( pinPair "@baseboard_fab2_lib.baseboard_fab2(sch_1):\PP2806\"
				( pinRef "@baseboard_fab2_lib.baseboard_fab2(sch_1):page57_i172:DDR0_DQ(41)" )
				( pinRef "@baseboard_fab2_lib.baseboard_fab2(sch_1):page77_i111:DQ(40)" )
				( attribute "RELATIVE_PROPAGATION_DELAY_SCOPE" "G"
					( Parent
						( matchGroupRef "@baseboard_fab2_lib.baseboard_fab2(sch_1):\MG_DQ-DQS_FAR_DIMM_NG_M_G_BYTE5\" )
					)
					( Status sCSetFlattened )
					( Origin gBackEnd )
				)
				( attribute "RELATIVE_PROPAGATION_DELAY" "0.00 MIL,195.00 MIL"
					( Parent
						( matchGroupRef "@baseboard_fab2_lib.baseboard_fab2(sch_1):\MG_DQ-DQS_FAR_DIMM_NG_M_G_BYTE5\" )
					)
					( Units "uMatchProp" "ns" 1.000000)
					( Status sCSetFlattened )
					( Origin gBackEnd )
				)
				( attribute "RELATIVE_PROPAGATION_DELAY_SCOPE" "G"
					( Parent
						( matchGroupRef "@crescent_city_bb_fab1_lib.crescent_city_bb_fab1(sch_1):\MG_DQ_FAR_DIMM_NG_M_G_BYTE5\" )
					)
					( Status sCSetFlattened )
					( Origin gBackEnd )
				)
				( attribute "RELATIVE_PROPAGATION_DELAY" "-50.00 MIL,50.00 MIL"
					( Parent
						( matchGroupRef "@crescent_city_bb_fab1_lib.crescent_city_bb_fab1(sch_1):\MG_DQ_FAR_DIMM_NG_M_G_BYTE5\" )
					)
					( Units "uMatchProp" "ns" 1.000000)
					( Status sCSetFlattened )
					( Origin gBackEnd )
				)
			)
			( pinPair "@baseboard_fab2_lib.baseboard_fab2(sch_1):\PP2808\"
				( pinRef "@baseboard_fab2_lib.baseboard_fab2(sch_1):page78_i13:DQ(41)" )
				( pinRef "@baseboard_fab2_lib.baseboard_fab2(sch_1):page57_i172:DDR0_DQ(41)" )
				( attribute "RELATIVE_PROPAGATION_DELAY_SCOPE" "G"
					( Parent
						( matchGroupRef "@baseboard_fab2_lib.baseboard_fab2(sch_1):\MG_DQ-DQS_NEAR_DIMM_NG_M_G_BYTE5\" )
					)
					( Status sCSetFlattened )
					( Origin gBackEnd )
				)
				( attribute "RELATIVE_PROPAGATION_DELAY" "0.00 MIL,195.00 MIL"
					( Parent
						( matchGroupRef "@baseboard_fab2_lib.baseboard_fab2(sch_1):\MG_DQ-DQS_NEAR_DIMM_NG_M_G_BYTE5\" )
					)
					( Units "uMatchProp" "ns" 1.000000)
					( Status sCSetFlattened )
					( Origin gBackEnd )
				)
				( attribute "RELATIVE_PROPAGATION_DELAY_SCOPE" "G"
					( Parent
						( matchGroupRef "@crescent_city_bb_fab1_lib.crescent_city_bb_fab1(sch_1):\MG_DQ_NEAR_DIMM_NG_M_G_BYTE5\" )
					)
					( Status sCSetFlattened )
					( Origin gBackEnd )
				)
				( attribute "RELATIVE_PROPAGATION_DELAY" "-50.00 MIL,50.00 MIL"
					( Parent
						( matchGroupRef "@crescent_city_bb_fab1_lib.crescent_city_bb_fab1(sch_1):\MG_DQ_NEAR_DIMM_NG_M_G_BYTE5\" )
					)
					( Units "uMatchProp" "ns" 1.000000)
					( Status sCSetFlattened )
					( Origin gBackEnd )
				)
			)
			( pinPair "@baseboard_fab2_lib.baseboard_fab2(sch_1):\PP2809\"
				( pinRef "@baseboard_fab2_lib.baseboard_fab2(sch_1):page57_i172:DDR0_DQ(42)" )
				( pinRef "@baseboard_fab2_lib.baseboard_fab2(sch_1):page77_i111:DQ(43)" )
				( attribute "RELATIVE_PROPAGATION_DELAY_SCOPE" "G"
					( Parent
						( matchGroupRef "@baseboard_fab2_lib.baseboard_fab2(sch_1):\MG_DQ-DQS_FAR_DIMM_NG_M_G_BYTE5\" )
					)
					( Status sCSetFlattened )
					( Origin gBackEnd )
				)
				( attribute "RELATIVE_PROPAGATION_DELAY" "0.00 MIL,195.00 MIL"
					( Parent
						( matchGroupRef "@baseboard_fab2_lib.baseboard_fab2(sch_1):\MG_DQ-DQS_FAR_DIMM_NG_M_G_BYTE5\" )
					)
					( Units "uMatchProp" "ns" 1.000000)
					( Status sCSetFlattened )
					( Origin gBackEnd )
				)
				( attribute "RELATIVE_PROPAGATION_DELAY_SCOPE" "G"
					( Parent
						( matchGroupRef "@crescent_city_bb_fab1_lib.crescent_city_bb_fab1(sch_1):\MG_DQ_FAR_DIMM_NG_M_G_BYTE5\" )
					)
					( Status sCSetFlattened )
					( Origin gBackEnd )
				)
				( attribute "RELATIVE_PROPAGATION_DELAY" "-50.00 MIL,50.00 MIL"
					( Parent
						( matchGroupRef "@crescent_city_bb_fab1_lib.crescent_city_bb_fab1(sch_1):\MG_DQ_FAR_DIMM_NG_M_G_BYTE5\" )
					)
					( Units "uMatchProp" "ns" 1.000000)
					( Status sCSetFlattened )
					( Origin gBackEnd )
				)
			)
			( pinPair "@baseboard_fab2_lib.baseboard_fab2(sch_1):\PP2811\"
				( pinRef "@baseboard_fab2_lib.baseboard_fab2(sch_1):page78_i13:DQ(42)" )
				( pinRef "@baseboard_fab2_lib.baseboard_fab2(sch_1):page57_i172:DDR0_DQ(42)" )
				( attribute "RELATIVE_PROPAGATION_DELAY_SCOPE" "G"
					( Parent
						( matchGroupRef "@baseboard_fab2_lib.baseboard_fab2(sch_1):\MG_DQ-DQS_NEAR_DIMM_NG_M_G_BYTE5\" )
					)
					( Status sCSetFlattened )
					( Origin gBackEnd )
				)
				( attribute "RELATIVE_PROPAGATION_DELAY" "0.00 MIL,195.00 MIL"
					( Parent
						( matchGroupRef "@baseboard_fab2_lib.baseboard_fab2(sch_1):\MG_DQ-DQS_NEAR_DIMM_NG_M_G_BYTE5\" )
					)
					( Units "uMatchProp" "ns" 1.000000)
					( Status sCSetFlattened )
					( Origin gBackEnd )
				)
				( attribute "RELATIVE_PROPAGATION_DELAY_SCOPE" "G"
					( Parent
						( matchGroupRef "@crescent_city_bb_fab1_lib.crescent_city_bb_fab1(sch_1):\MG_DQ_NEAR_DIMM_NG_M_G_BYTE5\" )
					)
					( Status sCSetFlattened )
					( Origin gBackEnd )
				)
				( attribute "RELATIVE_PROPAGATION_DELAY" "-50.00 MIL,50.00 MIL"
					( Parent
						( matchGroupRef "@crescent_city_bb_fab1_lib.crescent_city_bb_fab1(sch_1):\MG_DQ_NEAR_DIMM_NG_M_G_BYTE5\" )
					)
					( Units "uMatchProp" "ns" 1.000000)
					( Status sCSetFlattened )
					( Origin gBackEnd )
				)
			)
			( pinPair "@baseboard_fab2_lib.baseboard_fab2(sch_1):\PP2812\"
				( pinRef "@baseboard_fab2_lib.baseboard_fab2(sch_1):page57_i172:DDR0_DQ(43)" )
				( pinRef "@baseboard_fab2_lib.baseboard_fab2(sch_1):page77_i111:DQ(42)" )
				( attribute "RELATIVE_PROPAGATION_DELAY_SCOPE" "G"
					( Parent
						( matchGroupRef "@baseboard_fab2_lib.baseboard_fab2(sch_1):\MG_DQ-DQS_FAR_DIMM_NG_M_G_BYTE5\" )
					)
					( Status sCSetFlattened )
					( Origin gBackEnd )
				)
				( attribute "RELATIVE_PROPAGATION_DELAY" "0.00 MIL,195.00 MIL"
					( Parent
						( matchGroupRef "@baseboard_fab2_lib.baseboard_fab2(sch_1):\MG_DQ-DQS_FAR_DIMM_NG_M_G_BYTE5\" )
					)
					( Units "uMatchProp" "ns" 1.000000)
					( Status sCSetFlattened )
					( Origin gBackEnd )
				)
				( attribute "RELATIVE_PROPAGATION_DELAY_SCOPE" "G"
					( Parent
						( matchGroupRef "@crescent_city_bb_fab1_lib.crescent_city_bb_fab1(sch_1):\MG_DQ_FAR_DIMM_NG_M_G_BYTE5\" )
					)
					( Status sCSetFlattened )
					( Origin gBackEnd )
				)
				( attribute "RELATIVE_PROPAGATION_DELAY" "-50.00 MIL,50.00 MIL"
					( Parent
						( matchGroupRef "@crescent_city_bb_fab1_lib.crescent_city_bb_fab1(sch_1):\MG_DQ_FAR_DIMM_NG_M_G_BYTE5\" )
					)
					( Units "uMatchProp" "ns" 1.000000)
					( Status sCSetFlattened )
					( Origin gBackEnd )
				)
			)
			( pinPair "@baseboard_fab2_lib.baseboard_fab2(sch_1):\PP2814\"
				( pinRef "@baseboard_fab2_lib.baseboard_fab2(sch_1):page78_i13:DQ(43)" )
				( pinRef "@baseboard_fab2_lib.baseboard_fab2(sch_1):page57_i172:DDR0_DQ(43)" )
				( attribute "RELATIVE_PROPAGATION_DELAY_SCOPE" "G"
					( Parent
						( matchGroupRef "@baseboard_fab2_lib.baseboard_fab2(sch_1):\MG_DQ-DQS_NEAR_DIMM_NG_M_G_BYTE5\" )
					)
					( Status sCSetFlattened )
					( Origin gBackEnd )
				)
				( attribute "RELATIVE_PROPAGATION_DELAY" "0.00 MIL,195.00 MIL"
					( Parent
						( matchGroupRef "@baseboard_fab2_lib.baseboard_fab2(sch_1):\MG_DQ-DQS_NEAR_DIMM_NG_M_G_BYTE5\" )
					)
					( Units "uMatchProp" "ns" 1.000000)
					( Status sCSetFlattened )
					( Origin gBackEnd )
				)
				( attribute "RELATIVE_PROPAGATION_DELAY_SCOPE" "G"
					( Parent
						( matchGroupRef "@crescent_city_bb_fab1_lib.crescent_city_bb_fab1(sch_1):\MG_DQ_NEAR_DIMM_NG_M_G_BYTE5\" )
					)
					( Status sCSetFlattened )
					( Origin gBackEnd )
				)
				( attribute "RELATIVE_PROPAGATION_DELAY" "-50.00 MIL,50.00 MIL"
					( Parent
						( matchGroupRef "@crescent_city_bb_fab1_lib.crescent_city_bb_fab1(sch_1):\MG_DQ_NEAR_DIMM_NG_M_G_BYTE5\" )
					)
					( Units "uMatchProp" "ns" 1.000000)
					( Status sCSetFlattened )
					( Origin gBackEnd )
				)
			)
			( pinPair "@baseboard_fab2_lib.baseboard_fab2(sch_1):\PP2815\"
				( pinRef "@baseboard_fab2_lib.baseboard_fab2(sch_1):page57_i172:DDR0_DQ(44)" )
				( pinRef "@baseboard_fab2_lib.baseboard_fab2(sch_1):page77_i111:DQ(45)" )
				( attribute "RELATIVE_PROPAGATION_DELAY_SCOPE" "G"
					( Parent
						( matchGroupRef "@baseboard_fab2_lib.baseboard_fab2(sch_1):\MG_DQ-DQS_FAR_DIMM_NG_M_G_BYTE5\" )
					)
					( Status sCSetFlattened )
					( Origin gBackEnd )
				)
				( attribute "RELATIVE_PROPAGATION_DELAY" "0.00 MIL,195.00 MIL"
					( Parent
						( matchGroupRef "@baseboard_fab2_lib.baseboard_fab2(sch_1):\MG_DQ-DQS_FAR_DIMM_NG_M_G_BYTE5\" )
					)
					( Units "uMatchProp" "ns" 1.000000)
					( Status sCSetFlattened )
					( Origin gBackEnd )
				)
				( attribute "RELATIVE_PROPAGATION_DELAY_SCOPE" "G"
					( Parent
						( matchGroupRef "@crescent_city_bb_fab1_lib.crescent_city_bb_fab1(sch_1):\MG_DQ_FAR_DIMM_NG_M_G_BYTE5\" )
					)
					( Status sCSetFlattened )
					( Origin gBackEnd )
				)
				( attribute "RELATIVE_PROPAGATION_DELAY" "-50.00 MIL,50.00 MIL"
					( Parent
						( matchGroupRef "@crescent_city_bb_fab1_lib.crescent_city_bb_fab1(sch_1):\MG_DQ_FAR_DIMM_NG_M_G_BYTE5\" )
					)
					( Units "uMatchProp" "ns" 1.000000)
					( Status sCSetFlattened )
					( Origin gBackEnd )
				)
			)
			( pinPair "@baseboard_fab2_lib.baseboard_fab2(sch_1):\PP2817\"
				( pinRef "@baseboard_fab2_lib.baseboard_fab2(sch_1):page57_i172:DDR0_DQ(44)" )
				( pinRef "@baseboard_fab2_lib.baseboard_fab2(sch_1):page78_i13:DQ(44)" )
				( attribute "RELATIVE_PROPAGATION_DELAY_SCOPE" "G"
					( Parent
						( matchGroupRef "@baseboard_fab2_lib.baseboard_fab2(sch_1):\MG_DQ-DQS_NEAR_DIMM_NG_M_G_BYTE5\" )
					)
					( Status sCSetFlattened )
					( Origin gBackEnd )
				)
				( attribute "RELATIVE_PROPAGATION_DELAY" "0.00 MIL,195.00 MIL"
					( Parent
						( matchGroupRef "@baseboard_fab2_lib.baseboard_fab2(sch_1):\MG_DQ-DQS_NEAR_DIMM_NG_M_G_BYTE5\" )
					)
					( Units "uMatchProp" "ns" 1.000000)
					( Status sCSetFlattened )
					( Origin gBackEnd )
				)
				( attribute "RELATIVE_PROPAGATION_DELAY_SCOPE" "G"
					( Parent
						( matchGroupRef "@crescent_city_bb_fab1_lib.crescent_city_bb_fab1(sch_1):\MG_DQ_NEAR_DIMM_NG_M_G_BYTE5\" )
					)
					( Status sCSetFlattened )
					( Origin gBackEnd )
				)
				( attribute "RELATIVE_PROPAGATION_DELAY" "-50.00 MIL,50.00 MIL"
					( Parent
						( matchGroupRef "@crescent_city_bb_fab1_lib.crescent_city_bb_fab1(sch_1):\MG_DQ_NEAR_DIMM_NG_M_G_BYTE5\" )
					)
					( Units "uMatchProp" "ns" 1.000000)
					( Status sCSetFlattened )
					( Origin gBackEnd )
				)
			)
			( pinPair "@baseboard_fab2_lib.baseboard_fab2(sch_1):\PP5343\"
				( pinRef "@baseboard_fab2_lib.baseboard_fab2(sch_1):page23_i172:DDR0_DQ(0)" )
				( pinRef "@baseboard_fab2_lib.baseboard_fab2(sch_1):page43_i1:DQ(1)" )
				( attribute "RELATIVE_PROPAGATION_DELAY_SCOPE" "G"
					( Parent
						( matchGroupRef "@baseboard_fab2_lib.baseboard_fab2(sch_1):\MG_DQ-DQS_FAR_DIMM_NG_M_A_BYTE0\" )
					)
					( Status sCSetFlattened )
					( Origin gBackEnd )
				)
				( attribute "RELATIVE_PROPAGATION_DELAY" "0.00 MIL,195.00 MIL"
					( Parent
						( matchGroupRef "@baseboard_fab2_lib.baseboard_fab2(sch_1):\MG_DQ-DQS_FAR_DIMM_NG_M_A_BYTE0\" )
					)
					( Units "uMatchProp" "ns" 1.000000)
					( Status sCSetFlattened )
					( Origin gBackEnd )
				)
				( attribute "RELATIVE_PROPAGATION_DELAY_SCOPE" "G"
					( Parent
						( matchGroupRef "@baseboard_fab2_lib.baseboard_fab2(sch_1):\MG_DQ_FAR_DIMM_NG_M_A_BYTE0\" )
					)
					( Status sCSetFlattened )
					( Origin gBackEnd )
				)
				( attribute "RELATIVE_PROPAGATION_DELAY" "-50.00 MIL,50.00 MIL"
					( Parent
						( matchGroupRef "@baseboard_fab2_lib.baseboard_fab2(sch_1):\MG_DQ_FAR_DIMM_NG_M_A_BYTE0\" )
					)
					( Units "uMatchProp" "ns" 1.000000)
					( Status sCSetFlattened )
					( Origin gBackEnd )
				)
			)
			( pinPair "@baseboard_fab2_lib.baseboard_fab2(sch_1):\PP5345\"
				( pinRef "@baseboard_fab2_lib.baseboard_fab2(sch_1):page23_i172:DDR0_DQ(0)" )
				( pinRef "@baseboard_fab2_lib.baseboard_fab2(sch_1):page44_i13:DQ(0)" )
				( attribute "RELATIVE_PROPAGATION_DELAY_SCOPE" "G"
					( Parent
						( matchGroupRef "@baseboard_fab2_lib.baseboard_fab2(sch_1):\MG_DQ-DQS_NEAR_DIMM_NG_M_A_BYTE0\" )
					)
					( Status sCSetFlattened )
					( Origin gBackEnd )
				)
				( attribute "RELATIVE_PROPAGATION_DELAY" "0.00 MIL,195.00 MIL"
					( Parent
						( matchGroupRef "@baseboard_fab2_lib.baseboard_fab2(sch_1):\MG_DQ-DQS_NEAR_DIMM_NG_M_A_BYTE0\" )
					)
					( Units "uMatchProp" "ns" 1.000000)
					( Status sCSetFlattened )
					( Origin gBackEnd )
				)
				( attribute "RELATIVE_PROPAGATION_DELAY_SCOPE" "G"
					( Parent
						( matchGroupRef "@baseboard_fab2_lib.baseboard_fab2(sch_1):\MG_DQ_NEAR_DIMM_NG_M_A_BYTE0\" )
					)
					( Status sCSetFlattened )
					( Origin gBackEnd )
				)
				( attribute "RELATIVE_PROPAGATION_DELAY" "-50.00 MIL,50.00 MIL"
					( Parent
						( matchGroupRef "@baseboard_fab2_lib.baseboard_fab2(sch_1):\MG_DQ_NEAR_DIMM_NG_M_A_BYTE0\" )
					)
					( Units "uMatchProp" "ns" 1.000000)
					( Status sCSetFlattened )
					( Origin gBackEnd )
				)
			)
			( pinPair "@baseboard_fab2_lib.baseboard_fab2(sch_1):\PP5346\"
				( pinRef "@baseboard_fab2_lib.baseboard_fab2(sch_1):page23_i172:DDR0_DQ(1)" )
				( pinRef "@baseboard_fab2_lib.baseboard_fab2(sch_1):page43_i1:DQ(0)" )
				( attribute "RELATIVE_PROPAGATION_DELAY_SCOPE" "G"
					( Parent
						( matchGroupRef "@baseboard_fab2_lib.baseboard_fab2(sch_1):\MG_DQ-DQS_FAR_DIMM_NG_M_A_BYTE0\" )
					)
					( Status sCSetFlattened )
					( Origin gBackEnd )
				)
				( attribute "RELATIVE_PROPAGATION_DELAY" "0.00 MIL,195.00 MIL"
					( Parent
						( matchGroupRef "@baseboard_fab2_lib.baseboard_fab2(sch_1):\MG_DQ-DQS_FAR_DIMM_NG_M_A_BYTE0\" )
					)
					( Units "uMatchProp" "ns" 1.000000)
					( Status sCSetFlattened )
					( Origin gBackEnd )
				)
				( attribute "RELATIVE_PROPAGATION_DELAY_SCOPE" "G"
					( Parent
						( matchGroupRef "@baseboard_fab2_lib.baseboard_fab2(sch_1):\MG_DQ_FAR_DIMM_NG_M_A_BYTE0\" )
					)
					( Status sCSetFlattened )
					( Origin gBackEnd )
				)
				( attribute "RELATIVE_PROPAGATION_DELAY" "-50.00 MIL,50.00 MIL"
					( Parent
						( matchGroupRef "@baseboard_fab2_lib.baseboard_fab2(sch_1):\MG_DQ_FAR_DIMM_NG_M_A_BYTE0\" )
					)
					( Units "uMatchProp" "ns" 1.000000)
					( Status sCSetFlattened )
					( Origin gBackEnd )
				)
			)
			( pinPair "@baseboard_fab2_lib.baseboard_fab2(sch_1):\PP5348\"
				( pinRef "@baseboard_fab2_lib.baseboard_fab2(sch_1):page23_i172:DDR0_DQ(1)" )
				( pinRef "@baseboard_fab2_lib.baseboard_fab2(sch_1):page44_i13:DQ(1)" )
				( attribute "RELATIVE_PROPAGATION_DELAY_SCOPE" "G"
					( Parent
						( matchGroupRef "@baseboard_fab2_lib.baseboard_fab2(sch_1):\MG_DQ-DQS_NEAR_DIMM_NG_M_A_BYTE0\" )
					)
					( Status sCSetFlattened )
					( Origin gBackEnd )
				)
				( attribute "RELATIVE_PROPAGATION_DELAY" "0.00 MIL,195.00 MIL"
					( Parent
						( matchGroupRef "@baseboard_fab2_lib.baseboard_fab2(sch_1):\MG_DQ-DQS_NEAR_DIMM_NG_M_A_BYTE0\" )
					)
					( Units "uMatchProp" "ns" 1.000000)
					( Status sCSetFlattened )
					( Origin gBackEnd )
				)
				( attribute "RELATIVE_PROPAGATION_DELAY_SCOPE" "G"
					( Parent
						( matchGroupRef "@baseboard_fab2_lib.baseboard_fab2(sch_1):\MG_DQ_NEAR_DIMM_NG_M_A_BYTE0\" )
					)
					( Status sCSetFlattened )
					( Origin gBackEnd )
				)
				( attribute "RELATIVE_PROPAGATION_DELAY" "-50.00 MIL,50.00 MIL"
					( Parent
						( matchGroupRef "@baseboard_fab2_lib.baseboard_fab2(sch_1):\MG_DQ_NEAR_DIMM_NG_M_A_BYTE0\" )
					)
					( Units "uMatchProp" "ns" 1.000000)
					( Status sCSetFlattened )
					( Origin gBackEnd )
				)
			)
			( pinPair "@baseboard_fab2_lib.baseboard_fab2(sch_1):\PP5349\"
				( pinRef "@baseboard_fab2_lib.baseboard_fab2(sch_1):page23_i172:DDR0_DQ(2)" )
				( pinRef "@baseboard_fab2_lib.baseboard_fab2(sch_1):page43_i1:DQ(3)" )
				( attribute "RELATIVE_PROPAGATION_DELAY_SCOPE" "G"
					( Parent
						( matchGroupRef "@baseboard_fab2_lib.baseboard_fab2(sch_1):\MG_DQ-DQS_FAR_DIMM_NG_M_A_BYTE0\" )
					)
					( Status sCSetFlattened )
					( Origin gBackEnd )
				)
				( attribute "RELATIVE_PROPAGATION_DELAY" "0.00 MIL,195.00 MIL"
					( Parent
						( matchGroupRef "@baseboard_fab2_lib.baseboard_fab2(sch_1):\MG_DQ-DQS_FAR_DIMM_NG_M_A_BYTE0\" )
					)
					( Units "uMatchProp" "ns" 1.000000)
					( Status sCSetFlattened )
					( Origin gBackEnd )
				)
				( attribute "RELATIVE_PROPAGATION_DELAY_SCOPE" "G"
					( Parent
						( matchGroupRef "@baseboard_fab2_lib.baseboard_fab2(sch_1):\MG_DQ_FAR_DIMM_NG_M_A_BYTE0\" )
					)
					( Status sCSetFlattened )
					( Origin gBackEnd )
				)
				( attribute "RELATIVE_PROPAGATION_DELAY" "-50.00 MIL,50.00 MIL"
					( Parent
						( matchGroupRef "@baseboard_fab2_lib.baseboard_fab2(sch_1):\MG_DQ_FAR_DIMM_NG_M_A_BYTE0\" )
					)
					( Units "uMatchProp" "ns" 1.000000)
					( Status sCSetFlattened )
					( Origin gBackEnd )
				)
			)
			( pinPair "@baseboard_fab2_lib.baseboard_fab2(sch_1):\PP5351\"
				( pinRef "@baseboard_fab2_lib.baseboard_fab2(sch_1):page23_i172:DDR0_DQ(2)" )
				( pinRef "@baseboard_fab2_lib.baseboard_fab2(sch_1):page44_i13:DQ(2)" )
				( attribute "RELATIVE_PROPAGATION_DELAY_SCOPE" "G"
					( Parent
						( matchGroupRef "@baseboard_fab2_lib.baseboard_fab2(sch_1):\MG_DQ-DQS_NEAR_DIMM_NG_M_A_BYTE0\" )
					)
					( Status sCSetFlattened )
					( Origin gBackEnd )
				)
				( attribute "RELATIVE_PROPAGATION_DELAY" "0.00 MIL,195.00 MIL"
					( Parent
						( matchGroupRef "@baseboard_fab2_lib.baseboard_fab2(sch_1):\MG_DQ-DQS_NEAR_DIMM_NG_M_A_BYTE0\" )
					)
					( Units "uMatchProp" "ns" 1.000000)
					( Status sCSetFlattened )
					( Origin gBackEnd )
				)
				( attribute "RELATIVE_PROPAGATION_DELAY_SCOPE" "G"
					( Parent
						( matchGroupRef "@baseboard_fab2_lib.baseboard_fab2(sch_1):\MG_DQ_NEAR_DIMM_NG_M_A_BYTE0\" )
					)
					( Status sCSetFlattened )
					( Origin gBackEnd )
				)
				( attribute "RELATIVE_PROPAGATION_DELAY" "-50.00 MIL,50.00 MIL"
					( Parent
						( matchGroupRef "@baseboard_fab2_lib.baseboard_fab2(sch_1):\MG_DQ_NEAR_DIMM_NG_M_A_BYTE0\" )
					)
					( Units "uMatchProp" "ns" 1.000000)
					( Status sCSetFlattened )
					( Origin gBackEnd )
				)
			)
			( pinPair "@baseboard_fab2_lib.baseboard_fab2(sch_1):\PP5352\"
				( pinRef "@baseboard_fab2_lib.baseboard_fab2(sch_1):page23_i172:DDR0_DQ(3)" )
				( pinRef "@baseboard_fab2_lib.baseboard_fab2(sch_1):page43_i1:DQ(2)" )
				( attribute "RELATIVE_PROPAGATION_DELAY_SCOPE" "G"
					( Parent
						( matchGroupRef "@baseboard_fab2_lib.baseboard_fab2(sch_1):\MG_DQ-DQS_FAR_DIMM_NG_M_A_BYTE0\" )
					)
					( Status sCSetFlattened )
					( Origin gBackEnd )
				)
				( attribute "RELATIVE_PROPAGATION_DELAY" "0.00 MIL,195.00 MIL"
					( Parent
						( matchGroupRef "@baseboard_fab2_lib.baseboard_fab2(sch_1):\MG_DQ-DQS_FAR_DIMM_NG_M_A_BYTE0\" )
					)
					( Units "uMatchProp" "ns" 1.000000)
					( Status sCSetFlattened )
					( Origin gBackEnd )
				)
				( attribute "RELATIVE_PROPAGATION_DELAY_SCOPE" "G"
					( Parent
						( matchGroupRef "@baseboard_fab2_lib.baseboard_fab2(sch_1):\MG_DQ_FAR_DIMM_NG_M_A_BYTE0\" )
					)
					( Status sCSetFlattened )
					( Origin gBackEnd )
				)
				( attribute "RELATIVE_PROPAGATION_DELAY" "-50.00 MIL,50.00 MIL"
					( Parent
						( matchGroupRef "@baseboard_fab2_lib.baseboard_fab2(sch_1):\MG_DQ_FAR_DIMM_NG_M_A_BYTE0\" )
					)
					( Units "uMatchProp" "ns" 1.000000)
					( Status sCSetFlattened )
					( Origin gBackEnd )
				)
			)
			( pinPair "@baseboard_fab2_lib.baseboard_fab2(sch_1):\PP5354\"
				( pinRef "@baseboard_fab2_lib.baseboard_fab2(sch_1):page23_i172:DDR0_DQ(3)" )
				( pinRef "@baseboard_fab2_lib.baseboard_fab2(sch_1):page44_i13:DQ(3)" )
				( attribute "RELATIVE_PROPAGATION_DELAY_SCOPE" "G"
					( Parent
						( matchGroupRef "@baseboard_fab2_lib.baseboard_fab2(sch_1):\MG_DQ-DQS_NEAR_DIMM_NG_M_A_BYTE0\" )
					)
					( Status sCSetFlattened )
					( Origin gBackEnd )
				)
				( attribute "RELATIVE_PROPAGATION_DELAY" "0.00 MIL,195.00 MIL"
					( Parent
						( matchGroupRef "@baseboard_fab2_lib.baseboard_fab2(sch_1):\MG_DQ-DQS_NEAR_DIMM_NG_M_A_BYTE0\" )
					)
					( Units "uMatchProp" "ns" 1.000000)
					( Status sCSetFlattened )
					( Origin gBackEnd )
				)
				( attribute "RELATIVE_PROPAGATION_DELAY_SCOPE" "G"
					( Parent
						( matchGroupRef "@baseboard_fab2_lib.baseboard_fab2(sch_1):\MG_DQ_NEAR_DIMM_NG_M_A_BYTE0\" )
					)
					( Status sCSetFlattened )
					( Origin gBackEnd )
				)
				( attribute "RELATIVE_PROPAGATION_DELAY" "-50.00 MIL,50.00 MIL"
					( Parent
						( matchGroupRef "@baseboard_fab2_lib.baseboard_fab2(sch_1):\MG_DQ_NEAR_DIMM_NG_M_A_BYTE0\" )
					)
					( Units "uMatchProp" "ns" 1.000000)
					( Status sCSetFlattened )
					( Origin gBackEnd )
				)
			)
			( pinPair "@baseboard_fab2_lib.baseboard_fab2(sch_1):\PP5355\"
				( pinRef "@baseboard_fab2_lib.baseboard_fab2(sch_1):page23_i172:DDR0_DQ(4)" )
				( pinRef "@baseboard_fab2_lib.baseboard_fab2(sch_1):page43_i1:DQ(5)" )
				( attribute "RELATIVE_PROPAGATION_DELAY_SCOPE" "G"
					( Parent
						( matchGroupRef "@baseboard_fab2_lib.baseboard_fab2(sch_1):\MG_DQ-DQS_FAR_DIMM_NG_M_A_BYTE0\" )
					)
					( Status sCSetFlattened )
					( Origin gBackEnd )
				)
				( attribute "RELATIVE_PROPAGATION_DELAY" "0.00 MIL,195.00 MIL"
					( Parent
						( matchGroupRef "@baseboard_fab2_lib.baseboard_fab2(sch_1):\MG_DQ-DQS_FAR_DIMM_NG_M_A_BYTE0\" )
					)
					( Units "uMatchProp" "ns" 1.000000)
					( Status sCSetFlattened )
					( Origin gBackEnd )
				)
				( attribute "RELATIVE_PROPAGATION_DELAY_SCOPE" "G"
					( Parent
						( matchGroupRef "@baseboard_fab2_lib.baseboard_fab2(sch_1):\MG_DQ_FAR_DIMM_NG_M_A_BYTE0\" )
					)
					( Status sCSetFlattened )
					( Origin gBackEnd )
				)
				( attribute "RELATIVE_PROPAGATION_DELAY" "-50.00 MIL,50.00 MIL"
					( Parent
						( matchGroupRef "@baseboard_fab2_lib.baseboard_fab2(sch_1):\MG_DQ_FAR_DIMM_NG_M_A_BYTE0\" )
					)
					( Units "uMatchProp" "ns" 1.000000)
					( Status sCSetFlattened )
					( Origin gBackEnd )
				)
			)
			( pinPair "@baseboard_fab2_lib.baseboard_fab2(sch_1):\PP5357\"
				( pinRef "@baseboard_fab2_lib.baseboard_fab2(sch_1):page23_i172:DDR0_DQ(4)" )
				( pinRef "@baseboard_fab2_lib.baseboard_fab2(sch_1):page44_i13:DQ(4)" )
				( attribute "RELATIVE_PROPAGATION_DELAY_SCOPE" "G"
					( Parent
						( matchGroupRef "@baseboard_fab2_lib.baseboard_fab2(sch_1):\MG_DQ-DQS_NEAR_DIMM_NG_M_A_BYTE0\" )
					)
					( Status sCSetFlattened )
					( Origin gBackEnd )
				)
				( attribute "RELATIVE_PROPAGATION_DELAY" "0.00 MIL,195.00 MIL"
					( Parent
						( matchGroupRef "@baseboard_fab2_lib.baseboard_fab2(sch_1):\MG_DQ-DQS_NEAR_DIMM_NG_M_A_BYTE0\" )
					)
					( Units "uMatchProp" "ns" 1.000000)
					( Status sCSetFlattened )
					( Origin gBackEnd )
				)
				( attribute "RELATIVE_PROPAGATION_DELAY_SCOPE" "G"
					( Parent
						( matchGroupRef "@baseboard_fab2_lib.baseboard_fab2(sch_1):\MG_DQ_NEAR_DIMM_NG_M_A_BYTE0\" )
					)
					( Status sCSetFlattened )
					( Origin gBackEnd )
				)
				( attribute "RELATIVE_PROPAGATION_DELAY" "-50.00 MIL,50.00 MIL"
					( Parent
						( matchGroupRef "@baseboard_fab2_lib.baseboard_fab2(sch_1):\MG_DQ_NEAR_DIMM_NG_M_A_BYTE0\" )
					)
					( Units "uMatchProp" "ns" 1.000000)
					( Status sCSetFlattened )
					( Origin gBackEnd )
				)
			)
			( pinPair "@baseboard_fab2_lib.baseboard_fab2(sch_1):\PP5358\"
				( pinRef "@baseboard_fab2_lib.baseboard_fab2(sch_1):page23_i172:DDR0_DQ(5)" )
				( pinRef "@baseboard_fab2_lib.baseboard_fab2(sch_1):page43_i1:DQ(4)" )
				( attribute "RELATIVE_PROPAGATION_DELAY_SCOPE" "G"
					( Parent
						( matchGroupRef "@baseboard_fab2_lib.baseboard_fab2(sch_1):\MG_DQ-DQS_FAR_DIMM_NG_M_A_BYTE0\" )
					)
					( Status sCSetFlattened )
					( Origin gBackEnd )
				)
				( attribute "RELATIVE_PROPAGATION_DELAY" "0.00 MIL,195.00 MIL"
					( Parent
						( matchGroupRef "@baseboard_fab2_lib.baseboard_fab2(sch_1):\MG_DQ-DQS_FAR_DIMM_NG_M_A_BYTE0\" )
					)
					( Units "uMatchProp" "ns" 1.000000)
					( Status sCSetFlattened )
					( Origin gBackEnd )
				)
				( attribute "RELATIVE_PROPAGATION_DELAY_SCOPE" "G"
					( Parent
						( matchGroupRef "@baseboard_fab2_lib.baseboard_fab2(sch_1):\MG_DQ_FAR_DIMM_NG_M_A_BYTE0\" )
					)
					( Status sCSetFlattened )
					( Origin gBackEnd )
				)
				( attribute "RELATIVE_PROPAGATION_DELAY" "-50.00 MIL,50.00 MIL"
					( Parent
						( matchGroupRef "@baseboard_fab2_lib.baseboard_fab2(sch_1):\MG_DQ_FAR_DIMM_NG_M_A_BYTE0\" )
					)
					( Units "uMatchProp" "ns" 1.000000)
					( Status sCSetFlattened )
					( Origin gBackEnd )
				)
			)
			( pinPair "@baseboard_fab2_lib.baseboard_fab2(sch_1):\PP5360\"
				( pinRef "@baseboard_fab2_lib.baseboard_fab2(sch_1):page23_i172:DDR0_DQ(5)" )
				( pinRef "@baseboard_fab2_lib.baseboard_fab2(sch_1):page44_i13:DQ(5)" )
				( attribute "RELATIVE_PROPAGATION_DELAY_SCOPE" "G"
					( Parent
						( matchGroupRef "@baseboard_fab2_lib.baseboard_fab2(sch_1):\MG_DQ-DQS_NEAR_DIMM_NG_M_A_BYTE0\" )
					)
					( Status sCSetFlattened )
					( Origin gBackEnd )
				)
				( attribute "RELATIVE_PROPAGATION_DELAY" "0.00 MIL,195.00 MIL"
					( Parent
						( matchGroupRef "@baseboard_fab2_lib.baseboard_fab2(sch_1):\MG_DQ-DQS_NEAR_DIMM_NG_M_A_BYTE0\" )
					)
					( Units "uMatchProp" "ns" 1.000000)
					( Status sCSetFlattened )
					( Origin gBackEnd )
				)
				( attribute "RELATIVE_PROPAGATION_DELAY_SCOPE" "G"
					( Parent
						( matchGroupRef "@baseboard_fab2_lib.baseboard_fab2(sch_1):\MG_DQ_NEAR_DIMM_NG_M_A_BYTE0\" )
					)
					( Status sCSetFlattened )
					( Origin gBackEnd )
				)
				( attribute "RELATIVE_PROPAGATION_DELAY" "-50.00 MIL,50.00 MIL"
					( Parent
						( matchGroupRef "@baseboard_fab2_lib.baseboard_fab2(sch_1):\MG_DQ_NEAR_DIMM_NG_M_A_BYTE0\" )
					)
					( Units "uMatchProp" "ns" 1.000000)
					( Status sCSetFlattened )
					( Origin gBackEnd )
				)
			)
			( pinPair "@baseboard_fab2_lib.baseboard_fab2(sch_1):\PP5361\"
				( pinRef "@baseboard_fab2_lib.baseboard_fab2(sch_1):page23_i172:DDR0_DQ(6)" )
				( pinRef "@baseboard_fab2_lib.baseboard_fab2(sch_1):page43_i1:DQ(7)" )
				( attribute "RELATIVE_PROPAGATION_DELAY_SCOPE" "G"
					( Parent
						( matchGroupRef "@baseboard_fab2_lib.baseboard_fab2(sch_1):\MG_DQ-DQS_FAR_DIMM_NG_M_A_BYTE0\" )
					)
					( Status sCSetFlattened )
					( Origin gBackEnd )
				)
				( attribute "RELATIVE_PROPAGATION_DELAY" "0.00 MIL,195.00 MIL"
					( Parent
						( matchGroupRef "@baseboard_fab2_lib.baseboard_fab2(sch_1):\MG_DQ-DQS_FAR_DIMM_NG_M_A_BYTE0\" )
					)
					( Units "uMatchProp" "ns" 1.000000)
					( Status sCSetFlattened )
					( Origin gBackEnd )
				)
				( attribute "RELATIVE_PROPAGATION_DELAY_SCOPE" "G"
					( Parent
						( matchGroupRef "@baseboard_fab2_lib.baseboard_fab2(sch_1):\MG_DQ_FAR_DIMM_NG_M_A_BYTE0\" )
					)
					( Status sCSetFlattened )
					( Origin gBackEnd )
				)
				( attribute "RELATIVE_PROPAGATION_DELAY" "-50.00 MIL,50.00 MIL"
					( Parent
						( matchGroupRef "@baseboard_fab2_lib.baseboard_fab2(sch_1):\MG_DQ_FAR_DIMM_NG_M_A_BYTE0\" )
					)
					( Units "uMatchProp" "ns" 1.000000)
					( Status sCSetFlattened )
					( Origin gBackEnd )
				)
			)
			( pinPair "@baseboard_fab2_lib.baseboard_fab2(sch_1):\PP5363\"
				( pinRef "@baseboard_fab2_lib.baseboard_fab2(sch_1):page23_i172:DDR0_DQ(6)" )
				( pinRef "@baseboard_fab2_lib.baseboard_fab2(sch_1):page44_i13:DQ(6)" )
				( attribute "RELATIVE_PROPAGATION_DELAY_SCOPE" "G"
					( Parent
						( matchGroupRef "@baseboard_fab2_lib.baseboard_fab2(sch_1):\MG_DQ-DQS_NEAR_DIMM_NG_M_A_BYTE0\" )
					)
					( Status sCSetFlattened )
					( Origin gBackEnd )
				)
				( attribute "RELATIVE_PROPAGATION_DELAY" "0.00 MIL,195.00 MIL"
					( Parent
						( matchGroupRef "@baseboard_fab2_lib.baseboard_fab2(sch_1):\MG_DQ-DQS_NEAR_DIMM_NG_M_A_BYTE0\" )
					)
					( Units "uMatchProp" "ns" 1.000000)
					( Status sCSetFlattened )
					( Origin gBackEnd )
				)
				( attribute "RELATIVE_PROPAGATION_DELAY_SCOPE" "G"
					( Parent
						( matchGroupRef "@baseboard_fab2_lib.baseboard_fab2(sch_1):\MG_DQ_NEAR_DIMM_NG_M_A_BYTE0\" )
					)
					( Status sCSetFlattened )
					( Origin gBackEnd )
				)
				( attribute "RELATIVE_PROPAGATION_DELAY" "-50.00 MIL,50.00 MIL"
					( Parent
						( matchGroupRef "@baseboard_fab2_lib.baseboard_fab2(sch_1):\MG_DQ_NEAR_DIMM_NG_M_A_BYTE0\" )
					)
					( Units "uMatchProp" "ns" 1.000000)
					( Status sCSetFlattened )
					( Origin gBackEnd )
				)
			)
			( pinPair "@baseboard_fab2_lib.baseboard_fab2(sch_1):\PP5364\"
				( pinRef "@baseboard_fab2_lib.baseboard_fab2(sch_1):page23_i172:DDR0_DQ(7)" )
				( pinRef "@baseboard_fab2_lib.baseboard_fab2(sch_1):page43_i1:DQ(6)" )
				( attribute "RELATIVE_PROPAGATION_DELAY_SCOPE" "G"
					( Parent
						( matchGroupRef "@baseboard_fab2_lib.baseboard_fab2(sch_1):\MG_DQ-DQS_FAR_DIMM_NG_M_A_BYTE0\" )
					)
					( Status sCSetFlattened )
					( Origin gBackEnd )
				)
				( attribute "RELATIVE_PROPAGATION_DELAY" "0.00 MIL,195.00 MIL"
					( Parent
						( matchGroupRef "@baseboard_fab2_lib.baseboard_fab2(sch_1):\MG_DQ-DQS_FAR_DIMM_NG_M_A_BYTE0\" )
					)
					( Units "uMatchProp" "ns" 1.000000)
					( Status sCSetFlattened )
					( Origin gBackEnd )
				)
				( attribute "RELATIVE_PROPAGATION_DELAY_SCOPE" "G"
					( Parent
						( matchGroupRef "@baseboard_fab2_lib.baseboard_fab2(sch_1):\MG_DQ_FAR_DIMM_NG_M_A_BYTE0\" )
					)
					( Status sCSetFlattened )
					( Origin gBackEnd )
				)
				( attribute "RELATIVE_PROPAGATION_DELAY" "-50.00 MIL,50.00 MIL"
					( Parent
						( matchGroupRef "@baseboard_fab2_lib.baseboard_fab2(sch_1):\MG_DQ_FAR_DIMM_NG_M_A_BYTE0\" )
					)
					( Units "uMatchProp" "ns" 1.000000)
					( Status sCSetFlattened )
					( Origin gBackEnd )
				)
			)
			( pinPair "@baseboard_fab2_lib.baseboard_fab2(sch_1):\PP5366\"
				( pinRef "@baseboard_fab2_lib.baseboard_fab2(sch_1):page23_i172:DDR0_DQ(7)" )
				( pinRef "@baseboard_fab2_lib.baseboard_fab2(sch_1):page44_i13:DQ(7)" )
				( attribute "RELATIVE_PROPAGATION_DELAY_SCOPE" "G"
					( Parent
						( matchGroupRef "@baseboard_fab2_lib.baseboard_fab2(sch_1):\MG_DQ-DQS_NEAR_DIMM_NG_M_A_BYTE0\" )
					)
					( Status sCSetFlattened )
					( Origin gBackEnd )
				)
				( attribute "RELATIVE_PROPAGATION_DELAY" "0.00 MIL,195.00 MIL"
					( Parent
						( matchGroupRef "@baseboard_fab2_lib.baseboard_fab2(sch_1):\MG_DQ-DQS_NEAR_DIMM_NG_M_A_BYTE0\" )
					)
					( Units "uMatchProp" "ns" 1.000000)
					( Status sCSetFlattened )
					( Origin gBackEnd )
				)
				( attribute "RELATIVE_PROPAGATION_DELAY_SCOPE" "G"
					( Parent
						( matchGroupRef "@baseboard_fab2_lib.baseboard_fab2(sch_1):\MG_DQ_NEAR_DIMM_NG_M_A_BYTE0\" )
					)
					( Status sCSetFlattened )
					( Origin gBackEnd )
				)
				( attribute "RELATIVE_PROPAGATION_DELAY" "-50.00 MIL,50.00 MIL"
					( Parent
						( matchGroupRef "@baseboard_fab2_lib.baseboard_fab2(sch_1):\MG_DQ_NEAR_DIMM_NG_M_A_BYTE0\" )
					)
					( Units "uMatchProp" "ns" 1.000000)
					( Status sCSetFlattened )
					( Origin gBackEnd )
				)
			)
			( pinPair "@baseboard_fab2_lib.baseboard_fab2(sch_1):\PP841\"
				( pinRef "@baseboard_fab2_lib.baseboard_fab2(sch_1):page58_i172:DDR1_DQS_DN(2)" )
				( pinRef "@baseboard_fab2_lib.baseboard_fab2(sch_1):page79_i64:DQS2N" )
				( attribute "RELATIVE_PROPAGATION_DELAY_SCOPE" "G"
					( Parent
						( matchGroupRef "@baseboard_fab2_lib.baseboard_fab2(sch_1):\MG_DQ-DQS_FAR_DIMM_NG_M_H_BYTE2\" )
					)
					( Status sCSetFlattened )
					( Origin gBackEnd )
				)
				( attribute "RELATIVE_PROPAGATION_DELAY" ",5.00 MIL"
					( Parent
						( matchGroupRef "@baseboard_fab2_lib.baseboard_fab2(sch_1):\MG_DQ-DQS_FAR_DIMM_NG_M_H_BYTE2\" )
					)
					( Units "uMatchProp" "ns" 1.000000)
					( Status sCSetFlattened )
					( Origin gBackEnd )
				)
			)
			( pinPair "@baseboard_fab2_lib.baseboard_fab2(sch_1):\PP842\"
				( pinRef "@baseboard_fab2_lib.baseboard_fab2(sch_1):page80_i101:DQS2N" )
				( pinRef "@baseboard_fab2_lib.baseboard_fab2(sch_1):page58_i172:DDR1_DQS_DN(2)" )
				( attribute "RELATIVE_PROPAGATION_DELAY_SCOPE" "G"
					( Parent
						( matchGroupRef "@baseboard_fab2_lib.baseboard_fab2(sch_1):\MG_DQ-DQS_NEAR_DIMM_NG_M_H_BYTE2\" )
					)
					( Status sCSetFlattened )
					( Origin gBackEnd )
				)
				( attribute "RELATIVE_PROPAGATION_DELAY" ",5.00 MIL"
					( Parent
						( matchGroupRef "@baseboard_fab2_lib.baseboard_fab2(sch_1):\MG_DQ-DQS_NEAR_DIMM_NG_M_H_BYTE2\" )
					)
					( Units "uMatchProp" "ns" 1.000000)
					( Status sCSetFlattened )
					( Origin gBackEnd )
				)
			)
			( pinPair "@baseboard_fab2_lib.baseboard_fab2(sch_1):\PP844\"
				( pinRef "@baseboard_fab2_lib.baseboard_fab2(sch_1):page58_i172:DDR1_DQS_DP(2)" )
				( pinRef "@baseboard_fab2_lib.baseboard_fab2(sch_1):page79_i64:DQS2P" )
				( attribute "RELATIVE_PROPAGATION_DELAY_SCOPE" "G"
					( Parent
						( matchGroupRef "@baseboard_fab2_lib.baseboard_fab2(sch_1):\MG_DQ-DQS_FAR_DIMM_NG_M_H_BYTE2\" )
					)
					( Status sCSetFlattened )
					( Origin gBackEnd )
				)
				( attribute "RELATIVE_PROPAGATION_DELAY" ",5.00 MIL"
					( Parent
						( matchGroupRef "@baseboard_fab2_lib.baseboard_fab2(sch_1):\MG_DQ-DQS_FAR_DIMM_NG_M_H_BYTE2\" )
					)
					( Units "uMatchProp" "ns" 1.000000)
					( Status sCSetFlattened )
					( Origin gBackEnd )
				)
			)
			( pinPair "@baseboard_fab2_lib.baseboard_fab2(sch_1):\PP845\"
				( pinRef "@baseboard_fab2_lib.baseboard_fab2(sch_1):page80_i101:DQS2P" )
				( pinRef "@baseboard_fab2_lib.baseboard_fab2(sch_1):page58_i172:DDR1_DQS_DP(2)" )
				( attribute "RELATIVE_PROPAGATION_DELAY_SCOPE" "G"
					( Parent
						( matchGroupRef "@baseboard_fab2_lib.baseboard_fab2(sch_1):\MG_DQ-DQS_NEAR_DIMM_NG_M_H_BYTE2\" )
					)
					( Status sCSetFlattened )
					( Origin gBackEnd )
				)
				( attribute "RELATIVE_PROPAGATION_DELAY" ",5.00 MIL"
					( Parent
						( matchGroupRef "@baseboard_fab2_lib.baseboard_fab2(sch_1):\MG_DQ-DQS_NEAR_DIMM_NG_M_H_BYTE2\" )
					)
					( Units "uMatchProp" "ns" 1.000000)
					( Status sCSetFlattened )
					( Origin gBackEnd )
				)
			)
			( pinPair "@baseboard_fab2_lib.baseboard_fab2(sch_1):\PP829\"
				( pinRef "@baseboard_fab2_lib.baseboard_fab2(sch_1):page58_i172:DDR1_DQS_DN(3)" )
				( pinRef "@baseboard_fab2_lib.baseboard_fab2(sch_1):page79_i64:DQS3N" )
				( attribute "RELATIVE_PROPAGATION_DELAY_SCOPE" "G"
					( Parent
						( matchGroupRef "@baseboard_fab2_lib.baseboard_fab2(sch_1):\MG_DQ-DQS_FAR_DIMM_NG_M_H_BYTE3\" )
					)
					( Status sCSetFlattened )
					( Origin gBackEnd )
				)
				( attribute "RELATIVE_PROPAGATION_DELAY" ",5.00 MIL"
					( Parent
						( matchGroupRef "@baseboard_fab2_lib.baseboard_fab2(sch_1):\MG_DQ-DQS_FAR_DIMM_NG_M_H_BYTE3\" )
					)
					( Units "uMatchProp" "ns" 1.000000)
					( Status sCSetFlattened )
					( Origin gBackEnd )
				)
			)
			( pinPair "@baseboard_fab2_lib.baseboard_fab2(sch_1):\PP830\"
				( pinRef "@baseboard_fab2_lib.baseboard_fab2(sch_1):page80_i101:DQS3N" )
				( pinRef "@baseboard_fab2_lib.baseboard_fab2(sch_1):page58_i172:DDR1_DQS_DN(3)" )
				( attribute "RELATIVE_PROPAGATION_DELAY_SCOPE" "G"
					( Parent
						( matchGroupRef "@baseboard_fab2_lib.baseboard_fab2(sch_1):\MG_DQ-DQS_NEAR_DIMM_NG_M_H_BYTE3\" )
					)
					( Status sCSetFlattened )
					( Origin gBackEnd )
				)
				( attribute "RELATIVE_PROPAGATION_DELAY" ",5.00 MIL"
					( Parent
						( matchGroupRef "@baseboard_fab2_lib.baseboard_fab2(sch_1):\MG_DQ-DQS_NEAR_DIMM_NG_M_H_BYTE3\" )
					)
					( Units "uMatchProp" "ns" 1.000000)
					( Status sCSetFlattened )
					( Origin gBackEnd )
				)
			)
			( pinPair "@baseboard_fab2_lib.baseboard_fab2(sch_1):\PP832\"
				( pinRef "@baseboard_fab2_lib.baseboard_fab2(sch_1):page58_i172:DDR1_DQS_DP(3)" )
				( pinRef "@baseboard_fab2_lib.baseboard_fab2(sch_1):page79_i64:DQS3P" )
				( attribute "RELATIVE_PROPAGATION_DELAY_SCOPE" "G"
					( Parent
						( matchGroupRef "@baseboard_fab2_lib.baseboard_fab2(sch_1):\MG_DQ-DQS_FAR_DIMM_NG_M_H_BYTE3\" )
					)
					( Status sCSetFlattened )
					( Origin gBackEnd )
				)
				( attribute "RELATIVE_PROPAGATION_DELAY" ",5.00 MIL"
					( Parent
						( matchGroupRef "@baseboard_fab2_lib.baseboard_fab2(sch_1):\MG_DQ-DQS_FAR_DIMM_NG_M_H_BYTE3\" )
					)
					( Units "uMatchProp" "ns" 1.000000)
					( Status sCSetFlattened )
					( Origin gBackEnd )
				)
			)
			( pinPair "@baseboard_fab2_lib.baseboard_fab2(sch_1):\PP833\"
				( pinRef "@baseboard_fab2_lib.baseboard_fab2(sch_1):page80_i101:DQS3P" )
				( pinRef "@baseboard_fab2_lib.baseboard_fab2(sch_1):page58_i172:DDR1_DQS_DP(3)" )
				( attribute "RELATIVE_PROPAGATION_DELAY_SCOPE" "G"
					( Parent
						( matchGroupRef "@baseboard_fab2_lib.baseboard_fab2(sch_1):\MG_DQ-DQS_NEAR_DIMM_NG_M_H_BYTE3\" )
					)
					( Status sCSetFlattened )
					( Origin gBackEnd )
				)
				( attribute "RELATIVE_PROPAGATION_DELAY" ",5.00 MIL"
					( Parent
						( matchGroupRef "@baseboard_fab2_lib.baseboard_fab2(sch_1):\MG_DQ-DQS_NEAR_DIMM_NG_M_H_BYTE3\" )
					)
					( Units "uMatchProp" "ns" 1.000000)
					( Status sCSetFlattened )
					( Origin gBackEnd )
				)
			)
			( pinPair "@baseboard_fab2_lib.baseboard_fab2(sch_1):\PP817\"
				( pinRef "@baseboard_fab2_lib.baseboard_fab2(sch_1):page58_i172:DDR1_DQS_DN(4)" )
				( pinRef "@baseboard_fab2_lib.baseboard_fab2(sch_1):page79_i64:DQS4N" )
				( attribute "RELATIVE_PROPAGATION_DELAY_SCOPE" "G"
					( Parent
						( matchGroupRef "@baseboard_fab2_lib.baseboard_fab2(sch_1):\MG_DQ-DQS_FAR_DIMM_NG_M_H_BYTE4\" )
					)
					( Status sCSetFlattened )
					( Origin gBackEnd )
				)
				( attribute "RELATIVE_PROPAGATION_DELAY" ",5.00 MIL"
					( Parent
						( matchGroupRef "@baseboard_fab2_lib.baseboard_fab2(sch_1):\MG_DQ-DQS_FAR_DIMM_NG_M_H_BYTE4\" )
					)
					( Units "uMatchProp" "ns" 1.000000)
					( Status sCSetFlattened )
					( Origin gBackEnd )
				)
			)
			( pinPair "@baseboard_fab2_lib.baseboard_fab2(sch_1):\PP819\"
				( pinRef "@baseboard_fab2_lib.baseboard_fab2(sch_1):page80_i101:DQS4N" )
				( pinRef "@baseboard_fab2_lib.baseboard_fab2(sch_1):page58_i172:DDR1_DQS_DN(4)" )
				( attribute "RELATIVE_PROPAGATION_DELAY_SCOPE" "G"
					( Parent
						( matchGroupRef "@baseboard_fab2_lib.baseboard_fab2(sch_1):\MG_DQ-DQS_NEAR_DIMM_NG_M_H_BYTE4\" )
					)
					( Status sCSetFlattened )
					( Origin gBackEnd )
				)
				( attribute "RELATIVE_PROPAGATION_DELAY" ",5.00 MIL"
					( Parent
						( matchGroupRef "@baseboard_fab2_lib.baseboard_fab2(sch_1):\MG_DQ-DQS_NEAR_DIMM_NG_M_H_BYTE4\" )
					)
					( Units "uMatchProp" "ns" 1.000000)
					( Status sCSetFlattened )
					( Origin gBackEnd )
				)
			)
			( pinPair "@baseboard_fab2_lib.baseboard_fab2(sch_1):\PP820\"
				( pinRef "@baseboard_fab2_lib.baseboard_fab2(sch_1):page58_i172:DDR1_DQS_DP(4)" )
				( pinRef "@baseboard_fab2_lib.baseboard_fab2(sch_1):page79_i64:DQS4P" )
				( attribute "RELATIVE_PROPAGATION_DELAY_SCOPE" "G"
					( Parent
						( matchGroupRef "@baseboard_fab2_lib.baseboard_fab2(sch_1):\MG_DQ-DQS_FAR_DIMM_NG_M_H_BYTE4\" )
					)
					( Status sCSetFlattened )
					( Origin gBackEnd )
				)
				( attribute "RELATIVE_PROPAGATION_DELAY" ",5.00 MIL"
					( Parent
						( matchGroupRef "@baseboard_fab2_lib.baseboard_fab2(sch_1):\MG_DQ-DQS_FAR_DIMM_NG_M_H_BYTE4\" )
					)
					( Units "uMatchProp" "ns" 1.000000)
					( Status sCSetFlattened )
					( Origin gBackEnd )
				)
			)
			( pinPair "@baseboard_fab2_lib.baseboard_fab2(sch_1):\PP822\"
				( pinRef "@baseboard_fab2_lib.baseboard_fab2(sch_1):page80_i101:DQS4P" )
				( pinRef "@baseboard_fab2_lib.baseboard_fab2(sch_1):page58_i172:DDR1_DQS_DP(4)" )
				( attribute "RELATIVE_PROPAGATION_DELAY_SCOPE" "G"
					( Parent
						( matchGroupRef "@baseboard_fab2_lib.baseboard_fab2(sch_1):\MG_DQ-DQS_NEAR_DIMM_NG_M_H_BYTE4\" )
					)
					( Status sCSetFlattened )
					( Origin gBackEnd )
				)
				( attribute "RELATIVE_PROPAGATION_DELAY" ",5.00 MIL"
					( Parent
						( matchGroupRef "@baseboard_fab2_lib.baseboard_fab2(sch_1):\MG_DQ-DQS_NEAR_DIMM_NG_M_H_BYTE4\" )
					)
					( Units "uMatchProp" "ns" 1.000000)
					( Status sCSetFlattened )
					( Origin gBackEnd )
				)
			)
			( pinPair "@baseboard_fab2_lib.baseboard_fab2(sch_1):\PP805\"
				( pinRef "@baseboard_fab2_lib.baseboard_fab2(sch_1):page58_i172:DDR1_DQS_DN(5)" )
				( pinRef "@baseboard_fab2_lib.baseboard_fab2(sch_1):page79_i64:DQS5N" )
				( attribute "RELATIVE_PROPAGATION_DELAY_SCOPE" "G"
					( Parent
						( matchGroupRef "@baseboard_fab2_lib.baseboard_fab2(sch_1):\MG_DQ-DQS_FAR_DIMM_NG_M_H_BYTE5\" )
					)
					( Status sCSetFlattened )
					( Origin gBackEnd )
				)
				( attribute "RELATIVE_PROPAGATION_DELAY" ",5.00 MIL"
					( Parent
						( matchGroupRef "@baseboard_fab2_lib.baseboard_fab2(sch_1):\MG_DQ-DQS_FAR_DIMM_NG_M_H_BYTE5\" )
					)
					( Units "uMatchProp" "ns" 1.000000)
					( Status sCSetFlattened )
					( Origin gBackEnd )
				)
			)
			( pinPair "@baseboard_fab2_lib.baseboard_fab2(sch_1):\PP807\"
				( pinRef "@baseboard_fab2_lib.baseboard_fab2(sch_1):page80_i101:DQS5N" )
				( pinRef "@baseboard_fab2_lib.baseboard_fab2(sch_1):page58_i172:DDR1_DQS_DN(5)" )
				( attribute "RELATIVE_PROPAGATION_DELAY_SCOPE" "G"
					( Parent
						( matchGroupRef "@baseboard_fab2_lib.baseboard_fab2(sch_1):\MG_DQ-DQS_NEAR_DIMM_NG_M_H_BYTE5\" )
					)
					( Status sCSetFlattened )
					( Origin gBackEnd )
				)
				( attribute "RELATIVE_PROPAGATION_DELAY" ",5.00 MIL"
					( Parent
						( matchGroupRef "@baseboard_fab2_lib.baseboard_fab2(sch_1):\MG_DQ-DQS_NEAR_DIMM_NG_M_H_BYTE5\" )
					)
					( Units "uMatchProp" "ns" 1.000000)
					( Status sCSetFlattened )
					( Origin gBackEnd )
				)
			)
			( pinPair "@baseboard_fab2_lib.baseboard_fab2(sch_1):\PP808\"
				( pinRef "@baseboard_fab2_lib.baseboard_fab2(sch_1):page58_i172:DDR1_DQS_DP(5)" )
				( pinRef "@baseboard_fab2_lib.baseboard_fab2(sch_1):page79_i64:DQS5P" )
				( attribute "RELATIVE_PROPAGATION_DELAY_SCOPE" "G"
					( Parent
						( matchGroupRef "@baseboard_fab2_lib.baseboard_fab2(sch_1):\MG_DQ-DQS_FAR_DIMM_NG_M_H_BYTE5\" )
					)
					( Status sCSetFlattened )
					( Origin gBackEnd )
				)
				( attribute "RELATIVE_PROPAGATION_DELAY" ",5.00 MIL"
					( Parent
						( matchGroupRef "@baseboard_fab2_lib.baseboard_fab2(sch_1):\MG_DQ-DQS_FAR_DIMM_NG_M_H_BYTE5\" )
					)
					( Units "uMatchProp" "ns" 1.000000)
					( Status sCSetFlattened )
					( Origin gBackEnd )
				)
			)
			( pinPair "@baseboard_fab2_lib.baseboard_fab2(sch_1):\PP810\"
				( pinRef "@baseboard_fab2_lib.baseboard_fab2(sch_1):page80_i101:DQS5P" )
				( pinRef "@baseboard_fab2_lib.baseboard_fab2(sch_1):page58_i172:DDR1_DQS_DP(5)" )
				( attribute "RELATIVE_PROPAGATION_DELAY_SCOPE" "G"
					( Parent
						( matchGroupRef "@baseboard_fab2_lib.baseboard_fab2(sch_1):\MG_DQ-DQS_NEAR_DIMM_NG_M_H_BYTE5\" )
					)
					( Status sCSetFlattened )
					( Origin gBackEnd )
				)
				( attribute "RELATIVE_PROPAGATION_DELAY" ",5.00 MIL"
					( Parent
						( matchGroupRef "@baseboard_fab2_lib.baseboard_fab2(sch_1):\MG_DQ-DQS_NEAR_DIMM_NG_M_H_BYTE5\" )
					)
					( Units "uMatchProp" "ns" 1.000000)
					( Status sCSetFlattened )
					( Origin gBackEnd )
				)
			)
			( pinPair "@baseboard_fab2_lib.baseboard_fab2(sch_1):\PP793\"
				( pinRef "@baseboard_fab2_lib.baseboard_fab2(sch_1):page58_i172:DDR1_DQS_DN(6)" )
				( pinRef "@baseboard_fab2_lib.baseboard_fab2(sch_1):page79_i64:DQS6N" )
				( attribute "RELATIVE_PROPAGATION_DELAY_SCOPE" "G"
					( Parent
						( matchGroupRef "@baseboard_fab2_lib.baseboard_fab2(sch_1):\MG_DQ-DQS_FAR_DIMM_NG_M_H_BYTE6\" )
					)
					( Status sCSetFlattened )
					( Origin gBackEnd )
				)
				( attribute "RELATIVE_PROPAGATION_DELAY" ",5.00 MIL"
					( Parent
						( matchGroupRef "@baseboard_fab2_lib.baseboard_fab2(sch_1):\MG_DQ-DQS_FAR_DIMM_NG_M_H_BYTE6\" )
					)
					( Units "uMatchProp" "ns" 1.000000)
					( Status sCSetFlattened )
					( Origin gBackEnd )
				)
			)
			( pinPair "@baseboard_fab2_lib.baseboard_fab2(sch_1):\PP795\"
				( pinRef "@baseboard_fab2_lib.baseboard_fab2(sch_1):page80_i101:DQS6N" )
				( pinRef "@baseboard_fab2_lib.baseboard_fab2(sch_1):page58_i172:DDR1_DQS_DN(6)" )
				( attribute "RELATIVE_PROPAGATION_DELAY_SCOPE" "G"
					( Parent
						( matchGroupRef "@baseboard_fab2_lib.baseboard_fab2(sch_1):\MG_DQ-DQS_NEAR_DIMM_NG_M_H_BYTE6\" )
					)
					( Status sCSetFlattened )
					( Origin gBackEnd )
				)
				( attribute "RELATIVE_PROPAGATION_DELAY" ",5.00 MIL"
					( Parent
						( matchGroupRef "@baseboard_fab2_lib.baseboard_fab2(sch_1):\MG_DQ-DQS_NEAR_DIMM_NG_M_H_BYTE6\" )
					)
					( Units "uMatchProp" "ns" 1.000000)
					( Status sCSetFlattened )
					( Origin gBackEnd )
				)
			)
			( pinPair "@baseboard_fab2_lib.baseboard_fab2(sch_1):\PP796\"
				( pinRef "@baseboard_fab2_lib.baseboard_fab2(sch_1):page58_i172:DDR1_DQS_DP(6)" )
				( pinRef "@baseboard_fab2_lib.baseboard_fab2(sch_1):page79_i64:DQS6P" )
				( attribute "RELATIVE_PROPAGATION_DELAY_SCOPE" "G"
					( Parent
						( matchGroupRef "@baseboard_fab2_lib.baseboard_fab2(sch_1):\MG_DQ-DQS_FAR_DIMM_NG_M_H_BYTE6\" )
					)
					( Status sCSetFlattened )
					( Origin gBackEnd )
				)
				( attribute "RELATIVE_PROPAGATION_DELAY" ",5.00 MIL"
					( Parent
						( matchGroupRef "@baseboard_fab2_lib.baseboard_fab2(sch_1):\MG_DQ-DQS_FAR_DIMM_NG_M_H_BYTE6\" )
					)
					( Units "uMatchProp" "ns" 1.000000)
					( Status sCSetFlattened )
					( Origin gBackEnd )
				)
			)
			( pinPair "@baseboard_fab2_lib.baseboard_fab2(sch_1):\PP798\"
				( pinRef "@baseboard_fab2_lib.baseboard_fab2(sch_1):page80_i101:DQS6P" )
				( pinRef "@baseboard_fab2_lib.baseboard_fab2(sch_1):page58_i172:DDR1_DQS_DP(6)" )
				( attribute "RELATIVE_PROPAGATION_DELAY_SCOPE" "G"
					( Parent
						( matchGroupRef "@baseboard_fab2_lib.baseboard_fab2(sch_1):\MG_DQ-DQS_NEAR_DIMM_NG_M_H_BYTE6\" )
					)
					( Status sCSetFlattened )
					( Origin gBackEnd )
				)
				( attribute "RELATIVE_PROPAGATION_DELAY" ",5.00 MIL"
					( Parent
						( matchGroupRef "@baseboard_fab2_lib.baseboard_fab2(sch_1):\MG_DQ-DQS_NEAR_DIMM_NG_M_H_BYTE6\" )
					)
					( Units "uMatchProp" "ns" 1.000000)
					( Status sCSetFlattened )
					( Origin gBackEnd )
				)
			)
			( pinPair "@baseboard_fab2_lib.baseboard_fab2(sch_1):\PP781\"
				( pinRef "@baseboard_fab2_lib.baseboard_fab2(sch_1):page58_i172:DDR1_DQS_DN(7)" )
				( pinRef "@baseboard_fab2_lib.baseboard_fab2(sch_1):page79_i64:DQS7N" )
				( attribute "RELATIVE_PROPAGATION_DELAY_SCOPE" "G"
					( Parent
						( matchGroupRef "@baseboard_fab2_lib.baseboard_fab2(sch_1):\MG_DQ-DQS_FAR_DIMM_NG_M_H_BYTE7\" )
					)
					( Status sCSetFlattened )
					( Origin gBackEnd )
				)
				( attribute "RELATIVE_PROPAGATION_DELAY" ",5.00 MIL"
					( Parent
						( matchGroupRef "@baseboard_fab2_lib.baseboard_fab2(sch_1):\MG_DQ-DQS_FAR_DIMM_NG_M_H_BYTE7\" )
					)
					( Units "uMatchProp" "ns" 1.000000)
					( Status sCSetFlattened )
					( Origin gBackEnd )
				)
			)
			( pinPair "@baseboard_fab2_lib.baseboard_fab2(sch_1):\PP783\"
				( pinRef "@baseboard_fab2_lib.baseboard_fab2(sch_1):page80_i101:DQS7N" )
				( pinRef "@baseboard_fab2_lib.baseboard_fab2(sch_1):page58_i172:DDR1_DQS_DN(7)" )
				( attribute "RELATIVE_PROPAGATION_DELAY_SCOPE" "G"
					( Parent
						( matchGroupRef "@baseboard_fab2_lib.baseboard_fab2(sch_1):\MG_DQ-DQS_NEAR_DIMM_NG_M_H_BYTE7\" )
					)
					( Status sCSetFlattened )
					( Origin gBackEnd )
				)
				( attribute "RELATIVE_PROPAGATION_DELAY" ",5.00 MIL"
					( Parent
						( matchGroupRef "@baseboard_fab2_lib.baseboard_fab2(sch_1):\MG_DQ-DQS_NEAR_DIMM_NG_M_H_BYTE7\" )
					)
					( Units "uMatchProp" "ns" 1.000000)
					( Status sCSetFlattened )
					( Origin gBackEnd )
				)
			)
			( pinPair "@baseboard_fab2_lib.baseboard_fab2(sch_1):\PP784\"
				( pinRef "@baseboard_fab2_lib.baseboard_fab2(sch_1):page58_i172:DDR1_DQS_DP(7)" )
				( pinRef "@baseboard_fab2_lib.baseboard_fab2(sch_1):page79_i64:DQS7P" )
				( attribute "RELATIVE_PROPAGATION_DELAY_SCOPE" "G"
					( Parent
						( matchGroupRef "@baseboard_fab2_lib.baseboard_fab2(sch_1):\MG_DQ-DQS_FAR_DIMM_NG_M_H_BYTE7\" )
					)
					( Status sCSetFlattened )
					( Origin gBackEnd )
				)
				( attribute "RELATIVE_PROPAGATION_DELAY" ",5.00 MIL"
					( Parent
						( matchGroupRef "@baseboard_fab2_lib.baseboard_fab2(sch_1):\MG_DQ-DQS_FAR_DIMM_NG_M_H_BYTE7\" )
					)
					( Units "uMatchProp" "ns" 1.000000)
					( Status sCSetFlattened )
					( Origin gBackEnd )
				)
			)
			( pinPair "@baseboard_fab2_lib.baseboard_fab2(sch_1):\PP786\"
				( pinRef "@baseboard_fab2_lib.baseboard_fab2(sch_1):page80_i101:DQS7P" )
				( pinRef "@baseboard_fab2_lib.baseboard_fab2(sch_1):page58_i172:DDR1_DQS_DP(7)" )
				( attribute "RELATIVE_PROPAGATION_DELAY_SCOPE" "G"
					( Parent
						( matchGroupRef "@baseboard_fab2_lib.baseboard_fab2(sch_1):\MG_DQ-DQS_NEAR_DIMM_NG_M_H_BYTE7\" )
					)
					( Status sCSetFlattened )
					( Origin gBackEnd )
				)
				( attribute "RELATIVE_PROPAGATION_DELAY" ",5.00 MIL"
					( Parent
						( matchGroupRef "@baseboard_fab2_lib.baseboard_fab2(sch_1):\MG_DQ-DQS_NEAR_DIMM_NG_M_H_BYTE7\" )
					)
					( Units "uMatchProp" "ns" 1.000000)
					( Status sCSetFlattened )
					( Origin gBackEnd )
				)
			)
			( pinPair "@baseboard_fab2_lib.baseboard_fab2(sch_1):\PP769\"
				( pinRef "@baseboard_fab2_lib.baseboard_fab2(sch_1):page58_i172:DDR1_DQS_DN(8)" )
				( pinRef "@baseboard_fab2_lib.baseboard_fab2(sch_1):page79_i64:DQS8N" )
				( attribute "RELATIVE_PROPAGATION_DELAY_SCOPE" "G"
					( Parent
						( matchGroupRef "@baseboard_fab2_lib.baseboard_fab2(sch_1):\MG_DQ-DQS_FAR_DIMM_NG_M_H_BYTE-ECC\" )
					)
					( Status sCSetFlattened )
					( Origin gBackEnd )
				)
				( attribute "RELATIVE_PROPAGATION_DELAY" ",5.00 MIL"
					( Parent
						( matchGroupRef "@baseboard_fab2_lib.baseboard_fab2(sch_1):\MG_DQ-DQS_FAR_DIMM_NG_M_H_BYTE-ECC\" )
					)
					( Units "uMatchProp" "ns" 1.000000)
					( Status sCSetFlattened )
					( Origin gBackEnd )
				)
			)
			( pinPair "@baseboard_fab2_lib.baseboard_fab2(sch_1):\PP770\"
				( pinRef "@baseboard_fab2_lib.baseboard_fab2(sch_1):page80_i101:DQS8N" )
				( pinRef "@baseboard_fab2_lib.baseboard_fab2(sch_1):page58_i172:DDR1_DQS_DN(8)" )
				( attribute "RELATIVE_PROPAGATION_DELAY_SCOPE" "G"
					( Parent
						( matchGroupRef "@baseboard_fab2_lib.baseboard_fab2(sch_1):\MG_DQ-DQS_NEAR_DIMM_NG_M_H_BYTE-ECC\" )
					)
					( Status sCSetFlattened )
					( Origin gBackEnd )
				)
				( attribute "RELATIVE_PROPAGATION_DELAY" ",5.00 MIL"
					( Parent
						( matchGroupRef "@baseboard_fab2_lib.baseboard_fab2(sch_1):\MG_DQ-DQS_NEAR_DIMM_NG_M_H_BYTE-ECC\" )
					)
					( Units "uMatchProp" "ns" 1.000000)
					( Status sCSetFlattened )
					( Origin gBackEnd )
				)
			)
			( pinPair "@baseboard_fab2_lib.baseboard_fab2(sch_1):\PP772\"
				( pinRef "@baseboard_fab2_lib.baseboard_fab2(sch_1):page58_i172:DDR1_DQS_DP(8)" )
				( pinRef "@baseboard_fab2_lib.baseboard_fab2(sch_1):page79_i64:DQS8P" )
				( attribute "RELATIVE_PROPAGATION_DELAY_SCOPE" "G"
					( Parent
						( matchGroupRef "@baseboard_fab2_lib.baseboard_fab2(sch_1):\MG_DQ-DQS_FAR_DIMM_NG_M_H_BYTE-ECC\" )
					)
					( Status sCSetFlattened )
					( Origin gBackEnd )
				)
				( attribute "RELATIVE_PROPAGATION_DELAY" ",5.00 MIL"
					( Parent
						( matchGroupRef "@baseboard_fab2_lib.baseboard_fab2(sch_1):\MG_DQ-DQS_FAR_DIMM_NG_M_H_BYTE-ECC\" )
					)
					( Units "uMatchProp" "ns" 1.000000)
					( Status sCSetFlattened )
					( Origin gBackEnd )
				)
			)
			( pinPair "@baseboard_fab2_lib.baseboard_fab2(sch_1):\PP773\"
				( pinRef "@baseboard_fab2_lib.baseboard_fab2(sch_1):page80_i101:DQS8P" )
				( pinRef "@baseboard_fab2_lib.baseboard_fab2(sch_1):page58_i172:DDR1_DQS_DP(8)" )
				( attribute "RELATIVE_PROPAGATION_DELAY_SCOPE" "G"
					( Parent
						( matchGroupRef "@baseboard_fab2_lib.baseboard_fab2(sch_1):\MG_DQ-DQS_NEAR_DIMM_NG_M_H_BYTE-ECC\" )
					)
					( Status sCSetFlattened )
					( Origin gBackEnd )
				)
				( attribute "RELATIVE_PROPAGATION_DELAY" ",5.00 MIL"
					( Parent
						( matchGroupRef "@baseboard_fab2_lib.baseboard_fab2(sch_1):\MG_DQ-DQS_NEAR_DIMM_NG_M_H_BYTE-ECC\" )
					)
					( Units "uMatchProp" "ns" 1.000000)
					( Status sCSetFlattened )
					( Origin gBackEnd )
				)
			)
			( pinPair "@baseboard_fab2_lib.baseboard_fab2(sch_1):\PP859\"
				( pinRef "@baseboard_fab2_lib.baseboard_fab2(sch_1):page58_i172:DDR1_DQS_DN(9)" )
				( pinRef "@baseboard_fab2_lib.baseboard_fab2(sch_1):page79_i64:DQS9N" )
				( attribute "RELATIVE_PROPAGATION_DELAY_SCOPE" "G"
					( Parent
						( matchGroupRef "@baseboard_fab2_lib.baseboard_fab2(sch_1):\MG_DQ-DQS_FAR_DIMM_NG_M_H_BYTE0\" )
					)
					( Status sCSetFlattened )
					( Origin gBackEnd )
				)
				( attribute "RELATIVE_PROPAGATION_DELAY" ",5.00 MIL"
					( Parent
						( matchGroupRef "@baseboard_fab2_lib.baseboard_fab2(sch_1):\MG_DQ-DQS_FAR_DIMM_NG_M_H_BYTE0\" )
					)
					( Units "uMatchProp" "ns" 1.000000)
					( Status sCSetFlattened )
					( Origin gBackEnd )
				)
			)
			( pinPair "@baseboard_fab2_lib.baseboard_fab2(sch_1):\PP860\"
				( pinRef "@baseboard_fab2_lib.baseboard_fab2(sch_1):page80_i101:DQS9N" )
				( pinRef "@baseboard_fab2_lib.baseboard_fab2(sch_1):page58_i172:DDR1_DQS_DN(9)" )
				( attribute "RELATIVE_PROPAGATION_DELAY_SCOPE" "G"
					( Parent
						( matchGroupRef "@baseboard_fab2_lib.baseboard_fab2(sch_1):\MG_DQ-DQS_NEAR_DIMM_NG_M_H_BYTE0\" )
					)
					( Status sCSetFlattened )
					( Origin gBackEnd )
				)
				( attribute "RELATIVE_PROPAGATION_DELAY" ",5.00 MIL"
					( Parent
						( matchGroupRef "@baseboard_fab2_lib.baseboard_fab2(sch_1):\MG_DQ-DQS_NEAR_DIMM_NG_M_H_BYTE0\" )
					)
					( Units "uMatchProp" "ns" 1.000000)
					( Status sCSetFlattened )
					( Origin gBackEnd )
				)
			)
			( pinPair "@baseboard_fab2_lib.baseboard_fab2(sch_1):\PP862\"
				( pinRef "@baseboard_fab2_lib.baseboard_fab2(sch_1):page58_i172:DDR1_DQS_DP(9)" )
				( pinRef "@baseboard_fab2_lib.baseboard_fab2(sch_1):page79_i64:DQS9P" )
				( attribute "RELATIVE_PROPAGATION_DELAY_SCOPE" "G"
					( Parent
						( matchGroupRef "@baseboard_fab2_lib.baseboard_fab2(sch_1):\MG_DQ-DQS_FAR_DIMM_NG_M_H_BYTE0\" )
					)
					( Status sCSetFlattened )
					( Origin gBackEnd )
				)
				( attribute "RELATIVE_PROPAGATION_DELAY" ",5.00 MIL"
					( Parent
						( matchGroupRef "@baseboard_fab2_lib.baseboard_fab2(sch_1):\MG_DQ-DQS_FAR_DIMM_NG_M_H_BYTE0\" )
					)
					( Units "uMatchProp" "ns" 1.000000)
					( Status sCSetFlattened )
					( Origin gBackEnd )
				)
			)
			( pinPair "@baseboard_fab2_lib.baseboard_fab2(sch_1):\PP863\"
				( pinRef "@baseboard_fab2_lib.baseboard_fab2(sch_1):page80_i101:DQS9P" )
				( pinRef "@baseboard_fab2_lib.baseboard_fab2(sch_1):page58_i172:DDR1_DQS_DP(9)" )
				( attribute "RELATIVE_PROPAGATION_DELAY_SCOPE" "G"
					( Parent
						( matchGroupRef "@baseboard_fab2_lib.baseboard_fab2(sch_1):\MG_DQ-DQS_NEAR_DIMM_NG_M_H_BYTE0\" )
					)
					( Status sCSetFlattened )
					( Origin gBackEnd )
				)
				( attribute "RELATIVE_PROPAGATION_DELAY" ",5.00 MIL"
					( Parent
						( matchGroupRef "@baseboard_fab2_lib.baseboard_fab2(sch_1):\MG_DQ-DQS_NEAR_DIMM_NG_M_H_BYTE0\" )
					)
					( Units "uMatchProp" "ns" 1.000000)
					( Status sCSetFlattened )
					( Origin gBackEnd )
				)
			)
			( pinPair "@baseboard_fab2_lib.baseboard_fab2(sch_1):\PP847\"
				( pinRef "@baseboard_fab2_lib.baseboard_fab2(sch_1):page58_i172:DDR1_DQS_DN(10)" )
				( pinRef "@baseboard_fab2_lib.baseboard_fab2(sch_1):page79_i64:DQS10N" )
				( attribute "RELATIVE_PROPAGATION_DELAY_SCOPE" "G"
					( Parent
						( matchGroupRef "@baseboard_fab2_lib.baseboard_fab2(sch_1):\MG_DQ-DQS_FAR_DIMM_NG_M_H_BYTE1\" )
					)
					( Status sCSetFlattened )
					( Origin gBackEnd )
				)
				( attribute "RELATIVE_PROPAGATION_DELAY" ",5.00 MIL"
					( Parent
						( matchGroupRef "@baseboard_fab2_lib.baseboard_fab2(sch_1):\MG_DQ-DQS_FAR_DIMM_NG_M_H_BYTE1\" )
					)
					( Units "uMatchProp" "ns" 1.000000)
					( Status sCSetFlattened )
					( Origin gBackEnd )
				)
			)
			( pinPair "@baseboard_fab2_lib.baseboard_fab2(sch_1):\PP848\"
				( pinRef "@baseboard_fab2_lib.baseboard_fab2(sch_1):page80_i101:DQS10N" )
				( pinRef "@baseboard_fab2_lib.baseboard_fab2(sch_1):page58_i172:DDR1_DQS_DN(10)" )
				( attribute "RELATIVE_PROPAGATION_DELAY_SCOPE" "G"
					( Parent
						( matchGroupRef "@baseboard_fab2_lib.baseboard_fab2(sch_1):\MG_DQ-DQS_NEAR_DIMM_NG_M_H_BYTE1\" )
					)
					( Status sCSetFlattened )
					( Origin gBackEnd )
				)
				( attribute "RELATIVE_PROPAGATION_DELAY" ",5.00 MIL"
					( Parent
						( matchGroupRef "@baseboard_fab2_lib.baseboard_fab2(sch_1):\MG_DQ-DQS_NEAR_DIMM_NG_M_H_BYTE1\" )
					)
					( Units "uMatchProp" "ns" 1.000000)
					( Status sCSetFlattened )
					( Origin gBackEnd )
				)
			)
			( pinPair "@baseboard_fab2_lib.baseboard_fab2(sch_1):\PP850\"
				( pinRef "@baseboard_fab2_lib.baseboard_fab2(sch_1):page58_i172:DDR1_DQS_DP(10)" )
				( pinRef "@baseboard_fab2_lib.baseboard_fab2(sch_1):page79_i64:DQS10P" )
				( attribute "RELATIVE_PROPAGATION_DELAY_SCOPE" "G"
					( Parent
						( matchGroupRef "@baseboard_fab2_lib.baseboard_fab2(sch_1):\MG_DQ-DQS_FAR_DIMM_NG_M_H_BYTE1\" )
					)
					( Status sCSetFlattened )
					( Origin gBackEnd )
				)
				( attribute "RELATIVE_PROPAGATION_DELAY" ",5.00 MIL"
					( Parent
						( matchGroupRef "@baseboard_fab2_lib.baseboard_fab2(sch_1):\MG_DQ-DQS_FAR_DIMM_NG_M_H_BYTE1\" )
					)
					( Units "uMatchProp" "ns" 1.000000)
					( Status sCSetFlattened )
					( Origin gBackEnd )
				)
			)
			( pinPair "@baseboard_fab2_lib.baseboard_fab2(sch_1):\PP851\"
				( pinRef "@baseboard_fab2_lib.baseboard_fab2(sch_1):page80_i101:DQS10P" )
				( pinRef "@baseboard_fab2_lib.baseboard_fab2(sch_1):page58_i172:DDR1_DQS_DP(10)" )
				( attribute "RELATIVE_PROPAGATION_DELAY_SCOPE" "G"
					( Parent
						( matchGroupRef "@baseboard_fab2_lib.baseboard_fab2(sch_1):\MG_DQ-DQS_NEAR_DIMM_NG_M_H_BYTE1\" )
					)
					( Status sCSetFlattened )
					( Origin gBackEnd )
				)
				( attribute "RELATIVE_PROPAGATION_DELAY" ",5.00 MIL"
					( Parent
						( matchGroupRef "@baseboard_fab2_lib.baseboard_fab2(sch_1):\MG_DQ-DQS_NEAR_DIMM_NG_M_H_BYTE1\" )
					)
					( Units "uMatchProp" "ns" 1.000000)
					( Status sCSetFlattened )
					( Origin gBackEnd )
				)
			)
			( pinPair "@baseboard_fab2_lib.baseboard_fab2(sch_1):\PP835\"
				( pinRef "@baseboard_fab2_lib.baseboard_fab2(sch_1):page58_i172:DDR1_DQS_DN(11)" )
				( pinRef "@baseboard_fab2_lib.baseboard_fab2(sch_1):page79_i64:DQS11N" )
				( attribute "RELATIVE_PROPAGATION_DELAY_SCOPE" "G"
					( Parent
						( matchGroupRef "@baseboard_fab2_lib.baseboard_fab2(sch_1):\MG_DQ-DQS_FAR_DIMM_NG_M_H_BYTE2\" )
					)
					( Status sCSetFlattened )
					( Origin gBackEnd )
				)
				( attribute "RELATIVE_PROPAGATION_DELAY" ",5.00 MIL"
					( Parent
						( matchGroupRef "@baseboard_fab2_lib.baseboard_fab2(sch_1):\MG_DQ-DQS_FAR_DIMM_NG_M_H_BYTE2\" )
					)
					( Units "uMatchProp" "ns" 1.000000)
					( Status sCSetFlattened )
					( Origin gBackEnd )
				)
			)
			( pinPair "@baseboard_fab2_lib.baseboard_fab2(sch_1):\PP836\"
				( pinRef "@baseboard_fab2_lib.baseboard_fab2(sch_1):page80_i101:DQS11N" )
				( pinRef "@baseboard_fab2_lib.baseboard_fab2(sch_1):page58_i172:DDR1_DQS_DN(11)" )
				( attribute "RELATIVE_PROPAGATION_DELAY_SCOPE" "G"
					( Parent
						( matchGroupRef "@baseboard_fab2_lib.baseboard_fab2(sch_1):\MG_DQ-DQS_NEAR_DIMM_NG_M_H_BYTE2\" )
					)
					( Status sCSetFlattened )
					( Origin gBackEnd )
				)
				( attribute "RELATIVE_PROPAGATION_DELAY" ",5.00 MIL"
					( Parent
						( matchGroupRef "@baseboard_fab2_lib.baseboard_fab2(sch_1):\MG_DQ-DQS_NEAR_DIMM_NG_M_H_BYTE2\" )
					)
					( Units "uMatchProp" "ns" 1.000000)
					( Status sCSetFlattened )
					( Origin gBackEnd )
				)
			)
			( pinPair "@baseboard_fab2_lib.baseboard_fab2(sch_1):\PP838\"
				( pinRef "@baseboard_fab2_lib.baseboard_fab2(sch_1):page58_i172:DDR1_DQS_DP(11)" )
				( pinRef "@baseboard_fab2_lib.baseboard_fab2(sch_1):page79_i64:DQS11P" )
				( attribute "RELATIVE_PROPAGATION_DELAY_SCOPE" "G"
					( Parent
						( matchGroupRef "@baseboard_fab2_lib.baseboard_fab2(sch_1):\MG_DQ-DQS_FAR_DIMM_NG_M_H_BYTE2\" )
					)
					( Status sCSetFlattened )
					( Origin gBackEnd )
				)
				( attribute "RELATIVE_PROPAGATION_DELAY" ",5.00 MIL"
					( Parent
						( matchGroupRef "@baseboard_fab2_lib.baseboard_fab2(sch_1):\MG_DQ-DQS_FAR_DIMM_NG_M_H_BYTE2\" )
					)
					( Units "uMatchProp" "ns" 1.000000)
					( Status sCSetFlattened )
					( Origin gBackEnd )
				)
			)
			( pinPair "@baseboard_fab2_lib.baseboard_fab2(sch_1):\PP839\"
				( pinRef "@baseboard_fab2_lib.baseboard_fab2(sch_1):page80_i101:DQS11P" )
				( pinRef "@baseboard_fab2_lib.baseboard_fab2(sch_1):page58_i172:DDR1_DQS_DP(11)" )
				( attribute "RELATIVE_PROPAGATION_DELAY_SCOPE" "G"
					( Parent
						( matchGroupRef "@baseboard_fab2_lib.baseboard_fab2(sch_1):\MG_DQ-DQS_NEAR_DIMM_NG_M_H_BYTE2\" )
					)
					( Status sCSetFlattened )
					( Origin gBackEnd )
				)
				( attribute "RELATIVE_PROPAGATION_DELAY" ",5.00 MIL"
					( Parent
						( matchGroupRef "@baseboard_fab2_lib.baseboard_fab2(sch_1):\MG_DQ-DQS_NEAR_DIMM_NG_M_H_BYTE2\" )
					)
					( Units "uMatchProp" "ns" 1.000000)
					( Status sCSetFlattened )
					( Origin gBackEnd )
				)
			)
			( pinPair "@baseboard_fab2_lib.baseboard_fab2(sch_1):\PP823\"
				( pinRef "@baseboard_fab2_lib.baseboard_fab2(sch_1):page58_i172:DDR1_DQS_DN(12)" )
				( pinRef "@baseboard_fab2_lib.baseboard_fab2(sch_1):page79_i64:DQS12N" )
				( attribute "RELATIVE_PROPAGATION_DELAY_SCOPE" "G"
					( Parent
						( matchGroupRef "@baseboard_fab2_lib.baseboard_fab2(sch_1):\MG_DQ-DQS_FAR_DIMM_NG_M_H_BYTE3\" )
					)
					( Status sCSetFlattened )
					( Origin gBackEnd )
				)
				( attribute "RELATIVE_PROPAGATION_DELAY" ",5.00 MIL"
					( Parent
						( matchGroupRef "@baseboard_fab2_lib.baseboard_fab2(sch_1):\MG_DQ-DQS_FAR_DIMM_NG_M_H_BYTE3\" )
					)
					( Units "uMatchProp" "ns" 1.000000)
					( Status sCSetFlattened )
					( Origin gBackEnd )
				)
			)
			( pinPair "@baseboard_fab2_lib.baseboard_fab2(sch_1):\PP824\"
				( pinRef "@baseboard_fab2_lib.baseboard_fab2(sch_1):page80_i101:DQS12N" )
				( pinRef "@baseboard_fab2_lib.baseboard_fab2(sch_1):page58_i172:DDR1_DQS_DN(12)" )
				( attribute "RELATIVE_PROPAGATION_DELAY_SCOPE" "G"
					( Parent
						( matchGroupRef "@baseboard_fab2_lib.baseboard_fab2(sch_1):\MG_DQ-DQS_NEAR_DIMM_NG_M_H_BYTE3\" )
					)
					( Status sCSetFlattened )
					( Origin gBackEnd )
				)
				( attribute "RELATIVE_PROPAGATION_DELAY" ",5.00 MIL"
					( Parent
						( matchGroupRef "@baseboard_fab2_lib.baseboard_fab2(sch_1):\MG_DQ-DQS_NEAR_DIMM_NG_M_H_BYTE3\" )
					)
					( Units "uMatchProp" "ns" 1.000000)
					( Status sCSetFlattened )
					( Origin gBackEnd )
				)
			)
			( pinPair "@baseboard_fab2_lib.baseboard_fab2(sch_1):\PP826\"
				( pinRef "@baseboard_fab2_lib.baseboard_fab2(sch_1):page58_i172:DDR1_DQS_DP(12)" )
				( pinRef "@baseboard_fab2_lib.baseboard_fab2(sch_1):page79_i64:DQS12P" )
				( attribute "RELATIVE_PROPAGATION_DELAY_SCOPE" "G"
					( Parent
						( matchGroupRef "@baseboard_fab2_lib.baseboard_fab2(sch_1):\MG_DQ-DQS_FAR_DIMM_NG_M_H_BYTE3\" )
					)
					( Status sCSetFlattened )
					( Origin gBackEnd )
				)
				( attribute "RELATIVE_PROPAGATION_DELAY" ",5.00 MIL"
					( Parent
						( matchGroupRef "@baseboard_fab2_lib.baseboard_fab2(sch_1):\MG_DQ-DQS_FAR_DIMM_NG_M_H_BYTE3\" )
					)
					( Units "uMatchProp" "ns" 1.000000)
					( Status sCSetFlattened )
					( Origin gBackEnd )
				)
			)
			( pinPair "@baseboard_fab2_lib.baseboard_fab2(sch_1):\PP827\"
				( pinRef "@baseboard_fab2_lib.baseboard_fab2(sch_1):page80_i101:DQS12P" )
				( pinRef "@baseboard_fab2_lib.baseboard_fab2(sch_1):page58_i172:DDR1_DQS_DP(12)" )
				( attribute "RELATIVE_PROPAGATION_DELAY_SCOPE" "G"
					( Parent
						( matchGroupRef "@baseboard_fab2_lib.baseboard_fab2(sch_1):\MG_DQ-DQS_NEAR_DIMM_NG_M_H_BYTE3\" )
					)
					( Status sCSetFlattened )
					( Origin gBackEnd )
				)
				( attribute "RELATIVE_PROPAGATION_DELAY" ",5.00 MIL"
					( Parent
						( matchGroupRef "@baseboard_fab2_lib.baseboard_fab2(sch_1):\MG_DQ-DQS_NEAR_DIMM_NG_M_H_BYTE3\" )
					)
					( Units "uMatchProp" "ns" 1.000000)
					( Status sCSetFlattened )
					( Origin gBackEnd )
				)
			)
			( pinPair "@baseboard_fab2_lib.baseboard_fab2(sch_1):\PP811\"
				( pinRef "@baseboard_fab2_lib.baseboard_fab2(sch_1):page58_i172:DDR1_DQS_DN(13)" )
				( pinRef "@baseboard_fab2_lib.baseboard_fab2(sch_1):page79_i64:DQS13N" )
				( attribute "RELATIVE_PROPAGATION_DELAY_SCOPE" "G"
					( Parent
						( matchGroupRef "@baseboard_fab2_lib.baseboard_fab2(sch_1):\MG_DQ-DQS_FAR_DIMM_NG_M_H_BYTE4\" )
					)
					( Status sCSetFlattened )
					( Origin gBackEnd )
				)
				( attribute "RELATIVE_PROPAGATION_DELAY" ",5.00 MIL"
					( Parent
						( matchGroupRef "@baseboard_fab2_lib.baseboard_fab2(sch_1):\MG_DQ-DQS_FAR_DIMM_NG_M_H_BYTE4\" )
					)
					( Units "uMatchProp" "ns" 1.000000)
					( Status sCSetFlattened )
					( Origin gBackEnd )
				)
			)
			( pinPair "@baseboard_fab2_lib.baseboard_fab2(sch_1):\PP813\"
				( pinRef "@baseboard_fab2_lib.baseboard_fab2(sch_1):page80_i101:DQS13N" )
				( pinRef "@baseboard_fab2_lib.baseboard_fab2(sch_1):page58_i172:DDR1_DQS_DN(13)" )
				( attribute "RELATIVE_PROPAGATION_DELAY_SCOPE" "G"
					( Parent
						( matchGroupRef "@baseboard_fab2_lib.baseboard_fab2(sch_1):\MG_DQ-DQS_NEAR_DIMM_NG_M_H_BYTE4\" )
					)
					( Status sCSetFlattened )
					( Origin gBackEnd )
				)
				( attribute "RELATIVE_PROPAGATION_DELAY" ",5.00 MIL"
					( Parent
						( matchGroupRef "@baseboard_fab2_lib.baseboard_fab2(sch_1):\MG_DQ-DQS_NEAR_DIMM_NG_M_H_BYTE4\" )
					)
					( Units "uMatchProp" "ns" 1.000000)
					( Status sCSetFlattened )
					( Origin gBackEnd )
				)
			)
			( pinPair "@baseboard_fab2_lib.baseboard_fab2(sch_1):\PP814\"
				( pinRef "@baseboard_fab2_lib.baseboard_fab2(sch_1):page58_i172:DDR1_DQS_DP(13)" )
				( pinRef "@baseboard_fab2_lib.baseboard_fab2(sch_1):page79_i64:DQS13P" )
				( attribute "RELATIVE_PROPAGATION_DELAY_SCOPE" "G"
					( Parent
						( matchGroupRef "@baseboard_fab2_lib.baseboard_fab2(sch_1):\MG_DQ-DQS_FAR_DIMM_NG_M_H_BYTE4\" )
					)
					( Status sCSetFlattened )
					( Origin gBackEnd )
				)
				( attribute "RELATIVE_PROPAGATION_DELAY" ",5.00 MIL"
					( Parent
						( matchGroupRef "@baseboard_fab2_lib.baseboard_fab2(sch_1):\MG_DQ-DQS_FAR_DIMM_NG_M_H_BYTE4\" )
					)
					( Units "uMatchProp" "ns" 1.000000)
					( Status sCSetFlattened )
					( Origin gBackEnd )
				)
			)
			( pinPair "@baseboard_fab2_lib.baseboard_fab2(sch_1):\PP816\"
				( pinRef "@baseboard_fab2_lib.baseboard_fab2(sch_1):page80_i101:DQS13P" )
				( pinRef "@baseboard_fab2_lib.baseboard_fab2(sch_1):page58_i172:DDR1_DQS_DP(13)" )
				( attribute "RELATIVE_PROPAGATION_DELAY_SCOPE" "G"
					( Parent
						( matchGroupRef "@baseboard_fab2_lib.baseboard_fab2(sch_1):\MG_DQ-DQS_NEAR_DIMM_NG_M_H_BYTE4\" )
					)
					( Status sCSetFlattened )
					( Origin gBackEnd )
				)
				( attribute "RELATIVE_PROPAGATION_DELAY" ",5.00 MIL"
					( Parent
						( matchGroupRef "@baseboard_fab2_lib.baseboard_fab2(sch_1):\MG_DQ-DQS_NEAR_DIMM_NG_M_H_BYTE4\" )
					)
					( Units "uMatchProp" "ns" 1.000000)
					( Status sCSetFlattened )
					( Origin gBackEnd )
				)
			)
			( pinPair "@baseboard_fab2_lib.baseboard_fab2(sch_1):\PP799\"
				( pinRef "@baseboard_fab2_lib.baseboard_fab2(sch_1):page58_i172:DDR1_DQS_DN(14)" )
				( pinRef "@baseboard_fab2_lib.baseboard_fab2(sch_1):page79_i64:DQS14N" )
				( attribute "RELATIVE_PROPAGATION_DELAY_SCOPE" "G"
					( Parent
						( matchGroupRef "@baseboard_fab2_lib.baseboard_fab2(sch_1):\MG_DQ-DQS_FAR_DIMM_NG_M_H_BYTE5\" )
					)
					( Status sCSetFlattened )
					( Origin gBackEnd )
				)
				( attribute "RELATIVE_PROPAGATION_DELAY" ",5.00 MIL"
					( Parent
						( matchGroupRef "@baseboard_fab2_lib.baseboard_fab2(sch_1):\MG_DQ-DQS_FAR_DIMM_NG_M_H_BYTE5\" )
					)
					( Units "uMatchProp" "ns" 1.000000)
					( Status sCSetFlattened )
					( Origin gBackEnd )
				)
			)
			( pinPair "@baseboard_fab2_lib.baseboard_fab2(sch_1):\PP801\"
				( pinRef "@baseboard_fab2_lib.baseboard_fab2(sch_1):page80_i101:DQS14N" )
				( pinRef "@baseboard_fab2_lib.baseboard_fab2(sch_1):page58_i172:DDR1_DQS_DN(14)" )
				( attribute "RELATIVE_PROPAGATION_DELAY_SCOPE" "G"
					( Parent
						( matchGroupRef "@baseboard_fab2_lib.baseboard_fab2(sch_1):\MG_DQ-DQS_NEAR_DIMM_NG_M_H_BYTE5\" )
					)
					( Status sCSetFlattened )
					( Origin gBackEnd )
				)
				( attribute "RELATIVE_PROPAGATION_DELAY" ",5.00 MIL"
					( Parent
						( matchGroupRef "@baseboard_fab2_lib.baseboard_fab2(sch_1):\MG_DQ-DQS_NEAR_DIMM_NG_M_H_BYTE5\" )
					)
					( Units "uMatchProp" "ns" 1.000000)
					( Status sCSetFlattened )
					( Origin gBackEnd )
				)
			)
			( pinPair "@baseboard_fab2_lib.baseboard_fab2(sch_1):\PP802\"
				( pinRef "@baseboard_fab2_lib.baseboard_fab2(sch_1):page58_i172:DDR1_DQS_DP(14)" )
				( pinRef "@baseboard_fab2_lib.baseboard_fab2(sch_1):page79_i64:DQS14P" )
				( attribute "RELATIVE_PROPAGATION_DELAY_SCOPE" "G"
					( Parent
						( matchGroupRef "@baseboard_fab2_lib.baseboard_fab2(sch_1):\MG_DQ-DQS_FAR_DIMM_NG_M_H_BYTE5\" )
					)
					( Status sCSetFlattened )
					( Origin gBackEnd )
				)
				( attribute "RELATIVE_PROPAGATION_DELAY" ",5.00 MIL"
					( Parent
						( matchGroupRef "@baseboard_fab2_lib.baseboard_fab2(sch_1):\MG_DQ-DQS_FAR_DIMM_NG_M_H_BYTE5\" )
					)
					( Units "uMatchProp" "ns" 1.000000)
					( Status sCSetFlattened )
					( Origin gBackEnd )
				)
			)
			( pinPair "@baseboard_fab2_lib.baseboard_fab2(sch_1):\PP804\"
				( pinRef "@baseboard_fab2_lib.baseboard_fab2(sch_1):page80_i101:DQS14P" )
				( pinRef "@baseboard_fab2_lib.baseboard_fab2(sch_1):page58_i172:DDR1_DQS_DP(14)" )
				( attribute "RELATIVE_PROPAGATION_DELAY_SCOPE" "G"
					( Parent
						( matchGroupRef "@baseboard_fab2_lib.baseboard_fab2(sch_1):\MG_DQ-DQS_NEAR_DIMM_NG_M_H_BYTE5\" )
					)
					( Status sCSetFlattened )
					( Origin gBackEnd )
				)
				( attribute "RELATIVE_PROPAGATION_DELAY" ",5.00 MIL"
					( Parent
						( matchGroupRef "@baseboard_fab2_lib.baseboard_fab2(sch_1):\MG_DQ-DQS_NEAR_DIMM_NG_M_H_BYTE5\" )
					)
					( Units "uMatchProp" "ns" 1.000000)
					( Status sCSetFlattened )
					( Origin gBackEnd )
				)
			)
			( pinPair "@baseboard_fab2_lib.baseboard_fab2(sch_1):\PP787\"
				( pinRef "@baseboard_fab2_lib.baseboard_fab2(sch_1):page58_i172:DDR1_DQS_DN(15)" )
				( pinRef "@baseboard_fab2_lib.baseboard_fab2(sch_1):page79_i64:DQS15N" )
				( attribute "RELATIVE_PROPAGATION_DELAY_SCOPE" "G"
					( Parent
						( matchGroupRef "@baseboard_fab2_lib.baseboard_fab2(sch_1):\MG_DQ-DQS_FAR_DIMM_NG_M_H_BYTE6\" )
					)
					( Status sCSetFlattened )
					( Origin gBackEnd )
				)
				( attribute "RELATIVE_PROPAGATION_DELAY" ",5.00 MIL"
					( Parent
						( matchGroupRef "@baseboard_fab2_lib.baseboard_fab2(sch_1):\MG_DQ-DQS_FAR_DIMM_NG_M_H_BYTE6\" )
					)
					( Units "uMatchProp" "ns" 1.000000)
					( Status sCSetFlattened )
					( Origin gBackEnd )
				)
			)
			( pinPair "@baseboard_fab2_lib.baseboard_fab2(sch_1):\PP789\"
				( pinRef "@baseboard_fab2_lib.baseboard_fab2(sch_1):page80_i101:DQS15N" )
				( pinRef "@baseboard_fab2_lib.baseboard_fab2(sch_1):page58_i172:DDR1_DQS_DN(15)" )
				( attribute "RELATIVE_PROPAGATION_DELAY_SCOPE" "G"
					( Parent
						( matchGroupRef "@baseboard_fab2_lib.baseboard_fab2(sch_1):\MG_DQ-DQS_NEAR_DIMM_NG_M_H_BYTE6\" )
					)
					( Status sCSetFlattened )
					( Origin gBackEnd )
				)
				( attribute "RELATIVE_PROPAGATION_DELAY" ",5.00 MIL"
					( Parent
						( matchGroupRef "@baseboard_fab2_lib.baseboard_fab2(sch_1):\MG_DQ-DQS_NEAR_DIMM_NG_M_H_BYTE6\" )
					)
					( Units "uMatchProp" "ns" 1.000000)
					( Status sCSetFlattened )
					( Origin gBackEnd )
				)
			)
			( pinPair "@baseboard_fab2_lib.baseboard_fab2(sch_1):\PP790\"
				( pinRef "@baseboard_fab2_lib.baseboard_fab2(sch_1):page58_i172:DDR1_DQS_DP(15)" )
				( pinRef "@baseboard_fab2_lib.baseboard_fab2(sch_1):page79_i64:DQS15P" )
				( attribute "RELATIVE_PROPAGATION_DELAY_SCOPE" "G"
					( Parent
						( matchGroupRef "@baseboard_fab2_lib.baseboard_fab2(sch_1):\MG_DQ-DQS_FAR_DIMM_NG_M_H_BYTE6\" )
					)
					( Status sCSetFlattened )
					( Origin gBackEnd )
				)
				( attribute "RELATIVE_PROPAGATION_DELAY" ",5.00 MIL"
					( Parent
						( matchGroupRef "@baseboard_fab2_lib.baseboard_fab2(sch_1):\MG_DQ-DQS_FAR_DIMM_NG_M_H_BYTE6\" )
					)
					( Units "uMatchProp" "ns" 1.000000)
					( Status sCSetFlattened )
					( Origin gBackEnd )
				)
			)
			( pinPair "@baseboard_fab2_lib.baseboard_fab2(sch_1):\PP792\"
				( pinRef "@baseboard_fab2_lib.baseboard_fab2(sch_1):page80_i101:DQS15P" )
				( pinRef "@baseboard_fab2_lib.baseboard_fab2(sch_1):page58_i172:DDR1_DQS_DP(15)" )
				( attribute "RELATIVE_PROPAGATION_DELAY_SCOPE" "G"
					( Parent
						( matchGroupRef "@baseboard_fab2_lib.baseboard_fab2(sch_1):\MG_DQ-DQS_NEAR_DIMM_NG_M_H_BYTE6\" )
					)
					( Status sCSetFlattened )
					( Origin gBackEnd )
				)
				( attribute "RELATIVE_PROPAGATION_DELAY" ",5.00 MIL"
					( Parent
						( matchGroupRef "@baseboard_fab2_lib.baseboard_fab2(sch_1):\MG_DQ-DQS_NEAR_DIMM_NG_M_H_BYTE6\" )
					)
					( Units "uMatchProp" "ns" 1.000000)
					( Status sCSetFlattened )
					( Origin gBackEnd )
				)
			)
			( pinPair "@baseboard_fab2_lib.baseboard_fab2(sch_1):\PP775\"
				( pinRef "@baseboard_fab2_lib.baseboard_fab2(sch_1):page58_i172:DDR1_DQS_DN(16)" )
				( pinRef "@baseboard_fab2_lib.baseboard_fab2(sch_1):page79_i64:DQS16N" )
				( attribute "RELATIVE_PROPAGATION_DELAY_SCOPE" "G"
					( Parent
						( matchGroupRef "@baseboard_fab2_lib.baseboard_fab2(sch_1):\MG_DQ-DQS_FAR_DIMM_NG_M_H_BYTE7\" )
					)
					( Status sCSetFlattened )
					( Origin gBackEnd )
				)
				( attribute "RELATIVE_PROPAGATION_DELAY" ",5.00 MIL"
					( Parent
						( matchGroupRef "@baseboard_fab2_lib.baseboard_fab2(sch_1):\MG_DQ-DQS_FAR_DIMM_NG_M_H_BYTE7\" )
					)
					( Units "uMatchProp" "ns" 1.000000)
					( Status sCSetFlattened )
					( Origin gBackEnd )
				)
			)
			( pinPair "@baseboard_fab2_lib.baseboard_fab2(sch_1):\PP777\"
				( pinRef "@baseboard_fab2_lib.baseboard_fab2(sch_1):page80_i101:DQS16N" )
				( pinRef "@baseboard_fab2_lib.baseboard_fab2(sch_1):page58_i172:DDR1_DQS_DN(16)" )
				( attribute "RELATIVE_PROPAGATION_DELAY_SCOPE" "G"
					( Parent
						( matchGroupRef "@baseboard_fab2_lib.baseboard_fab2(sch_1):\MG_DQ-DQS_NEAR_DIMM_NG_M_H_BYTE7\" )
					)
					( Status sCSetFlattened )
					( Origin gBackEnd )
				)
				( attribute "RELATIVE_PROPAGATION_DELAY" ",5.00 MIL"
					( Parent
						( matchGroupRef "@baseboard_fab2_lib.baseboard_fab2(sch_1):\MG_DQ-DQS_NEAR_DIMM_NG_M_H_BYTE7\" )
					)
					( Units "uMatchProp" "ns" 1.000000)
					( Status sCSetFlattened )
					( Origin gBackEnd )
				)
			)
			( pinPair "@baseboard_fab2_lib.baseboard_fab2(sch_1):\PP778\"
				( pinRef "@baseboard_fab2_lib.baseboard_fab2(sch_1):page58_i172:DDR1_DQS_DP(16)" )
				( pinRef "@baseboard_fab2_lib.baseboard_fab2(sch_1):page79_i64:DQS16P" )
				( attribute "RELATIVE_PROPAGATION_DELAY_SCOPE" "G"
					( Parent
						( matchGroupRef "@baseboard_fab2_lib.baseboard_fab2(sch_1):\MG_DQ-DQS_FAR_DIMM_NG_M_H_BYTE7\" )
					)
					( Status sCSetFlattened )
					( Origin gBackEnd )
				)
				( attribute "RELATIVE_PROPAGATION_DELAY" ",5.00 MIL"
					( Parent
						( matchGroupRef "@baseboard_fab2_lib.baseboard_fab2(sch_1):\MG_DQ-DQS_FAR_DIMM_NG_M_H_BYTE7\" )
					)
					( Units "uMatchProp" "ns" 1.000000)
					( Status sCSetFlattened )
					( Origin gBackEnd )
				)
			)
			( pinPair "@baseboard_fab2_lib.baseboard_fab2(sch_1):\PP780\"
				( pinRef "@baseboard_fab2_lib.baseboard_fab2(sch_1):page80_i101:DQS16P" )
				( pinRef "@baseboard_fab2_lib.baseboard_fab2(sch_1):page58_i172:DDR1_DQS_DP(16)" )
				( attribute "RELATIVE_PROPAGATION_DELAY_SCOPE" "G"
					( Parent
						( matchGroupRef "@baseboard_fab2_lib.baseboard_fab2(sch_1):\MG_DQ-DQS_NEAR_DIMM_NG_M_H_BYTE7\" )
					)
					( Status sCSetFlattened )
					( Origin gBackEnd )
				)
				( attribute "RELATIVE_PROPAGATION_DELAY" ",5.00 MIL"
					( Parent
						( matchGroupRef "@baseboard_fab2_lib.baseboard_fab2(sch_1):\MG_DQ-DQS_NEAR_DIMM_NG_M_H_BYTE7\" )
					)
					( Units "uMatchProp" "ns" 1.000000)
					( Status sCSetFlattened )
					( Origin gBackEnd )
				)
			)
			( pinPair "@baseboard_fab2_lib.baseboard_fab2(sch_1):\PP763\"
				( pinRef "@baseboard_fab2_lib.baseboard_fab2(sch_1):page58_i172:DDR1_DQS_DN(17)" )
				( pinRef "@baseboard_fab2_lib.baseboard_fab2(sch_1):page79_i64:DQS17N" )
				( attribute "RELATIVE_PROPAGATION_DELAY_SCOPE" "G"
					( Parent
						( matchGroupRef "@baseboard_fab2_lib.baseboard_fab2(sch_1):\MG_DQ-DQS_FAR_DIMM_NG_M_H_BYTE-ECC\" )
					)
					( Status sCSetFlattened )
					( Origin gBackEnd )
				)
				( attribute "RELATIVE_PROPAGATION_DELAY" ",5.00 MIL"
					( Parent
						( matchGroupRef "@baseboard_fab2_lib.baseboard_fab2(sch_1):\MG_DQ-DQS_FAR_DIMM_NG_M_H_BYTE-ECC\" )
					)
					( Units "uMatchProp" "ns" 1.000000)
					( Status sCSetFlattened )
					( Origin gBackEnd )
				)
			)
			( pinPair "@baseboard_fab2_lib.baseboard_fab2(sch_1):\PP764\"
				( pinRef "@baseboard_fab2_lib.baseboard_fab2(sch_1):page80_i101:DQS17N" )
				( pinRef "@baseboard_fab2_lib.baseboard_fab2(sch_1):page58_i172:DDR1_DQS_DN(17)" )
				( attribute "RELATIVE_PROPAGATION_DELAY_SCOPE" "G"
					( Parent
						( matchGroupRef "@baseboard_fab2_lib.baseboard_fab2(sch_1):\MG_DQ-DQS_NEAR_DIMM_NG_M_H_BYTE-ECC\" )
					)
					( Status sCSetFlattened )
					( Origin gBackEnd )
				)
				( attribute "RELATIVE_PROPAGATION_DELAY" ",5.00 MIL"
					( Parent
						( matchGroupRef "@baseboard_fab2_lib.baseboard_fab2(sch_1):\MG_DQ-DQS_NEAR_DIMM_NG_M_H_BYTE-ECC\" )
					)
					( Units "uMatchProp" "ns" 1.000000)
					( Status sCSetFlattened )
					( Origin gBackEnd )
				)
			)
			( pinPair "@baseboard_fab2_lib.baseboard_fab2(sch_1):\PP766\"
				( pinRef "@baseboard_fab2_lib.baseboard_fab2(sch_1):page58_i172:DDR1_DQS_DP(17)" )
				( pinRef "@baseboard_fab2_lib.baseboard_fab2(sch_1):page79_i64:DQS17P" )
				( attribute "RELATIVE_PROPAGATION_DELAY_SCOPE" "G"
					( Parent
						( matchGroupRef "@baseboard_fab2_lib.baseboard_fab2(sch_1):\MG_DQ-DQS_FAR_DIMM_NG_M_H_BYTE-ECC\" )
					)
					( Status sCSetFlattened )
					( Origin gBackEnd )
				)
				( attribute "RELATIVE_PROPAGATION_DELAY" ",5.00 MIL"
					( Parent
						( matchGroupRef "@baseboard_fab2_lib.baseboard_fab2(sch_1):\MG_DQ-DQS_FAR_DIMM_NG_M_H_BYTE-ECC\" )
					)
					( Units "uMatchProp" "ns" 1.000000)
					( Status sCSetFlattened )
					( Origin gBackEnd )
				)
			)
			( pinPair "@baseboard_fab2_lib.baseboard_fab2(sch_1):\PP767\"
				( pinRef "@baseboard_fab2_lib.baseboard_fab2(sch_1):page80_i101:DQS17P" )
				( pinRef "@baseboard_fab2_lib.baseboard_fab2(sch_1):page58_i172:DDR1_DQS_DP(17)" )
				( attribute "RELATIVE_PROPAGATION_DELAY_SCOPE" "G"
					( Parent
						( matchGroupRef "@baseboard_fab2_lib.baseboard_fab2(sch_1):\MG_DQ-DQS_NEAR_DIMM_NG_M_H_BYTE-ECC\" )
					)
					( Status sCSetFlattened )
					( Origin gBackEnd )
				)
				( attribute "RELATIVE_PROPAGATION_DELAY" ",5.00 MIL"
					( Parent
						( matchGroupRef "@baseboard_fab2_lib.baseboard_fab2(sch_1):\MG_DQ-DQS_NEAR_DIMM_NG_M_H_BYTE-ECC\" )
					)
					( Units "uMatchProp" "ns" 1.000000)
					( Status sCSetFlattened )
					( Origin gBackEnd )
				)
			)
			( pinPair "@baseboard_fab2_lib.baseboard_fab2(sch_1):\PP1669\"
				( pinRef "@baseboard_fab2_lib.baseboard_fab2(sch_1):page59_i172:DDR2_DQS_DN(0)" )
				( pinRef "@baseboard_fab2_lib.baseboard_fab2(sch_1):page81_i67:DQS0N" )
				( attribute "RELATIVE_PROPAGATION_DELAY_SCOPE" "G"
					( Parent
						( matchGroupRef "@baseboard_fab2_lib.baseboard_fab2(sch_1):\MG_DQ-DQS_FAR_DIMM_NG_M_J_BYTE0\" )
					)
					( Status sCSetFlattened )
					( Origin gBackEnd )
				)
				( attribute "RELATIVE_PROPAGATION_DELAY" ",5.00 MIL"
					( Parent
						( matchGroupRef "@baseboard_fab2_lib.baseboard_fab2(sch_1):\MG_DQ-DQS_FAR_DIMM_NG_M_J_BYTE0\" )
					)
					( Units "uMatchProp" "ns" 1.000000)
					( Status sCSetFlattened )
					( Origin gBackEnd )
				)
			)
			( pinPair "@baseboard_fab2_lib.baseboard_fab2(sch_1):\PP1670\"
				( pinRef "@baseboard_fab2_lib.baseboard_fab2(sch_1):page82_i64:DQS0N" )
				( pinRef "@baseboard_fab2_lib.baseboard_fab2(sch_1):page59_i172:DDR2_DQS_DN(0)" )
				( attribute "RELATIVE_PROPAGATION_DELAY_SCOPE" "G"
					( Parent
						( matchGroupRef "@baseboard_fab2_lib.baseboard_fab2(sch_1):\MG_DQ-DQS_NEAR_DIMM_NG_M_J_BYTE0\" )
					)
					( Status sCSetFlattened )
					( Origin gBackEnd )
				)
				( attribute "RELATIVE_PROPAGATION_DELAY" ",5.00 MIL"
					( Parent
						( matchGroupRef "@baseboard_fab2_lib.baseboard_fab2(sch_1):\MG_DQ-DQS_NEAR_DIMM_NG_M_J_BYTE0\" )
					)
					( Units "uMatchProp" "ns" 1.000000)
					( Status sCSetFlattened )
					( Origin gBackEnd )
				)
			)
			( pinPair "@baseboard_fab2_lib.baseboard_fab2(sch_1):\PP1672\"
				( pinRef "@baseboard_fab2_lib.baseboard_fab2(sch_1):page59_i172:DDR2_DQS_DP(0)" )
				( pinRef "@baseboard_fab2_lib.baseboard_fab2(sch_1):page81_i67:DQS0P" )
				( attribute "RELATIVE_PROPAGATION_DELAY_SCOPE" "G"
					( Parent
						( matchGroupRef "@baseboard_fab2_lib.baseboard_fab2(sch_1):\MG_DQ-DQS_FAR_DIMM_NG_M_J_BYTE0\" )
					)
					( Status sCSetFlattened )
					( Origin gBackEnd )
				)
				( attribute "RELATIVE_PROPAGATION_DELAY" ",5.00 MIL"
					( Parent
						( matchGroupRef "@baseboard_fab2_lib.baseboard_fab2(sch_1):\MG_DQ-DQS_FAR_DIMM_NG_M_J_BYTE0\" )
					)
					( Units "uMatchProp" "ns" 1.000000)
					( Status sCSetFlattened )
					( Origin gBackEnd )
				)
			)
			( pinPair "@baseboard_fab2_lib.baseboard_fab2(sch_1):\PP1673\"
				( pinRef "@baseboard_fab2_lib.baseboard_fab2(sch_1):page82_i64:DQS0P" )
				( pinRef "@baseboard_fab2_lib.baseboard_fab2(sch_1):page59_i172:DDR2_DQS_DP(0)" )
				( attribute "RELATIVE_PROPAGATION_DELAY_SCOPE" "G"
					( Parent
						( matchGroupRef "@baseboard_fab2_lib.baseboard_fab2(sch_1):\MG_DQ-DQS_NEAR_DIMM_NG_M_J_BYTE0\" )
					)
					( Status sCSetFlattened )
					( Origin gBackEnd )
				)
				( attribute "RELATIVE_PROPAGATION_DELAY" ",5.00 MIL"
					( Parent
						( matchGroupRef "@baseboard_fab2_lib.baseboard_fab2(sch_1):\MG_DQ-DQS_NEAR_DIMM_NG_M_J_BYTE0\" )
					)
					( Units "uMatchProp" "ns" 1.000000)
					( Status sCSetFlattened )
					( Origin gBackEnd )
				)
			)
			( pinPair "@baseboard_fab2_lib.baseboard_fab2(sch_1):\PP1657\"
				( pinRef "@baseboard_fab2_lib.baseboard_fab2(sch_1):page59_i172:DDR2_DQS_DN(1)" )
				( pinRef "@baseboard_fab2_lib.baseboard_fab2(sch_1):page81_i67:DQS1N" )
				( attribute "RELATIVE_PROPAGATION_DELAY_SCOPE" "G"
					( Parent
						( matchGroupRef "@baseboard_fab2_lib.baseboard_fab2(sch_1):\MG_DQ-DQS_FAR_DIMM_NG_M_J_BYTE1\" )
					)
					( Status sCSetFlattened )
					( Origin gBackEnd )
				)
				( attribute "RELATIVE_PROPAGATION_DELAY" ",5.00 MIL"
					( Parent
						( matchGroupRef "@baseboard_fab2_lib.baseboard_fab2(sch_1):\MG_DQ-DQS_FAR_DIMM_NG_M_J_BYTE1\" )
					)
					( Units "uMatchProp" "ns" 1.000000)
					( Status sCSetFlattened )
					( Origin gBackEnd )
				)
			)
			( pinPair "@baseboard_fab2_lib.baseboard_fab2(sch_1):\PP1658\"
				( pinRef "@baseboard_fab2_lib.baseboard_fab2(sch_1):page82_i64:DQS1N" )
				( pinRef "@baseboard_fab2_lib.baseboard_fab2(sch_1):page59_i172:DDR2_DQS_DN(1)" )
				( attribute "RELATIVE_PROPAGATION_DELAY_SCOPE" "G"
					( Parent
						( matchGroupRef "@baseboard_fab2_lib.baseboard_fab2(sch_1):\MG_DQ-DQS_NEAR_DIMM_NG_M_J_BYTE1\" )
					)
					( Status sCSetFlattened )
					( Origin gBackEnd )
				)
				( attribute "RELATIVE_PROPAGATION_DELAY" ",5.00 MIL"
					( Parent
						( matchGroupRef "@baseboard_fab2_lib.baseboard_fab2(sch_1):\MG_DQ-DQS_NEAR_DIMM_NG_M_J_BYTE1\" )
					)
					( Units "uMatchProp" "ns" 1.000000)
					( Status sCSetFlattened )
					( Origin gBackEnd )
				)
			)
			( pinPair "@baseboard_fab2_lib.baseboard_fab2(sch_1):\PP1660\"
				( pinRef "@baseboard_fab2_lib.baseboard_fab2(sch_1):page59_i172:DDR2_DQS_DP(1)" )
				( pinRef "@baseboard_fab2_lib.baseboard_fab2(sch_1):page81_i67:DQS1P" )
				( attribute "RELATIVE_PROPAGATION_DELAY_SCOPE" "G"
					( Parent
						( matchGroupRef "@baseboard_fab2_lib.baseboard_fab2(sch_1):\MG_DQ-DQS_FAR_DIMM_NG_M_J_BYTE1\" )
					)
					( Status sCSetFlattened )
					( Origin gBackEnd )
				)
				( attribute "RELATIVE_PROPAGATION_DELAY" ",5.00 MIL"
					( Parent
						( matchGroupRef "@baseboard_fab2_lib.baseboard_fab2(sch_1):\MG_DQ-DQS_FAR_DIMM_NG_M_J_BYTE1\" )
					)
					( Units "uMatchProp" "ns" 1.000000)
					( Status sCSetFlattened )
					( Origin gBackEnd )
				)
			)
			( pinPair "@baseboard_fab2_lib.baseboard_fab2(sch_1):\PP1661\"
				( pinRef "@baseboard_fab2_lib.baseboard_fab2(sch_1):page82_i64:DQS1P" )
				( pinRef "@baseboard_fab2_lib.baseboard_fab2(sch_1):page59_i172:DDR2_DQS_DP(1)" )
				( attribute "RELATIVE_PROPAGATION_DELAY_SCOPE" "G"
					( Parent
						( matchGroupRef "@baseboard_fab2_lib.baseboard_fab2(sch_1):\MG_DQ-DQS_NEAR_DIMM_NG_M_J_BYTE1\" )
					)
					( Status sCSetFlattened )
					( Origin gBackEnd )
				)
				( attribute "RELATIVE_PROPAGATION_DELAY" ",5.00 MIL"
					( Parent
						( matchGroupRef "@baseboard_fab2_lib.baseboard_fab2(sch_1):\MG_DQ-DQS_NEAR_DIMM_NG_M_J_BYTE1\" )
					)
					( Units "uMatchProp" "ns" 1.000000)
					( Status sCSetFlattened )
					( Origin gBackEnd )
				)
			)
			( pinPair "@baseboard_fab2_lib.baseboard_fab2(sch_1):\PP1645\"
				( pinRef "@baseboard_fab2_lib.baseboard_fab2(sch_1):page59_i172:DDR2_DQS_DN(2)" )
				( pinRef "@baseboard_fab2_lib.baseboard_fab2(sch_1):page81_i67:DQS2N" )
				( attribute "RELATIVE_PROPAGATION_DELAY_SCOPE" "G"
					( Parent
						( matchGroupRef "@baseboard_fab2_lib.baseboard_fab2(sch_1):\MG_DQ-DQS_FAR_DIMM_NG_M_J_BYTE2\" )
					)
					( Status sCSetFlattened )
					( Origin gBackEnd )
				)
				( attribute "RELATIVE_PROPAGATION_DELAY" ",5.00 MIL"
					( Parent
						( matchGroupRef "@baseboard_fab2_lib.baseboard_fab2(sch_1):\MG_DQ-DQS_FAR_DIMM_NG_M_J_BYTE2\" )
					)
					( Units "uMatchProp" "ns" 1.000000)
					( Status sCSetFlattened )
					( Origin gBackEnd )
				)
			)
			( pinPair "@baseboard_fab2_lib.baseboard_fab2(sch_1):\PP1646\"
				( pinRef "@baseboard_fab2_lib.baseboard_fab2(sch_1):page82_i64:DQS2N" )
				( pinRef "@baseboard_fab2_lib.baseboard_fab2(sch_1):page59_i172:DDR2_DQS_DN(2)" )
				( attribute "RELATIVE_PROPAGATION_DELAY_SCOPE" "G"
					( Parent
						( matchGroupRef "@baseboard_fab2_lib.baseboard_fab2(sch_1):\MG_DQ-DQS_NEAR_DIMM_NG_M_J_BYTE2\" )
					)
					( Status sCSetFlattened )
					( Origin gBackEnd )
				)
				( attribute "RELATIVE_PROPAGATION_DELAY" ",5.00 MIL"
					( Parent
						( matchGroupRef "@baseboard_fab2_lib.baseboard_fab2(sch_1):\MG_DQ-DQS_NEAR_DIMM_NG_M_J_BYTE2\" )
					)
					( Units "uMatchProp" "ns" 1.000000)
					( Status sCSetFlattened )
					( Origin gBackEnd )
				)
			)
			( pinPair "@baseboard_fab2_lib.baseboard_fab2(sch_1):\PP1648\"
				( pinRef "@baseboard_fab2_lib.baseboard_fab2(sch_1):page59_i172:DDR2_DQS_DP(2)" )
				( pinRef "@baseboard_fab2_lib.baseboard_fab2(sch_1):page81_i67:DQS2P" )
				( attribute "RELATIVE_PROPAGATION_DELAY_SCOPE" "G"
					( Parent
						( matchGroupRef "@baseboard_fab2_lib.baseboard_fab2(sch_1):\MG_DQ-DQS_FAR_DIMM_NG_M_J_BYTE2\" )
					)
					( Status sCSetFlattened )
					( Origin gBackEnd )
				)
				( attribute "RELATIVE_PROPAGATION_DELAY" ",5.00 MIL"
					( Parent
						( matchGroupRef "@baseboard_fab2_lib.baseboard_fab2(sch_1):\MG_DQ-DQS_FAR_DIMM_NG_M_J_BYTE2\" )
					)
					( Units "uMatchProp" "ns" 1.000000)
					( Status sCSetFlattened )
					( Origin gBackEnd )
				)
			)
			( pinPair "@baseboard_fab2_lib.baseboard_fab2(sch_1):\PP1649\"
				( pinRef "@baseboard_fab2_lib.baseboard_fab2(sch_1):page82_i64:DQS2P" )
				( pinRef "@baseboard_fab2_lib.baseboard_fab2(sch_1):page59_i172:DDR2_DQS_DP(2)" )
				( attribute "RELATIVE_PROPAGATION_DELAY_SCOPE" "G"
					( Parent
						( matchGroupRef "@baseboard_fab2_lib.baseboard_fab2(sch_1):\MG_DQ-DQS_NEAR_DIMM_NG_M_J_BYTE2\" )
					)
					( Status sCSetFlattened )
					( Origin gBackEnd )
				)
				( attribute "RELATIVE_PROPAGATION_DELAY" ",5.00 MIL"
					( Parent
						( matchGroupRef "@baseboard_fab2_lib.baseboard_fab2(sch_1):\MG_DQ-DQS_NEAR_DIMM_NG_M_J_BYTE2\" )
					)
					( Units "uMatchProp" "ns" 1.000000)
					( Status sCSetFlattened )
					( Origin gBackEnd )
				)
			)
			( pinPair "@baseboard_fab2_lib.baseboard_fab2(sch_1):\PP1633\"
				( pinRef "@baseboard_fab2_lib.baseboard_fab2(sch_1):page59_i172:DDR2_DQS_DN(3)" )
				( pinRef "@baseboard_fab2_lib.baseboard_fab2(sch_1):page81_i67:DQS3N" )
				( attribute "RELATIVE_PROPAGATION_DELAY_SCOPE" "G"
					( Parent
						( matchGroupRef "@baseboard_fab2_lib.baseboard_fab2(sch_1):\MG_DQ-DQS_FAR_DIMM_NG_M_J_BYTE3\" )
					)
					( Status sCSetFlattened )
					( Origin gBackEnd )
				)
				( attribute "RELATIVE_PROPAGATION_DELAY" ",5.00 MIL"
					( Parent
						( matchGroupRef "@baseboard_fab2_lib.baseboard_fab2(sch_1):\MG_DQ-DQS_FAR_DIMM_NG_M_J_BYTE3\" )
					)
					( Units "uMatchProp" "ns" 1.000000)
					( Status sCSetFlattened )
					( Origin gBackEnd )
				)
			)
			( pinPair "@baseboard_fab2_lib.baseboard_fab2(sch_1):\PP1634\"
				( pinRef "@baseboard_fab2_lib.baseboard_fab2(sch_1):page82_i64:DQS3N" )
				( pinRef "@baseboard_fab2_lib.baseboard_fab2(sch_1):page59_i172:DDR2_DQS_DN(3)" )
				( attribute "RELATIVE_PROPAGATION_DELAY_SCOPE" "G"
					( Parent
						( matchGroupRef "@baseboard_fab2_lib.baseboard_fab2(sch_1):\MG_DQ-DQS_NEAR_DIMM_NG_M_J_BYTE3\" )
					)
					( Status sCSetFlattened )
					( Origin gBackEnd )
				)
				( attribute "RELATIVE_PROPAGATION_DELAY" ",5.00 MIL"
					( Parent
						( matchGroupRef "@baseboard_fab2_lib.baseboard_fab2(sch_1):\MG_DQ-DQS_NEAR_DIMM_NG_M_J_BYTE3\" )
					)
					( Units "uMatchProp" "ns" 1.000000)
					( Status sCSetFlattened )
					( Origin gBackEnd )
				)
			)
			( pinPair "@baseboard_fab2_lib.baseboard_fab2(sch_1):\PP1636\"
				( pinRef "@baseboard_fab2_lib.baseboard_fab2(sch_1):page59_i172:DDR2_DQS_DP(3)" )
				( pinRef "@baseboard_fab2_lib.baseboard_fab2(sch_1):page81_i67:DQS3P" )
				( attribute "RELATIVE_PROPAGATION_DELAY_SCOPE" "G"
					( Parent
						( matchGroupRef "@baseboard_fab2_lib.baseboard_fab2(sch_1):\MG_DQ-DQS_FAR_DIMM_NG_M_J_BYTE3\" )
					)
					( Status sCSetFlattened )
					( Origin gBackEnd )
				)
				( attribute "RELATIVE_PROPAGATION_DELAY" ",5.00 MIL"
					( Parent
						( matchGroupRef "@baseboard_fab2_lib.baseboard_fab2(sch_1):\MG_DQ-DQS_FAR_DIMM_NG_M_J_BYTE3\" )
					)
					( Units "uMatchProp" "ns" 1.000000)
					( Status sCSetFlattened )
					( Origin gBackEnd )
				)
			)
			( pinPair "@baseboard_fab2_lib.baseboard_fab2(sch_1):\PP1637\"
				( pinRef "@baseboard_fab2_lib.baseboard_fab2(sch_1):page82_i64:DQS3P" )
				( pinRef "@baseboard_fab2_lib.baseboard_fab2(sch_1):page59_i172:DDR2_DQS_DP(3)" )
				( attribute "RELATIVE_PROPAGATION_DELAY_SCOPE" "G"
					( Parent
						( matchGroupRef "@baseboard_fab2_lib.baseboard_fab2(sch_1):\MG_DQ-DQS_NEAR_DIMM_NG_M_J_BYTE3\" )
					)
					( Status sCSetFlattened )
					( Origin gBackEnd )
				)
				( attribute "RELATIVE_PROPAGATION_DELAY" ",5.00 MIL"
					( Parent
						( matchGroupRef "@baseboard_fab2_lib.baseboard_fab2(sch_1):\MG_DQ-DQS_NEAR_DIMM_NG_M_J_BYTE3\" )
					)
					( Units "uMatchProp" "ns" 1.000000)
					( Status sCSetFlattened )
					( Origin gBackEnd )
				)
			)
			( pinPair "@baseboard_fab2_lib.baseboard_fab2(sch_1):\PP1621\"
				( pinRef "@baseboard_fab2_lib.baseboard_fab2(sch_1):page59_i172:DDR2_DQS_DN(4)" )
				( pinRef "@baseboard_fab2_lib.baseboard_fab2(sch_1):page81_i67:DQS4N" )
				( attribute "RELATIVE_PROPAGATION_DELAY_SCOPE" "G"
					( Parent
						( matchGroupRef "@baseboard_fab2_lib.baseboard_fab2(sch_1):\MG_DQ-DQS_FAR_DIMM_NG_M_J_BYTE4\" )
					)
					( Status sCSetFlattened )
					( Origin gBackEnd )
				)
				( attribute "RELATIVE_PROPAGATION_DELAY" ",5.00 MIL"
					( Parent
						( matchGroupRef "@baseboard_fab2_lib.baseboard_fab2(sch_1):\MG_DQ-DQS_FAR_DIMM_NG_M_J_BYTE4\" )
					)
					( Units "uMatchProp" "ns" 1.000000)
					( Status sCSetFlattened )
					( Origin gBackEnd )
				)
			)
			( pinPair "@baseboard_fab2_lib.baseboard_fab2(sch_1):\PP1623\"
				( pinRef "@baseboard_fab2_lib.baseboard_fab2(sch_1):page82_i64:DQS4N" )
				( pinRef "@baseboard_fab2_lib.baseboard_fab2(sch_1):page59_i172:DDR2_DQS_DN(4)" )
				( attribute "RELATIVE_PROPAGATION_DELAY_SCOPE" "G"
					( Parent
						( matchGroupRef "@baseboard_fab2_lib.baseboard_fab2(sch_1):\MG_DQ-DQS_NEAR_DIMM_NG_M_J_BYTE4\" )
					)
					( Status sCSetFlattened )
					( Origin gBackEnd )
				)
				( attribute "RELATIVE_PROPAGATION_DELAY" ",5.00 MIL"
					( Parent
						( matchGroupRef "@baseboard_fab2_lib.baseboard_fab2(sch_1):\MG_DQ-DQS_NEAR_DIMM_NG_M_J_BYTE4\" )
					)
					( Units "uMatchProp" "ns" 1.000000)
					( Status sCSetFlattened )
					( Origin gBackEnd )
				)
			)
			( pinPair "@baseboard_fab2_lib.baseboard_fab2(sch_1):\PP1624\"
				( pinRef "@baseboard_fab2_lib.baseboard_fab2(sch_1):page59_i172:DDR2_DQS_DP(4)" )
				( pinRef "@baseboard_fab2_lib.baseboard_fab2(sch_1):page81_i67:DQS4P" )
				( attribute "RELATIVE_PROPAGATION_DELAY_SCOPE" "G"
					( Parent
						( matchGroupRef "@baseboard_fab2_lib.baseboard_fab2(sch_1):\MG_DQ-DQS_FAR_DIMM_NG_M_J_BYTE4\" )
					)
					( Status sCSetFlattened )
					( Origin gBackEnd )
				)
				( attribute "RELATIVE_PROPAGATION_DELAY" ",5.00 MIL"
					( Parent
						( matchGroupRef "@baseboard_fab2_lib.baseboard_fab2(sch_1):\MG_DQ-DQS_FAR_DIMM_NG_M_J_BYTE4\" )
					)
					( Units "uMatchProp" "ns" 1.000000)
					( Status sCSetFlattened )
					( Origin gBackEnd )
				)
			)
			( pinPair "@baseboard_fab2_lib.baseboard_fab2(sch_1):\PP1626\"
				( pinRef "@baseboard_fab2_lib.baseboard_fab2(sch_1):page82_i64:DQS4P" )
				( pinRef "@baseboard_fab2_lib.baseboard_fab2(sch_1):page59_i172:DDR2_DQS_DP(4)" )
				( attribute "RELATIVE_PROPAGATION_DELAY_SCOPE" "G"
					( Parent
						( matchGroupRef "@baseboard_fab2_lib.baseboard_fab2(sch_1):\MG_DQ-DQS_NEAR_DIMM_NG_M_J_BYTE4\" )
					)
					( Status sCSetFlattened )
					( Origin gBackEnd )
				)
				( attribute "RELATIVE_PROPAGATION_DELAY" ",5.00 MIL"
					( Parent
						( matchGroupRef "@baseboard_fab2_lib.baseboard_fab2(sch_1):\MG_DQ-DQS_NEAR_DIMM_NG_M_J_BYTE4\" )
					)
					( Units "uMatchProp" "ns" 1.000000)
					( Status sCSetFlattened )
					( Origin gBackEnd )
				)
			)
			( pinPair "@baseboard_fab2_lib.baseboard_fab2(sch_1):\PP1609\"
				( pinRef "@baseboard_fab2_lib.baseboard_fab2(sch_1):page59_i172:DDR2_DQS_DN(5)" )
				( pinRef "@baseboard_fab2_lib.baseboard_fab2(sch_1):page81_i67:DQS5N" )
				( attribute "RELATIVE_PROPAGATION_DELAY_SCOPE" "G"
					( Parent
						( matchGroupRef "@baseboard_fab2_lib.baseboard_fab2(sch_1):\MG_DQ-DQS_FAR_DIMM_NG_M_J_BYTE5\" )
					)
					( Status sCSetFlattened )
					( Origin gBackEnd )
				)
				( attribute "RELATIVE_PROPAGATION_DELAY" ",5.00 MIL"
					( Parent
						( matchGroupRef "@baseboard_fab2_lib.baseboard_fab2(sch_1):\MG_DQ-DQS_FAR_DIMM_NG_M_J_BYTE5\" )
					)
					( Units "uMatchProp" "ns" 1.000000)
					( Status sCSetFlattened )
					( Origin gBackEnd )
				)
			)
			( pinPair "@baseboard_fab2_lib.baseboard_fab2(sch_1):\PP1611\"
				( pinRef "@baseboard_fab2_lib.baseboard_fab2(sch_1):page82_i64:DQS5N" )
				( pinRef "@baseboard_fab2_lib.baseboard_fab2(sch_1):page59_i172:DDR2_DQS_DN(5)" )
				( attribute "RELATIVE_PROPAGATION_DELAY_SCOPE" "G"
					( Parent
						( matchGroupRef "@baseboard_fab2_lib.baseboard_fab2(sch_1):\MG_DQ-DQS_NEAR_DIMM_NG_M_J_BYTE5\" )
					)
					( Status sCSetFlattened )
					( Origin gBackEnd )
				)
				( attribute "RELATIVE_PROPAGATION_DELAY" ",5.00 MIL"
					( Parent
						( matchGroupRef "@baseboard_fab2_lib.baseboard_fab2(sch_1):\MG_DQ-DQS_NEAR_DIMM_NG_M_J_BYTE5\" )
					)
					( Units "uMatchProp" "ns" 1.000000)
					( Status sCSetFlattened )
					( Origin gBackEnd )
				)
			)
			( pinPair "@baseboard_fab2_lib.baseboard_fab2(sch_1):\PP1612\"
				( pinRef "@baseboard_fab2_lib.baseboard_fab2(sch_1):page59_i172:DDR2_DQS_DP(5)" )
				( pinRef "@baseboard_fab2_lib.baseboard_fab2(sch_1):page81_i67:DQS5P" )
				( attribute "RELATIVE_PROPAGATION_DELAY_SCOPE" "G"
					( Parent
						( matchGroupRef "@baseboard_fab2_lib.baseboard_fab2(sch_1):\MG_DQ-DQS_FAR_DIMM_NG_M_J_BYTE5\" )
					)
					( Status sCSetFlattened )
					( Origin gBackEnd )
				)
				( attribute "RELATIVE_PROPAGATION_DELAY" ",5.00 MIL"
					( Parent
						( matchGroupRef "@baseboard_fab2_lib.baseboard_fab2(sch_1):\MG_DQ-DQS_FAR_DIMM_NG_M_J_BYTE5\" )
					)
					( Units "uMatchProp" "ns" 1.000000)
					( Status sCSetFlattened )
					( Origin gBackEnd )
				)
			)
			( pinPair "@baseboard_fab2_lib.baseboard_fab2(sch_1):\PP1614\"
				( pinRef "@baseboard_fab2_lib.baseboard_fab2(sch_1):page82_i64:DQS5P" )
				( pinRef "@baseboard_fab2_lib.baseboard_fab2(sch_1):page59_i172:DDR2_DQS_DP(5)" )
				( attribute "RELATIVE_PROPAGATION_DELAY_SCOPE" "G"
					( Parent
						( matchGroupRef "@baseboard_fab2_lib.baseboard_fab2(sch_1):\MG_DQ-DQS_NEAR_DIMM_NG_M_J_BYTE5\" )
					)
					( Status sCSetFlattened )
					( Origin gBackEnd )
				)
				( attribute "RELATIVE_PROPAGATION_DELAY" ",5.00 MIL"
					( Parent
						( matchGroupRef "@baseboard_fab2_lib.baseboard_fab2(sch_1):\MG_DQ-DQS_NEAR_DIMM_NG_M_J_BYTE5\" )
					)
					( Units "uMatchProp" "ns" 1.000000)
					( Status sCSetFlattened )
					( Origin gBackEnd )
				)
			)
			( pinPair "@baseboard_fab2_lib.baseboard_fab2(sch_1):\PP1597\"
				( pinRef "@baseboard_fab2_lib.baseboard_fab2(sch_1):page59_i172:DDR2_DQS_DN(6)" )
				( pinRef "@baseboard_fab2_lib.baseboard_fab2(sch_1):page81_i67:DQS6N" )
				( attribute "RELATIVE_PROPAGATION_DELAY_SCOPE" "G"
					( Parent
						( matchGroupRef "@baseboard_fab2_lib.baseboard_fab2(sch_1):\MG_DQ-DQS_FAR_DIMM_NG_M_J_BYTE6\" )
					)
					( Status sCSetFlattened )
					( Origin gBackEnd )
				)
				( attribute "RELATIVE_PROPAGATION_DELAY" ",5.00 MIL"
					( Parent
						( matchGroupRef "@baseboard_fab2_lib.baseboard_fab2(sch_1):\MG_DQ-DQS_FAR_DIMM_NG_M_J_BYTE6\" )
					)
					( Units "uMatchProp" "ns" 1.000000)
					( Status sCSetFlattened )
					( Origin gBackEnd )
				)
			)
			( pinPair "@baseboard_fab2_lib.baseboard_fab2(sch_1):\PP1599\"
				( pinRef "@baseboard_fab2_lib.baseboard_fab2(sch_1):page82_i64:DQS6N" )
				( pinRef "@baseboard_fab2_lib.baseboard_fab2(sch_1):page59_i172:DDR2_DQS_DN(6)" )
				( attribute "RELATIVE_PROPAGATION_DELAY_SCOPE" "G"
					( Parent
						( matchGroupRef "@baseboard_fab2_lib.baseboard_fab2(sch_1):\MG_DQ-DQS_NEAR_DIMM_NG_M_J_BYTE6\" )
					)
					( Status sCSetFlattened )
					( Origin gBackEnd )
				)
				( attribute "RELATIVE_PROPAGATION_DELAY" ",5.00 MIL"
					( Parent
						( matchGroupRef "@baseboard_fab2_lib.baseboard_fab2(sch_1):\MG_DQ-DQS_NEAR_DIMM_NG_M_J_BYTE6\" )
					)
					( Units "uMatchProp" "ns" 1.000000)
					( Status sCSetFlattened )
					( Origin gBackEnd )
				)
			)
			( pinPair "@baseboard_fab2_lib.baseboard_fab2(sch_1):\PP1600\"
				( pinRef "@baseboard_fab2_lib.baseboard_fab2(sch_1):page59_i172:DDR2_DQS_DP(6)" )
				( pinRef "@baseboard_fab2_lib.baseboard_fab2(sch_1):page81_i67:DQS6P" )
				( attribute "RELATIVE_PROPAGATION_DELAY_SCOPE" "G"
					( Parent
						( matchGroupRef "@baseboard_fab2_lib.baseboard_fab2(sch_1):\MG_DQ-DQS_FAR_DIMM_NG_M_J_BYTE6\" )
					)
					( Status sCSetFlattened )
					( Origin gBackEnd )
				)
				( attribute "RELATIVE_PROPAGATION_DELAY" ",5.00 MIL"
					( Parent
						( matchGroupRef "@baseboard_fab2_lib.baseboard_fab2(sch_1):\MG_DQ-DQS_FAR_DIMM_NG_M_J_BYTE6\" )
					)
					( Units "uMatchProp" "ns" 1.000000)
					( Status sCSetFlattened )
					( Origin gBackEnd )
				)
			)
			( pinPair "@baseboard_fab2_lib.baseboard_fab2(sch_1):\PP1602\"
				( pinRef "@baseboard_fab2_lib.baseboard_fab2(sch_1):page82_i64:DQS6P" )
				( pinRef "@baseboard_fab2_lib.baseboard_fab2(sch_1):page59_i172:DDR2_DQS_DP(6)" )
				( attribute "RELATIVE_PROPAGATION_DELAY_SCOPE" "G"
					( Parent
						( matchGroupRef "@baseboard_fab2_lib.baseboard_fab2(sch_1):\MG_DQ-DQS_NEAR_DIMM_NG_M_J_BYTE6\" )
					)
					( Status sCSetFlattened )
					( Origin gBackEnd )
				)
				( attribute "RELATIVE_PROPAGATION_DELAY" ",5.00 MIL"
					( Parent
						( matchGroupRef "@baseboard_fab2_lib.baseboard_fab2(sch_1):\MG_DQ-DQS_NEAR_DIMM_NG_M_J_BYTE6\" )
					)
					( Units "uMatchProp" "ns" 1.000000)
					( Status sCSetFlattened )
					( Origin gBackEnd )
				)
			)
			( pinPair "@baseboard_fab2_lib.baseboard_fab2(sch_1):\PP1585\"
				( pinRef "@baseboard_fab2_lib.baseboard_fab2(sch_1):page59_i172:DDR2_DQS_DN(7)" )
				( pinRef "@baseboard_fab2_lib.baseboard_fab2(sch_1):page81_i67:DQS7N" )
				( attribute "RELATIVE_PROPAGATION_DELAY_SCOPE" "G"
					( Parent
						( matchGroupRef "@baseboard_fab2_lib.baseboard_fab2(sch_1):\MG_DQ-DQS_FAR_DIMM_NG_M_J_BYTE7\" )
					)
					( Status sCSetFlattened )
					( Origin gBackEnd )
				)
				( attribute "RELATIVE_PROPAGATION_DELAY" ",5.00 MIL"
					( Parent
						( matchGroupRef "@baseboard_fab2_lib.baseboard_fab2(sch_1):\MG_DQ-DQS_FAR_DIMM_NG_M_J_BYTE7\" )
					)
					( Units "uMatchProp" "ns" 1.000000)
					( Status sCSetFlattened )
					( Origin gBackEnd )
				)
			)
			( pinPair "@baseboard_fab2_lib.baseboard_fab2(sch_1):\PP1587\"
				( pinRef "@baseboard_fab2_lib.baseboard_fab2(sch_1):page82_i64:DQS7N" )
				( pinRef "@baseboard_fab2_lib.baseboard_fab2(sch_1):page59_i172:DDR2_DQS_DN(7)" )
				( attribute "RELATIVE_PROPAGATION_DELAY_SCOPE" "G"
					( Parent
						( matchGroupRef "@baseboard_fab2_lib.baseboard_fab2(sch_1):\MG_DQ-DQS_NEAR_DIMM_NG_M_J_BYTE7\" )
					)
					( Status sCSetFlattened )
					( Origin gBackEnd )
				)
				( attribute "RELATIVE_PROPAGATION_DELAY" ",5.00 MIL"
					( Parent
						( matchGroupRef "@baseboard_fab2_lib.baseboard_fab2(sch_1):\MG_DQ-DQS_NEAR_DIMM_NG_M_J_BYTE7\" )
					)
					( Units "uMatchProp" "ns" 1.000000)
					( Status sCSetFlattened )
					( Origin gBackEnd )
				)
			)
			( pinPair "@baseboard_fab2_lib.baseboard_fab2(sch_1):\PP1588\"
				( pinRef "@baseboard_fab2_lib.baseboard_fab2(sch_1):page59_i172:DDR2_DQS_DP(7)" )
				( pinRef "@baseboard_fab2_lib.baseboard_fab2(sch_1):page81_i67:DQS7P" )
				( attribute "RELATIVE_PROPAGATION_DELAY_SCOPE" "G"
					( Parent
						( matchGroupRef "@baseboard_fab2_lib.baseboard_fab2(sch_1):\MG_DQ-DQS_FAR_DIMM_NG_M_J_BYTE7\" )
					)
					( Status sCSetFlattened )
					( Origin gBackEnd )
				)
				( attribute "RELATIVE_PROPAGATION_DELAY" ",5.00 MIL"
					( Parent
						( matchGroupRef "@baseboard_fab2_lib.baseboard_fab2(sch_1):\MG_DQ-DQS_FAR_DIMM_NG_M_J_BYTE7\" )
					)
					( Units "uMatchProp" "ns" 1.000000)
					( Status sCSetFlattened )
					( Origin gBackEnd )
				)
			)
			( pinPair "@baseboard_fab2_lib.baseboard_fab2(sch_1):\PP1590\"
				( pinRef "@baseboard_fab2_lib.baseboard_fab2(sch_1):page82_i64:DQS7P" )
				( pinRef "@baseboard_fab2_lib.baseboard_fab2(sch_1):page59_i172:DDR2_DQS_DP(7)" )
				( attribute "RELATIVE_PROPAGATION_DELAY_SCOPE" "G"
					( Parent
						( matchGroupRef "@baseboard_fab2_lib.baseboard_fab2(sch_1):\MG_DQ-DQS_NEAR_DIMM_NG_M_J_BYTE7\" )
					)
					( Status sCSetFlattened )
					( Origin gBackEnd )
				)
				( attribute "RELATIVE_PROPAGATION_DELAY" ",5.00 MIL"
					( Parent
						( matchGroupRef "@baseboard_fab2_lib.baseboard_fab2(sch_1):\MG_DQ-DQS_NEAR_DIMM_NG_M_J_BYTE7\" )
					)
					( Units "uMatchProp" "ns" 1.000000)
					( Status sCSetFlattened )
					( Origin gBackEnd )
				)
			)
			( pinPair "@baseboard_fab2_lib.baseboard_fab2(sch_1):\PP1249\"
				( pinRef "@baseboard_fab2_lib.baseboard_fab2(sch_1):page59_i172:DDR2_DQS_DN(8)" )
				( pinRef "@baseboard_fab2_lib.baseboard_fab2(sch_1):page81_i67:DQS8N" )
				( attribute "RELATIVE_PROPAGATION_DELAY_SCOPE" "G"
					( Parent
						( matchGroupRef "@baseboard_fab2_lib.baseboard_fab2(sch_1):\MG_DQ-DQS_FAR_DIMM_NG_M_J_BYTE-ECC\" )
					)
					( Status sCSetFlattened )
					( Origin gBackEnd )
				)
				( attribute "RELATIVE_PROPAGATION_DELAY" ",5.00 MIL"
					( Parent
						( matchGroupRef "@baseboard_fab2_lib.baseboard_fab2(sch_1):\MG_DQ-DQS_FAR_DIMM_NG_M_J_BYTE-ECC\" )
					)
					( Units "uMatchProp" "ns" 1.000000)
					( Status sCSetFlattened )
					( Origin gBackEnd )
				)
			)
			( pinPair "@baseboard_fab2_lib.baseboard_fab2(sch_1):\PP1250\"
				( pinRef "@baseboard_fab2_lib.baseboard_fab2(sch_1):page82_i64:DQS8N" )
				( pinRef "@baseboard_fab2_lib.baseboard_fab2(sch_1):page59_i172:DDR2_DQS_DN(8)" )
				( attribute "RELATIVE_PROPAGATION_DELAY_SCOPE" "G"
					( Parent
						( matchGroupRef "@baseboard_fab2_lib.baseboard_fab2(sch_1):\MG_DQ-DQS_NEAR_DIMM_NG_M_J_BYTE-ECC\" )
					)
					( Status sCSetFlattened )
					( Origin gBackEnd )
				)
				( attribute "RELATIVE_PROPAGATION_DELAY" ",5.00 MIL"
					( Parent
						( matchGroupRef "@baseboard_fab2_lib.baseboard_fab2(sch_1):\MG_DQ-DQS_NEAR_DIMM_NG_M_J_BYTE-ECC\" )
					)
					( Units "uMatchProp" "ns" 1.000000)
					( Status sCSetFlattened )
					( Origin gBackEnd )
				)
			)
			( pinPair "@baseboard_fab2_lib.baseboard_fab2(sch_1):\PP1252\"
				( pinRef "@baseboard_fab2_lib.baseboard_fab2(sch_1):page59_i172:DDR2_DQS_DP(8)" )
				( pinRef "@baseboard_fab2_lib.baseboard_fab2(sch_1):page81_i67:DQS8P" )
				( attribute "RELATIVE_PROPAGATION_DELAY_SCOPE" "G"
					( Parent
						( matchGroupRef "@baseboard_fab2_lib.baseboard_fab2(sch_1):\MG_DQ-DQS_FAR_DIMM_NG_M_J_BYTE-ECC\" )
					)
					( Status sCSetFlattened )
					( Origin gBackEnd )
				)
				( attribute "RELATIVE_PROPAGATION_DELAY" ",5.00 MIL"
					( Parent
						( matchGroupRef "@baseboard_fab2_lib.baseboard_fab2(sch_1):\MG_DQ-DQS_FAR_DIMM_NG_M_J_BYTE-ECC\" )
					)
					( Units "uMatchProp" "ns" 1.000000)
					( Status sCSetFlattened )
					( Origin gBackEnd )
				)
			)
			( pinPair "@baseboard_fab2_lib.baseboard_fab2(sch_1):\PP1253\"
				( pinRef "@baseboard_fab2_lib.baseboard_fab2(sch_1):page82_i64:DQS8P" )
				( pinRef "@baseboard_fab2_lib.baseboard_fab2(sch_1):page59_i172:DDR2_DQS_DP(8)" )
				( attribute "RELATIVE_PROPAGATION_DELAY_SCOPE" "G"
					( Parent
						( matchGroupRef "@baseboard_fab2_lib.baseboard_fab2(sch_1):\MG_DQ-DQS_NEAR_DIMM_NG_M_J_BYTE-ECC\" )
					)
					( Status sCSetFlattened )
					( Origin gBackEnd )
				)
				( attribute "RELATIVE_PROPAGATION_DELAY" ",5.00 MIL"
					( Parent
						( matchGroupRef "@baseboard_fab2_lib.baseboard_fab2(sch_1):\MG_DQ-DQS_NEAR_DIMM_NG_M_J_BYTE-ECC\" )
					)
					( Units "uMatchProp" "ns" 1.000000)
					( Status sCSetFlattened )
					( Origin gBackEnd )
				)
			)
			( pinPair "@baseboard_fab2_lib.baseboard_fab2(sch_1):\PP1663\"
				( pinRef "@baseboard_fab2_lib.baseboard_fab2(sch_1):page59_i172:DDR2_DQS_DN(9)" )
				( pinRef "@baseboard_fab2_lib.baseboard_fab2(sch_1):page81_i67:DQS9N" )
				( attribute "RELATIVE_PROPAGATION_DELAY_SCOPE" "G"
					( Parent
						( matchGroupRef "@baseboard_fab2_lib.baseboard_fab2(sch_1):\MG_DQ-DQS_FAR_DIMM_NG_M_J_BYTE0\" )
					)
					( Status sCSetFlattened )
					( Origin gBackEnd )
				)
				( attribute "RELATIVE_PROPAGATION_DELAY" ",5.00 MIL"
					( Parent
						( matchGroupRef "@baseboard_fab2_lib.baseboard_fab2(sch_1):\MG_DQ-DQS_FAR_DIMM_NG_M_J_BYTE0\" )
					)
					( Units "uMatchProp" "ns" 1.000000)
					( Status sCSetFlattened )
					( Origin gBackEnd )
				)
			)
			( pinPair "@baseboard_fab2_lib.baseboard_fab2(sch_1):\PP1664\"
				( pinRef "@baseboard_fab2_lib.baseboard_fab2(sch_1):page82_i64:DQS9N" )
				( pinRef "@baseboard_fab2_lib.baseboard_fab2(sch_1):page59_i172:DDR2_DQS_DN(9)" )
				( attribute "RELATIVE_PROPAGATION_DELAY_SCOPE" "G"
					( Parent
						( matchGroupRef "@baseboard_fab2_lib.baseboard_fab2(sch_1):\MG_DQ-DQS_NEAR_DIMM_NG_M_J_BYTE0\" )
					)
					( Status sCSetFlattened )
					( Origin gBackEnd )
				)
				( attribute "RELATIVE_PROPAGATION_DELAY" ",5.00 MIL"
					( Parent
						( matchGroupRef "@baseboard_fab2_lib.baseboard_fab2(sch_1):\MG_DQ-DQS_NEAR_DIMM_NG_M_J_BYTE0\" )
					)
					( Units "uMatchProp" "ns" 1.000000)
					( Status sCSetFlattened )
					( Origin gBackEnd )
				)
			)
			( pinPair "@baseboard_fab2_lib.baseboard_fab2(sch_1):\PP1666\"
				( pinRef "@baseboard_fab2_lib.baseboard_fab2(sch_1):page59_i172:DDR2_DQS_DP(9)" )
				( pinRef "@baseboard_fab2_lib.baseboard_fab2(sch_1):page81_i67:DQS9P" )
				( attribute "RELATIVE_PROPAGATION_DELAY_SCOPE" "G"
					( Parent
						( matchGroupRef "@baseboard_fab2_lib.baseboard_fab2(sch_1):\MG_DQ-DQS_FAR_DIMM_NG_M_J_BYTE0\" )
					)
					( Status sCSetFlattened )
					( Origin gBackEnd )
				)
				( attribute "RELATIVE_PROPAGATION_DELAY" ",5.00 MIL"
					( Parent
						( matchGroupRef "@baseboard_fab2_lib.baseboard_fab2(sch_1):\MG_DQ-DQS_FAR_DIMM_NG_M_J_BYTE0\" )
					)
					( Units "uMatchProp" "ns" 1.000000)
					( Status sCSetFlattened )
					( Origin gBackEnd )
				)
			)
			( pinPair "@baseboard_fab2_lib.baseboard_fab2(sch_1):\PP1667\"
				( pinRef "@baseboard_fab2_lib.baseboard_fab2(sch_1):page82_i64:DQS9P" )
				( pinRef "@baseboard_fab2_lib.baseboard_fab2(sch_1):page59_i172:DDR2_DQS_DP(9)" )
				( attribute "RELATIVE_PROPAGATION_DELAY_SCOPE" "G"
					( Parent
						( matchGroupRef "@baseboard_fab2_lib.baseboard_fab2(sch_1):\MG_DQ-DQS_NEAR_DIMM_NG_M_J_BYTE0\" )
					)
					( Status sCSetFlattened )
					( Origin gBackEnd )
				)
				( attribute "RELATIVE_PROPAGATION_DELAY" ",5.00 MIL"
					( Parent
						( matchGroupRef "@baseboard_fab2_lib.baseboard_fab2(sch_1):\MG_DQ-DQS_NEAR_DIMM_NG_M_J_BYTE0\" )
					)
					( Units "uMatchProp" "ns" 1.000000)
					( Status sCSetFlattened )
					( Origin gBackEnd )
				)
			)
			( pinPair "@baseboard_fab2_lib.baseboard_fab2(sch_1):\PP1651\"
				( pinRef "@baseboard_fab2_lib.baseboard_fab2(sch_1):page59_i172:DDR2_DQS_DN(10)" )
				( pinRef "@baseboard_fab2_lib.baseboard_fab2(sch_1):page81_i67:DQS10N" )
				( attribute "RELATIVE_PROPAGATION_DELAY_SCOPE" "G"
					( Parent
						( matchGroupRef "@baseboard_fab2_lib.baseboard_fab2(sch_1):\MG_DQ-DQS_FAR_DIMM_NG_M_J_BYTE1\" )
					)
					( Status sCSetFlattened )
					( Origin gBackEnd )
				)
				( attribute "RELATIVE_PROPAGATION_DELAY" ",5.00 MIL"
					( Parent
						( matchGroupRef "@baseboard_fab2_lib.baseboard_fab2(sch_1):\MG_DQ-DQS_FAR_DIMM_NG_M_J_BYTE1\" )
					)
					( Units "uMatchProp" "ns" 1.000000)
					( Status sCSetFlattened )
					( Origin gBackEnd )
				)
			)
			( pinPair "@baseboard_fab2_lib.baseboard_fab2(sch_1):\PP1652\"
				( pinRef "@baseboard_fab2_lib.baseboard_fab2(sch_1):page82_i64:DQS10N" )
				( pinRef "@baseboard_fab2_lib.baseboard_fab2(sch_1):page59_i172:DDR2_DQS_DN(10)" )
				( attribute "RELATIVE_PROPAGATION_DELAY_SCOPE" "G"
					( Parent
						( matchGroupRef "@baseboard_fab2_lib.baseboard_fab2(sch_1):\MG_DQ-DQS_NEAR_DIMM_NG_M_J_BYTE1\" )
					)
					( Status sCSetFlattened )
					( Origin gBackEnd )
				)
				( attribute "RELATIVE_PROPAGATION_DELAY" ",5.00 MIL"
					( Parent
						( matchGroupRef "@baseboard_fab2_lib.baseboard_fab2(sch_1):\MG_DQ-DQS_NEAR_DIMM_NG_M_J_BYTE1\" )
					)
					( Units "uMatchProp" "ns" 1.000000)
					( Status sCSetFlattened )
					( Origin gBackEnd )
				)
			)
			( pinPair "@baseboard_fab2_lib.baseboard_fab2(sch_1):\PP1654\"
				( pinRef "@baseboard_fab2_lib.baseboard_fab2(sch_1):page59_i172:DDR2_DQS_DP(10)" )
				( pinRef "@baseboard_fab2_lib.baseboard_fab2(sch_1):page81_i67:DQS10P" )
				( attribute "RELATIVE_PROPAGATION_DELAY_SCOPE" "G"
					( Parent
						( matchGroupRef "@baseboard_fab2_lib.baseboard_fab2(sch_1):\MG_DQ-DQS_FAR_DIMM_NG_M_J_BYTE1\" )
					)
					( Status sCSetFlattened )
					( Origin gBackEnd )
				)
				( attribute "RELATIVE_PROPAGATION_DELAY" ",5.00 MIL"
					( Parent
						( matchGroupRef "@baseboard_fab2_lib.baseboard_fab2(sch_1):\MG_DQ-DQS_FAR_DIMM_NG_M_J_BYTE1\" )
					)
					( Units "uMatchProp" "ns" 1.000000)
					( Status sCSetFlattened )
					( Origin gBackEnd )
				)
			)
			( pinPair "@baseboard_fab2_lib.baseboard_fab2(sch_1):\PP1655\"
				( pinRef "@baseboard_fab2_lib.baseboard_fab2(sch_1):page82_i64:DQS10P" )
				( pinRef "@baseboard_fab2_lib.baseboard_fab2(sch_1):page59_i172:DDR2_DQS_DP(10)" )
				( attribute "RELATIVE_PROPAGATION_DELAY_SCOPE" "G"
					( Parent
						( matchGroupRef "@baseboard_fab2_lib.baseboard_fab2(sch_1):\MG_DQ-DQS_NEAR_DIMM_NG_M_J_BYTE1\" )
					)
					( Status sCSetFlattened )
					( Origin gBackEnd )
				)
				( attribute "RELATIVE_PROPAGATION_DELAY" ",5.00 MIL"
					( Parent
						( matchGroupRef "@baseboard_fab2_lib.baseboard_fab2(sch_1):\MG_DQ-DQS_NEAR_DIMM_NG_M_J_BYTE1\" )
					)
					( Units "uMatchProp" "ns" 1.000000)
					( Status sCSetFlattened )
					( Origin gBackEnd )
				)
			)
			( pinPair "@baseboard_fab2_lib.baseboard_fab2(sch_1):\PP1639\"
				( pinRef "@baseboard_fab2_lib.baseboard_fab2(sch_1):page59_i172:DDR2_DQS_DN(11)" )
				( pinRef "@baseboard_fab2_lib.baseboard_fab2(sch_1):page81_i67:DQS11N" )
				( attribute "RELATIVE_PROPAGATION_DELAY_SCOPE" "G"
					( Parent
						( matchGroupRef "@baseboard_fab2_lib.baseboard_fab2(sch_1):\MG_DQ-DQS_FAR_DIMM_NG_M_J_BYTE2\" )
					)
					( Status sCSetFlattened )
					( Origin gBackEnd )
				)
				( attribute "RELATIVE_PROPAGATION_DELAY" ",5.00 MIL"
					( Parent
						( matchGroupRef "@baseboard_fab2_lib.baseboard_fab2(sch_1):\MG_DQ-DQS_FAR_DIMM_NG_M_J_BYTE2\" )
					)
					( Units "uMatchProp" "ns" 1.000000)
					( Status sCSetFlattened )
					( Origin gBackEnd )
				)
			)
			( pinPair "@baseboard_fab2_lib.baseboard_fab2(sch_1):\PP1640\"
				( pinRef "@baseboard_fab2_lib.baseboard_fab2(sch_1):page82_i64:DQS11N" )
				( pinRef "@baseboard_fab2_lib.baseboard_fab2(sch_1):page59_i172:DDR2_DQS_DN(11)" )
				( attribute "RELATIVE_PROPAGATION_DELAY_SCOPE" "G"
					( Parent
						( matchGroupRef "@baseboard_fab2_lib.baseboard_fab2(sch_1):\MG_DQ-DQS_NEAR_DIMM_NG_M_J_BYTE2\" )
					)
					( Status sCSetFlattened )
					( Origin gBackEnd )
				)
				( attribute "RELATIVE_PROPAGATION_DELAY" ",5.00 MIL"
					( Parent
						( matchGroupRef "@baseboard_fab2_lib.baseboard_fab2(sch_1):\MG_DQ-DQS_NEAR_DIMM_NG_M_J_BYTE2\" )
					)
					( Units "uMatchProp" "ns" 1.000000)
					( Status sCSetFlattened )
					( Origin gBackEnd )
				)
			)
			( pinPair "@baseboard_fab2_lib.baseboard_fab2(sch_1):\PP1642\"
				( pinRef "@baseboard_fab2_lib.baseboard_fab2(sch_1):page59_i172:DDR2_DQS_DP(11)" )
				( pinRef "@baseboard_fab2_lib.baseboard_fab2(sch_1):page81_i67:DQS11P" )
				( attribute "RELATIVE_PROPAGATION_DELAY_SCOPE" "G"
					( Parent
						( matchGroupRef "@baseboard_fab2_lib.baseboard_fab2(sch_1):\MG_DQ-DQS_FAR_DIMM_NG_M_J_BYTE2\" )
					)
					( Status sCSetFlattened )
					( Origin gBackEnd )
				)
				( attribute "RELATIVE_PROPAGATION_DELAY" ",5.00 MIL"
					( Parent
						( matchGroupRef "@baseboard_fab2_lib.baseboard_fab2(sch_1):\MG_DQ-DQS_FAR_DIMM_NG_M_J_BYTE2\" )
					)
					( Units "uMatchProp" "ns" 1.000000)
					( Status sCSetFlattened )
					( Origin gBackEnd )
				)
			)
			( pinPair "@baseboard_fab2_lib.baseboard_fab2(sch_1):\PP1643\"
				( pinRef "@baseboard_fab2_lib.baseboard_fab2(sch_1):page82_i64:DQS11P" )
				( pinRef "@baseboard_fab2_lib.baseboard_fab2(sch_1):page59_i172:DDR2_DQS_DP(11)" )
				( attribute "RELATIVE_PROPAGATION_DELAY_SCOPE" "G"
					( Parent
						( matchGroupRef "@baseboard_fab2_lib.baseboard_fab2(sch_1):\MG_DQ-DQS_NEAR_DIMM_NG_M_J_BYTE2\" )
					)
					( Status sCSetFlattened )
					( Origin gBackEnd )
				)
				( attribute "RELATIVE_PROPAGATION_DELAY" ",5.00 MIL"
					( Parent
						( matchGroupRef "@baseboard_fab2_lib.baseboard_fab2(sch_1):\MG_DQ-DQS_NEAR_DIMM_NG_M_J_BYTE2\" )
					)
					( Units "uMatchProp" "ns" 1.000000)
					( Status sCSetFlattened )
					( Origin gBackEnd )
				)
			)
			( pinPair "@baseboard_fab2_lib.baseboard_fab2(sch_1):\PP1627\"
				( pinRef "@baseboard_fab2_lib.baseboard_fab2(sch_1):page59_i172:DDR2_DQS_DN(12)" )
				( pinRef "@baseboard_fab2_lib.baseboard_fab2(sch_1):page81_i67:DQS12N" )
				( attribute "RELATIVE_PROPAGATION_DELAY_SCOPE" "G"
					( Parent
						( matchGroupRef "@baseboard_fab2_lib.baseboard_fab2(sch_1):\MG_DQ-DQS_FAR_DIMM_NG_M_J_BYTE3\" )
					)
					( Status sCSetFlattened )
					( Origin gBackEnd )
				)
				( attribute "RELATIVE_PROPAGATION_DELAY" ",5.00 MIL"
					( Parent
						( matchGroupRef "@baseboard_fab2_lib.baseboard_fab2(sch_1):\MG_DQ-DQS_FAR_DIMM_NG_M_J_BYTE3\" )
					)
					( Units "uMatchProp" "ns" 1.000000)
					( Status sCSetFlattened )
					( Origin gBackEnd )
				)
			)
			( pinPair "@baseboard_fab2_lib.baseboard_fab2(sch_1):\PP1628\"
				( pinRef "@baseboard_fab2_lib.baseboard_fab2(sch_1):page82_i64:DQS12N" )
				( pinRef "@baseboard_fab2_lib.baseboard_fab2(sch_1):page59_i172:DDR2_DQS_DN(12)" )
				( attribute "RELATIVE_PROPAGATION_DELAY_SCOPE" "G"
					( Parent
						( matchGroupRef "@baseboard_fab2_lib.baseboard_fab2(sch_1):\MG_DQ-DQS_NEAR_DIMM_NG_M_J_BYTE3\" )
					)
					( Status sCSetFlattened )
					( Origin gBackEnd )
				)
				( attribute "RELATIVE_PROPAGATION_DELAY" ",5.00 MIL"
					( Parent
						( matchGroupRef "@baseboard_fab2_lib.baseboard_fab2(sch_1):\MG_DQ-DQS_NEAR_DIMM_NG_M_J_BYTE3\" )
					)
					( Units "uMatchProp" "ns" 1.000000)
					( Status sCSetFlattened )
					( Origin gBackEnd )
				)
			)
			( pinPair "@baseboard_fab2_lib.baseboard_fab2(sch_1):\PP1630\"
				( pinRef "@baseboard_fab2_lib.baseboard_fab2(sch_1):page59_i172:DDR2_DQS_DP(12)" )
				( pinRef "@baseboard_fab2_lib.baseboard_fab2(sch_1):page81_i67:DQS12P" )
				( attribute "RELATIVE_PROPAGATION_DELAY_SCOPE" "G"
					( Parent
						( matchGroupRef "@baseboard_fab2_lib.baseboard_fab2(sch_1):\MG_DQ-DQS_FAR_DIMM_NG_M_J_BYTE3\" )
					)
					( Status sCSetFlattened )
					( Origin gBackEnd )
				)
				( attribute "RELATIVE_PROPAGATION_DELAY" ",5.00 MIL"
					( Parent
						( matchGroupRef "@baseboard_fab2_lib.baseboard_fab2(sch_1):\MG_DQ-DQS_FAR_DIMM_NG_M_J_BYTE3\" )
					)
					( Units "uMatchProp" "ns" 1.000000)
					( Status sCSetFlattened )
					( Origin gBackEnd )
				)
			)
			( pinPair "@baseboard_fab2_lib.baseboard_fab2(sch_1):\PP1631\"
				( pinRef "@baseboard_fab2_lib.baseboard_fab2(sch_1):page82_i64:DQS12P" )
				( pinRef "@baseboard_fab2_lib.baseboard_fab2(sch_1):page59_i172:DDR2_DQS_DP(12)" )
				( attribute "RELATIVE_PROPAGATION_DELAY_SCOPE" "G"
					( Parent
						( matchGroupRef "@baseboard_fab2_lib.baseboard_fab2(sch_1):\MG_DQ-DQS_NEAR_DIMM_NG_M_J_BYTE3\" )
					)
					( Status sCSetFlattened )
					( Origin gBackEnd )
				)
				( attribute "RELATIVE_PROPAGATION_DELAY" ",5.00 MIL"
					( Parent
						( matchGroupRef "@baseboard_fab2_lib.baseboard_fab2(sch_1):\MG_DQ-DQS_NEAR_DIMM_NG_M_J_BYTE3\" )
					)
					( Units "uMatchProp" "ns" 1.000000)
					( Status sCSetFlattened )
					( Origin gBackEnd )
				)
			)
			( pinPair "@baseboard_fab2_lib.baseboard_fab2(sch_1):\PP1615\"
				( pinRef "@baseboard_fab2_lib.baseboard_fab2(sch_1):page59_i172:DDR2_DQS_DN(13)" )
				( pinRef "@baseboard_fab2_lib.baseboard_fab2(sch_1):page81_i67:DQS13N" )
				( attribute "RELATIVE_PROPAGATION_DELAY_SCOPE" "G"
					( Parent
						( matchGroupRef "@baseboard_fab2_lib.baseboard_fab2(sch_1):\MG_DQ-DQS_FAR_DIMM_NG_M_J_BYTE4\" )
					)
					( Status sCSetFlattened )
					( Origin gBackEnd )
				)
				( attribute "RELATIVE_PROPAGATION_DELAY" ",5.00 MIL"
					( Parent
						( matchGroupRef "@baseboard_fab2_lib.baseboard_fab2(sch_1):\MG_DQ-DQS_FAR_DIMM_NG_M_J_BYTE4\" )
					)
					( Units "uMatchProp" "ns" 1.000000)
					( Status sCSetFlattened )
					( Origin gBackEnd )
				)
			)
			( pinPair "@baseboard_fab2_lib.baseboard_fab2(sch_1):\PP1617\"
				( pinRef "@baseboard_fab2_lib.baseboard_fab2(sch_1):page82_i64:DQS13N" )
				( pinRef "@baseboard_fab2_lib.baseboard_fab2(sch_1):page59_i172:DDR2_DQS_DN(13)" )
				( attribute "RELATIVE_PROPAGATION_DELAY_SCOPE" "G"
					( Parent
						( matchGroupRef "@baseboard_fab2_lib.baseboard_fab2(sch_1):\MG_DQ-DQS_NEAR_DIMM_NG_M_J_BYTE4\" )
					)
					( Status sCSetFlattened )
					( Origin gBackEnd )
				)
				( attribute "RELATIVE_PROPAGATION_DELAY" ",5.00 MIL"
					( Parent
						( matchGroupRef "@baseboard_fab2_lib.baseboard_fab2(sch_1):\MG_DQ-DQS_NEAR_DIMM_NG_M_J_BYTE4\" )
					)
					( Units "uMatchProp" "ns" 1.000000)
					( Status sCSetFlattened )
					( Origin gBackEnd )
				)
			)
			( pinPair "@baseboard_fab2_lib.baseboard_fab2(sch_1):\PP1618\"
				( pinRef "@baseboard_fab2_lib.baseboard_fab2(sch_1):page59_i172:DDR2_DQS_DP(13)" )
				( pinRef "@baseboard_fab2_lib.baseboard_fab2(sch_1):page81_i67:DQS13P" )
				( attribute "RELATIVE_PROPAGATION_DELAY_SCOPE" "G"
					( Parent
						( matchGroupRef "@baseboard_fab2_lib.baseboard_fab2(sch_1):\MG_DQ-DQS_FAR_DIMM_NG_M_J_BYTE4\" )
					)
					( Status sCSetFlattened )
					( Origin gBackEnd )
				)
				( attribute "RELATIVE_PROPAGATION_DELAY" ",5.00 MIL"
					( Parent
						( matchGroupRef "@baseboard_fab2_lib.baseboard_fab2(sch_1):\MG_DQ-DQS_FAR_DIMM_NG_M_J_BYTE4\" )
					)
					( Units "uMatchProp" "ns" 1.000000)
					( Status sCSetFlattened )
					( Origin gBackEnd )
				)
			)
			( pinPair "@baseboard_fab2_lib.baseboard_fab2(sch_1):\PP1620\"
				( pinRef "@baseboard_fab2_lib.baseboard_fab2(sch_1):page82_i64:DQS13P" )
				( pinRef "@baseboard_fab2_lib.baseboard_fab2(sch_1):page59_i172:DDR2_DQS_DP(13)" )
				( attribute "RELATIVE_PROPAGATION_DELAY_SCOPE" "G"
					( Parent
						( matchGroupRef "@baseboard_fab2_lib.baseboard_fab2(sch_1):\MG_DQ-DQS_NEAR_DIMM_NG_M_J_BYTE4\" )
					)
					( Status sCSetFlattened )
					( Origin gBackEnd )
				)
				( attribute "RELATIVE_PROPAGATION_DELAY" ",5.00 MIL"
					( Parent
						( matchGroupRef "@baseboard_fab2_lib.baseboard_fab2(sch_1):\MG_DQ-DQS_NEAR_DIMM_NG_M_J_BYTE4\" )
					)
					( Units "uMatchProp" "ns" 1.000000)
					( Status sCSetFlattened )
					( Origin gBackEnd )
				)
			)
			( pinPair "@baseboard_fab2_lib.baseboard_fab2(sch_1):\PP1603\"
				( pinRef "@baseboard_fab2_lib.baseboard_fab2(sch_1):page59_i172:DDR2_DQS_DN(14)" )
				( pinRef "@baseboard_fab2_lib.baseboard_fab2(sch_1):page81_i67:DQS14N" )
				( attribute "RELATIVE_PROPAGATION_DELAY_SCOPE" "G"
					( Parent
						( matchGroupRef "@baseboard_fab2_lib.baseboard_fab2(sch_1):\MG_DQ-DQS_FAR_DIMM_NG_M_J_BYTE5\" )
					)
					( Status sCSetFlattened )
					( Origin gBackEnd )
				)
				( attribute "RELATIVE_PROPAGATION_DELAY" ",5.00 MIL"
					( Parent
						( matchGroupRef "@baseboard_fab2_lib.baseboard_fab2(sch_1):\MG_DQ-DQS_FAR_DIMM_NG_M_J_BYTE5\" )
					)
					( Units "uMatchProp" "ns" 1.000000)
					( Status sCSetFlattened )
					( Origin gBackEnd )
				)
			)
			( pinPair "@baseboard_fab2_lib.baseboard_fab2(sch_1):\PP1605\"
				( pinRef "@baseboard_fab2_lib.baseboard_fab2(sch_1):page82_i64:DQS14N" )
				( pinRef "@baseboard_fab2_lib.baseboard_fab2(sch_1):page59_i172:DDR2_DQS_DN(14)" )
				( attribute "RELATIVE_PROPAGATION_DELAY_SCOPE" "G"
					( Parent
						( matchGroupRef "@baseboard_fab2_lib.baseboard_fab2(sch_1):\MG_DQ-DQS_NEAR_DIMM_NG_M_J_BYTE5\" )
					)
					( Status sCSetFlattened )
					( Origin gBackEnd )
				)
				( attribute "RELATIVE_PROPAGATION_DELAY" ",5.00 MIL"
					( Parent
						( matchGroupRef "@baseboard_fab2_lib.baseboard_fab2(sch_1):\MG_DQ-DQS_NEAR_DIMM_NG_M_J_BYTE5\" )
					)
					( Units "uMatchProp" "ns" 1.000000)
					( Status sCSetFlattened )
					( Origin gBackEnd )
				)
			)
			( pinPair "@baseboard_fab2_lib.baseboard_fab2(sch_1):\PP1606\"
				( pinRef "@baseboard_fab2_lib.baseboard_fab2(sch_1):page59_i172:DDR2_DQS_DP(14)" )
				( pinRef "@baseboard_fab2_lib.baseboard_fab2(sch_1):page81_i67:DQS14P" )
				( attribute "RELATIVE_PROPAGATION_DELAY_SCOPE" "G"
					( Parent
						( matchGroupRef "@baseboard_fab2_lib.baseboard_fab2(sch_1):\MG_DQ-DQS_FAR_DIMM_NG_M_J_BYTE5\" )
					)
					( Status sCSetFlattened )
					( Origin gBackEnd )
				)
				( attribute "RELATIVE_PROPAGATION_DELAY" ",5.00 MIL"
					( Parent
						( matchGroupRef "@baseboard_fab2_lib.baseboard_fab2(sch_1):\MG_DQ-DQS_FAR_DIMM_NG_M_J_BYTE5\" )
					)
					( Units "uMatchProp" "ns" 1.000000)
					( Status sCSetFlattened )
					( Origin gBackEnd )
				)
			)
			( pinPair "@baseboard_fab2_lib.baseboard_fab2(sch_1):\PP1608\"
				( pinRef "@baseboard_fab2_lib.baseboard_fab2(sch_1):page82_i64:DQS14P" )
				( pinRef "@baseboard_fab2_lib.baseboard_fab2(sch_1):page59_i172:DDR2_DQS_DP(14)" )
				( attribute "RELATIVE_PROPAGATION_DELAY_SCOPE" "G"
					( Parent
						( matchGroupRef "@baseboard_fab2_lib.baseboard_fab2(sch_1):\MG_DQ-DQS_NEAR_DIMM_NG_M_J_BYTE5\" )
					)
					( Status sCSetFlattened )
					( Origin gBackEnd )
				)
				( attribute "RELATIVE_PROPAGATION_DELAY" ",5.00 MIL"
					( Parent
						( matchGroupRef "@baseboard_fab2_lib.baseboard_fab2(sch_1):\MG_DQ-DQS_NEAR_DIMM_NG_M_J_BYTE5\" )
					)
					( Units "uMatchProp" "ns" 1.000000)
					( Status sCSetFlattened )
					( Origin gBackEnd )
				)
			)
			( pinPair "@baseboard_fab2_lib.baseboard_fab2(sch_1):\PP1591\"
				( pinRef "@baseboard_fab2_lib.baseboard_fab2(sch_1):page59_i172:DDR2_DQS_DN(15)" )
				( pinRef "@baseboard_fab2_lib.baseboard_fab2(sch_1):page81_i67:DQS15N" )
				( attribute "RELATIVE_PROPAGATION_DELAY_SCOPE" "G"
					( Parent
						( matchGroupRef "@baseboard_fab2_lib.baseboard_fab2(sch_1):\MG_DQ-DQS_FAR_DIMM_NG_M_J_BYTE6\" )
					)
					( Status sCSetFlattened )
					( Origin gBackEnd )
				)
				( attribute "RELATIVE_PROPAGATION_DELAY" ",5.00 MIL"
					( Parent
						( matchGroupRef "@baseboard_fab2_lib.baseboard_fab2(sch_1):\MG_DQ-DQS_FAR_DIMM_NG_M_J_BYTE6\" )
					)
					( Units "uMatchProp" "ns" 1.000000)
					( Status sCSetFlattened )
					( Origin gBackEnd )
				)
			)
			( pinPair "@baseboard_fab2_lib.baseboard_fab2(sch_1):\PP1593\"
				( pinRef "@baseboard_fab2_lib.baseboard_fab2(sch_1):page82_i64:DQS15N" )
				( pinRef "@baseboard_fab2_lib.baseboard_fab2(sch_1):page59_i172:DDR2_DQS_DN(15)" )
				( attribute "RELATIVE_PROPAGATION_DELAY_SCOPE" "G"
					( Parent
						( matchGroupRef "@baseboard_fab2_lib.baseboard_fab2(sch_1):\MG_DQ-DQS_NEAR_DIMM_NG_M_J_BYTE6\" )
					)
					( Status sCSetFlattened )
					( Origin gBackEnd )
				)
				( attribute "RELATIVE_PROPAGATION_DELAY" ",5.00 MIL"
					( Parent
						( matchGroupRef "@baseboard_fab2_lib.baseboard_fab2(sch_1):\MG_DQ-DQS_NEAR_DIMM_NG_M_J_BYTE6\" )
					)
					( Units "uMatchProp" "ns" 1.000000)
					( Status sCSetFlattened )
					( Origin gBackEnd )
				)
			)
			( pinPair "@baseboard_fab2_lib.baseboard_fab2(sch_1):\PP1594\"
				( pinRef "@baseboard_fab2_lib.baseboard_fab2(sch_1):page59_i172:DDR2_DQS_DP(15)" )
				( pinRef "@baseboard_fab2_lib.baseboard_fab2(sch_1):page81_i67:DQS15P" )
				( attribute "RELATIVE_PROPAGATION_DELAY_SCOPE" "G"
					( Parent
						( matchGroupRef "@baseboard_fab2_lib.baseboard_fab2(sch_1):\MG_DQ-DQS_FAR_DIMM_NG_M_J_BYTE6\" )
					)
					( Status sCSetFlattened )
					( Origin gBackEnd )
				)
				( attribute "RELATIVE_PROPAGATION_DELAY" ",5.00 MIL"
					( Parent
						( matchGroupRef "@baseboard_fab2_lib.baseboard_fab2(sch_1):\MG_DQ-DQS_FAR_DIMM_NG_M_J_BYTE6\" )
					)
					( Units "uMatchProp" "ns" 1.000000)
					( Status sCSetFlattened )
					( Origin gBackEnd )
				)
			)
			( pinPair "@baseboard_fab2_lib.baseboard_fab2(sch_1):\PP1596\"
				( pinRef "@baseboard_fab2_lib.baseboard_fab2(sch_1):page82_i64:DQS15P" )
				( pinRef "@baseboard_fab2_lib.baseboard_fab2(sch_1):page59_i172:DDR2_DQS_DP(15)" )
				( attribute "RELATIVE_PROPAGATION_DELAY_SCOPE" "G"
					( Parent
						( matchGroupRef "@baseboard_fab2_lib.baseboard_fab2(sch_1):\MG_DQ-DQS_NEAR_DIMM_NG_M_J_BYTE6\" )
					)
					( Status sCSetFlattened )
					( Origin gBackEnd )
				)
				( attribute "RELATIVE_PROPAGATION_DELAY" ",5.00 MIL"
					( Parent
						( matchGroupRef "@baseboard_fab2_lib.baseboard_fab2(sch_1):\MG_DQ-DQS_NEAR_DIMM_NG_M_J_BYTE6\" )
					)
					( Units "uMatchProp" "ns" 1.000000)
					( Status sCSetFlattened )
					( Origin gBackEnd )
				)
			)
			( pinPair "@baseboard_fab2_lib.baseboard_fab2(sch_1):\PP1579\"
				( pinRef "@baseboard_fab2_lib.baseboard_fab2(sch_1):page59_i172:DDR2_DQS_DN(16)" )
				( pinRef "@baseboard_fab2_lib.baseboard_fab2(sch_1):page81_i67:DQS16N" )
				( attribute "RELATIVE_PROPAGATION_DELAY_SCOPE" "G"
					( Parent
						( matchGroupRef "@baseboard_fab2_lib.baseboard_fab2(sch_1):\MG_DQ-DQS_FAR_DIMM_NG_M_J_BYTE7\" )
					)
					( Status sCSetFlattened )
					( Origin gBackEnd )
				)
				( attribute "RELATIVE_PROPAGATION_DELAY" ",5.00 MIL"
					( Parent
						( matchGroupRef "@baseboard_fab2_lib.baseboard_fab2(sch_1):\MG_DQ-DQS_FAR_DIMM_NG_M_J_BYTE7\" )
					)
					( Units "uMatchProp" "ns" 1.000000)
					( Status sCSetFlattened )
					( Origin gBackEnd )
				)
			)
			( pinPair "@baseboard_fab2_lib.baseboard_fab2(sch_1):\PP1581\"
				( pinRef "@baseboard_fab2_lib.baseboard_fab2(sch_1):page82_i64:DQS16N" )
				( pinRef "@baseboard_fab2_lib.baseboard_fab2(sch_1):page59_i172:DDR2_DQS_DN(16)" )
				( attribute "RELATIVE_PROPAGATION_DELAY_SCOPE" "G"
					( Parent
						( matchGroupRef "@baseboard_fab2_lib.baseboard_fab2(sch_1):\MG_DQ-DQS_NEAR_DIMM_NG_M_J_BYTE7\" )
					)
					( Status sCSetFlattened )
					( Origin gBackEnd )
				)
				( attribute "RELATIVE_PROPAGATION_DELAY" ",5.00 MIL"
					( Parent
						( matchGroupRef "@baseboard_fab2_lib.baseboard_fab2(sch_1):\MG_DQ-DQS_NEAR_DIMM_NG_M_J_BYTE7\" )
					)
					( Units "uMatchProp" "ns" 1.000000)
					( Status sCSetFlattened )
					( Origin gBackEnd )
				)
			)
			( pinPair "@baseboard_fab2_lib.baseboard_fab2(sch_1):\PP1582\"
				( pinRef "@baseboard_fab2_lib.baseboard_fab2(sch_1):page59_i172:DDR2_DQS_DP(16)" )
				( pinRef "@baseboard_fab2_lib.baseboard_fab2(sch_1):page81_i67:DQS16P" )
				( attribute "RELATIVE_PROPAGATION_DELAY_SCOPE" "G"
					( Parent
						( matchGroupRef "@baseboard_fab2_lib.baseboard_fab2(sch_1):\MG_DQ-DQS_FAR_DIMM_NG_M_J_BYTE7\" )
					)
					( Status sCSetFlattened )
					( Origin gBackEnd )
				)
				( attribute "RELATIVE_PROPAGATION_DELAY" ",5.00 MIL"
					( Parent
						( matchGroupRef "@baseboard_fab2_lib.baseboard_fab2(sch_1):\MG_DQ-DQS_FAR_DIMM_NG_M_J_BYTE7\" )
					)
					( Units "uMatchProp" "ns" 1.000000)
					( Status sCSetFlattened )
					( Origin gBackEnd )
				)
			)
			( pinPair "@baseboard_fab2_lib.baseboard_fab2(sch_1):\PP1584\"
				( pinRef "@baseboard_fab2_lib.baseboard_fab2(sch_1):page82_i64:DQS16P" )
				( pinRef "@baseboard_fab2_lib.baseboard_fab2(sch_1):page59_i172:DDR2_DQS_DP(16)" )
				( attribute "RELATIVE_PROPAGATION_DELAY_SCOPE" "G"
					( Parent
						( matchGroupRef "@baseboard_fab2_lib.baseboard_fab2(sch_1):\MG_DQ-DQS_NEAR_DIMM_NG_M_J_BYTE7\" )
					)
					( Status sCSetFlattened )
					( Origin gBackEnd )
				)
				( attribute "RELATIVE_PROPAGATION_DELAY" ",5.00 MIL"
					( Parent
						( matchGroupRef "@baseboard_fab2_lib.baseboard_fab2(sch_1):\MG_DQ-DQS_NEAR_DIMM_NG_M_J_BYTE7\" )
					)
					( Units "uMatchProp" "ns" 1.000000)
					( Status sCSetFlattened )
					( Origin gBackEnd )
				)
			)
			( pinPair "@baseboard_fab2_lib.baseboard_fab2(sch_1):\PP1243\"
				( pinRef "@baseboard_fab2_lib.baseboard_fab2(sch_1):page59_i172:DDR2_DQS_DN(17)" )
				( pinRef "@baseboard_fab2_lib.baseboard_fab2(sch_1):page81_i67:DQS17N" )
				( attribute "RELATIVE_PROPAGATION_DELAY_SCOPE" "G"
					( Parent
						( matchGroupRef "@baseboard_fab2_lib.baseboard_fab2(sch_1):\MG_DQ-DQS_FAR_DIMM_NG_M_J_BYTE-ECC\" )
					)
					( Status sCSetFlattened )
					( Origin gBackEnd )
				)
				( attribute "RELATIVE_PROPAGATION_DELAY" ",5.00 MIL"
					( Parent
						( matchGroupRef "@baseboard_fab2_lib.baseboard_fab2(sch_1):\MG_DQ-DQS_FAR_DIMM_NG_M_J_BYTE-ECC\" )
					)
					( Units "uMatchProp" "ns" 1.000000)
					( Status sCSetFlattened )
					( Origin gBackEnd )
				)
			)
			( pinPair "@baseboard_fab2_lib.baseboard_fab2(sch_1):\PP1244\"
				( pinRef "@baseboard_fab2_lib.baseboard_fab2(sch_1):page82_i64:DQS17N" )
				( pinRef "@baseboard_fab2_lib.baseboard_fab2(sch_1):page59_i172:DDR2_DQS_DN(17)" )
				( attribute "RELATIVE_PROPAGATION_DELAY_SCOPE" "G"
					( Parent
						( matchGroupRef "@baseboard_fab2_lib.baseboard_fab2(sch_1):\MG_DQ-DQS_NEAR_DIMM_NG_M_J_BYTE-ECC\" )
					)
					( Status sCSetFlattened )
					( Origin gBackEnd )
				)
				( attribute "RELATIVE_PROPAGATION_DELAY" ",5.00 MIL"
					( Parent
						( matchGroupRef "@baseboard_fab2_lib.baseboard_fab2(sch_1):\MG_DQ-DQS_NEAR_DIMM_NG_M_J_BYTE-ECC\" )
					)
					( Units "uMatchProp" "ns" 1.000000)
					( Status sCSetFlattened )
					( Origin gBackEnd )
				)
			)
			( pinPair "@baseboard_fab2_lib.baseboard_fab2(sch_1):\PP1246\"
				( pinRef "@baseboard_fab2_lib.baseboard_fab2(sch_1):page59_i172:DDR2_DQS_DP(17)" )
				( pinRef "@baseboard_fab2_lib.baseboard_fab2(sch_1):page81_i67:DQS17P" )
				( attribute "RELATIVE_PROPAGATION_DELAY_SCOPE" "G"
					( Parent
						( matchGroupRef "@baseboard_fab2_lib.baseboard_fab2(sch_1):\MG_DQ-DQS_FAR_DIMM_NG_M_J_BYTE-ECC\" )
					)
					( Status sCSetFlattened )
					( Origin gBackEnd )
				)
				( attribute "RELATIVE_PROPAGATION_DELAY" ",5.00 MIL"
					( Parent
						( matchGroupRef "@baseboard_fab2_lib.baseboard_fab2(sch_1):\MG_DQ-DQS_FAR_DIMM_NG_M_J_BYTE-ECC\" )
					)
					( Units "uMatchProp" "ns" 1.000000)
					( Status sCSetFlattened )
					( Origin gBackEnd )
				)
			)
			( pinPair "@baseboard_fab2_lib.baseboard_fab2(sch_1):\PP1247\"
				( pinRef "@baseboard_fab2_lib.baseboard_fab2(sch_1):page82_i64:DQS17P" )
				( pinRef "@baseboard_fab2_lib.baseboard_fab2(sch_1):page59_i172:DDR2_DQS_DP(17)" )
				( attribute "RELATIVE_PROPAGATION_DELAY_SCOPE" "G"
					( Parent
						( matchGroupRef "@baseboard_fab2_lib.baseboard_fab2(sch_1):\MG_DQ-DQS_NEAR_DIMM_NG_M_J_BYTE-ECC\" )
					)
					( Status sCSetFlattened )
					( Origin gBackEnd )
				)
				( attribute "RELATIVE_PROPAGATION_DELAY" ",5.00 MIL"
					( Parent
						( matchGroupRef "@baseboard_fab2_lib.baseboard_fab2(sch_1):\MG_DQ-DQS_NEAR_DIMM_NG_M_J_BYTE-ECC\" )
					)
					( Units "uMatchProp" "ns" 1.000000)
					( Status sCSetFlattened )
					( Origin gBackEnd )
				)
			)
			( pinPair "@baseboard_fab2_lib.baseboard_fab2(sch_1):\PP1573\"
				( pinRef "@baseboard_fab2_lib.baseboard_fab2(sch_1):page60_i172:DDR3_DQS_DN(0)" )
				( pinRef "@baseboard_fab2_lib.baseboard_fab2(sch_1):page83_i66:DQS0N" )
				( attribute "RELATIVE_PROPAGATION_DELAY_SCOPE" "G"
					( Parent
						( matchGroupRef "@baseboard_fab2_lib.baseboard_fab2(sch_1):\MG_DQ-DQS_FAR_DIMM_NG_M_K_BYTE0\" )
					)
					( Status sCSetFlattened )
					( Origin gBackEnd )
				)
				( attribute "RELATIVE_PROPAGATION_DELAY" ",5.00 MIL"
					( Parent
						( matchGroupRef "@baseboard_fab2_lib.baseboard_fab2(sch_1):\MG_DQ-DQS_FAR_DIMM_NG_M_K_BYTE0\" )
					)
					( Units "uMatchProp" "ns" 1.000000)
					( Status sCSetFlattened )
					( Origin gBackEnd )
				)
			)
			( pinPair "@baseboard_fab2_lib.baseboard_fab2(sch_1):\PP1574\"
				( pinRef "@baseboard_fab2_lib.baseboard_fab2(sch_1):page84_i102:DQS0N" )
				( pinRef "@baseboard_fab2_lib.baseboard_fab2(sch_1):page60_i172:DDR3_DQS_DN(0)" )
				( attribute "RELATIVE_PROPAGATION_DELAY_SCOPE" "G"
					( Parent
						( matchGroupRef "@baseboard_fab2_lib.baseboard_fab2(sch_1):\MG_DQ-DQS_NEAR_DIMM_NG_M_K_BYTE0\" )
					)
					( Status sCSetFlattened )
					( Origin gBackEnd )
				)
				( attribute "RELATIVE_PROPAGATION_DELAY" ",5.00 MIL"
					( Parent
						( matchGroupRef "@baseboard_fab2_lib.baseboard_fab2(sch_1):\MG_DQ-DQS_NEAR_DIMM_NG_M_K_BYTE0\" )
					)
					( Units "uMatchProp" "ns" 1.000000)
					( Status sCSetFlattened )
					( Origin gBackEnd )
				)
			)
			( pinPair "@baseboard_fab2_lib.baseboard_fab2(sch_1):\PP1576\"
				( pinRef "@baseboard_fab2_lib.baseboard_fab2(sch_1):page60_i172:DDR3_DQS_DP(0)" )
				( pinRef "@baseboard_fab2_lib.baseboard_fab2(sch_1):page83_i66:DQS0P" )
				( attribute "RELATIVE_PROPAGATION_DELAY_SCOPE" "G"
					( Parent
						( matchGroupRef "@baseboard_fab2_lib.baseboard_fab2(sch_1):\MG_DQ-DQS_FAR_DIMM_NG_M_K_BYTE0\" )
					)
					( Status sCSetFlattened )
					( Origin gBackEnd )
				)
				( attribute "RELATIVE_PROPAGATION_DELAY" ",5.00 MIL"
					( Parent
						( matchGroupRef "@baseboard_fab2_lib.baseboard_fab2(sch_1):\MG_DQ-DQS_FAR_DIMM_NG_M_K_BYTE0\" )
					)
					( Units "uMatchProp" "ns" 1.000000)
					( Status sCSetFlattened )
					( Origin gBackEnd )
				)
			)
			( pinPair "@baseboard_fab2_lib.baseboard_fab2(sch_1):\PP1577\"
				( pinRef "@baseboard_fab2_lib.baseboard_fab2(sch_1):page84_i102:DQS0P" )
				( pinRef "@baseboard_fab2_lib.baseboard_fab2(sch_1):page60_i172:DDR3_DQS_DP(0)" )
				( attribute "RELATIVE_PROPAGATION_DELAY_SCOPE" "G"
					( Parent
						( matchGroupRef "@baseboard_fab2_lib.baseboard_fab2(sch_1):\MG_DQ-DQS_NEAR_DIMM_NG_M_K_BYTE0\" )
					)
					( Status sCSetFlattened )
					( Origin gBackEnd )
				)
				( attribute "RELATIVE_PROPAGATION_DELAY" ",5.00 MIL"
					( Parent
						( matchGroupRef "@baseboard_fab2_lib.baseboard_fab2(sch_1):\MG_DQ-DQS_NEAR_DIMM_NG_M_K_BYTE0\" )
					)
					( Units "uMatchProp" "ns" 1.000000)
					( Status sCSetFlattened )
					( Origin gBackEnd )
				)
			)
			( pinPair "@baseboard_fab2_lib.baseboard_fab2(sch_1):\PP1561\"
				( pinRef "@baseboard_fab2_lib.baseboard_fab2(sch_1):page60_i172:DDR3_DQS_DN(1)" )
				( pinRef "@baseboard_fab2_lib.baseboard_fab2(sch_1):page83_i66:DQS1N" )
				( attribute "RELATIVE_PROPAGATION_DELAY_SCOPE" "G"
					( Parent
						( matchGroupRef "@baseboard_fab2_lib.baseboard_fab2(sch_1):\MG_DQ-DQS_FAR_DIMM_NG_M_K_BYTE1\" )
					)
					( Status sCSetFlattened )
					( Origin gBackEnd )
				)
				( attribute "RELATIVE_PROPAGATION_DELAY" ",5.00 MIL"
					( Parent
						( matchGroupRef "@baseboard_fab2_lib.baseboard_fab2(sch_1):\MG_DQ-DQS_FAR_DIMM_NG_M_K_BYTE1\" )
					)
					( Units "uMatchProp" "ns" 1.000000)
					( Status sCSetFlattened )
					( Origin gBackEnd )
				)
			)
			( pinPair "@baseboard_fab2_lib.baseboard_fab2(sch_1):\PP1562\"
				( pinRef "@baseboard_fab2_lib.baseboard_fab2(sch_1):page84_i102:DQS1N" )
				( pinRef "@baseboard_fab2_lib.baseboard_fab2(sch_1):page60_i172:DDR3_DQS_DN(1)" )
				( attribute "RELATIVE_PROPAGATION_DELAY_SCOPE" "G"
					( Parent
						( matchGroupRef "@baseboard_fab2_lib.baseboard_fab2(sch_1):\MG_DQ-DQS_NEAR_DIMM_NG_M_K_BYTE1\" )
					)
					( Status sCSetFlattened )
					( Origin gBackEnd )
				)
				( attribute "RELATIVE_PROPAGATION_DELAY" ",5.00 MIL"
					( Parent
						( matchGroupRef "@baseboard_fab2_lib.baseboard_fab2(sch_1):\MG_DQ-DQS_NEAR_DIMM_NG_M_K_BYTE1\" )
					)
					( Units "uMatchProp" "ns" 1.000000)
					( Status sCSetFlattened )
					( Origin gBackEnd )
				)
			)
			( pinPair "@baseboard_fab2_lib.baseboard_fab2(sch_1):\PP1564\"
				( pinRef "@baseboard_fab2_lib.baseboard_fab2(sch_1):page60_i172:DDR3_DQS_DP(1)" )
				( pinRef "@baseboard_fab2_lib.baseboard_fab2(sch_1):page83_i66:DQS1P" )
				( attribute "RELATIVE_PROPAGATION_DELAY_SCOPE" "G"
					( Parent
						( matchGroupRef "@baseboard_fab2_lib.baseboard_fab2(sch_1):\MG_DQ-DQS_FAR_DIMM_NG_M_K_BYTE1\" )
					)
					( Status sCSetFlattened )
					( Origin gBackEnd )
				)
				( attribute "RELATIVE_PROPAGATION_DELAY" ",5.00 MIL"
					( Parent
						( matchGroupRef "@baseboard_fab2_lib.baseboard_fab2(sch_1):\MG_DQ-DQS_FAR_DIMM_NG_M_K_BYTE1\" )
					)
					( Units "uMatchProp" "ns" 1.000000)
					( Status sCSetFlattened )
					( Origin gBackEnd )
				)
			)
			( pinPair "@baseboard_fab2_lib.baseboard_fab2(sch_1):\PP1565\"
				( pinRef "@baseboard_fab2_lib.baseboard_fab2(sch_1):page84_i102:DQS1P" )
				( pinRef "@baseboard_fab2_lib.baseboard_fab2(sch_1):page60_i172:DDR3_DQS_DP(1)" )
				( attribute "RELATIVE_PROPAGATION_DELAY_SCOPE" "G"
					( Parent
						( matchGroupRef "@baseboard_fab2_lib.baseboard_fab2(sch_1):\MG_DQ-DQS_NEAR_DIMM_NG_M_K_BYTE1\" )
					)
					( Status sCSetFlattened )
					( Origin gBackEnd )
				)
				( attribute "RELATIVE_PROPAGATION_DELAY" ",5.00 MIL"
					( Parent
						( matchGroupRef "@baseboard_fab2_lib.baseboard_fab2(sch_1):\MG_DQ-DQS_NEAR_DIMM_NG_M_K_BYTE1\" )
					)
					( Units "uMatchProp" "ns" 1.000000)
					( Status sCSetFlattened )
					( Origin gBackEnd )
				)
			)
			( pinPair "@baseboard_fab2_lib.baseboard_fab2(sch_1):\PP1549\"
				( pinRef "@baseboard_fab2_lib.baseboard_fab2(sch_1):page60_i172:DDR3_DQS_DN(2)" )
				( pinRef "@baseboard_fab2_lib.baseboard_fab2(sch_1):page83_i66:DQS2N" )
				( attribute "RELATIVE_PROPAGATION_DELAY_SCOPE" "G"
					( Parent
						( matchGroupRef "@baseboard_fab2_lib.baseboard_fab2(sch_1):\MG_DQ-DQS_FAR_DIMM_NG_M_K_BYTE2\" )
					)
					( Status sCSetFlattened )
					( Origin gBackEnd )
				)
				( attribute "RELATIVE_PROPAGATION_DELAY" ",5.00 MIL"
					( Parent
						( matchGroupRef "@baseboard_fab2_lib.baseboard_fab2(sch_1):\MG_DQ-DQS_FAR_DIMM_NG_M_K_BYTE2\" )
					)
					( Units "uMatchProp" "ns" 1.000000)
					( Status sCSetFlattened )
					( Origin gBackEnd )
				)
			)
			( pinPair "@baseboard_fab2_lib.baseboard_fab2(sch_1):\PP1550\"
				( pinRef "@baseboard_fab2_lib.baseboard_fab2(sch_1):page84_i102:DQS2N" )
				( pinRef "@baseboard_fab2_lib.baseboard_fab2(sch_1):page60_i172:DDR3_DQS_DN(2)" )
				( attribute "RELATIVE_PROPAGATION_DELAY_SCOPE" "G"
					( Parent
						( matchGroupRef "@baseboard_fab2_lib.baseboard_fab2(sch_1):\MG_DQ-DQS_NEAR_DIMM_NG_M_K_BYTE2\" )
					)
					( Status sCSetFlattened )
					( Origin gBackEnd )
				)
				( attribute "RELATIVE_PROPAGATION_DELAY" ",5.00 MIL"
					( Parent
						( matchGroupRef "@baseboard_fab2_lib.baseboard_fab2(sch_1):\MG_DQ-DQS_NEAR_DIMM_NG_M_K_BYTE2\" )
					)
					( Units "uMatchProp" "ns" 1.000000)
					( Status sCSetFlattened )
					( Origin gBackEnd )
				)
			)
			( pinPair "@baseboard_fab2_lib.baseboard_fab2(sch_1):\PP1552\"
				( pinRef "@baseboard_fab2_lib.baseboard_fab2(sch_1):page60_i172:DDR3_DQS_DP(2)" )
				( pinRef "@baseboard_fab2_lib.baseboard_fab2(sch_1):page83_i66:DQS2P" )
				( attribute "RELATIVE_PROPAGATION_DELAY_SCOPE" "G"
					( Parent
						( matchGroupRef "@baseboard_fab2_lib.baseboard_fab2(sch_1):\MG_DQ-DQS_FAR_DIMM_NG_M_K_BYTE2\" )
					)
					( Status sCSetFlattened )
					( Origin gBackEnd )
				)
				( attribute "RELATIVE_PROPAGATION_DELAY" ",5.00 MIL"
					( Parent
						( matchGroupRef "@baseboard_fab2_lib.baseboard_fab2(sch_1):\MG_DQ-DQS_FAR_DIMM_NG_M_K_BYTE2\" )
					)
					( Units "uMatchProp" "ns" 1.000000)
					( Status sCSetFlattened )
					( Origin gBackEnd )
				)
			)
			( pinPair "@baseboard_fab2_lib.baseboard_fab2(sch_1):\PP1553\"
				( pinRef "@baseboard_fab2_lib.baseboard_fab2(sch_1):page84_i102:DQS2P" )
				( pinRef "@baseboard_fab2_lib.baseboard_fab2(sch_1):page60_i172:DDR3_DQS_DP(2)" )
				( attribute "RELATIVE_PROPAGATION_DELAY_SCOPE" "G"
					( Parent
						( matchGroupRef "@baseboard_fab2_lib.baseboard_fab2(sch_1):\MG_DQ-DQS_NEAR_DIMM_NG_M_K_BYTE2\" )
					)
					( Status sCSetFlattened )
					( Origin gBackEnd )
				)
				( attribute "RELATIVE_PROPAGATION_DELAY" ",5.00 MIL"
					( Parent
						( matchGroupRef "@baseboard_fab2_lib.baseboard_fab2(sch_1):\MG_DQ-DQS_NEAR_DIMM_NG_M_K_BYTE2\" )
					)
					( Units "uMatchProp" "ns" 1.000000)
					( Status sCSetFlattened )
					( Origin gBackEnd )
				)
			)
			( pinPair "@baseboard_fab2_lib.baseboard_fab2(sch_1):\PP1537\"
				( pinRef "@baseboard_fab2_lib.baseboard_fab2(sch_1):page60_i172:DDR3_DQS_DN(3)" )
				( pinRef "@baseboard_fab2_lib.baseboard_fab2(sch_1):page83_i66:DQS3N" )
				( attribute "RELATIVE_PROPAGATION_DELAY_SCOPE" "G"
					( Parent
						( matchGroupRef "@baseboard_fab2_lib.baseboard_fab2(sch_1):\MG_DQ-DQS_FAR_DIMM_NG_M_K_BYTE3\" )
					)
					( Status sCSetFlattened )
					( Origin gBackEnd )
				)
				( attribute "RELATIVE_PROPAGATION_DELAY" ",5.00 MIL"
					( Parent
						( matchGroupRef "@baseboard_fab2_lib.baseboard_fab2(sch_1):\MG_DQ-DQS_FAR_DIMM_NG_M_K_BYTE3\" )
					)
					( Units "uMatchProp" "ns" 1.000000)
					( Status sCSetFlattened )
					( Origin gBackEnd )
				)
			)
			( pinPair "@baseboard_fab2_lib.baseboard_fab2(sch_1):\PP1538\"
				( pinRef "@baseboard_fab2_lib.baseboard_fab2(sch_1):page84_i102:DQS3N" )
				( pinRef "@baseboard_fab2_lib.baseboard_fab2(sch_1):page60_i172:DDR3_DQS_DN(3)" )
				( attribute "RELATIVE_PROPAGATION_DELAY_SCOPE" "G"
					( Parent
						( matchGroupRef "@baseboard_fab2_lib.baseboard_fab2(sch_1):\MG_DQ-DQS_NEAR_DIMM_NG_M_K_BYTE3\" )
					)
					( Status sCSetFlattened )
					( Origin gBackEnd )
				)
				( attribute "RELATIVE_PROPAGATION_DELAY" ",5.00 MIL"
					( Parent
						( matchGroupRef "@baseboard_fab2_lib.baseboard_fab2(sch_1):\MG_DQ-DQS_NEAR_DIMM_NG_M_K_BYTE3\" )
					)
					( Units "uMatchProp" "ns" 1.000000)
					( Status sCSetFlattened )
					( Origin gBackEnd )
				)
			)
			( pinPair "@baseboard_fab2_lib.baseboard_fab2(sch_1):\PP1540\"
				( pinRef "@baseboard_fab2_lib.baseboard_fab2(sch_1):page60_i172:DDR3_DQS_DP(3)" )
				( pinRef "@baseboard_fab2_lib.baseboard_fab2(sch_1):page83_i66:DQS3P" )
				( attribute "RELATIVE_PROPAGATION_DELAY_SCOPE" "G"
					( Parent
						( matchGroupRef "@baseboard_fab2_lib.baseboard_fab2(sch_1):\MG_DQ-DQS_FAR_DIMM_NG_M_K_BYTE3\" )
					)
					( Status sCSetFlattened )
					( Origin gBackEnd )
				)
				( attribute "RELATIVE_PROPAGATION_DELAY" ",5.00 MIL"
					( Parent
						( matchGroupRef "@baseboard_fab2_lib.baseboard_fab2(sch_1):\MG_DQ-DQS_FAR_DIMM_NG_M_K_BYTE3\" )
					)
					( Units "uMatchProp" "ns" 1.000000)
					( Status sCSetFlattened )
					( Origin gBackEnd )
				)
			)
			( pinPair "@baseboard_fab2_lib.baseboard_fab2(sch_1):\PP1541\"
				( pinRef "@baseboard_fab2_lib.baseboard_fab2(sch_1):page84_i102:DQS3P" )
				( pinRef "@baseboard_fab2_lib.baseboard_fab2(sch_1):page60_i172:DDR3_DQS_DP(3)" )
				( attribute "RELATIVE_PROPAGATION_DELAY_SCOPE" "G"
					( Parent
						( matchGroupRef "@baseboard_fab2_lib.baseboard_fab2(sch_1):\MG_DQ-DQS_NEAR_DIMM_NG_M_K_BYTE3\" )
					)
					( Status sCSetFlattened )
					( Origin gBackEnd )
				)
				( attribute "RELATIVE_PROPAGATION_DELAY" ",5.00 MIL"
					( Parent
						( matchGroupRef "@baseboard_fab2_lib.baseboard_fab2(sch_1):\MG_DQ-DQS_NEAR_DIMM_NG_M_K_BYTE3\" )
					)
					( Units "uMatchProp" "ns" 1.000000)
					( Status sCSetFlattened )
					( Origin gBackEnd )
				)
			)
			( pinPair "@baseboard_fab2_lib.baseboard_fab2(sch_1):\PP1525\"
				( pinRef "@baseboard_fab2_lib.baseboard_fab2(sch_1):page60_i172:DDR3_DQS_DN(4)" )
				( pinRef "@baseboard_fab2_lib.baseboard_fab2(sch_1):page83_i66:DQS4N" )
				( attribute "RELATIVE_PROPAGATION_DELAY_SCOPE" "G"
					( Parent
						( matchGroupRef "@baseboard_fab2_lib.baseboard_fab2(sch_1):\MG_DQ-DQS_FAR_DIMM_NG_M_K_BYTE4\" )
					)
					( Status sCSetFlattened )
					( Origin gBackEnd )
				)
				( attribute "RELATIVE_PROPAGATION_DELAY" ",5.00 MIL"
					( Parent
						( matchGroupRef "@baseboard_fab2_lib.baseboard_fab2(sch_1):\MG_DQ-DQS_FAR_DIMM_NG_M_K_BYTE4\" )
					)
					( Units "uMatchProp" "ns" 1.000000)
					( Status sCSetFlattened )
					( Origin gBackEnd )
				)
			)
			( pinPair "@baseboard_fab2_lib.baseboard_fab2(sch_1):\PP1527\"
				( pinRef "@baseboard_fab2_lib.baseboard_fab2(sch_1):page84_i102:DQS4N" )
				( pinRef "@baseboard_fab2_lib.baseboard_fab2(sch_1):page60_i172:DDR3_DQS_DN(4)" )
				( attribute "RELATIVE_PROPAGATION_DELAY_SCOPE" "G"
					( Parent
						( matchGroupRef "@baseboard_fab2_lib.baseboard_fab2(sch_1):\MG_DQ-DQS_NEAR_DIMM_NG_M_K_BYTE4\" )
					)
					( Status sCSetFlattened )
					( Origin gBackEnd )
				)
				( attribute "RELATIVE_PROPAGATION_DELAY" ",5.00 MIL"
					( Parent
						( matchGroupRef "@baseboard_fab2_lib.baseboard_fab2(sch_1):\MG_DQ-DQS_NEAR_DIMM_NG_M_K_BYTE4\" )
					)
					( Units "uMatchProp" "ns" 1.000000)
					( Status sCSetFlattened )
					( Origin gBackEnd )
				)
			)
			( pinPair "@baseboard_fab2_lib.baseboard_fab2(sch_1):\PP1528\"
				( pinRef "@baseboard_fab2_lib.baseboard_fab2(sch_1):page60_i172:DDR3_DQS_DP(4)" )
				( pinRef "@baseboard_fab2_lib.baseboard_fab2(sch_1):page83_i66:DQS4P" )
				( attribute "RELATIVE_PROPAGATION_DELAY_SCOPE" "G"
					( Parent
						( matchGroupRef "@baseboard_fab2_lib.baseboard_fab2(sch_1):\MG_DQ-DQS_FAR_DIMM_NG_M_K_BYTE4\" )
					)
					( Status sCSetFlattened )
					( Origin gBackEnd )
				)
				( attribute "RELATIVE_PROPAGATION_DELAY" ",5.00 MIL"
					( Parent
						( matchGroupRef "@baseboard_fab2_lib.baseboard_fab2(sch_1):\MG_DQ-DQS_FAR_DIMM_NG_M_K_BYTE4\" )
					)
					( Units "uMatchProp" "ns" 1.000000)
					( Status sCSetFlattened )
					( Origin gBackEnd )
				)
			)
			( pinPair "@baseboard_fab2_lib.baseboard_fab2(sch_1):\PP1530\"
				( pinRef "@baseboard_fab2_lib.baseboard_fab2(sch_1):page84_i102:DQS4P" )
				( pinRef "@baseboard_fab2_lib.baseboard_fab2(sch_1):page60_i172:DDR3_DQS_DP(4)" )
				( attribute "RELATIVE_PROPAGATION_DELAY_SCOPE" "G"
					( Parent
						( matchGroupRef "@baseboard_fab2_lib.baseboard_fab2(sch_1):\MG_DQ-DQS_NEAR_DIMM_NG_M_K_BYTE4\" )
					)
					( Status sCSetFlattened )
					( Origin gBackEnd )
				)
				( attribute "RELATIVE_PROPAGATION_DELAY" ",5.00 MIL"
					( Parent
						( matchGroupRef "@baseboard_fab2_lib.baseboard_fab2(sch_1):\MG_DQ-DQS_NEAR_DIMM_NG_M_K_BYTE4\" )
					)
					( Units "uMatchProp" "ns" 1.000000)
					( Status sCSetFlattened )
					( Origin gBackEnd )
				)
			)
			( pinPair "@baseboard_fab2_lib.baseboard_fab2(sch_1):\PP1513\"
				( pinRef "@baseboard_fab2_lib.baseboard_fab2(sch_1):page60_i172:DDR3_DQS_DN(5)" )
				( pinRef "@baseboard_fab2_lib.baseboard_fab2(sch_1):page83_i66:DQS5N" )
				( attribute "RELATIVE_PROPAGATION_DELAY_SCOPE" "G"
					( Parent
						( matchGroupRef "@baseboard_fab2_lib.baseboard_fab2(sch_1):\MG_DQ-DQS_FAR_DIMM_NG_M_K_BYTE5\" )
					)
					( Status sCSetFlattened )
					( Origin gBackEnd )
				)
				( attribute "RELATIVE_PROPAGATION_DELAY" ",5.00 MIL"
					( Parent
						( matchGroupRef "@baseboard_fab2_lib.baseboard_fab2(sch_1):\MG_DQ-DQS_FAR_DIMM_NG_M_K_BYTE5\" )
					)
					( Units "uMatchProp" "ns" 1.000000)
					( Status sCSetFlattened )
					( Origin gBackEnd )
				)
			)
			( pinPair "@baseboard_fab2_lib.baseboard_fab2(sch_1):\PP1515\"
				( pinRef "@baseboard_fab2_lib.baseboard_fab2(sch_1):page84_i102:DQS5N" )
				( pinRef "@baseboard_fab2_lib.baseboard_fab2(sch_1):page60_i172:DDR3_DQS_DN(5)" )
				( attribute "RELATIVE_PROPAGATION_DELAY_SCOPE" "G"
					( Parent
						( matchGroupRef "@baseboard_fab2_lib.baseboard_fab2(sch_1):\MG_DQ-DQS_NEAR_DIMM_NG_M_K_BYTE5\" )
					)
					( Status sCSetFlattened )
					( Origin gBackEnd )
				)
				( attribute "RELATIVE_PROPAGATION_DELAY" ",5.00 MIL"
					( Parent
						( matchGroupRef "@baseboard_fab2_lib.baseboard_fab2(sch_1):\MG_DQ-DQS_NEAR_DIMM_NG_M_K_BYTE5\" )
					)
					( Units "uMatchProp" "ns" 1.000000)
					( Status sCSetFlattened )
					( Origin gBackEnd )
				)
			)
			( pinPair "@baseboard_fab2_lib.baseboard_fab2(sch_1):\PP1516\"
				( pinRef "@baseboard_fab2_lib.baseboard_fab2(sch_1):page60_i172:DDR3_DQS_DP(5)" )
				( pinRef "@baseboard_fab2_lib.baseboard_fab2(sch_1):page83_i66:DQS5P" )
				( attribute "RELATIVE_PROPAGATION_DELAY_SCOPE" "G"
					( Parent
						( matchGroupRef "@baseboard_fab2_lib.baseboard_fab2(sch_1):\MG_DQ-DQS_FAR_DIMM_NG_M_K_BYTE5\" )
					)
					( Status sCSetFlattened )
					( Origin gBackEnd )
				)
				( attribute "RELATIVE_PROPAGATION_DELAY" ",5.00 MIL"
					( Parent
						( matchGroupRef "@baseboard_fab2_lib.baseboard_fab2(sch_1):\MG_DQ-DQS_FAR_DIMM_NG_M_K_BYTE5\" )
					)
					( Units "uMatchProp" "ns" 1.000000)
					( Status sCSetFlattened )
					( Origin gBackEnd )
				)
			)
			( pinPair "@baseboard_fab2_lib.baseboard_fab2(sch_1):\PP1518\"
				( pinRef "@baseboard_fab2_lib.baseboard_fab2(sch_1):page60_i172:DDR3_DQS_DP(5)" )
				( pinRef "@baseboard_fab2_lib.baseboard_fab2(sch_1):page84_i102:DQS5P" )
				( attribute "RELATIVE_PROPAGATION_DELAY_SCOPE" "G"
					( Parent
						( matchGroupRef "@baseboard_fab2_lib.baseboard_fab2(sch_1):\MG_DQ-DQS_NEAR_DIMM_NG_M_K_BYTE5\" )
					)
					( Status sCSetFlattened )
					( Origin gBackEnd )
				)
				( attribute "RELATIVE_PROPAGATION_DELAY" ",5.00 MIL"
					( Parent
						( matchGroupRef "@baseboard_fab2_lib.baseboard_fab2(sch_1):\MG_DQ-DQS_NEAR_DIMM_NG_M_K_BYTE5\" )
					)
					( Units "uMatchProp" "ns" 1.000000)
					( Status sCSetFlattened )
					( Origin gBackEnd )
				)
			)
			( pinPair "@baseboard_fab2_lib.baseboard_fab2(sch_1):\PP1501\"
				( pinRef "@baseboard_fab2_lib.baseboard_fab2(sch_1):page60_i172:DDR3_DQS_DN(6)" )
				( pinRef "@baseboard_fab2_lib.baseboard_fab2(sch_1):page83_i66:DQS6N" )
				( attribute "RELATIVE_PROPAGATION_DELAY_SCOPE" "G"
					( Parent
						( matchGroupRef "@baseboard_fab2_lib.baseboard_fab2(sch_1):\MG_DQ-DQS_FAR_DIMM_NG_M_K_BYTE6\" )
					)
					( Status sCSetFlattened )
					( Origin gBackEnd )
				)
				( attribute "RELATIVE_PROPAGATION_DELAY" ",5.00 MIL"
					( Parent
						( matchGroupRef "@baseboard_fab2_lib.baseboard_fab2(sch_1):\MG_DQ-DQS_FAR_DIMM_NG_M_K_BYTE6\" )
					)
					( Units "uMatchProp" "ns" 1.000000)
					( Status sCSetFlattened )
					( Origin gBackEnd )
				)
			)
			( pinPair "@baseboard_fab2_lib.baseboard_fab2(sch_1):\PP1503\"
				( pinRef "@baseboard_fab2_lib.baseboard_fab2(sch_1):page60_i172:DDR3_DQS_DN(6)" )
				( pinRef "@baseboard_fab2_lib.baseboard_fab2(sch_1):page84_i102:DQS6N" )
				( attribute "RELATIVE_PROPAGATION_DELAY_SCOPE" "G"
					( Parent
						( matchGroupRef "@baseboard_fab2_lib.baseboard_fab2(sch_1):\MG_DQ-DQS_NEAR_DIMM_NG_M_K_BYTE6\" )
					)
					( Status sCSetFlattened )
					( Origin gBackEnd )
				)
				( attribute "RELATIVE_PROPAGATION_DELAY" ",5.00 MIL"
					( Parent
						( matchGroupRef "@baseboard_fab2_lib.baseboard_fab2(sch_1):\MG_DQ-DQS_NEAR_DIMM_NG_M_K_BYTE6\" )
					)
					( Units "uMatchProp" "ns" 1.000000)
					( Status sCSetFlattened )
					( Origin gBackEnd )
				)
			)
			( pinPair "@baseboard_fab2_lib.baseboard_fab2(sch_1):\PP1504\"
				( pinRef "@baseboard_fab2_lib.baseboard_fab2(sch_1):page60_i172:DDR3_DQS_DP(6)" )
				( pinRef "@baseboard_fab2_lib.baseboard_fab2(sch_1):page83_i66:DQS6P" )
				( attribute "RELATIVE_PROPAGATION_DELAY_SCOPE" "G"
					( Parent
						( matchGroupRef "@baseboard_fab2_lib.baseboard_fab2(sch_1):\MG_DQ-DQS_FAR_DIMM_NG_M_K_BYTE6\" )
					)
					( Status sCSetFlattened )
					( Origin gBackEnd )
				)
				( attribute "RELATIVE_PROPAGATION_DELAY" ",5.00 MIL"
					( Parent
						( matchGroupRef "@baseboard_fab2_lib.baseboard_fab2(sch_1):\MG_DQ-DQS_FAR_DIMM_NG_M_K_BYTE6\" )
					)
					( Units "uMatchProp" "ns" 1.000000)
					( Status sCSetFlattened )
					( Origin gBackEnd )
				)
			)
			( pinPair "@baseboard_fab2_lib.baseboard_fab2(sch_1):\PP1506\"
				( pinRef "@baseboard_fab2_lib.baseboard_fab2(sch_1):page84_i102:DQS6P" )
				( pinRef "@baseboard_fab2_lib.baseboard_fab2(sch_1):page60_i172:DDR3_DQS_DP(6)" )
				( attribute "RELATIVE_PROPAGATION_DELAY_SCOPE" "G"
					( Parent
						( matchGroupRef "@baseboard_fab2_lib.baseboard_fab2(sch_1):\MG_DQ-DQS_NEAR_DIMM_NG_M_K_BYTE6\" )
					)
					( Status sCSetFlattened )
					( Origin gBackEnd )
				)
				( attribute "RELATIVE_PROPAGATION_DELAY" ",5.00 MIL"
					( Parent
						( matchGroupRef "@baseboard_fab2_lib.baseboard_fab2(sch_1):\MG_DQ-DQS_NEAR_DIMM_NG_M_K_BYTE6\" )
					)
					( Units "uMatchProp" "ns" 1.000000)
					( Status sCSetFlattened )
					( Origin gBackEnd )
				)
			)
			( pinPair "@baseboard_fab2_lib.baseboard_fab2(sch_1):\PP1489\"
				( pinRef "@baseboard_fab2_lib.baseboard_fab2(sch_1):page60_i172:DDR3_DQS_DN(7)" )
				( pinRef "@baseboard_fab2_lib.baseboard_fab2(sch_1):page83_i66:DQS7N" )
				( attribute "RELATIVE_PROPAGATION_DELAY_SCOPE" "G"
					( Parent
						( matchGroupRef "@baseboard_fab2_lib.baseboard_fab2(sch_1):\MG_DQ-DQS_FAR_DIMM_NG_M_K_BYTE7\" )
					)
					( Status sCSetFlattened )
					( Origin gBackEnd )
				)
				( attribute "RELATIVE_PROPAGATION_DELAY" ",5.00 MIL"
					( Parent
						( matchGroupRef "@baseboard_fab2_lib.baseboard_fab2(sch_1):\MG_DQ-DQS_FAR_DIMM_NG_M_K_BYTE7\" )
					)
					( Units "uMatchProp" "ns" 1.000000)
					( Status sCSetFlattened )
					( Origin gBackEnd )
				)
			)
			( pinPair "@baseboard_fab2_lib.baseboard_fab2(sch_1):\PP1491\"
				( pinRef "@baseboard_fab2_lib.baseboard_fab2(sch_1):page84_i102:DQS7N" )
				( pinRef "@baseboard_fab2_lib.baseboard_fab2(sch_1):page60_i172:DDR3_DQS_DN(7)" )
				( attribute "RELATIVE_PROPAGATION_DELAY_SCOPE" "G"
					( Parent
						( matchGroupRef "@baseboard_fab2_lib.baseboard_fab2(sch_1):\MG_DQ-DQS_NEAR_DIMM_NG_M_K_BYTE7\" )
					)
					( Status sCSetFlattened )
					( Origin gBackEnd )
				)
				( attribute "RELATIVE_PROPAGATION_DELAY" ",5.00 MIL"
					( Parent
						( matchGroupRef "@baseboard_fab2_lib.baseboard_fab2(sch_1):\MG_DQ-DQS_NEAR_DIMM_NG_M_K_BYTE7\" )
					)
					( Units "uMatchProp" "ns" 1.000000)
					( Status sCSetFlattened )
					( Origin gBackEnd )
				)
			)
			( pinPair "@baseboard_fab2_lib.baseboard_fab2(sch_1):\PP1492\"
				( pinRef "@baseboard_fab2_lib.baseboard_fab2(sch_1):page60_i172:DDR3_DQS_DP(7)" )
				( pinRef "@baseboard_fab2_lib.baseboard_fab2(sch_1):page83_i66:DQS7P" )
				( attribute "RELATIVE_PROPAGATION_DELAY_SCOPE" "G"
					( Parent
						( matchGroupRef "@baseboard_fab2_lib.baseboard_fab2(sch_1):\MG_DQ-DQS_FAR_DIMM_NG_M_K_BYTE7\" )
					)
					( Status sCSetFlattened )
					( Origin gBackEnd )
				)
				( attribute "RELATIVE_PROPAGATION_DELAY" ",5.00 MIL"
					( Parent
						( matchGroupRef "@baseboard_fab2_lib.baseboard_fab2(sch_1):\MG_DQ-DQS_FAR_DIMM_NG_M_K_BYTE7\" )
					)
					( Units "uMatchProp" "ns" 1.000000)
					( Status sCSetFlattened )
					( Origin gBackEnd )
				)
			)
			( pinPair "@baseboard_fab2_lib.baseboard_fab2(sch_1):\PP1494\"
				( pinRef "@baseboard_fab2_lib.baseboard_fab2(sch_1):page84_i102:DQS7P" )
				( pinRef "@baseboard_fab2_lib.baseboard_fab2(sch_1):page60_i172:DDR3_DQS_DP(7)" )
				( attribute "RELATIVE_PROPAGATION_DELAY_SCOPE" "G"
					( Parent
						( matchGroupRef "@baseboard_fab2_lib.baseboard_fab2(sch_1):\MG_DQ-DQS_NEAR_DIMM_NG_M_K_BYTE7\" )
					)
					( Status sCSetFlattened )
					( Origin gBackEnd )
				)
				( attribute "RELATIVE_PROPAGATION_DELAY" ",5.00 MIL"
					( Parent
						( matchGroupRef "@baseboard_fab2_lib.baseboard_fab2(sch_1):\MG_DQ-DQS_NEAR_DIMM_NG_M_K_BYTE7\" )
					)
					( Units "uMatchProp" "ns" 1.000000)
					( Status sCSetFlattened )
					( Origin gBackEnd )
				)
			)
			( pinPair "@baseboard_fab2_lib.baseboard_fab2(sch_1):\PP1261\"
				( pinRef "@baseboard_fab2_lib.baseboard_fab2(sch_1):page60_i172:DDR3_DQS_DN(8)" )
				( pinRef "@baseboard_fab2_lib.baseboard_fab2(sch_1):page83_i66:DQS8N" )
				( attribute "RELATIVE_PROPAGATION_DELAY_SCOPE" "G"
					( Parent
						( matchGroupRef "@baseboard_fab2_lib.baseboard_fab2(sch_1):\MG_DQ-DQS_FAR_DIMM_NG_M_K_BYTE-ECC\" )
					)
					( Status sCSetFlattened )
					( Origin gBackEnd )
				)
				( attribute "RELATIVE_PROPAGATION_DELAY" ",5.00 MIL"
					( Parent
						( matchGroupRef "@baseboard_fab2_lib.baseboard_fab2(sch_1):\MG_DQ-DQS_FAR_DIMM_NG_M_K_BYTE-ECC\" )
					)
					( Units "uMatchProp" "ns" 1.000000)
					( Status sCSetFlattened )
					( Origin gBackEnd )
				)
			)
			( pinPair "@baseboard_fab2_lib.baseboard_fab2(sch_1):\PP1262\"
				( pinRef "@baseboard_fab2_lib.baseboard_fab2(sch_1):page84_i102:DQS8N" )
				( pinRef "@baseboard_fab2_lib.baseboard_fab2(sch_1):page60_i172:DDR3_DQS_DN(8)" )
				( attribute "RELATIVE_PROPAGATION_DELAY_SCOPE" "G"
					( Parent
						( matchGroupRef "@baseboard_fab2_lib.baseboard_fab2(sch_1):\MG_DQ-DQS_NEAR_DIMM_NG_M_K_BYTE-ECC\" )
					)
					( Status sCSetFlattened )
					( Origin gBackEnd )
				)
				( attribute "RELATIVE_PROPAGATION_DELAY" ",5.00 MIL"
					( Parent
						( matchGroupRef "@baseboard_fab2_lib.baseboard_fab2(sch_1):\MG_DQ-DQS_NEAR_DIMM_NG_M_K_BYTE-ECC\" )
					)
					( Units "uMatchProp" "ns" 1.000000)
					( Status sCSetFlattened )
					( Origin gBackEnd )
				)
			)
			( pinPair "@baseboard_fab2_lib.baseboard_fab2(sch_1):\PP1264\"
				( pinRef "@baseboard_fab2_lib.baseboard_fab2(sch_1):page60_i172:DDR3_DQS_DP(8)" )
				( pinRef "@baseboard_fab2_lib.baseboard_fab2(sch_1):page83_i66:DQS8P" )
				( attribute "RELATIVE_PROPAGATION_DELAY_SCOPE" "G"
					( Parent
						( matchGroupRef "@baseboard_fab2_lib.baseboard_fab2(sch_1):\MG_DQ-DQS_FAR_DIMM_NG_M_K_BYTE-ECC\" )
					)
					( Status sCSetFlattened )
					( Origin gBackEnd )
				)
				( attribute "RELATIVE_PROPAGATION_DELAY" ",5.00 MIL"
					( Parent
						( matchGroupRef "@baseboard_fab2_lib.baseboard_fab2(sch_1):\MG_DQ-DQS_FAR_DIMM_NG_M_K_BYTE-ECC\" )
					)
					( Units "uMatchProp" "ns" 1.000000)
					( Status sCSetFlattened )
					( Origin gBackEnd )
				)
			)
			( pinPair "@baseboard_fab2_lib.baseboard_fab2(sch_1):\PP1265\"
				( pinRef "@baseboard_fab2_lib.baseboard_fab2(sch_1):page84_i102:DQS8P" )
				( pinRef "@baseboard_fab2_lib.baseboard_fab2(sch_1):page60_i172:DDR3_DQS_DP(8)" )
				( attribute "RELATIVE_PROPAGATION_DELAY_SCOPE" "G"
					( Parent
						( matchGroupRef "@baseboard_fab2_lib.baseboard_fab2(sch_1):\MG_DQ-DQS_NEAR_DIMM_NG_M_K_BYTE-ECC\" )
					)
					( Status sCSetFlattened )
					( Origin gBackEnd )
				)
				( attribute "RELATIVE_PROPAGATION_DELAY" ",5.00 MIL"
					( Parent
						( matchGroupRef "@baseboard_fab2_lib.baseboard_fab2(sch_1):\MG_DQ-DQS_NEAR_DIMM_NG_M_K_BYTE-ECC\" )
					)
					( Units "uMatchProp" "ns" 1.000000)
					( Status sCSetFlattened )
					( Origin gBackEnd )
				)
			)
			( pinPair "@baseboard_fab2_lib.baseboard_fab2(sch_1):\PP1567\"
				( pinRef "@baseboard_fab2_lib.baseboard_fab2(sch_1):page60_i172:DDR3_DQS_DN(9)" )
				( pinRef "@baseboard_fab2_lib.baseboard_fab2(sch_1):page83_i66:DQS9N" )
				( attribute "RELATIVE_PROPAGATION_DELAY_SCOPE" "G"
					( Parent
						( matchGroupRef "@baseboard_fab2_lib.baseboard_fab2(sch_1):\MG_DQ-DQS_FAR_DIMM_NG_M_K_BYTE0\" )
					)
					( Status sCSetFlattened )
					( Origin gBackEnd )
				)
				( attribute "RELATIVE_PROPAGATION_DELAY" ",5.00 MIL"
					( Parent
						( matchGroupRef "@baseboard_fab2_lib.baseboard_fab2(sch_1):\MG_DQ-DQS_FAR_DIMM_NG_M_K_BYTE0\" )
					)
					( Units "uMatchProp" "ns" 1.000000)
					( Status sCSetFlattened )
					( Origin gBackEnd )
				)
			)
			( pinPair "@baseboard_fab2_lib.baseboard_fab2(sch_1):\PP1568\"
				( pinRef "@baseboard_fab2_lib.baseboard_fab2(sch_1):page84_i102:DQS9N" )
				( pinRef "@baseboard_fab2_lib.baseboard_fab2(sch_1):page60_i172:DDR3_DQS_DN(9)" )
				( attribute "RELATIVE_PROPAGATION_DELAY_SCOPE" "G"
					( Parent
						( matchGroupRef "@baseboard_fab2_lib.baseboard_fab2(sch_1):\MG_DQ-DQS_NEAR_DIMM_NG_M_K_BYTE0\" )
					)
					( Status sCSetFlattened )
					( Origin gBackEnd )
				)
				( attribute "RELATIVE_PROPAGATION_DELAY" ",5.00 MIL"
					( Parent
						( matchGroupRef "@baseboard_fab2_lib.baseboard_fab2(sch_1):\MG_DQ-DQS_NEAR_DIMM_NG_M_K_BYTE0\" )
					)
					( Units "uMatchProp" "ns" 1.000000)
					( Status sCSetFlattened )
					( Origin gBackEnd )
				)
			)
			( pinPair "@baseboard_fab2_lib.baseboard_fab2(sch_1):\PP1570\"
				( pinRef "@baseboard_fab2_lib.baseboard_fab2(sch_1):page60_i172:DDR3_DQS_DP(9)" )
				( pinRef "@baseboard_fab2_lib.baseboard_fab2(sch_1):page83_i66:DQS9P" )
				( attribute "RELATIVE_PROPAGATION_DELAY_SCOPE" "G"
					( Parent
						( matchGroupRef "@baseboard_fab2_lib.baseboard_fab2(sch_1):\MG_DQ-DQS_FAR_DIMM_NG_M_K_BYTE0\" )
					)
					( Status sCSetFlattened )
					( Origin gBackEnd )
				)
				( attribute "RELATIVE_PROPAGATION_DELAY" ",5.00 MIL"
					( Parent
						( matchGroupRef "@baseboard_fab2_lib.baseboard_fab2(sch_1):\MG_DQ-DQS_FAR_DIMM_NG_M_K_BYTE0\" )
					)
					( Units "uMatchProp" "ns" 1.000000)
					( Status sCSetFlattened )
					( Origin gBackEnd )
				)
			)
			( pinPair "@baseboard_fab2_lib.baseboard_fab2(sch_1):\PP1571\"
				( pinRef "@baseboard_fab2_lib.baseboard_fab2(sch_1):page84_i102:DQS9P" )
				( pinRef "@baseboard_fab2_lib.baseboard_fab2(sch_1):page60_i172:DDR3_DQS_DP(9)" )
				( attribute "RELATIVE_PROPAGATION_DELAY_SCOPE" "G"
					( Parent
						( matchGroupRef "@baseboard_fab2_lib.baseboard_fab2(sch_1):\MG_DQ-DQS_NEAR_DIMM_NG_M_K_BYTE0\" )
					)
					( Status sCSetFlattened )
					( Origin gBackEnd )
				)
				( attribute "RELATIVE_PROPAGATION_DELAY" ",5.00 MIL"
					( Parent
						( matchGroupRef "@baseboard_fab2_lib.baseboard_fab2(sch_1):\MG_DQ-DQS_NEAR_DIMM_NG_M_K_BYTE0\" )
					)
					( Units "uMatchProp" "ns" 1.000000)
					( Status sCSetFlattened )
					( Origin gBackEnd )
				)
			)
			( pinPair "@baseboard_fab2_lib.baseboard_fab2(sch_1):\PP1555\"
				( pinRef "@baseboard_fab2_lib.baseboard_fab2(sch_1):page60_i172:DDR3_DQS_DN(10)" )
				( pinRef "@baseboard_fab2_lib.baseboard_fab2(sch_1):page83_i66:DQS10N" )
				( attribute "RELATIVE_PROPAGATION_DELAY_SCOPE" "G"
					( Parent
						( matchGroupRef "@baseboard_fab2_lib.baseboard_fab2(sch_1):\MG_DQ-DQS_FAR_DIMM_NG_M_K_BYTE1\" )
					)
					( Status sCSetFlattened )
					( Origin gBackEnd )
				)
				( attribute "RELATIVE_PROPAGATION_DELAY" ",5.00 MIL"
					( Parent
						( matchGroupRef "@baseboard_fab2_lib.baseboard_fab2(sch_1):\MG_DQ-DQS_FAR_DIMM_NG_M_K_BYTE1\" )
					)
					( Units "uMatchProp" "ns" 1.000000)
					( Status sCSetFlattened )
					( Origin gBackEnd )
				)
			)
			( pinPair "@baseboard_fab2_lib.baseboard_fab2(sch_1):\PP1556\"
				( pinRef "@baseboard_fab2_lib.baseboard_fab2(sch_1):page84_i102:DQS10N" )
				( pinRef "@baseboard_fab2_lib.baseboard_fab2(sch_1):page60_i172:DDR3_DQS_DN(10)" )
				( attribute "RELATIVE_PROPAGATION_DELAY_SCOPE" "G"
					( Parent
						( matchGroupRef "@baseboard_fab2_lib.baseboard_fab2(sch_1):\MG_DQ-DQS_NEAR_DIMM_NG_M_K_BYTE1\" )
					)
					( Status sCSetFlattened )
					( Origin gBackEnd )
				)
				( attribute "RELATIVE_PROPAGATION_DELAY" ",5.00 MIL"
					( Parent
						( matchGroupRef "@baseboard_fab2_lib.baseboard_fab2(sch_1):\MG_DQ-DQS_NEAR_DIMM_NG_M_K_BYTE1\" )
					)
					( Units "uMatchProp" "ns" 1.000000)
					( Status sCSetFlattened )
					( Origin gBackEnd )
				)
			)
			( pinPair "@baseboard_fab2_lib.baseboard_fab2(sch_1):\PP1558\"
				( pinRef "@baseboard_fab2_lib.baseboard_fab2(sch_1):page60_i172:DDR3_DQS_DP(10)" )
				( pinRef "@baseboard_fab2_lib.baseboard_fab2(sch_1):page83_i66:DQS10P" )
				( attribute "RELATIVE_PROPAGATION_DELAY_SCOPE" "G"
					( Parent
						( matchGroupRef "@baseboard_fab2_lib.baseboard_fab2(sch_1):\MG_DQ-DQS_FAR_DIMM_NG_M_K_BYTE1\" )
					)
					( Status sCSetFlattened )
					( Origin gBackEnd )
				)
				( attribute "RELATIVE_PROPAGATION_DELAY" ",5.00 MIL"
					( Parent
						( matchGroupRef "@baseboard_fab2_lib.baseboard_fab2(sch_1):\MG_DQ-DQS_FAR_DIMM_NG_M_K_BYTE1\" )
					)
					( Units "uMatchProp" "ns" 1.000000)
					( Status sCSetFlattened )
					( Origin gBackEnd )
				)
			)
			( pinPair "@baseboard_fab2_lib.baseboard_fab2(sch_1):\PP1559\"
				( pinRef "@baseboard_fab2_lib.baseboard_fab2(sch_1):page84_i102:DQS10P" )
				( pinRef "@baseboard_fab2_lib.baseboard_fab2(sch_1):page60_i172:DDR3_DQS_DP(10)" )
				( attribute "RELATIVE_PROPAGATION_DELAY_SCOPE" "G"
					( Parent
						( matchGroupRef "@baseboard_fab2_lib.baseboard_fab2(sch_1):\MG_DQ-DQS_NEAR_DIMM_NG_M_K_BYTE1\" )
					)
					( Status sCSetFlattened )
					( Origin gBackEnd )
				)
				( attribute "RELATIVE_PROPAGATION_DELAY" ",5.00 MIL"
					( Parent
						( matchGroupRef "@baseboard_fab2_lib.baseboard_fab2(sch_1):\MG_DQ-DQS_NEAR_DIMM_NG_M_K_BYTE1\" )
					)
					( Units "uMatchProp" "ns" 1.000000)
					( Status sCSetFlattened )
					( Origin gBackEnd )
				)
			)
			( pinPair "@baseboard_fab2_lib.baseboard_fab2(sch_1):\PP1543\"
				( pinRef "@baseboard_fab2_lib.baseboard_fab2(sch_1):page60_i172:DDR3_DQS_DN(11)" )
				( pinRef "@baseboard_fab2_lib.baseboard_fab2(sch_1):page83_i66:DQS11N" )
				( attribute "RELATIVE_PROPAGATION_DELAY_SCOPE" "G"
					( Parent
						( matchGroupRef "@baseboard_fab2_lib.baseboard_fab2(sch_1):\MG_DQ-DQS_FAR_DIMM_NG_M_K_BYTE2\" )
					)
					( Status sCSetFlattened )
					( Origin gBackEnd )
				)
				( attribute "RELATIVE_PROPAGATION_DELAY" ",5.00 MIL"
					( Parent
						( matchGroupRef "@baseboard_fab2_lib.baseboard_fab2(sch_1):\MG_DQ-DQS_FAR_DIMM_NG_M_K_BYTE2\" )
					)
					( Units "uMatchProp" "ns" 1.000000)
					( Status sCSetFlattened )
					( Origin gBackEnd )
				)
			)
			( pinPair "@baseboard_fab2_lib.baseboard_fab2(sch_1):\PP1544\"
				( pinRef "@baseboard_fab2_lib.baseboard_fab2(sch_1):page84_i102:DQS11N" )
				( pinRef "@baseboard_fab2_lib.baseboard_fab2(sch_1):page60_i172:DDR3_DQS_DN(11)" )
				( attribute "RELATIVE_PROPAGATION_DELAY_SCOPE" "G"
					( Parent
						( matchGroupRef "@baseboard_fab2_lib.baseboard_fab2(sch_1):\MG_DQ-DQS_NEAR_DIMM_NG_M_K_BYTE2\" )
					)
					( Status sCSetFlattened )
					( Origin gBackEnd )
				)
				( attribute "RELATIVE_PROPAGATION_DELAY" ",5.00 MIL"
					( Parent
						( matchGroupRef "@baseboard_fab2_lib.baseboard_fab2(sch_1):\MG_DQ-DQS_NEAR_DIMM_NG_M_K_BYTE2\" )
					)
					( Units "uMatchProp" "ns" 1.000000)
					( Status sCSetFlattened )
					( Origin gBackEnd )
				)
			)
			( pinPair "@baseboard_fab2_lib.baseboard_fab2(sch_1):\PP1546\"
				( pinRef "@baseboard_fab2_lib.baseboard_fab2(sch_1):page60_i172:DDR3_DQS_DP(11)" )
				( pinRef "@baseboard_fab2_lib.baseboard_fab2(sch_1):page83_i66:DQS11P" )
				( attribute "RELATIVE_PROPAGATION_DELAY_SCOPE" "G"
					( Parent
						( matchGroupRef "@baseboard_fab2_lib.baseboard_fab2(sch_1):\MG_DQ-DQS_FAR_DIMM_NG_M_K_BYTE2\" )
					)
					( Status sCSetFlattened )
					( Origin gBackEnd )
				)
				( attribute "RELATIVE_PROPAGATION_DELAY" ",5.00 MIL"
					( Parent
						( matchGroupRef "@baseboard_fab2_lib.baseboard_fab2(sch_1):\MG_DQ-DQS_FAR_DIMM_NG_M_K_BYTE2\" )
					)
					( Units "uMatchProp" "ns" 1.000000)
					( Status sCSetFlattened )
					( Origin gBackEnd )
				)
			)
			( pinPair "@baseboard_fab2_lib.baseboard_fab2(sch_1):\PP1547\"
				( pinRef "@baseboard_fab2_lib.baseboard_fab2(sch_1):page84_i102:DQS11P" )
				( pinRef "@baseboard_fab2_lib.baseboard_fab2(sch_1):page60_i172:DDR3_DQS_DP(11)" )
				( attribute "RELATIVE_PROPAGATION_DELAY_SCOPE" "G"
					( Parent
						( matchGroupRef "@baseboard_fab2_lib.baseboard_fab2(sch_1):\MG_DQ-DQS_NEAR_DIMM_NG_M_K_BYTE2\" )
					)
					( Status sCSetFlattened )
					( Origin gBackEnd )
				)
				( attribute "RELATIVE_PROPAGATION_DELAY" ",5.00 MIL"
					( Parent
						( matchGroupRef "@baseboard_fab2_lib.baseboard_fab2(sch_1):\MG_DQ-DQS_NEAR_DIMM_NG_M_K_BYTE2\" )
					)
					( Units "uMatchProp" "ns" 1.000000)
					( Status sCSetFlattened )
					( Origin gBackEnd )
				)
			)
			( pinPair "@baseboard_fab2_lib.baseboard_fab2(sch_1):\PP1531\"
				( pinRef "@baseboard_fab2_lib.baseboard_fab2(sch_1):page60_i172:DDR3_DQS_DN(12)" )
				( pinRef "@baseboard_fab2_lib.baseboard_fab2(sch_1):page83_i66:DQS12N" )
				( attribute "RELATIVE_PROPAGATION_DELAY_SCOPE" "G"
					( Parent
						( matchGroupRef "@baseboard_fab2_lib.baseboard_fab2(sch_1):\MG_DQ-DQS_FAR_DIMM_NG_M_K_BYTE3\" )
					)
					( Status sCSetFlattened )
					( Origin gBackEnd )
				)
				( attribute "RELATIVE_PROPAGATION_DELAY" ",5.00 MIL"
					( Parent
						( matchGroupRef "@baseboard_fab2_lib.baseboard_fab2(sch_1):\MG_DQ-DQS_FAR_DIMM_NG_M_K_BYTE3\" )
					)
					( Units "uMatchProp" "ns" 1.000000)
					( Status sCSetFlattened )
					( Origin gBackEnd )
				)
			)
			( pinPair "@baseboard_fab2_lib.baseboard_fab2(sch_1):\PP1532\"
				( pinRef "@baseboard_fab2_lib.baseboard_fab2(sch_1):page84_i102:DQS12N" )
				( pinRef "@baseboard_fab2_lib.baseboard_fab2(sch_1):page60_i172:DDR3_DQS_DN(12)" )
				( attribute "RELATIVE_PROPAGATION_DELAY_SCOPE" "G"
					( Parent
						( matchGroupRef "@baseboard_fab2_lib.baseboard_fab2(sch_1):\MG_DQ-DQS_NEAR_DIMM_NG_M_K_BYTE3\" )
					)
					( Status sCSetFlattened )
					( Origin gBackEnd )
				)
				( attribute "RELATIVE_PROPAGATION_DELAY" ",5.00 MIL"
					( Parent
						( matchGroupRef "@baseboard_fab2_lib.baseboard_fab2(sch_1):\MG_DQ-DQS_NEAR_DIMM_NG_M_K_BYTE3\" )
					)
					( Units "uMatchProp" "ns" 1.000000)
					( Status sCSetFlattened )
					( Origin gBackEnd )
				)
			)
			( pinPair "@baseboard_fab2_lib.baseboard_fab2(sch_1):\PP1534\"
				( pinRef "@baseboard_fab2_lib.baseboard_fab2(sch_1):page60_i172:DDR3_DQS_DP(12)" )
				( pinRef "@baseboard_fab2_lib.baseboard_fab2(sch_1):page83_i66:DQS12P" )
				( attribute "RELATIVE_PROPAGATION_DELAY_SCOPE" "G"
					( Parent
						( matchGroupRef "@baseboard_fab2_lib.baseboard_fab2(sch_1):\MG_DQ-DQS_FAR_DIMM_NG_M_K_BYTE3\" )
					)
					( Status sCSetFlattened )
					( Origin gBackEnd )
				)
				( attribute "RELATIVE_PROPAGATION_DELAY" ",5.00 MIL"
					( Parent
						( matchGroupRef "@baseboard_fab2_lib.baseboard_fab2(sch_1):\MG_DQ-DQS_FAR_DIMM_NG_M_K_BYTE3\" )
					)
					( Units "uMatchProp" "ns" 1.000000)
					( Status sCSetFlattened )
					( Origin gBackEnd )
				)
			)
			( pinPair "@baseboard_fab2_lib.baseboard_fab2(sch_1):\PP1535\"
				( pinRef "@baseboard_fab2_lib.baseboard_fab2(sch_1):page84_i102:DQS12P" )
				( pinRef "@baseboard_fab2_lib.baseboard_fab2(sch_1):page60_i172:DDR3_DQS_DP(12)" )
				( attribute "RELATIVE_PROPAGATION_DELAY_SCOPE" "G"
					( Parent
						( matchGroupRef "@baseboard_fab2_lib.baseboard_fab2(sch_1):\MG_DQ-DQS_NEAR_DIMM_NG_M_K_BYTE3\" )
					)
					( Status sCSetFlattened )
					( Origin gBackEnd )
				)
				( attribute "RELATIVE_PROPAGATION_DELAY" ",5.00 MIL"
					( Parent
						( matchGroupRef "@baseboard_fab2_lib.baseboard_fab2(sch_1):\MG_DQ-DQS_NEAR_DIMM_NG_M_K_BYTE3\" )
					)
					( Units "uMatchProp" "ns" 1.000000)
					( Status sCSetFlattened )
					( Origin gBackEnd )
				)
			)
			( pinPair "@baseboard_fab2_lib.baseboard_fab2(sch_1):\PP1519\"
				( pinRef "@baseboard_fab2_lib.baseboard_fab2(sch_1):page60_i172:DDR3_DQS_DN(13)" )
				( pinRef "@baseboard_fab2_lib.baseboard_fab2(sch_1):page83_i66:DQS13N" )
				( attribute "RELATIVE_PROPAGATION_DELAY_SCOPE" "G"
					( Parent
						( matchGroupRef "@baseboard_fab2_lib.baseboard_fab2(sch_1):\MG_DQ-DQS_FAR_DIMM_NG_M_K_BYTE4\" )
					)
					( Status sCSetFlattened )
					( Origin gBackEnd )
				)
				( attribute "RELATIVE_PROPAGATION_DELAY" ",5.00 MIL"
					( Parent
						( matchGroupRef "@baseboard_fab2_lib.baseboard_fab2(sch_1):\MG_DQ-DQS_FAR_DIMM_NG_M_K_BYTE4\" )
					)
					( Units "uMatchProp" "ns" 1.000000)
					( Status sCSetFlattened )
					( Origin gBackEnd )
				)
			)
			( pinPair "@baseboard_fab2_lib.baseboard_fab2(sch_1):\PP1521\"
				( pinRef "@baseboard_fab2_lib.baseboard_fab2(sch_1):page84_i102:DQS13N" )
				( pinRef "@baseboard_fab2_lib.baseboard_fab2(sch_1):page60_i172:DDR3_DQS_DN(13)" )
				( attribute "RELATIVE_PROPAGATION_DELAY_SCOPE" "G"
					( Parent
						( matchGroupRef "@baseboard_fab2_lib.baseboard_fab2(sch_1):\MG_DQ-DQS_NEAR_DIMM_NG_M_K_BYTE4\" )
					)
					( Status sCSetFlattened )
					( Origin gBackEnd )
				)
				( attribute "RELATIVE_PROPAGATION_DELAY" ",5.00 MIL"
					( Parent
						( matchGroupRef "@baseboard_fab2_lib.baseboard_fab2(sch_1):\MG_DQ-DQS_NEAR_DIMM_NG_M_K_BYTE4\" )
					)
					( Units "uMatchProp" "ns" 1.000000)
					( Status sCSetFlattened )
					( Origin gBackEnd )
				)
			)
			( pinPair "@baseboard_fab2_lib.baseboard_fab2(sch_1):\PP1522\"
				( pinRef "@baseboard_fab2_lib.baseboard_fab2(sch_1):page60_i172:DDR3_DQS_DP(13)" )
				( pinRef "@baseboard_fab2_lib.baseboard_fab2(sch_1):page83_i66:DQS13P" )
				( attribute "RELATIVE_PROPAGATION_DELAY_SCOPE" "G"
					( Parent
						( matchGroupRef "@baseboard_fab2_lib.baseboard_fab2(sch_1):\MG_DQ-DQS_FAR_DIMM_NG_M_K_BYTE4\" )
					)
					( Status sCSetFlattened )
					( Origin gBackEnd )
				)
				( attribute "RELATIVE_PROPAGATION_DELAY" ",5.00 MIL"
					( Parent
						( matchGroupRef "@baseboard_fab2_lib.baseboard_fab2(sch_1):\MG_DQ-DQS_FAR_DIMM_NG_M_K_BYTE4\" )
					)
					( Units "uMatchProp" "ns" 1.000000)
					( Status sCSetFlattened )
					( Origin gBackEnd )
				)
			)
			( pinPair "@baseboard_fab2_lib.baseboard_fab2(sch_1):\PP1524\"
				( pinRef "@baseboard_fab2_lib.baseboard_fab2(sch_1):page84_i102:DQS13P" )
				( pinRef "@baseboard_fab2_lib.baseboard_fab2(sch_1):page60_i172:DDR3_DQS_DP(13)" )
				( attribute "RELATIVE_PROPAGATION_DELAY_SCOPE" "G"
					( Parent
						( matchGroupRef "@baseboard_fab2_lib.baseboard_fab2(sch_1):\MG_DQ-DQS_NEAR_DIMM_NG_M_K_BYTE4\" )
					)
					( Status sCSetFlattened )
					( Origin gBackEnd )
				)
				( attribute "RELATIVE_PROPAGATION_DELAY" ",5.00 MIL"
					( Parent
						( matchGroupRef "@baseboard_fab2_lib.baseboard_fab2(sch_1):\MG_DQ-DQS_NEAR_DIMM_NG_M_K_BYTE4\" )
					)
					( Units "uMatchProp" "ns" 1.000000)
					( Status sCSetFlattened )
					( Origin gBackEnd )
				)
			)
			( pinPair "@baseboard_fab2_lib.baseboard_fab2(sch_1):\PP1507\"
				( pinRef "@baseboard_fab2_lib.baseboard_fab2(sch_1):page60_i172:DDR3_DQS_DN(14)" )
				( pinRef "@baseboard_fab2_lib.baseboard_fab2(sch_1):page83_i66:DQS14N" )
				( attribute "RELATIVE_PROPAGATION_DELAY_SCOPE" "G"
					( Parent
						( matchGroupRef "@baseboard_fab2_lib.baseboard_fab2(sch_1):\MG_DQ-DQS_FAR_DIMM_NG_M_K_BYTE5\" )
					)
					( Status sCSetFlattened )
					( Origin gBackEnd )
				)
				( attribute "RELATIVE_PROPAGATION_DELAY" ",5.00 MIL"
					( Parent
						( matchGroupRef "@baseboard_fab2_lib.baseboard_fab2(sch_1):\MG_DQ-DQS_FAR_DIMM_NG_M_K_BYTE5\" )
					)
					( Units "uMatchProp" "ns" 1.000000)
					( Status sCSetFlattened )
					( Origin gBackEnd )
				)
			)
			( pinPair "@baseboard_fab2_lib.baseboard_fab2(sch_1):\PP1509\"
				( pinRef "@baseboard_fab2_lib.baseboard_fab2(sch_1):page84_i102:DQS14N" )
				( pinRef "@baseboard_fab2_lib.baseboard_fab2(sch_1):page60_i172:DDR3_DQS_DN(14)" )
				( attribute "RELATIVE_PROPAGATION_DELAY_SCOPE" "G"
					( Parent
						( matchGroupRef "@baseboard_fab2_lib.baseboard_fab2(sch_1):\MG_DQ-DQS_NEAR_DIMM_NG_M_K_BYTE5\" )
					)
					( Status sCSetFlattened )
					( Origin gBackEnd )
				)
				( attribute "RELATIVE_PROPAGATION_DELAY" ",5.00 MIL"
					( Parent
						( matchGroupRef "@baseboard_fab2_lib.baseboard_fab2(sch_1):\MG_DQ-DQS_NEAR_DIMM_NG_M_K_BYTE5\" )
					)
					( Units "uMatchProp" "ns" 1.000000)
					( Status sCSetFlattened )
					( Origin gBackEnd )
				)
			)
			( pinPair "@baseboard_fab2_lib.baseboard_fab2(sch_1):\PP1510\"
				( pinRef "@baseboard_fab2_lib.baseboard_fab2(sch_1):page60_i172:DDR3_DQS_DP(14)" )
				( pinRef "@baseboard_fab2_lib.baseboard_fab2(sch_1):page83_i66:DQS14P" )
				( attribute "RELATIVE_PROPAGATION_DELAY_SCOPE" "G"
					( Parent
						( matchGroupRef "@baseboard_fab2_lib.baseboard_fab2(sch_1):\MG_DQ-DQS_FAR_DIMM_NG_M_K_BYTE5\" )
					)
					( Status sCSetFlattened )
					( Origin gBackEnd )
				)
				( attribute "RELATIVE_PROPAGATION_DELAY" ",5.00 MIL"
					( Parent
						( matchGroupRef "@baseboard_fab2_lib.baseboard_fab2(sch_1):\MG_DQ-DQS_FAR_DIMM_NG_M_K_BYTE5\" )
					)
					( Units "uMatchProp" "ns" 1.000000)
					( Status sCSetFlattened )
					( Origin gBackEnd )
				)
			)
			( pinPair "@baseboard_fab2_lib.baseboard_fab2(sch_1):\PP1512\"
				( pinRef "@baseboard_fab2_lib.baseboard_fab2(sch_1):page84_i102:DQS14P" )
				( pinRef "@baseboard_fab2_lib.baseboard_fab2(sch_1):page60_i172:DDR3_DQS_DP(14)" )
				( attribute "RELATIVE_PROPAGATION_DELAY_SCOPE" "G"
					( Parent
						( matchGroupRef "@baseboard_fab2_lib.baseboard_fab2(sch_1):\MG_DQ-DQS_NEAR_DIMM_NG_M_K_BYTE5\" )
					)
					( Status sCSetFlattened )
					( Origin gBackEnd )
				)
				( attribute "RELATIVE_PROPAGATION_DELAY" ",5.00 MIL"
					( Parent
						( matchGroupRef "@baseboard_fab2_lib.baseboard_fab2(sch_1):\MG_DQ-DQS_NEAR_DIMM_NG_M_K_BYTE5\" )
					)
					( Units "uMatchProp" "ns" 1.000000)
					( Status sCSetFlattened )
					( Origin gBackEnd )
				)
			)
			( pinPair "@baseboard_fab2_lib.baseboard_fab2(sch_1):\PP1495\"
				( pinRef "@baseboard_fab2_lib.baseboard_fab2(sch_1):page60_i172:DDR3_DQS_DN(15)" )
				( pinRef "@baseboard_fab2_lib.baseboard_fab2(sch_1):page83_i66:DQS15N" )
				( attribute "RELATIVE_PROPAGATION_DELAY_SCOPE" "G"
					( Parent
						( matchGroupRef "@baseboard_fab2_lib.baseboard_fab2(sch_1):\MG_DQ-DQS_FAR_DIMM_NG_M_K_BYTE6\" )
					)
					( Status sCSetFlattened )
					( Origin gBackEnd )
				)
				( attribute "RELATIVE_PROPAGATION_DELAY" ",5.00 MIL"
					( Parent
						( matchGroupRef "@baseboard_fab2_lib.baseboard_fab2(sch_1):\MG_DQ-DQS_FAR_DIMM_NG_M_K_BYTE6\" )
					)
					( Units "uMatchProp" "ns" 1.000000)
					( Status sCSetFlattened )
					( Origin gBackEnd )
				)
			)
			( pinPair "@baseboard_fab2_lib.baseboard_fab2(sch_1):\PP1497\"
				( pinRef "@baseboard_fab2_lib.baseboard_fab2(sch_1):page84_i102:DQS15N" )
				( pinRef "@baseboard_fab2_lib.baseboard_fab2(sch_1):page60_i172:DDR3_DQS_DN(15)" )
				( attribute "RELATIVE_PROPAGATION_DELAY_SCOPE" "G"
					( Parent
						( matchGroupRef "@baseboard_fab2_lib.baseboard_fab2(sch_1):\MG_DQ-DQS_NEAR_DIMM_NG_M_K_BYTE6\" )
					)
					( Status sCSetFlattened )
					( Origin gBackEnd )
				)
				( attribute "RELATIVE_PROPAGATION_DELAY" ",5.00 MIL"
					( Parent
						( matchGroupRef "@baseboard_fab2_lib.baseboard_fab2(sch_1):\MG_DQ-DQS_NEAR_DIMM_NG_M_K_BYTE6\" )
					)
					( Units "uMatchProp" "ns" 1.000000)
					( Status sCSetFlattened )
					( Origin gBackEnd )
				)
			)
			( pinPair "@baseboard_fab2_lib.baseboard_fab2(sch_1):\PP1498\"
				( pinRef "@baseboard_fab2_lib.baseboard_fab2(sch_1):page60_i172:DDR3_DQS_DP(15)" )
				( pinRef "@baseboard_fab2_lib.baseboard_fab2(sch_1):page83_i66:DQS15P" )
				( attribute "RELATIVE_PROPAGATION_DELAY_SCOPE" "G"
					( Parent
						( matchGroupRef "@baseboard_fab2_lib.baseboard_fab2(sch_1):\MG_DQ-DQS_FAR_DIMM_NG_M_K_BYTE6\" )
					)
					( Status sCSetFlattened )
					( Origin gBackEnd )
				)
				( attribute "RELATIVE_PROPAGATION_DELAY" ",5.00 MIL"
					( Parent
						( matchGroupRef "@baseboard_fab2_lib.baseboard_fab2(sch_1):\MG_DQ-DQS_FAR_DIMM_NG_M_K_BYTE6\" )
					)
					( Units "uMatchProp" "ns" 1.000000)
					( Status sCSetFlattened )
					( Origin gBackEnd )
				)
			)
			( pinPair "@baseboard_fab2_lib.baseboard_fab2(sch_1):\PP1500\"
				( pinRef "@baseboard_fab2_lib.baseboard_fab2(sch_1):page84_i102:DQS15P" )
				( pinRef "@baseboard_fab2_lib.baseboard_fab2(sch_1):page60_i172:DDR3_DQS_DP(15)" )
				( attribute "RELATIVE_PROPAGATION_DELAY_SCOPE" "G"
					( Parent
						( matchGroupRef "@baseboard_fab2_lib.baseboard_fab2(sch_1):\MG_DQ-DQS_NEAR_DIMM_NG_M_K_BYTE6\" )
					)
					( Status sCSetFlattened )
					( Origin gBackEnd )
				)
				( attribute "RELATIVE_PROPAGATION_DELAY" ",5.00 MIL"
					( Parent
						( matchGroupRef "@baseboard_fab2_lib.baseboard_fab2(sch_1):\MG_DQ-DQS_NEAR_DIMM_NG_M_K_BYTE6\" )
					)
					( Units "uMatchProp" "ns" 1.000000)
					( Status sCSetFlattened )
					( Origin gBackEnd )
				)
			)
			( pinPair "@baseboard_fab2_lib.baseboard_fab2(sch_1):\PP1483\"
				( pinRef "@baseboard_fab2_lib.baseboard_fab2(sch_1):page60_i172:DDR3_DQS_DN(16)" )
				( pinRef "@baseboard_fab2_lib.baseboard_fab2(sch_1):page83_i66:DQS16N" )
				( attribute "RELATIVE_PROPAGATION_DELAY_SCOPE" "G"
					( Parent
						( matchGroupRef "@baseboard_fab2_lib.baseboard_fab2(sch_1):\MG_DQ-DQS_FAR_DIMM_NG_M_K_BYTE7\" )
					)
					( Status sCSetFlattened )
					( Origin gBackEnd )
				)
				( attribute "RELATIVE_PROPAGATION_DELAY" ",5.00 MIL"
					( Parent
						( matchGroupRef "@baseboard_fab2_lib.baseboard_fab2(sch_1):\MG_DQ-DQS_FAR_DIMM_NG_M_K_BYTE7\" )
					)
					( Units "uMatchProp" "ns" 1.000000)
					( Status sCSetFlattened )
					( Origin gBackEnd )
				)
			)
			( pinPair "@baseboard_fab2_lib.baseboard_fab2(sch_1):\PP1485\"
				( pinRef "@baseboard_fab2_lib.baseboard_fab2(sch_1):page84_i102:DQS16N" )
				( pinRef "@baseboard_fab2_lib.baseboard_fab2(sch_1):page60_i172:DDR3_DQS_DN(16)" )
				( attribute "RELATIVE_PROPAGATION_DELAY_SCOPE" "G"
					( Parent
						( matchGroupRef "@baseboard_fab2_lib.baseboard_fab2(sch_1):\MG_DQ-DQS_NEAR_DIMM_NG_M_K_BYTE7\" )
					)
					( Status sCSetFlattened )
					( Origin gBackEnd )
				)
				( attribute "RELATIVE_PROPAGATION_DELAY" ",5.00 MIL"
					( Parent
						( matchGroupRef "@baseboard_fab2_lib.baseboard_fab2(sch_1):\MG_DQ-DQS_NEAR_DIMM_NG_M_K_BYTE7\" )
					)
					( Units "uMatchProp" "ns" 1.000000)
					( Status sCSetFlattened )
					( Origin gBackEnd )
				)
			)
			( pinPair "@baseboard_fab2_lib.baseboard_fab2(sch_1):\PP1486\"
				( pinRef "@baseboard_fab2_lib.baseboard_fab2(sch_1):page60_i172:DDR3_DQS_DP(16)" )
				( pinRef "@baseboard_fab2_lib.baseboard_fab2(sch_1):page83_i66:DQS16P" )
				( attribute "RELATIVE_PROPAGATION_DELAY_SCOPE" "G"
					( Parent
						( matchGroupRef "@baseboard_fab2_lib.baseboard_fab2(sch_1):\MG_DQ-DQS_FAR_DIMM_NG_M_K_BYTE7\" )
					)
					( Status sCSetFlattened )
					( Origin gBackEnd )
				)
				( attribute "RELATIVE_PROPAGATION_DELAY" ",5.00 MIL"
					( Parent
						( matchGroupRef "@baseboard_fab2_lib.baseboard_fab2(sch_1):\MG_DQ-DQS_FAR_DIMM_NG_M_K_BYTE7\" )
					)
					( Units "uMatchProp" "ns" 1.000000)
					( Status sCSetFlattened )
					( Origin gBackEnd )
				)
			)
			( pinPair "@baseboard_fab2_lib.baseboard_fab2(sch_1):\PP1488\"
				( pinRef "@baseboard_fab2_lib.baseboard_fab2(sch_1):page84_i102:DQS16P" )
				( pinRef "@baseboard_fab2_lib.baseboard_fab2(sch_1):page60_i172:DDR3_DQS_DP(16)" )
				( attribute "RELATIVE_PROPAGATION_DELAY_SCOPE" "G"
					( Parent
						( matchGroupRef "@baseboard_fab2_lib.baseboard_fab2(sch_1):\MG_DQ-DQS_NEAR_DIMM_NG_M_K_BYTE7\" )
					)
					( Status sCSetFlattened )
					( Origin gBackEnd )
				)
				( attribute "RELATIVE_PROPAGATION_DELAY" ",5.00 MIL"
					( Parent
						( matchGroupRef "@baseboard_fab2_lib.baseboard_fab2(sch_1):\MG_DQ-DQS_NEAR_DIMM_NG_M_K_BYTE7\" )
					)
					( Units "uMatchProp" "ns" 1.000000)
					( Status sCSetFlattened )
					( Origin gBackEnd )
				)
			)
			( pinPair "@baseboard_fab2_lib.baseboard_fab2(sch_1):\PP1255\"
				( pinRef "@baseboard_fab2_lib.baseboard_fab2(sch_1):page60_i172:DDR3_DQS_DN(17)" )
				( pinRef "@baseboard_fab2_lib.baseboard_fab2(sch_1):page83_i66:DQS17N" )
				( attribute "RELATIVE_PROPAGATION_DELAY_SCOPE" "G"
					( Parent
						( matchGroupRef "@baseboard_fab2_lib.baseboard_fab2(sch_1):\MG_DQ-DQS_FAR_DIMM_NG_M_K_BYTE-ECC\" )
					)
					( Status sCSetFlattened )
					( Origin gBackEnd )
				)
				( attribute "RELATIVE_PROPAGATION_DELAY" ",5.00 MIL"
					( Parent
						( matchGroupRef "@baseboard_fab2_lib.baseboard_fab2(sch_1):\MG_DQ-DQS_FAR_DIMM_NG_M_K_BYTE-ECC\" )
					)
					( Units "uMatchProp" "ns" 1.000000)
					( Status sCSetFlattened )
					( Origin gBackEnd )
				)
			)
			( pinPair "@baseboard_fab2_lib.baseboard_fab2(sch_1):\PP1256\"
				( pinRef "@baseboard_fab2_lib.baseboard_fab2(sch_1):page84_i102:DQS17N" )
				( pinRef "@baseboard_fab2_lib.baseboard_fab2(sch_1):page60_i172:DDR3_DQS_DN(17)" )
				( attribute "RELATIVE_PROPAGATION_DELAY_SCOPE" "G"
					( Parent
						( matchGroupRef "@baseboard_fab2_lib.baseboard_fab2(sch_1):\MG_DQ-DQS_NEAR_DIMM_NG_M_K_BYTE-ECC\" )
					)
					( Status sCSetFlattened )
					( Origin gBackEnd )
				)
				( attribute "RELATIVE_PROPAGATION_DELAY" ",5.00 MIL"
					( Parent
						( matchGroupRef "@baseboard_fab2_lib.baseboard_fab2(sch_1):\MG_DQ-DQS_NEAR_DIMM_NG_M_K_BYTE-ECC\" )
					)
					( Units "uMatchProp" "ns" 1.000000)
					( Status sCSetFlattened )
					( Origin gBackEnd )
				)
			)
			( pinPair "@baseboard_fab2_lib.baseboard_fab2(sch_1):\PP1258\"
				( pinRef "@baseboard_fab2_lib.baseboard_fab2(sch_1):page60_i172:DDR3_DQS_DP(17)" )
				( pinRef "@baseboard_fab2_lib.baseboard_fab2(sch_1):page83_i66:DQS17P" )
				( attribute "RELATIVE_PROPAGATION_DELAY_SCOPE" "G"
					( Parent
						( matchGroupRef "@baseboard_fab2_lib.baseboard_fab2(sch_1):\MG_DQ-DQS_FAR_DIMM_NG_M_K_BYTE-ECC\" )
					)
					( Status sCSetFlattened )
					( Origin gBackEnd )
				)
				( attribute "RELATIVE_PROPAGATION_DELAY" ",5.00 MIL"
					( Parent
						( matchGroupRef "@baseboard_fab2_lib.baseboard_fab2(sch_1):\MG_DQ-DQS_FAR_DIMM_NG_M_K_BYTE-ECC\" )
					)
					( Units "uMatchProp" "ns" 1.000000)
					( Status sCSetFlattened )
					( Origin gBackEnd )
				)
			)
			( pinPair "@baseboard_fab2_lib.baseboard_fab2(sch_1):\PP1259\"
				( pinRef "@baseboard_fab2_lib.baseboard_fab2(sch_1):page84_i102:DQS17P" )
				( pinRef "@baseboard_fab2_lib.baseboard_fab2(sch_1):page60_i172:DDR3_DQS_DP(17)" )
				( attribute "RELATIVE_PROPAGATION_DELAY_SCOPE" "G"
					( Parent
						( matchGroupRef "@baseboard_fab2_lib.baseboard_fab2(sch_1):\MG_DQ-DQS_NEAR_DIMM_NG_M_K_BYTE-ECC\" )
					)
					( Status sCSetFlattened )
					( Origin gBackEnd )
				)
				( attribute "RELATIVE_PROPAGATION_DELAY" ",5.00 MIL"
					( Parent
						( matchGroupRef "@baseboard_fab2_lib.baseboard_fab2(sch_1):\MG_DQ-DQS_NEAR_DIMM_NG_M_K_BYTE-ECC\" )
					)
					( Units "uMatchProp" "ns" 1.000000)
					( Status sCSetFlattened )
					( Origin gBackEnd )
				)
			)
			( pinPair "@baseboard_fab2_lib.baseboard_fab2(sch_1):\PP1477\"
				( pinRef "@baseboard_fab2_lib.baseboard_fab2(sch_1):page61_i172:DDR4_DQS_DN(0)" )
				( pinRef "@baseboard_fab2_lib.baseboard_fab2(sch_1):page85_i66:DQS0N" )
				( attribute "RELATIVE_PROPAGATION_DELAY_SCOPE" "G"
					( Parent
						( matchGroupRef "@baseboard_fab2_lib.baseboard_fab2(sch_1):\MG_DQ-DQS_FAR_DIMM_NG_M_L_BYTE0\" )
					)
					( Status sCSetFlattened )
					( Origin gBackEnd )
				)
				( attribute "RELATIVE_PROPAGATION_DELAY" ",5.00 MIL"
					( Parent
						( matchGroupRef "@baseboard_fab2_lib.baseboard_fab2(sch_1):\MG_DQ-DQS_FAR_DIMM_NG_M_L_BYTE0\" )
					)
					( Units "uMatchProp" "ns" 1.000000)
					( Status sCSetFlattened )
					( Origin gBackEnd )
				)
			)
			( pinPair "@baseboard_fab2_lib.baseboard_fab2(sch_1):\PP1478\"
				( pinRef "@baseboard_fab2_lib.baseboard_fab2(sch_1):page86_i100:DQS0N" )
				( pinRef "@baseboard_fab2_lib.baseboard_fab2(sch_1):page61_i172:DDR4_DQS_DN(0)" )
				( attribute "RELATIVE_PROPAGATION_DELAY_SCOPE" "G"
					( Parent
						( matchGroupRef "@baseboard_fab2_lib.baseboard_fab2(sch_1):\MG_DQ-DQS_NEAR_DIMM_NG_M_L_BYTE0\" )
					)
					( Status sCSetFlattened )
					( Origin gBackEnd )
				)
				( attribute "RELATIVE_PROPAGATION_DELAY" ",5.00 MIL"
					( Parent
						( matchGroupRef "@baseboard_fab2_lib.baseboard_fab2(sch_1):\MG_DQ-DQS_NEAR_DIMM_NG_M_L_BYTE0\" )
					)
					( Units "uMatchProp" "ns" 1.000000)
					( Status sCSetFlattened )
					( Origin gBackEnd )
				)
			)
			( pinPair "@baseboard_fab2_lib.baseboard_fab2(sch_1):\PP1480\"
				( pinRef "@baseboard_fab2_lib.baseboard_fab2(sch_1):page61_i172:DDR4_DQS_DP(0)" )
				( pinRef "@baseboard_fab2_lib.baseboard_fab2(sch_1):page85_i66:DQS0P" )
				( attribute "RELATIVE_PROPAGATION_DELAY_SCOPE" "G"
					( Parent
						( matchGroupRef "@baseboard_fab2_lib.baseboard_fab2(sch_1):\MG_DQ-DQS_FAR_DIMM_NG_M_L_BYTE0\" )
					)
					( Status sCSetFlattened )
					( Origin gBackEnd )
				)
				( attribute "RELATIVE_PROPAGATION_DELAY" ",5.00 MIL"
					( Parent
						( matchGroupRef "@baseboard_fab2_lib.baseboard_fab2(sch_1):\MG_DQ-DQS_FAR_DIMM_NG_M_L_BYTE0\" )
					)
					( Units "uMatchProp" "ns" 1.000000)
					( Status sCSetFlattened )
					( Origin gBackEnd )
				)
			)
			( pinPair "@baseboard_fab2_lib.baseboard_fab2(sch_1):\PP1481\"
				( pinRef "@baseboard_fab2_lib.baseboard_fab2(sch_1):page86_i100:DQS0P" )
				( pinRef "@baseboard_fab2_lib.baseboard_fab2(sch_1):page61_i172:DDR4_DQS_DP(0)" )
				( attribute "RELATIVE_PROPAGATION_DELAY_SCOPE" "G"
					( Parent
						( matchGroupRef "@baseboard_fab2_lib.baseboard_fab2(sch_1):\MG_DQ-DQS_NEAR_DIMM_NG_M_L_BYTE0\" )
					)
					( Status sCSetFlattened )
					( Origin gBackEnd )
				)
				( attribute "RELATIVE_PROPAGATION_DELAY" ",5.00 MIL"
					( Parent
						( matchGroupRef "@baseboard_fab2_lib.baseboard_fab2(sch_1):\MG_DQ-DQS_NEAR_DIMM_NG_M_L_BYTE0\" )
					)
					( Units "uMatchProp" "ns" 1.000000)
					( Status sCSetFlattened )
					( Origin gBackEnd )
				)
			)
			( pinPair "@baseboard_fab2_lib.baseboard_fab2(sch_1):\PP1465\"
				( pinRef "@baseboard_fab2_lib.baseboard_fab2(sch_1):page61_i172:DDR4_DQS_DN(1)" )
				( pinRef "@baseboard_fab2_lib.baseboard_fab2(sch_1):page85_i66:DQS1N" )
				( attribute "RELATIVE_PROPAGATION_DELAY_SCOPE" "G"
					( Parent
						( matchGroupRef "@baseboard_fab2_lib.baseboard_fab2(sch_1):\MG_DQ-DQS_FAR_DIMM_NG_M_L_BYTE1\" )
					)
					( Status sCSetFlattened )
					( Origin gBackEnd )
				)
				( attribute "RELATIVE_PROPAGATION_DELAY" ",5.00 MIL"
					( Parent
						( matchGroupRef "@baseboard_fab2_lib.baseboard_fab2(sch_1):\MG_DQ-DQS_FAR_DIMM_NG_M_L_BYTE1\" )
					)
					( Units "uMatchProp" "ns" 1.000000)
					( Status sCSetFlattened )
					( Origin gBackEnd )
				)
			)
			( pinPair "@baseboard_fab2_lib.baseboard_fab2(sch_1):\PP1466\"
				( pinRef "@baseboard_fab2_lib.baseboard_fab2(sch_1):page86_i100:DQS1N" )
				( pinRef "@baseboard_fab2_lib.baseboard_fab2(sch_1):page61_i172:DDR4_DQS_DN(1)" )
				( attribute "RELATIVE_PROPAGATION_DELAY_SCOPE" "G"
					( Parent
						( matchGroupRef "@baseboard_fab2_lib.baseboard_fab2(sch_1):\MG_DQ-DQS_NEAR_DIMM_NG_M_L_BYTE1\" )
					)
					( Status sCSetFlattened )
					( Origin gBackEnd )
				)
				( attribute "RELATIVE_PROPAGATION_DELAY" ",5.00 MIL"
					( Parent
						( matchGroupRef "@baseboard_fab2_lib.baseboard_fab2(sch_1):\MG_DQ-DQS_NEAR_DIMM_NG_M_L_BYTE1\" )
					)
					( Units "uMatchProp" "ns" 1.000000)
					( Status sCSetFlattened )
					( Origin gBackEnd )
				)
			)
			( pinPair "@baseboard_fab2_lib.baseboard_fab2(sch_1):\PP1468\"
				( pinRef "@baseboard_fab2_lib.baseboard_fab2(sch_1):page61_i172:DDR4_DQS_DP(1)" )
				( pinRef "@baseboard_fab2_lib.baseboard_fab2(sch_1):page85_i66:DQS1P" )
				( attribute "RELATIVE_PROPAGATION_DELAY_SCOPE" "G"
					( Parent
						( matchGroupRef "@baseboard_fab2_lib.baseboard_fab2(sch_1):\MG_DQ-DQS_FAR_DIMM_NG_M_L_BYTE1\" )
					)
					( Status sCSetFlattened )
					( Origin gBackEnd )
				)
				( attribute "RELATIVE_PROPAGATION_DELAY" ",5.00 MIL"
					( Parent
						( matchGroupRef "@baseboard_fab2_lib.baseboard_fab2(sch_1):\MG_DQ-DQS_FAR_DIMM_NG_M_L_BYTE1\" )
					)
					( Units "uMatchProp" "ns" 1.000000)
					( Status sCSetFlattened )
					( Origin gBackEnd )
				)
			)
			( pinPair "@baseboard_fab2_lib.baseboard_fab2(sch_1):\PP1469\"
				( pinRef "@baseboard_fab2_lib.baseboard_fab2(sch_1):page86_i100:DQS1P" )
				( pinRef "@baseboard_fab2_lib.baseboard_fab2(sch_1):page61_i172:DDR4_DQS_DP(1)" )
				( attribute "RELATIVE_PROPAGATION_DELAY_SCOPE" "G"
					( Parent
						( matchGroupRef "@baseboard_fab2_lib.baseboard_fab2(sch_1):\MG_DQ-DQS_NEAR_DIMM_NG_M_L_BYTE1\" )
					)
					( Status sCSetFlattened )
					( Origin gBackEnd )
				)
				( attribute "RELATIVE_PROPAGATION_DELAY" ",5.00 MIL"
					( Parent
						( matchGroupRef "@baseboard_fab2_lib.baseboard_fab2(sch_1):\MG_DQ-DQS_NEAR_DIMM_NG_M_L_BYTE1\" )
					)
					( Units "uMatchProp" "ns" 1.000000)
					( Status sCSetFlattened )
					( Origin gBackEnd )
				)
			)
			( pinPair "@baseboard_fab2_lib.baseboard_fab2(sch_1):\PP1453\"
				( pinRef "@baseboard_fab2_lib.baseboard_fab2(sch_1):page61_i172:DDR4_DQS_DN(2)" )
				( pinRef "@baseboard_fab2_lib.baseboard_fab2(sch_1):page85_i66:DQS2N" )
				( attribute "RELATIVE_PROPAGATION_DELAY_SCOPE" "G"
					( Parent
						( matchGroupRef "@baseboard_fab2_lib.baseboard_fab2(sch_1):\MG_DQ-DQS_FAR_DIMM_NG_M_L_BYTE2\" )
					)
					( Status sCSetFlattened )
					( Origin gBackEnd )
				)
				( attribute "RELATIVE_PROPAGATION_DELAY" ",5.00 MIL"
					( Parent
						( matchGroupRef "@baseboard_fab2_lib.baseboard_fab2(sch_1):\MG_DQ-DQS_FAR_DIMM_NG_M_L_BYTE2\" )
					)
					( Units "uMatchProp" "ns" 1.000000)
					( Status sCSetFlattened )
					( Origin gBackEnd )
				)
			)
			( pinPair "@baseboard_fab2_lib.baseboard_fab2(sch_1):\PP1454\"
				( pinRef "@baseboard_fab2_lib.baseboard_fab2(sch_1):page86_i100:DQS2N" )
				( pinRef "@baseboard_fab2_lib.baseboard_fab2(sch_1):page61_i172:DDR4_DQS_DN(2)" )
				( attribute "RELATIVE_PROPAGATION_DELAY_SCOPE" "G"
					( Parent
						( matchGroupRef "@baseboard_fab2_lib.baseboard_fab2(sch_1):\MG_DQ-DQS_NEAR_DIMM_NG_M_L_BYTE2\" )
					)
					( Status sCSetFlattened )
					( Origin gBackEnd )
				)
				( attribute "RELATIVE_PROPAGATION_DELAY" ",5.00 MIL"
					( Parent
						( matchGroupRef "@baseboard_fab2_lib.baseboard_fab2(sch_1):\MG_DQ-DQS_NEAR_DIMM_NG_M_L_BYTE2\" )
					)
					( Units "uMatchProp" "ns" 1.000000)
					( Status sCSetFlattened )
					( Origin gBackEnd )
				)
			)
			( pinPair "@baseboard_fab2_lib.baseboard_fab2(sch_1):\PP1456\"
				( pinRef "@baseboard_fab2_lib.baseboard_fab2(sch_1):page61_i172:DDR4_DQS_DP(2)" )
				( pinRef "@baseboard_fab2_lib.baseboard_fab2(sch_1):page85_i66:DQS2P" )
				( attribute "RELATIVE_PROPAGATION_DELAY_SCOPE" "G"
					( Parent
						( matchGroupRef "@baseboard_fab2_lib.baseboard_fab2(sch_1):\MG_DQ-DQS_FAR_DIMM_NG_M_L_BYTE2\" )
					)
					( Status sCSetFlattened )
					( Origin gBackEnd )
				)
				( attribute "RELATIVE_PROPAGATION_DELAY" ",5.00 MIL"
					( Parent
						( matchGroupRef "@baseboard_fab2_lib.baseboard_fab2(sch_1):\MG_DQ-DQS_FAR_DIMM_NG_M_L_BYTE2\" )
					)
					( Units "uMatchProp" "ns" 1.000000)
					( Status sCSetFlattened )
					( Origin gBackEnd )
				)
			)
			( pinPair "@baseboard_fab2_lib.baseboard_fab2(sch_1):\PP1457\"
				( pinRef "@baseboard_fab2_lib.baseboard_fab2(sch_1):page86_i100:DQS2P" )
				( pinRef "@baseboard_fab2_lib.baseboard_fab2(sch_1):page61_i172:DDR4_DQS_DP(2)" )
				( attribute "RELATIVE_PROPAGATION_DELAY_SCOPE" "G"
					( Parent
						( matchGroupRef "@baseboard_fab2_lib.baseboard_fab2(sch_1):\MG_DQ-DQS_NEAR_DIMM_NG_M_L_BYTE2\" )
					)
					( Status sCSetFlattened )
					( Origin gBackEnd )
				)
				( attribute "RELATIVE_PROPAGATION_DELAY" ",5.00 MIL"
					( Parent
						( matchGroupRef "@baseboard_fab2_lib.baseboard_fab2(sch_1):\MG_DQ-DQS_NEAR_DIMM_NG_M_L_BYTE2\" )
					)
					( Units "uMatchProp" "ns" 1.000000)
					( Status sCSetFlattened )
					( Origin gBackEnd )
				)
			)
			( pinPair "@baseboard_fab2_lib.baseboard_fab2(sch_1):\PP1441\"
				( pinRef "@baseboard_fab2_lib.baseboard_fab2(sch_1):page61_i172:DDR4_DQS_DN(3)" )
				( pinRef "@baseboard_fab2_lib.baseboard_fab2(sch_1):page85_i66:DQS3N" )
				( attribute "RELATIVE_PROPAGATION_DELAY_SCOPE" "G"
					( Parent
						( matchGroupRef "@baseboard_fab2_lib.baseboard_fab2(sch_1):\MG_DQ-DQS_FAR_DIMM_NG_M_L_BYTE3\" )
					)
					( Status sCSetFlattened )
					( Origin gBackEnd )
				)
				( attribute "RELATIVE_PROPAGATION_DELAY" ",5.00 MIL"
					( Parent
						( matchGroupRef "@baseboard_fab2_lib.baseboard_fab2(sch_1):\MG_DQ-DQS_FAR_DIMM_NG_M_L_BYTE3\" )
					)
					( Units "uMatchProp" "ns" 1.000000)
					( Status sCSetFlattened )
					( Origin gBackEnd )
				)
			)
			( pinPair "@baseboard_fab2_lib.baseboard_fab2(sch_1):\PP1442\"
				( pinRef "@baseboard_fab2_lib.baseboard_fab2(sch_1):page86_i100:DQS3N" )
				( pinRef "@baseboard_fab2_lib.baseboard_fab2(sch_1):page61_i172:DDR4_DQS_DN(3)" )
				( attribute "RELATIVE_PROPAGATION_DELAY_SCOPE" "G"
					( Parent
						( matchGroupRef "@baseboard_fab2_lib.baseboard_fab2(sch_1):\MG_DQ-DQS_NEAR_DIMM_NG_M_L_BYTE3\" )
					)
					( Status sCSetFlattened )
					( Origin gBackEnd )
				)
				( attribute "RELATIVE_PROPAGATION_DELAY" ",5.00 MIL"
					( Parent
						( matchGroupRef "@baseboard_fab2_lib.baseboard_fab2(sch_1):\MG_DQ-DQS_NEAR_DIMM_NG_M_L_BYTE3\" )
					)
					( Units "uMatchProp" "ns" 1.000000)
					( Status sCSetFlattened )
					( Origin gBackEnd )
				)
			)
			( pinPair "@baseboard_fab2_lib.baseboard_fab2(sch_1):\PP1444\"
				( pinRef "@baseboard_fab2_lib.baseboard_fab2(sch_1):page61_i172:DDR4_DQS_DP(3)" )
				( pinRef "@baseboard_fab2_lib.baseboard_fab2(sch_1):page85_i66:DQS3P" )
				( attribute "RELATIVE_PROPAGATION_DELAY_SCOPE" "G"
					( Parent
						( matchGroupRef "@baseboard_fab2_lib.baseboard_fab2(sch_1):\MG_DQ-DQS_FAR_DIMM_NG_M_L_BYTE3\" )
					)
					( Status sCSetFlattened )
					( Origin gBackEnd )
				)
				( attribute "RELATIVE_PROPAGATION_DELAY" ",5.00 MIL"
					( Parent
						( matchGroupRef "@baseboard_fab2_lib.baseboard_fab2(sch_1):\MG_DQ-DQS_FAR_DIMM_NG_M_L_BYTE3\" )
					)
					( Units "uMatchProp" "ns" 1.000000)
					( Status sCSetFlattened )
					( Origin gBackEnd )
				)
			)
			( pinPair "@baseboard_fab2_lib.baseboard_fab2(sch_1):\PP1445\"
				( pinRef "@baseboard_fab2_lib.baseboard_fab2(sch_1):page86_i100:DQS3P" )
				( pinRef "@baseboard_fab2_lib.baseboard_fab2(sch_1):page61_i172:DDR4_DQS_DP(3)" )
				( attribute "RELATIVE_PROPAGATION_DELAY_SCOPE" "G"
					( Parent
						( matchGroupRef "@baseboard_fab2_lib.baseboard_fab2(sch_1):\MG_DQ-DQS_NEAR_DIMM_NG_M_L_BYTE3\" )
					)
					( Status sCSetFlattened )
					( Origin gBackEnd )
				)
				( attribute "RELATIVE_PROPAGATION_DELAY" ",5.00 MIL"
					( Parent
						( matchGroupRef "@baseboard_fab2_lib.baseboard_fab2(sch_1):\MG_DQ-DQS_NEAR_DIMM_NG_M_L_BYTE3\" )
					)
					( Units "uMatchProp" "ns" 1.000000)
					( Status sCSetFlattened )
					( Origin gBackEnd )
				)
			)
			( pinPair "@baseboard_fab2_lib.baseboard_fab2(sch_1):\PP1429\"
				( pinRef "@baseboard_fab2_lib.baseboard_fab2(sch_1):page61_i172:DDR4_DQS_DN(4)" )
				( pinRef "@baseboard_fab2_lib.baseboard_fab2(sch_1):page85_i66:DQS4N" )
				( attribute "RELATIVE_PROPAGATION_DELAY_SCOPE" "G"
					( Parent
						( matchGroupRef "@baseboard_fab2_lib.baseboard_fab2(sch_1):\MG_DQ-DQS_FAR_DIMM_NG_M_L_BYTE4\" )
					)
					( Status sCSetFlattened )
					( Origin gBackEnd )
				)
				( attribute "RELATIVE_PROPAGATION_DELAY" ",5.00 MIL"
					( Parent
						( matchGroupRef "@baseboard_fab2_lib.baseboard_fab2(sch_1):\MG_DQ-DQS_FAR_DIMM_NG_M_L_BYTE4\" )
					)
					( Units "uMatchProp" "ns" 1.000000)
					( Status sCSetFlattened )
					( Origin gBackEnd )
				)
			)
			( pinPair "@baseboard_fab2_lib.baseboard_fab2(sch_1):\PP1431\"
				( pinRef "@baseboard_fab2_lib.baseboard_fab2(sch_1):page61_i172:DDR4_DQS_DN(4)" )
				( pinRef "@baseboard_fab2_lib.baseboard_fab2(sch_1):page86_i100:DQS4N" )
				( attribute "RELATIVE_PROPAGATION_DELAY_SCOPE" "G"
					( Parent
						( matchGroupRef "@baseboard_fab2_lib.baseboard_fab2(sch_1):\MG_DQ-DQS_NEAR_DIMM_NG_M_L_BYTE4\" )
					)
					( Status sCSetFlattened )
					( Origin gBackEnd )
				)
				( attribute "RELATIVE_PROPAGATION_DELAY" ",5.00 MIL"
					( Parent
						( matchGroupRef "@baseboard_fab2_lib.baseboard_fab2(sch_1):\MG_DQ-DQS_NEAR_DIMM_NG_M_L_BYTE4\" )
					)
					( Units "uMatchProp" "ns" 1.000000)
					( Status sCSetFlattened )
					( Origin gBackEnd )
				)
			)
			( pinPair "@baseboard_fab2_lib.baseboard_fab2(sch_1):\PP1432\"
				( pinRef "@baseboard_fab2_lib.baseboard_fab2(sch_1):page61_i172:DDR4_DQS_DP(4)" )
				( pinRef "@baseboard_fab2_lib.baseboard_fab2(sch_1):page85_i66:DQS4P" )
				( attribute "RELATIVE_PROPAGATION_DELAY_SCOPE" "G"
					( Parent
						( matchGroupRef "@baseboard_fab2_lib.baseboard_fab2(sch_1):\MG_DQ-DQS_FAR_DIMM_NG_M_L_BYTE4\" )
					)
					( Status sCSetFlattened )
					( Origin gBackEnd )
				)
				( attribute "RELATIVE_PROPAGATION_DELAY" ",5.00 MIL"
					( Parent
						( matchGroupRef "@baseboard_fab2_lib.baseboard_fab2(sch_1):\MG_DQ-DQS_FAR_DIMM_NG_M_L_BYTE4\" )
					)
					( Units "uMatchProp" "ns" 1.000000)
					( Status sCSetFlattened )
					( Origin gBackEnd )
				)
			)
			( pinPair "@baseboard_fab2_lib.baseboard_fab2(sch_1):\PP1434\"
				( pinRef "@baseboard_fab2_lib.baseboard_fab2(sch_1):page86_i100:DQS4P" )
				( pinRef "@baseboard_fab2_lib.baseboard_fab2(sch_1):page61_i172:DDR4_DQS_DP(4)" )
				( attribute "RELATIVE_PROPAGATION_DELAY_SCOPE" "G"
					( Parent
						( matchGroupRef "@baseboard_fab2_lib.baseboard_fab2(sch_1):\MG_DQ-DQS_NEAR_DIMM_NG_M_L_BYTE4\" )
					)
					( Status sCSetFlattened )
					( Origin gBackEnd )
				)
				( attribute "RELATIVE_PROPAGATION_DELAY" ",5.00 MIL"
					( Parent
						( matchGroupRef "@baseboard_fab2_lib.baseboard_fab2(sch_1):\MG_DQ-DQS_NEAR_DIMM_NG_M_L_BYTE4\" )
					)
					( Units "uMatchProp" "ns" 1.000000)
					( Status sCSetFlattened )
					( Origin gBackEnd )
				)
			)
			( pinPair "@baseboard_fab2_lib.baseboard_fab2(sch_1):\PP1417\"
				( pinRef "@baseboard_fab2_lib.baseboard_fab2(sch_1):page61_i172:DDR4_DQS_DN(5)" )
				( pinRef "@baseboard_fab2_lib.baseboard_fab2(sch_1):page85_i66:DQS5N" )
				( attribute "RELATIVE_PROPAGATION_DELAY_SCOPE" "G"
					( Parent
						( matchGroupRef "@baseboard_fab2_lib.baseboard_fab2(sch_1):\MG_DQ-DQS_FAR_DIMM_NG_M_L_BYTE5\" )
					)
					( Status sCSetFlattened )
					( Origin gBackEnd )
				)
				( attribute "RELATIVE_PROPAGATION_DELAY" ",5.00 MIL"
					( Parent
						( matchGroupRef "@baseboard_fab2_lib.baseboard_fab2(sch_1):\MG_DQ-DQS_FAR_DIMM_NG_M_L_BYTE5\" )
					)
					( Units "uMatchProp" "ns" 1.000000)
					( Status sCSetFlattened )
					( Origin gBackEnd )
				)
			)
			( pinPair "@baseboard_fab2_lib.baseboard_fab2(sch_1):\PP1419\"
				( pinRef "@baseboard_fab2_lib.baseboard_fab2(sch_1):page86_i100:DQS5N" )
				( pinRef "@baseboard_fab2_lib.baseboard_fab2(sch_1):page61_i172:DDR4_DQS_DN(5)" )
				( attribute "RELATIVE_PROPAGATION_DELAY_SCOPE" "G"
					( Parent
						( matchGroupRef "@baseboard_fab2_lib.baseboard_fab2(sch_1):\MG_DQ-DQS_NEAR_DIMM_NG_M_L_BYTE5\" )
					)
					( Status sCSetFlattened )
					( Origin gBackEnd )
				)
				( attribute "RELATIVE_PROPAGATION_DELAY" ",5.00 MIL"
					( Parent
						( matchGroupRef "@baseboard_fab2_lib.baseboard_fab2(sch_1):\MG_DQ-DQS_NEAR_DIMM_NG_M_L_BYTE5\" )
					)
					( Units "uMatchProp" "ns" 1.000000)
					( Status sCSetFlattened )
					( Origin gBackEnd )
				)
			)
			( pinPair "@baseboard_fab2_lib.baseboard_fab2(sch_1):\PP1420\"
				( pinRef "@baseboard_fab2_lib.baseboard_fab2(sch_1):page61_i172:DDR4_DQS_DP(5)" )
				( pinRef "@baseboard_fab2_lib.baseboard_fab2(sch_1):page85_i66:DQS5P" )
				( attribute "RELATIVE_PROPAGATION_DELAY_SCOPE" "G"
					( Parent
						( matchGroupRef "@baseboard_fab2_lib.baseboard_fab2(sch_1):\MG_DQ-DQS_FAR_DIMM_NG_M_L_BYTE5\" )
					)
					( Status sCSetFlattened )
					( Origin gBackEnd )
				)
				( attribute "RELATIVE_PROPAGATION_DELAY" ",5.00 MIL"
					( Parent
						( matchGroupRef "@baseboard_fab2_lib.baseboard_fab2(sch_1):\MG_DQ-DQS_FAR_DIMM_NG_M_L_BYTE5\" )
					)
					( Units "uMatchProp" "ns" 1.000000)
					( Status sCSetFlattened )
					( Origin gBackEnd )
				)
			)
			( pinPair "@baseboard_fab2_lib.baseboard_fab2(sch_1):\PP1422\"
				( pinRef "@baseboard_fab2_lib.baseboard_fab2(sch_1):page86_i100:DQS5P" )
				( pinRef "@baseboard_fab2_lib.baseboard_fab2(sch_1):page61_i172:DDR4_DQS_DP(5)" )
				( attribute "RELATIVE_PROPAGATION_DELAY_SCOPE" "G"
					( Parent
						( matchGroupRef "@baseboard_fab2_lib.baseboard_fab2(sch_1):\MG_DQ-DQS_NEAR_DIMM_NG_M_L_BYTE5\" )
					)
					( Status sCSetFlattened )
					( Origin gBackEnd )
				)
				( attribute "RELATIVE_PROPAGATION_DELAY" ",5.00 MIL"
					( Parent
						( matchGroupRef "@baseboard_fab2_lib.baseboard_fab2(sch_1):\MG_DQ-DQS_NEAR_DIMM_NG_M_L_BYTE5\" )
					)
					( Units "uMatchProp" "ns" 1.000000)
					( Status sCSetFlattened )
					( Origin gBackEnd )
				)
			)
			( pinPair "@baseboard_fab2_lib.baseboard_fab2(sch_1):\PP1405\"
				( pinRef "@baseboard_fab2_lib.baseboard_fab2(sch_1):page61_i172:DDR4_DQS_DN(6)" )
				( pinRef "@baseboard_fab2_lib.baseboard_fab2(sch_1):page85_i66:DQS6N" )
				( attribute "RELATIVE_PROPAGATION_DELAY_SCOPE" "G"
					( Parent
						( matchGroupRef "@baseboard_fab2_lib.baseboard_fab2(sch_1):\MG_DQ-DQS_FAR_DIMM_NG_M_L_BYTE6\" )
					)
					( Status sCSetFlattened )
					( Origin gBackEnd )
				)
				( attribute "RELATIVE_PROPAGATION_DELAY" ",5.00 MIL"
					( Parent
						( matchGroupRef "@baseboard_fab2_lib.baseboard_fab2(sch_1):\MG_DQ-DQS_FAR_DIMM_NG_M_L_BYTE6\" )
					)
					( Units "uMatchProp" "ns" 1.000000)
					( Status sCSetFlattened )
					( Origin gBackEnd )
				)
			)
			( pinPair "@baseboard_fab2_lib.baseboard_fab2(sch_1):\PP1407\"
				( pinRef "@baseboard_fab2_lib.baseboard_fab2(sch_1):page86_i100:DQS6N" )
				( pinRef "@baseboard_fab2_lib.baseboard_fab2(sch_1):page61_i172:DDR4_DQS_DN(6)" )
				( attribute "RELATIVE_PROPAGATION_DELAY_SCOPE" "G"
					( Parent
						( matchGroupRef "@baseboard_fab2_lib.baseboard_fab2(sch_1):\MG_DQ-DQS_NEAR_DIMM_NG_M_L_BYTE6\" )
					)
					( Status sCSetFlattened )
					( Origin gBackEnd )
				)
				( attribute "RELATIVE_PROPAGATION_DELAY" ",5.00 MIL"
					( Parent
						( matchGroupRef "@baseboard_fab2_lib.baseboard_fab2(sch_1):\MG_DQ-DQS_NEAR_DIMM_NG_M_L_BYTE6\" )
					)
					( Units "uMatchProp" "ns" 1.000000)
					( Status sCSetFlattened )
					( Origin gBackEnd )
				)
			)
			( pinPair "@baseboard_fab2_lib.baseboard_fab2(sch_1):\PP1408\"
				( pinRef "@baseboard_fab2_lib.baseboard_fab2(sch_1):page61_i172:DDR4_DQS_DP(6)" )
				( pinRef "@baseboard_fab2_lib.baseboard_fab2(sch_1):page85_i66:DQS6P" )
				( attribute "RELATIVE_PROPAGATION_DELAY_SCOPE" "G"
					( Parent
						( matchGroupRef "@baseboard_fab2_lib.baseboard_fab2(sch_1):\MG_DQ-DQS_FAR_DIMM_NG_M_L_BYTE6\" )
					)
					( Status sCSetFlattened )
					( Origin gBackEnd )
				)
				( attribute "RELATIVE_PROPAGATION_DELAY" ",5.00 MIL"
					( Parent
						( matchGroupRef "@baseboard_fab2_lib.baseboard_fab2(sch_1):\MG_DQ-DQS_FAR_DIMM_NG_M_L_BYTE6\" )
					)
					( Units "uMatchProp" "ns" 1.000000)
					( Status sCSetFlattened )
					( Origin gBackEnd )
				)
			)
			( pinPair "@baseboard_fab2_lib.baseboard_fab2(sch_1):\PP1410\"
				( pinRef "@baseboard_fab2_lib.baseboard_fab2(sch_1):page86_i100:DQS6P" )
				( pinRef "@baseboard_fab2_lib.baseboard_fab2(sch_1):page61_i172:DDR4_DQS_DP(6)" )
				( attribute "RELATIVE_PROPAGATION_DELAY_SCOPE" "G"
					( Parent
						( matchGroupRef "@baseboard_fab2_lib.baseboard_fab2(sch_1):\MG_DQ-DQS_NEAR_DIMM_NG_M_L_BYTE6\" )
					)
					( Status sCSetFlattened )
					( Origin gBackEnd )
				)
				( attribute "RELATIVE_PROPAGATION_DELAY" ",5.00 MIL"
					( Parent
						( matchGroupRef "@baseboard_fab2_lib.baseboard_fab2(sch_1):\MG_DQ-DQS_NEAR_DIMM_NG_M_L_BYTE6\" )
					)
					( Units "uMatchProp" "ns" 1.000000)
					( Status sCSetFlattened )
					( Origin gBackEnd )
				)
			)
			( pinPair "@baseboard_fab2_lib.baseboard_fab2(sch_1):\PP1393\"
				( pinRef "@baseboard_fab2_lib.baseboard_fab2(sch_1):page61_i172:DDR4_DQS_DN(7)" )
				( pinRef "@baseboard_fab2_lib.baseboard_fab2(sch_1):page85_i66:DQS7N" )
				( attribute "RELATIVE_PROPAGATION_DELAY_SCOPE" "G"
					( Parent
						( matchGroupRef "@baseboard_fab2_lib.baseboard_fab2(sch_1):\MG_DQ-DQS_FAR_DIMM_NG_M_L_BYTE7\" )
					)
					( Status sCSetFlattened )
					( Origin gBackEnd )
				)
				( attribute "RELATIVE_PROPAGATION_DELAY" ",5.00 MIL"
					( Parent
						( matchGroupRef "@baseboard_fab2_lib.baseboard_fab2(sch_1):\MG_DQ-DQS_FAR_DIMM_NG_M_L_BYTE7\" )
					)
					( Units "uMatchProp" "ns" 1.000000)
					( Status sCSetFlattened )
					( Origin gBackEnd )
				)
			)
			( pinPair "@baseboard_fab2_lib.baseboard_fab2(sch_1):\PP1395\"
				( pinRef "@baseboard_fab2_lib.baseboard_fab2(sch_1):page61_i172:DDR4_DQS_DN(7)" )
				( pinRef "@baseboard_fab2_lib.baseboard_fab2(sch_1):page86_i100:DQS7N" )
				( attribute "RELATIVE_PROPAGATION_DELAY_SCOPE" "G"
					( Parent
						( matchGroupRef "@baseboard_fab2_lib.baseboard_fab2(sch_1):\MG_DQ-DQS_NEAR_DIMM_NG_M_L_BYTE7\" )
					)
					( Status sCSetFlattened )
					( Origin gBackEnd )
				)
				( attribute "RELATIVE_PROPAGATION_DELAY" ",5.00 MIL"
					( Parent
						( matchGroupRef "@baseboard_fab2_lib.baseboard_fab2(sch_1):\MG_DQ-DQS_NEAR_DIMM_NG_M_L_BYTE7\" )
					)
					( Units "uMatchProp" "ns" 1.000000)
					( Status sCSetFlattened )
					( Origin gBackEnd )
				)
			)
			( pinPair "@baseboard_fab2_lib.baseboard_fab2(sch_1):\PP1396\"
				( pinRef "@baseboard_fab2_lib.baseboard_fab2(sch_1):page61_i172:DDR4_DQS_DP(7)" )
				( pinRef "@baseboard_fab2_lib.baseboard_fab2(sch_1):page85_i66:DQS7P" )
				( attribute "RELATIVE_PROPAGATION_DELAY_SCOPE" "G"
					( Parent
						( matchGroupRef "@baseboard_fab2_lib.baseboard_fab2(sch_1):\MG_DQ-DQS_FAR_DIMM_NG_M_L_BYTE7\" )
					)
					( Status sCSetFlattened )
					( Origin gBackEnd )
				)
				( attribute "RELATIVE_PROPAGATION_DELAY" ",5.00 MIL"
					( Parent
						( matchGroupRef "@baseboard_fab2_lib.baseboard_fab2(sch_1):\MG_DQ-DQS_FAR_DIMM_NG_M_L_BYTE7\" )
					)
					( Units "uMatchProp" "ns" 1.000000)
					( Status sCSetFlattened )
					( Origin gBackEnd )
				)
			)
			( pinPair "@baseboard_fab2_lib.baseboard_fab2(sch_1):\PP1398\"
				( pinRef "@baseboard_fab2_lib.baseboard_fab2(sch_1):page61_i172:DDR4_DQS_DP(7)" )
				( pinRef "@baseboard_fab2_lib.baseboard_fab2(sch_1):page86_i100:DQS7P" )
				( attribute "RELATIVE_PROPAGATION_DELAY_SCOPE" "G"
					( Parent
						( matchGroupRef "@baseboard_fab2_lib.baseboard_fab2(sch_1):\MG_DQ-DQS_NEAR_DIMM_NG_M_L_BYTE7\" )
					)
					( Status sCSetFlattened )
					( Origin gBackEnd )
				)
				( attribute "RELATIVE_PROPAGATION_DELAY" ",5.00 MIL"
					( Parent
						( matchGroupRef "@baseboard_fab2_lib.baseboard_fab2(sch_1):\MG_DQ-DQS_NEAR_DIMM_NG_M_L_BYTE7\" )
					)
					( Units "uMatchProp" "ns" 1.000000)
					( Status sCSetFlattened )
					( Origin gBackEnd )
				)
			)
			( pinPair "@baseboard_fab2_lib.baseboard_fab2(sch_1):\PP1273\"
				( pinRef "@baseboard_fab2_lib.baseboard_fab2(sch_1):page61_i172:DDR4_DQS_DN(8)" )
				( pinRef "@baseboard_fab2_lib.baseboard_fab2(sch_1):page85_i66:DQS8N" )
				( attribute "RELATIVE_PROPAGATION_DELAY_SCOPE" "G"
					( Parent
						( matchGroupRef "@baseboard_fab2_lib.baseboard_fab2(sch_1):\MG_DQ-DQS_FAR_DIMM_NG_M_L_BYTE-ECC\" )
					)
					( Status sCSetFlattened )
					( Origin gBackEnd )
				)
				( attribute "RELATIVE_PROPAGATION_DELAY" ",5.00 MIL"
					( Parent
						( matchGroupRef "@baseboard_fab2_lib.baseboard_fab2(sch_1):\MG_DQ-DQS_FAR_DIMM_NG_M_L_BYTE-ECC\" )
					)
					( Units "uMatchProp" "ns" 1.000000)
					( Status sCSetFlattened )
					( Origin gBackEnd )
				)
			)
			( pinPair "@baseboard_fab2_lib.baseboard_fab2(sch_1):\PP1274\"
				( pinRef "@baseboard_fab2_lib.baseboard_fab2(sch_1):page86_i100:DQS8N" )
				( pinRef "@baseboard_fab2_lib.baseboard_fab2(sch_1):page61_i172:DDR4_DQS_DN(8)" )
				( attribute "RELATIVE_PROPAGATION_DELAY_SCOPE" "G"
					( Parent
						( matchGroupRef "@baseboard_fab2_lib.baseboard_fab2(sch_1):\MG_DQ-DQS_NEAR_DIMM_NG_M_L_BYTE-ECC\" )
					)
					( Status sCSetFlattened )
					( Origin gBackEnd )
				)
				( attribute "RELATIVE_PROPAGATION_DELAY" ",5.00 MIL"
					( Parent
						( matchGroupRef "@baseboard_fab2_lib.baseboard_fab2(sch_1):\MG_DQ-DQS_NEAR_DIMM_NG_M_L_BYTE-ECC\" )
					)
					( Units "uMatchProp" "ns" 1.000000)
					( Status sCSetFlattened )
					( Origin gBackEnd )
				)
			)
			( pinPair "@baseboard_fab2_lib.baseboard_fab2(sch_1):\PP1276\"
				( pinRef "@baseboard_fab2_lib.baseboard_fab2(sch_1):page61_i172:DDR4_DQS_DP(8)" )
				( pinRef "@baseboard_fab2_lib.baseboard_fab2(sch_1):page85_i66:DQS8P" )
				( attribute "RELATIVE_PROPAGATION_DELAY_SCOPE" "G"
					( Parent
						( matchGroupRef "@baseboard_fab2_lib.baseboard_fab2(sch_1):\MG_DQ-DQS_FAR_DIMM_NG_M_L_BYTE-ECC\" )
					)
					( Status sCSetFlattened )
					( Origin gBackEnd )
				)
				( attribute "RELATIVE_PROPAGATION_DELAY" ",5.00 MIL"
					( Parent
						( matchGroupRef "@baseboard_fab2_lib.baseboard_fab2(sch_1):\MG_DQ-DQS_FAR_DIMM_NG_M_L_BYTE-ECC\" )
					)
					( Units "uMatchProp" "ns" 1.000000)
					( Status sCSetFlattened )
					( Origin gBackEnd )
				)
			)
			( pinPair "@baseboard_fab2_lib.baseboard_fab2(sch_1):\PP1277\"
				( pinRef "@baseboard_fab2_lib.baseboard_fab2(sch_1):page86_i100:DQS8P" )
				( pinRef "@baseboard_fab2_lib.baseboard_fab2(sch_1):page61_i172:DDR4_DQS_DP(8)" )
				( attribute "RELATIVE_PROPAGATION_DELAY_SCOPE" "G"
					( Parent
						( matchGroupRef "@baseboard_fab2_lib.baseboard_fab2(sch_1):\MG_DQ-DQS_NEAR_DIMM_NG_M_L_BYTE-ECC\" )
					)
					( Status sCSetFlattened )
					( Origin gBackEnd )
				)
				( attribute "RELATIVE_PROPAGATION_DELAY" ",5.00 MIL"
					( Parent
						( matchGroupRef "@baseboard_fab2_lib.baseboard_fab2(sch_1):\MG_DQ-DQS_NEAR_DIMM_NG_M_L_BYTE-ECC\" )
					)
					( Units "uMatchProp" "ns" 1.000000)
					( Status sCSetFlattened )
					( Origin gBackEnd )
				)
			)
			( pinPair "@baseboard_fab2_lib.baseboard_fab2(sch_1):\PP1471\"
				( pinRef "@baseboard_fab2_lib.baseboard_fab2(sch_1):page61_i172:DDR4_DQS_DN(9)" )
				( pinRef "@baseboard_fab2_lib.baseboard_fab2(sch_1):page85_i66:DQS9N" )
				( attribute "RELATIVE_PROPAGATION_DELAY_SCOPE" "G"
					( Parent
						( matchGroupRef "@baseboard_fab2_lib.baseboard_fab2(sch_1):\MG_DQ-DQS_FAR_DIMM_NG_M_L_BYTE0\" )
					)
					( Status sCSetFlattened )
					( Origin gBackEnd )
				)
				( attribute "RELATIVE_PROPAGATION_DELAY" ",5.00 MIL"
					( Parent
						( matchGroupRef "@baseboard_fab2_lib.baseboard_fab2(sch_1):\MG_DQ-DQS_FAR_DIMM_NG_M_L_BYTE0\" )
					)
					( Units "uMatchProp" "ns" 1.000000)
					( Status sCSetFlattened )
					( Origin gBackEnd )
				)
			)
			( pinPair "@baseboard_fab2_lib.baseboard_fab2(sch_1):\PP1472\"
				( pinRef "@baseboard_fab2_lib.baseboard_fab2(sch_1):page86_i100:DQS9N" )
				( pinRef "@baseboard_fab2_lib.baseboard_fab2(sch_1):page61_i172:DDR4_DQS_DN(9)" )
				( attribute "RELATIVE_PROPAGATION_DELAY_SCOPE" "G"
					( Parent
						( matchGroupRef "@baseboard_fab2_lib.baseboard_fab2(sch_1):\MG_DQ-DQS_NEAR_DIMM_NG_M_L_BYTE0\" )
					)
					( Status sCSetFlattened )
					( Origin gBackEnd )
				)
				( attribute "RELATIVE_PROPAGATION_DELAY" ",5.00 MIL"
					( Parent
						( matchGroupRef "@baseboard_fab2_lib.baseboard_fab2(sch_1):\MG_DQ-DQS_NEAR_DIMM_NG_M_L_BYTE0\" )
					)
					( Units "uMatchProp" "ns" 1.000000)
					( Status sCSetFlattened )
					( Origin gBackEnd )
				)
			)
			( pinPair "@baseboard_fab2_lib.baseboard_fab2(sch_1):\PP1474\"
				( pinRef "@baseboard_fab2_lib.baseboard_fab2(sch_1):page61_i172:DDR4_DQS_DP(9)" )
				( pinRef "@baseboard_fab2_lib.baseboard_fab2(sch_1):page85_i66:DQS9P" )
				( attribute "RELATIVE_PROPAGATION_DELAY_SCOPE" "G"
					( Parent
						( matchGroupRef "@baseboard_fab2_lib.baseboard_fab2(sch_1):\MG_DQ-DQS_FAR_DIMM_NG_M_L_BYTE0\" )
					)
					( Status sCSetFlattened )
					( Origin gBackEnd )
				)
				( attribute "RELATIVE_PROPAGATION_DELAY" ",5.00 MIL"
					( Parent
						( matchGroupRef "@baseboard_fab2_lib.baseboard_fab2(sch_1):\MG_DQ-DQS_FAR_DIMM_NG_M_L_BYTE0\" )
					)
					( Units "uMatchProp" "ns" 1.000000)
					( Status sCSetFlattened )
					( Origin gBackEnd )
				)
			)
			( pinPair "@baseboard_fab2_lib.baseboard_fab2(sch_1):\PP1475\"
				( pinRef "@baseboard_fab2_lib.baseboard_fab2(sch_1):page86_i100:DQS9P" )
				( pinRef "@baseboard_fab2_lib.baseboard_fab2(sch_1):page61_i172:DDR4_DQS_DP(9)" )
				( attribute "RELATIVE_PROPAGATION_DELAY_SCOPE" "G"
					( Parent
						( matchGroupRef "@baseboard_fab2_lib.baseboard_fab2(sch_1):\MG_DQ-DQS_NEAR_DIMM_NG_M_L_BYTE0\" )
					)
					( Status sCSetFlattened )
					( Origin gBackEnd )
				)
				( attribute "RELATIVE_PROPAGATION_DELAY" ",5.00 MIL"
					( Parent
						( matchGroupRef "@baseboard_fab2_lib.baseboard_fab2(sch_1):\MG_DQ-DQS_NEAR_DIMM_NG_M_L_BYTE0\" )
					)
					( Units "uMatchProp" "ns" 1.000000)
					( Status sCSetFlattened )
					( Origin gBackEnd )
				)
			)
			( pinPair "@baseboard_fab2_lib.baseboard_fab2(sch_1):\PP1459\"
				( pinRef "@baseboard_fab2_lib.baseboard_fab2(sch_1):page61_i172:DDR4_DQS_DN(10)" )
				( pinRef "@baseboard_fab2_lib.baseboard_fab2(sch_1):page85_i66:DQS10N" )
				( attribute "RELATIVE_PROPAGATION_DELAY_SCOPE" "G"
					( Parent
						( matchGroupRef "@baseboard_fab2_lib.baseboard_fab2(sch_1):\MG_DQ-DQS_FAR_DIMM_NG_M_L_BYTE1\" )
					)
					( Status sCSetFlattened )
					( Origin gBackEnd )
				)
				( attribute "RELATIVE_PROPAGATION_DELAY" ",5.00 MIL"
					( Parent
						( matchGroupRef "@baseboard_fab2_lib.baseboard_fab2(sch_1):\MG_DQ-DQS_FAR_DIMM_NG_M_L_BYTE1\" )
					)
					( Units "uMatchProp" "ns" 1.000000)
					( Status sCSetFlattened )
					( Origin gBackEnd )
				)
			)
			( pinPair "@baseboard_fab2_lib.baseboard_fab2(sch_1):\PP1460\"
				( pinRef "@baseboard_fab2_lib.baseboard_fab2(sch_1):page86_i100:DQS10N" )
				( pinRef "@baseboard_fab2_lib.baseboard_fab2(sch_1):page61_i172:DDR4_DQS_DN(10)" )
				( attribute "RELATIVE_PROPAGATION_DELAY_SCOPE" "G"
					( Parent
						( matchGroupRef "@baseboard_fab2_lib.baseboard_fab2(sch_1):\MG_DQ-DQS_NEAR_DIMM_NG_M_L_BYTE1\" )
					)
					( Status sCSetFlattened )
					( Origin gBackEnd )
				)
				( attribute "RELATIVE_PROPAGATION_DELAY" ",5.00 MIL"
					( Parent
						( matchGroupRef "@baseboard_fab2_lib.baseboard_fab2(sch_1):\MG_DQ-DQS_NEAR_DIMM_NG_M_L_BYTE1\" )
					)
					( Units "uMatchProp" "ns" 1.000000)
					( Status sCSetFlattened )
					( Origin gBackEnd )
				)
			)
			( pinPair "@baseboard_fab2_lib.baseboard_fab2(sch_1):\PP1462\"
				( pinRef "@baseboard_fab2_lib.baseboard_fab2(sch_1):page61_i172:DDR4_DQS_DP(10)" )
				( pinRef "@baseboard_fab2_lib.baseboard_fab2(sch_1):page85_i66:DQS10P" )
				( attribute "RELATIVE_PROPAGATION_DELAY_SCOPE" "G"
					( Parent
						( matchGroupRef "@baseboard_fab2_lib.baseboard_fab2(sch_1):\MG_DQ-DQS_FAR_DIMM_NG_M_L_BYTE1\" )
					)
					( Status sCSetFlattened )
					( Origin gBackEnd )
				)
				( attribute "RELATIVE_PROPAGATION_DELAY" ",5.00 MIL"
					( Parent
						( matchGroupRef "@baseboard_fab2_lib.baseboard_fab2(sch_1):\MG_DQ-DQS_FAR_DIMM_NG_M_L_BYTE1\" )
					)
					( Units "uMatchProp" "ns" 1.000000)
					( Status sCSetFlattened )
					( Origin gBackEnd )
				)
			)
			( pinPair "@baseboard_fab2_lib.baseboard_fab2(sch_1):\PP1463\"
				( pinRef "@baseboard_fab2_lib.baseboard_fab2(sch_1):page86_i100:DQS10P" )
				( pinRef "@baseboard_fab2_lib.baseboard_fab2(sch_1):page61_i172:DDR4_DQS_DP(10)" )
				( attribute "RELATIVE_PROPAGATION_DELAY_SCOPE" "G"
					( Parent
						( matchGroupRef "@baseboard_fab2_lib.baseboard_fab2(sch_1):\MG_DQ-DQS_NEAR_DIMM_NG_M_L_BYTE1\" )
					)
					( Status sCSetFlattened )
					( Origin gBackEnd )
				)
				( attribute "RELATIVE_PROPAGATION_DELAY" ",5.00 MIL"
					( Parent
						( matchGroupRef "@baseboard_fab2_lib.baseboard_fab2(sch_1):\MG_DQ-DQS_NEAR_DIMM_NG_M_L_BYTE1\" )
					)
					( Units "uMatchProp" "ns" 1.000000)
					( Status sCSetFlattened )
					( Origin gBackEnd )
				)
			)
			( pinPair "@baseboard_fab2_lib.baseboard_fab2(sch_1):\PP1447\"
				( pinRef "@baseboard_fab2_lib.baseboard_fab2(sch_1):page61_i172:DDR4_DQS_DN(11)" )
				( pinRef "@baseboard_fab2_lib.baseboard_fab2(sch_1):page85_i66:DQS11N" )
				( attribute "RELATIVE_PROPAGATION_DELAY_SCOPE" "G"
					( Parent
						( matchGroupRef "@baseboard_fab2_lib.baseboard_fab2(sch_1):\MG_DQ-DQS_FAR_DIMM_NG_M_L_BYTE2\" )
					)
					( Status sCSetFlattened )
					( Origin gBackEnd )
				)
				( attribute "RELATIVE_PROPAGATION_DELAY" ",5.00 MIL"
					( Parent
						( matchGroupRef "@baseboard_fab2_lib.baseboard_fab2(sch_1):\MG_DQ-DQS_FAR_DIMM_NG_M_L_BYTE2\" )
					)
					( Units "uMatchProp" "ns" 1.000000)
					( Status sCSetFlattened )
					( Origin gBackEnd )
				)
			)
			( pinPair "@baseboard_fab2_lib.baseboard_fab2(sch_1):\PP1448\"
				( pinRef "@baseboard_fab2_lib.baseboard_fab2(sch_1):page86_i100:DQS11N" )
				( pinRef "@baseboard_fab2_lib.baseboard_fab2(sch_1):page61_i172:DDR4_DQS_DN(11)" )
				( attribute "RELATIVE_PROPAGATION_DELAY_SCOPE" "G"
					( Parent
						( matchGroupRef "@baseboard_fab2_lib.baseboard_fab2(sch_1):\MG_DQ-DQS_NEAR_DIMM_NG_M_L_BYTE2\" )
					)
					( Status sCSetFlattened )
					( Origin gBackEnd )
				)
				( attribute "RELATIVE_PROPAGATION_DELAY" ",5.00 MIL"
					( Parent
						( matchGroupRef "@baseboard_fab2_lib.baseboard_fab2(sch_1):\MG_DQ-DQS_NEAR_DIMM_NG_M_L_BYTE2\" )
					)
					( Units "uMatchProp" "ns" 1.000000)
					( Status sCSetFlattened )
					( Origin gBackEnd )
				)
			)
			( pinPair "@baseboard_fab2_lib.baseboard_fab2(sch_1):\PP1450\"
				( pinRef "@baseboard_fab2_lib.baseboard_fab2(sch_1):page61_i172:DDR4_DQS_DP(11)" )
				( pinRef "@baseboard_fab2_lib.baseboard_fab2(sch_1):page85_i66:DQS11P" )
				( attribute "RELATIVE_PROPAGATION_DELAY_SCOPE" "G"
					( Parent
						( matchGroupRef "@baseboard_fab2_lib.baseboard_fab2(sch_1):\MG_DQ-DQS_FAR_DIMM_NG_M_L_BYTE2\" )
					)
					( Status sCSetFlattened )
					( Origin gBackEnd )
				)
				( attribute "RELATIVE_PROPAGATION_DELAY" ",5.00 MIL"
					( Parent
						( matchGroupRef "@baseboard_fab2_lib.baseboard_fab2(sch_1):\MG_DQ-DQS_FAR_DIMM_NG_M_L_BYTE2\" )
					)
					( Units "uMatchProp" "ns" 1.000000)
					( Status sCSetFlattened )
					( Origin gBackEnd )
				)
			)
			( pinPair "@baseboard_fab2_lib.baseboard_fab2(sch_1):\PP1451\"
				( pinRef "@baseboard_fab2_lib.baseboard_fab2(sch_1):page86_i100:DQS11P" )
				( pinRef "@baseboard_fab2_lib.baseboard_fab2(sch_1):page61_i172:DDR4_DQS_DP(11)" )
				( attribute "RELATIVE_PROPAGATION_DELAY_SCOPE" "G"
					( Parent
						( matchGroupRef "@baseboard_fab2_lib.baseboard_fab2(sch_1):\MG_DQ-DQS_NEAR_DIMM_NG_M_L_BYTE2\" )
					)
					( Status sCSetFlattened )
					( Origin gBackEnd )
				)
				( attribute "RELATIVE_PROPAGATION_DELAY" ",5.00 MIL"
					( Parent
						( matchGroupRef "@baseboard_fab2_lib.baseboard_fab2(sch_1):\MG_DQ-DQS_NEAR_DIMM_NG_M_L_BYTE2\" )
					)
					( Units "uMatchProp" "ns" 1.000000)
					( Status sCSetFlattened )
					( Origin gBackEnd )
				)
			)
			( pinPair "@baseboard_fab2_lib.baseboard_fab2(sch_1):\PP1435\"
				( pinRef "@baseboard_fab2_lib.baseboard_fab2(sch_1):page61_i172:DDR4_DQS_DN(12)" )
				( pinRef "@baseboard_fab2_lib.baseboard_fab2(sch_1):page85_i66:DQS12N" )
				( attribute "RELATIVE_PROPAGATION_DELAY_SCOPE" "G"
					( Parent
						( matchGroupRef "@baseboard_fab2_lib.baseboard_fab2(sch_1):\MG_DQ-DQS_FAR_DIMM_NG_M_L_BYTE3\" )
					)
					( Status sCSetFlattened )
					( Origin gBackEnd )
				)
				( attribute "RELATIVE_PROPAGATION_DELAY" ",5.00 MIL"
					( Parent
						( matchGroupRef "@baseboard_fab2_lib.baseboard_fab2(sch_1):\MG_DQ-DQS_FAR_DIMM_NG_M_L_BYTE3\" )
					)
					( Units "uMatchProp" "ns" 1.000000)
					( Status sCSetFlattened )
					( Origin gBackEnd )
				)
			)
			( pinPair "@baseboard_fab2_lib.baseboard_fab2(sch_1):\PP1436\"
				( pinRef "@baseboard_fab2_lib.baseboard_fab2(sch_1):page86_i100:DQS12N" )
				( pinRef "@baseboard_fab2_lib.baseboard_fab2(sch_1):page61_i172:DDR4_DQS_DN(12)" )
				( attribute "RELATIVE_PROPAGATION_DELAY_SCOPE" "G"
					( Parent
						( matchGroupRef "@baseboard_fab2_lib.baseboard_fab2(sch_1):\MG_DQ-DQS_NEAR_DIMM_NG_M_L_BYTE3\" )
					)
					( Status sCSetFlattened )
					( Origin gBackEnd )
				)
				( attribute "RELATIVE_PROPAGATION_DELAY" ",5.00 MIL"
					( Parent
						( matchGroupRef "@baseboard_fab2_lib.baseboard_fab2(sch_1):\MG_DQ-DQS_NEAR_DIMM_NG_M_L_BYTE3\" )
					)
					( Units "uMatchProp" "ns" 1.000000)
					( Status sCSetFlattened )
					( Origin gBackEnd )
				)
			)
			( pinPair "@baseboard_fab2_lib.baseboard_fab2(sch_1):\PP1438\"
				( pinRef "@baseboard_fab2_lib.baseboard_fab2(sch_1):page61_i172:DDR4_DQS_DP(12)" )
				( pinRef "@baseboard_fab2_lib.baseboard_fab2(sch_1):page85_i66:DQS12P" )
				( attribute "RELATIVE_PROPAGATION_DELAY_SCOPE" "G"
					( Parent
						( matchGroupRef "@baseboard_fab2_lib.baseboard_fab2(sch_1):\MG_DQ-DQS_FAR_DIMM_NG_M_L_BYTE3\" )
					)
					( Status sCSetFlattened )
					( Origin gBackEnd )
				)
				( attribute "RELATIVE_PROPAGATION_DELAY" ",5.00 MIL"
					( Parent
						( matchGroupRef "@baseboard_fab2_lib.baseboard_fab2(sch_1):\MG_DQ-DQS_FAR_DIMM_NG_M_L_BYTE3\" )
					)
					( Units "uMatchProp" "ns" 1.000000)
					( Status sCSetFlattened )
					( Origin gBackEnd )
				)
			)
			( pinPair "@baseboard_fab2_lib.baseboard_fab2(sch_1):\PP1439\"
				( pinRef "@baseboard_fab2_lib.baseboard_fab2(sch_1):page86_i100:DQS12P" )
				( pinRef "@baseboard_fab2_lib.baseboard_fab2(sch_1):page61_i172:DDR4_DQS_DP(12)" )
				( attribute "RELATIVE_PROPAGATION_DELAY_SCOPE" "G"
					( Parent
						( matchGroupRef "@baseboard_fab2_lib.baseboard_fab2(sch_1):\MG_DQ-DQS_NEAR_DIMM_NG_M_L_BYTE3\" )
					)
					( Status sCSetFlattened )
					( Origin gBackEnd )
				)
				( attribute "RELATIVE_PROPAGATION_DELAY" ",5.00 MIL"
					( Parent
						( matchGroupRef "@baseboard_fab2_lib.baseboard_fab2(sch_1):\MG_DQ-DQS_NEAR_DIMM_NG_M_L_BYTE3\" )
					)
					( Units "uMatchProp" "ns" 1.000000)
					( Status sCSetFlattened )
					( Origin gBackEnd )
				)
			)
			( pinPair "@baseboard_fab2_lib.baseboard_fab2(sch_1):\PP1423\"
				( pinRef "@baseboard_fab2_lib.baseboard_fab2(sch_1):page61_i172:DDR4_DQS_DN(13)" )
				( pinRef "@baseboard_fab2_lib.baseboard_fab2(sch_1):page85_i66:DQS13N" )
				( attribute "RELATIVE_PROPAGATION_DELAY_SCOPE" "G"
					( Parent
						( matchGroupRef "@baseboard_fab2_lib.baseboard_fab2(sch_1):\MG_DQ-DQS_FAR_DIMM_NG_M_L_BYTE4\" )
					)
					( Status sCSetFlattened )
					( Origin gBackEnd )
				)
				( attribute "RELATIVE_PROPAGATION_DELAY" ",5.00 MIL"
					( Parent
						( matchGroupRef "@baseboard_fab2_lib.baseboard_fab2(sch_1):\MG_DQ-DQS_FAR_DIMM_NG_M_L_BYTE4\" )
					)
					( Units "uMatchProp" "ns" 1.000000)
					( Status sCSetFlattened )
					( Origin gBackEnd )
				)
			)
			( pinPair "@baseboard_fab2_lib.baseboard_fab2(sch_1):\PP1425\"
				( pinRef "@baseboard_fab2_lib.baseboard_fab2(sch_1):page86_i100:DQS13N" )
				( pinRef "@baseboard_fab2_lib.baseboard_fab2(sch_1):page61_i172:DDR4_DQS_DN(13)" )
				( attribute "RELATIVE_PROPAGATION_DELAY_SCOPE" "G"
					( Parent
						( matchGroupRef "@baseboard_fab2_lib.baseboard_fab2(sch_1):\MG_DQ-DQS_NEAR_DIMM_NG_M_L_BYTE4\" )
					)
					( Status sCSetFlattened )
					( Origin gBackEnd )
				)
				( attribute "RELATIVE_PROPAGATION_DELAY" ",5.00 MIL"
					( Parent
						( matchGroupRef "@baseboard_fab2_lib.baseboard_fab2(sch_1):\MG_DQ-DQS_NEAR_DIMM_NG_M_L_BYTE4\" )
					)
					( Units "uMatchProp" "ns" 1.000000)
					( Status sCSetFlattened )
					( Origin gBackEnd )
				)
			)
			( pinPair "@baseboard_fab2_lib.baseboard_fab2(sch_1):\PP1426\"
				( pinRef "@baseboard_fab2_lib.baseboard_fab2(sch_1):page61_i172:DDR4_DQS_DP(13)" )
				( pinRef "@baseboard_fab2_lib.baseboard_fab2(sch_1):page85_i66:DQS13P" )
				( attribute "RELATIVE_PROPAGATION_DELAY_SCOPE" "G"
					( Parent
						( matchGroupRef "@baseboard_fab2_lib.baseboard_fab2(sch_1):\MG_DQ-DQS_FAR_DIMM_NG_M_L_BYTE4\" )
					)
					( Status sCSetFlattened )
					( Origin gBackEnd )
				)
				( attribute "RELATIVE_PROPAGATION_DELAY" ",5.00 MIL"
					( Parent
						( matchGroupRef "@baseboard_fab2_lib.baseboard_fab2(sch_1):\MG_DQ-DQS_FAR_DIMM_NG_M_L_BYTE4\" )
					)
					( Units "uMatchProp" "ns" 1.000000)
					( Status sCSetFlattened )
					( Origin gBackEnd )
				)
			)
			( pinPair "@baseboard_fab2_lib.baseboard_fab2(sch_1):\PP1428\"
				( pinRef "@baseboard_fab2_lib.baseboard_fab2(sch_1):page61_i172:DDR4_DQS_DP(13)" )
				( pinRef "@baseboard_fab2_lib.baseboard_fab2(sch_1):page86_i100:DQS13P" )
				( attribute "RELATIVE_PROPAGATION_DELAY_SCOPE" "G"
					( Parent
						( matchGroupRef "@baseboard_fab2_lib.baseboard_fab2(sch_1):\MG_DQ-DQS_NEAR_DIMM_NG_M_L_BYTE4\" )
					)
					( Status sCSetFlattened )
					( Origin gBackEnd )
				)
				( attribute "RELATIVE_PROPAGATION_DELAY" ",5.00 MIL"
					( Parent
						( matchGroupRef "@baseboard_fab2_lib.baseboard_fab2(sch_1):\MG_DQ-DQS_NEAR_DIMM_NG_M_L_BYTE4\" )
					)
					( Units "uMatchProp" "ns" 1.000000)
					( Status sCSetFlattened )
					( Origin gBackEnd )
				)
			)
			( pinPair "@baseboard_fab2_lib.baseboard_fab2(sch_1):\PP1411\"
				( pinRef "@baseboard_fab2_lib.baseboard_fab2(sch_1):page61_i172:DDR4_DQS_DN(14)" )
				( pinRef "@baseboard_fab2_lib.baseboard_fab2(sch_1):page85_i66:DQS14N" )
				( attribute "RELATIVE_PROPAGATION_DELAY_SCOPE" "G"
					( Parent
						( matchGroupRef "@baseboard_fab2_lib.baseboard_fab2(sch_1):\MG_DQ-DQS_FAR_DIMM_NG_M_L_BYTE5\" )
					)
					( Status sCSetFlattened )
					( Origin gBackEnd )
				)
				( attribute "RELATIVE_PROPAGATION_DELAY" ",5.00 MIL"
					( Parent
						( matchGroupRef "@baseboard_fab2_lib.baseboard_fab2(sch_1):\MG_DQ-DQS_FAR_DIMM_NG_M_L_BYTE5\" )
					)
					( Units "uMatchProp" "ns" 1.000000)
					( Status sCSetFlattened )
					( Origin gBackEnd )
				)
			)
			( pinPair "@baseboard_fab2_lib.baseboard_fab2(sch_1):\PP1413\"
				( pinRef "@baseboard_fab2_lib.baseboard_fab2(sch_1):page86_i100:DQS14N" )
				( pinRef "@baseboard_fab2_lib.baseboard_fab2(sch_1):page61_i172:DDR4_DQS_DN(14)" )
				( attribute "RELATIVE_PROPAGATION_DELAY_SCOPE" "G"
					( Parent
						( matchGroupRef "@baseboard_fab2_lib.baseboard_fab2(sch_1):\MG_DQ-DQS_NEAR_DIMM_NG_M_L_BYTE5\" )
					)
					( Status sCSetFlattened )
					( Origin gBackEnd )
				)
				( attribute "RELATIVE_PROPAGATION_DELAY" ",5.00 MIL"
					( Parent
						( matchGroupRef "@baseboard_fab2_lib.baseboard_fab2(sch_1):\MG_DQ-DQS_NEAR_DIMM_NG_M_L_BYTE5\" )
					)
					( Units "uMatchProp" "ns" 1.000000)
					( Status sCSetFlattened )
					( Origin gBackEnd )
				)
			)
			( pinPair "@baseboard_fab2_lib.baseboard_fab2(sch_1):\PP1414\"
				( pinRef "@baseboard_fab2_lib.baseboard_fab2(sch_1):page61_i172:DDR4_DQS_DP(14)" )
				( pinRef "@baseboard_fab2_lib.baseboard_fab2(sch_1):page85_i66:DQS14P" )
				( attribute "RELATIVE_PROPAGATION_DELAY_SCOPE" "G"
					( Parent
						( matchGroupRef "@baseboard_fab2_lib.baseboard_fab2(sch_1):\MG_DQ-DQS_FAR_DIMM_NG_M_L_BYTE5\" )
					)
					( Status sCSetFlattened )
					( Origin gBackEnd )
				)
				( attribute "RELATIVE_PROPAGATION_DELAY" ",5.00 MIL"
					( Parent
						( matchGroupRef "@baseboard_fab2_lib.baseboard_fab2(sch_1):\MG_DQ-DQS_FAR_DIMM_NG_M_L_BYTE5\" )
					)
					( Units "uMatchProp" "ns" 1.000000)
					( Status sCSetFlattened )
					( Origin gBackEnd )
				)
			)
			( pinPair "@baseboard_fab2_lib.baseboard_fab2(sch_1):\PP1416\"
				( pinRef "@baseboard_fab2_lib.baseboard_fab2(sch_1):page86_i100:DQS14P" )
				( pinRef "@baseboard_fab2_lib.baseboard_fab2(sch_1):page61_i172:DDR4_DQS_DP(14)" )
				( attribute "RELATIVE_PROPAGATION_DELAY_SCOPE" "G"
					( Parent
						( matchGroupRef "@baseboard_fab2_lib.baseboard_fab2(sch_1):\MG_DQ-DQS_NEAR_DIMM_NG_M_L_BYTE5\" )
					)
					( Status sCSetFlattened )
					( Origin gBackEnd )
				)
				( attribute "RELATIVE_PROPAGATION_DELAY" ",5.00 MIL"
					( Parent
						( matchGroupRef "@baseboard_fab2_lib.baseboard_fab2(sch_1):\MG_DQ-DQS_NEAR_DIMM_NG_M_L_BYTE5\" )
					)
					( Units "uMatchProp" "ns" 1.000000)
					( Status sCSetFlattened )
					( Origin gBackEnd )
				)
			)
			( pinPair "@baseboard_fab2_lib.baseboard_fab2(sch_1):\PP1399\"
				( pinRef "@baseboard_fab2_lib.baseboard_fab2(sch_1):page61_i172:DDR4_DQS_DN(15)" )
				( pinRef "@baseboard_fab2_lib.baseboard_fab2(sch_1):page85_i66:DQS15N" )
				( attribute "RELATIVE_PROPAGATION_DELAY_SCOPE" "G"
					( Parent
						( matchGroupRef "@baseboard_fab2_lib.baseboard_fab2(sch_1):\MG_DQ-DQS_FAR_DIMM_NG_M_L_BYTE6\" )
					)
					( Status sCSetFlattened )
					( Origin gBackEnd )
				)
				( attribute "RELATIVE_PROPAGATION_DELAY" ",5.00 MIL"
					( Parent
						( matchGroupRef "@baseboard_fab2_lib.baseboard_fab2(sch_1):\MG_DQ-DQS_FAR_DIMM_NG_M_L_BYTE6\" )
					)
					( Units "uMatchProp" "ns" 1.000000)
					( Status sCSetFlattened )
					( Origin gBackEnd )
				)
			)
			( pinPair "@baseboard_fab2_lib.baseboard_fab2(sch_1):\PP1401\"
				( pinRef "@baseboard_fab2_lib.baseboard_fab2(sch_1):page86_i100:DQS15N" )
				( pinRef "@baseboard_fab2_lib.baseboard_fab2(sch_1):page61_i172:DDR4_DQS_DN(15)" )
				( attribute "RELATIVE_PROPAGATION_DELAY_SCOPE" "G"
					( Parent
						( matchGroupRef "@baseboard_fab2_lib.baseboard_fab2(sch_1):\MG_DQ-DQS_NEAR_DIMM_NG_M_L_BYTE6\" )
					)
					( Status sCSetFlattened )
					( Origin gBackEnd )
				)
				( attribute "RELATIVE_PROPAGATION_DELAY" ",5.00 MIL"
					( Parent
						( matchGroupRef "@baseboard_fab2_lib.baseboard_fab2(sch_1):\MG_DQ-DQS_NEAR_DIMM_NG_M_L_BYTE6\" )
					)
					( Units "uMatchProp" "ns" 1.000000)
					( Status sCSetFlattened )
					( Origin gBackEnd )
				)
			)
			( pinPair "@baseboard_fab2_lib.baseboard_fab2(sch_1):\PP1402\"
				( pinRef "@baseboard_fab2_lib.baseboard_fab2(sch_1):page61_i172:DDR4_DQS_DP(15)" )
				( pinRef "@baseboard_fab2_lib.baseboard_fab2(sch_1):page85_i66:DQS15P" )
				( attribute "RELATIVE_PROPAGATION_DELAY_SCOPE" "G"
					( Parent
						( matchGroupRef "@baseboard_fab2_lib.baseboard_fab2(sch_1):\MG_DQ-DQS_FAR_DIMM_NG_M_L_BYTE6\" )
					)
					( Status sCSetFlattened )
					( Origin gBackEnd )
				)
				( attribute "RELATIVE_PROPAGATION_DELAY" ",5.00 MIL"
					( Parent
						( matchGroupRef "@baseboard_fab2_lib.baseboard_fab2(sch_1):\MG_DQ-DQS_FAR_DIMM_NG_M_L_BYTE6\" )
					)
					( Units "uMatchProp" "ns" 1.000000)
					( Status sCSetFlattened )
					( Origin gBackEnd )
				)
			)
			( pinPair "@baseboard_fab2_lib.baseboard_fab2(sch_1):\PP1404\"
				( pinRef "@baseboard_fab2_lib.baseboard_fab2(sch_1):page86_i100:DQS15P" )
				( pinRef "@baseboard_fab2_lib.baseboard_fab2(sch_1):page61_i172:DDR4_DQS_DP(15)" )
				( attribute "RELATIVE_PROPAGATION_DELAY_SCOPE" "G"
					( Parent
						( matchGroupRef "@baseboard_fab2_lib.baseboard_fab2(sch_1):\MG_DQ-DQS_NEAR_DIMM_NG_M_L_BYTE6\" )
					)
					( Status sCSetFlattened )
					( Origin gBackEnd )
				)
				( attribute "RELATIVE_PROPAGATION_DELAY" ",5.00 MIL"
					( Parent
						( matchGroupRef "@baseboard_fab2_lib.baseboard_fab2(sch_1):\MG_DQ-DQS_NEAR_DIMM_NG_M_L_BYTE6\" )
					)
					( Units "uMatchProp" "ns" 1.000000)
					( Status sCSetFlattened )
					( Origin gBackEnd )
				)
			)
			( pinPair "@baseboard_fab2_lib.baseboard_fab2(sch_1):\PP1387\"
				( pinRef "@baseboard_fab2_lib.baseboard_fab2(sch_1):page61_i172:DDR4_DQS_DN(16)" )
				( pinRef "@baseboard_fab2_lib.baseboard_fab2(sch_1):page85_i66:DQS16N" )
				( attribute "RELATIVE_PROPAGATION_DELAY_SCOPE" "G"
					( Parent
						( matchGroupRef "@baseboard_fab2_lib.baseboard_fab2(sch_1):\MG_DQ-DQS_FAR_DIMM_NG_M_L_BYTE7\" )
					)
					( Status sCSetFlattened )
					( Origin gBackEnd )
				)
				( attribute "RELATIVE_PROPAGATION_DELAY" ",5.00 MIL"
					( Parent
						( matchGroupRef "@baseboard_fab2_lib.baseboard_fab2(sch_1):\MG_DQ-DQS_FAR_DIMM_NG_M_L_BYTE7\" )
					)
					( Units "uMatchProp" "ns" 1.000000)
					( Status sCSetFlattened )
					( Origin gBackEnd )
				)
			)
			( pinPair "@baseboard_fab2_lib.baseboard_fab2(sch_1):\PP1389\"
				( pinRef "@baseboard_fab2_lib.baseboard_fab2(sch_1):page61_i172:DDR4_DQS_DN(16)" )
				( pinRef "@baseboard_fab2_lib.baseboard_fab2(sch_1):page86_i100:DQS16N" )
				( attribute "RELATIVE_PROPAGATION_DELAY_SCOPE" "G"
					( Parent
						( matchGroupRef "@baseboard_fab2_lib.baseboard_fab2(sch_1):\MG_DQ-DQS_NEAR_DIMM_NG_M_L_BYTE7\" )
					)
					( Status sCSetFlattened )
					( Origin gBackEnd )
				)
				( attribute "RELATIVE_PROPAGATION_DELAY" ",5.00 MIL"
					( Parent
						( matchGroupRef "@baseboard_fab2_lib.baseboard_fab2(sch_1):\MG_DQ-DQS_NEAR_DIMM_NG_M_L_BYTE7\" )
					)
					( Units "uMatchProp" "ns" 1.000000)
					( Status sCSetFlattened )
					( Origin gBackEnd )
				)
			)
			( pinPair "@baseboard_fab2_lib.baseboard_fab2(sch_1):\PP1390\"
				( pinRef "@baseboard_fab2_lib.baseboard_fab2(sch_1):page61_i172:DDR4_DQS_DP(16)" )
				( pinRef "@baseboard_fab2_lib.baseboard_fab2(sch_1):page85_i66:DQS16P" )
				( attribute "RELATIVE_PROPAGATION_DELAY_SCOPE" "G"
					( Parent
						( matchGroupRef "@baseboard_fab2_lib.baseboard_fab2(sch_1):\MG_DQ-DQS_FAR_DIMM_NG_M_L_BYTE7\" )
					)
					( Status sCSetFlattened )
					( Origin gBackEnd )
				)
				( attribute "RELATIVE_PROPAGATION_DELAY" ",5.00 MIL"
					( Parent
						( matchGroupRef "@baseboard_fab2_lib.baseboard_fab2(sch_1):\MG_DQ-DQS_FAR_DIMM_NG_M_L_BYTE7\" )
					)
					( Units "uMatchProp" "ns" 1.000000)
					( Status sCSetFlattened )
					( Origin gBackEnd )
				)
			)
			( pinPair "@baseboard_fab2_lib.baseboard_fab2(sch_1):\PP1392\"
				( pinRef "@baseboard_fab2_lib.baseboard_fab2(sch_1):page61_i172:DDR4_DQS_DP(16)" )
				( pinRef "@baseboard_fab2_lib.baseboard_fab2(sch_1):page86_i100:DQS16P" )
				( attribute "RELATIVE_PROPAGATION_DELAY_SCOPE" "G"
					( Parent
						( matchGroupRef "@baseboard_fab2_lib.baseboard_fab2(sch_1):\MG_DQ-DQS_NEAR_DIMM_NG_M_L_BYTE7\" )
					)
					( Status sCSetFlattened )
					( Origin gBackEnd )
				)
				( attribute "RELATIVE_PROPAGATION_DELAY" ",5.00 MIL"
					( Parent
						( matchGroupRef "@baseboard_fab2_lib.baseboard_fab2(sch_1):\MG_DQ-DQS_NEAR_DIMM_NG_M_L_BYTE7\" )
					)
					( Units "uMatchProp" "ns" 1.000000)
					( Status sCSetFlattened )
					( Origin gBackEnd )
				)
			)
			( pinPair "@baseboard_fab2_lib.baseboard_fab2(sch_1):\PP1267\"
				( pinRef "@baseboard_fab2_lib.baseboard_fab2(sch_1):page61_i172:DDR4_DQS_DN(17)" )
				( pinRef "@baseboard_fab2_lib.baseboard_fab2(sch_1):page85_i66:DQS17N" )
				( attribute "RELATIVE_PROPAGATION_DELAY_SCOPE" "G"
					( Parent
						( matchGroupRef "@baseboard_fab2_lib.baseboard_fab2(sch_1):\MG_DQ-DQS_FAR_DIMM_NG_M_L_BYTE-ECC\" )
					)
					( Status sCSetFlattened )
					( Origin gBackEnd )
				)
				( attribute "RELATIVE_PROPAGATION_DELAY" ",5.00 MIL"
					( Parent
						( matchGroupRef "@baseboard_fab2_lib.baseboard_fab2(sch_1):\MG_DQ-DQS_FAR_DIMM_NG_M_L_BYTE-ECC\" )
					)
					( Units "uMatchProp" "ns" 1.000000)
					( Status sCSetFlattened )
					( Origin gBackEnd )
				)
			)
			( pinPair "@baseboard_fab2_lib.baseboard_fab2(sch_1):\PP1268\"
				( pinRef "@baseboard_fab2_lib.baseboard_fab2(sch_1):page86_i100:DQS17N" )
				( pinRef "@baseboard_fab2_lib.baseboard_fab2(sch_1):page61_i172:DDR4_DQS_DN(17)" )
				( attribute "RELATIVE_PROPAGATION_DELAY_SCOPE" "G"
					( Parent
						( matchGroupRef "@baseboard_fab2_lib.baseboard_fab2(sch_1):\MG_DQ-DQS_NEAR_DIMM_NG_M_L_BYTE-ECC\" )
					)
					( Status sCSetFlattened )
					( Origin gBackEnd )
				)
				( attribute "RELATIVE_PROPAGATION_DELAY" ",5.00 MIL"
					( Parent
						( matchGroupRef "@baseboard_fab2_lib.baseboard_fab2(sch_1):\MG_DQ-DQS_NEAR_DIMM_NG_M_L_BYTE-ECC\" )
					)
					( Units "uMatchProp" "ns" 1.000000)
					( Status sCSetFlattened )
					( Origin gBackEnd )
				)
			)
			( pinPair "@baseboard_fab2_lib.baseboard_fab2(sch_1):\PP1270\"
				( pinRef "@baseboard_fab2_lib.baseboard_fab2(sch_1):page61_i172:DDR4_DQS_DP(17)" )
				( pinRef "@baseboard_fab2_lib.baseboard_fab2(sch_1):page85_i66:DQS17P" )
				( attribute "RELATIVE_PROPAGATION_DELAY_SCOPE" "G"
					( Parent
						( matchGroupRef "@baseboard_fab2_lib.baseboard_fab2(sch_1):\MG_DQ-DQS_FAR_DIMM_NG_M_L_BYTE-ECC\" )
					)
					( Status sCSetFlattened )
					( Origin gBackEnd )
				)
				( attribute "RELATIVE_PROPAGATION_DELAY" ",5.00 MIL"
					( Parent
						( matchGroupRef "@baseboard_fab2_lib.baseboard_fab2(sch_1):\MG_DQ-DQS_FAR_DIMM_NG_M_L_BYTE-ECC\" )
					)
					( Units "uMatchProp" "ns" 1.000000)
					( Status sCSetFlattened )
					( Origin gBackEnd )
				)
			)
			( pinPair "@baseboard_fab2_lib.baseboard_fab2(sch_1):\PP1271\"
				( pinRef "@baseboard_fab2_lib.baseboard_fab2(sch_1):page86_i100:DQS17P" )
				( pinRef "@baseboard_fab2_lib.baseboard_fab2(sch_1):page61_i172:DDR4_DQS_DP(17)" )
				( attribute "RELATIVE_PROPAGATION_DELAY_SCOPE" "G"
					( Parent
						( matchGroupRef "@baseboard_fab2_lib.baseboard_fab2(sch_1):\MG_DQ-DQS_NEAR_DIMM_NG_M_L_BYTE-ECC\" )
					)
					( Status sCSetFlattened )
					( Origin gBackEnd )
				)
				( attribute "RELATIVE_PROPAGATION_DELAY" ",5.00 MIL"
					( Parent
						( matchGroupRef "@baseboard_fab2_lib.baseboard_fab2(sch_1):\MG_DQ-DQS_NEAR_DIMM_NG_M_L_BYTE-ECC\" )
					)
					( Units "uMatchProp" "ns" 1.000000)
					( Status sCSetFlattened )
					( Origin gBackEnd )
				)
			)
			( pinPair "@baseboard_fab2_lib.baseboard_fab2(sch_1):\PP1381\"
				( pinRef "@baseboard_fab2_lib.baseboard_fab2(sch_1):page62_i172:DDR5_DQS_DN(0)" )
				( pinRef "@baseboard_fab2_lib.baseboard_fab2(sch_1):page87_i187:DQS0N" )
				( attribute "RELATIVE_PROPAGATION_DELAY_SCOPE" "G"
					( Parent
						( matchGroupRef "@baseboard_fab2_lib.baseboard_fab2(sch_1):\MG_DQ-DQS_FAR_DIMM_NG_M_M_BYTE0\" )
					)
					( Status sCSetFlattened )
					( Origin gBackEnd )
				)
				( attribute "RELATIVE_PROPAGATION_DELAY" ",5.00 MIL"
					( Parent
						( matchGroupRef "@baseboard_fab2_lib.baseboard_fab2(sch_1):\MG_DQ-DQS_FAR_DIMM_NG_M_M_BYTE0\" )
					)
					( Units "uMatchProp" "ns" 1.000000)
					( Status sCSetFlattened )
					( Origin gBackEnd )
				)
			)
			( pinPair "@baseboard_fab2_lib.baseboard_fab2(sch_1):\PP1382\"
				( pinRef "@baseboard_fab2_lib.baseboard_fab2(sch_1):page88_i87:DQS0N" )
				( pinRef "@baseboard_fab2_lib.baseboard_fab2(sch_1):page62_i172:DDR5_DQS_DN(0)" )
				( attribute "RELATIVE_PROPAGATION_DELAY_SCOPE" "G"
					( Parent
						( matchGroupRef "@baseboard_fab2_lib.baseboard_fab2(sch_1):\MG_DQ-DQS_NEAR_DIMM_NG_M_M_BYTE0\" )
					)
					( Status sCSetFlattened )
					( Origin gBackEnd )
				)
				( attribute "RELATIVE_PROPAGATION_DELAY" ",5.00 MIL"
					( Parent
						( matchGroupRef "@baseboard_fab2_lib.baseboard_fab2(sch_1):\MG_DQ-DQS_NEAR_DIMM_NG_M_M_BYTE0\" )
					)
					( Units "uMatchProp" "ns" 1.000000)
					( Status sCSetFlattened )
					( Origin gBackEnd )
				)
			)
			( pinPair "@baseboard_fab2_lib.baseboard_fab2(sch_1):\PP1384\"
				( pinRef "@baseboard_fab2_lib.baseboard_fab2(sch_1):page62_i172:DDR5_DQS_DP(0)" )
				( pinRef "@baseboard_fab2_lib.baseboard_fab2(sch_1):page87_i187:DQS0P" )
				( attribute "RELATIVE_PROPAGATION_DELAY_SCOPE" "G"
					( Parent
						( matchGroupRef "@baseboard_fab2_lib.baseboard_fab2(sch_1):\MG_DQ-DQS_FAR_DIMM_NG_M_M_BYTE0\" )
					)
					( Status sCSetFlattened )
					( Origin gBackEnd )
				)
				( attribute "RELATIVE_PROPAGATION_DELAY" ",5.00 MIL"
					( Parent
						( matchGroupRef "@baseboard_fab2_lib.baseboard_fab2(sch_1):\MG_DQ-DQS_FAR_DIMM_NG_M_M_BYTE0\" )
					)
					( Units "uMatchProp" "ns" 1.000000)
					( Status sCSetFlattened )
					( Origin gBackEnd )
				)
			)
			( pinPair "@baseboard_fab2_lib.baseboard_fab2(sch_1):\PP1385\"
				( pinRef "@baseboard_fab2_lib.baseboard_fab2(sch_1):page88_i87:DQS0P" )
				( pinRef "@baseboard_fab2_lib.baseboard_fab2(sch_1):page62_i172:DDR5_DQS_DP(0)" )
				( attribute "RELATIVE_PROPAGATION_DELAY_SCOPE" "G"
					( Parent
						( matchGroupRef "@baseboard_fab2_lib.baseboard_fab2(sch_1):\MG_DQ-DQS_NEAR_DIMM_NG_M_M_BYTE0\" )
					)
					( Status sCSetFlattened )
					( Origin gBackEnd )
				)
				( attribute "RELATIVE_PROPAGATION_DELAY" ",5.00 MIL"
					( Parent
						( matchGroupRef "@baseboard_fab2_lib.baseboard_fab2(sch_1):\MG_DQ-DQS_NEAR_DIMM_NG_M_M_BYTE0\" )
					)
					( Units "uMatchProp" "ns" 1.000000)
					( Status sCSetFlattened )
					( Origin gBackEnd )
				)
			)
			( pinPair "@baseboard_fab2_lib.baseboard_fab2(sch_1):\PP1369\"
				( pinRef "@baseboard_fab2_lib.baseboard_fab2(sch_1):page62_i172:DDR5_DQS_DN(1)" )
				( pinRef "@baseboard_fab2_lib.baseboard_fab2(sch_1):page87_i187:DQS1N" )
				( attribute "RELATIVE_PROPAGATION_DELAY_SCOPE" "G"
					( Parent
						( matchGroupRef "@baseboard_fab2_lib.baseboard_fab2(sch_1):\MG_DQ-DQS_FAR_DIMM_NG_M_M_BYTE1\" )
					)
					( Status sCSetFlattened )
					( Origin gBackEnd )
				)
				( attribute "RELATIVE_PROPAGATION_DELAY" ",5.00 MIL"
					( Parent
						( matchGroupRef "@baseboard_fab2_lib.baseboard_fab2(sch_1):\MG_DQ-DQS_FAR_DIMM_NG_M_M_BYTE1\" )
					)
					( Units "uMatchProp" "ns" 1.000000)
					( Status sCSetFlattened )
					( Origin gBackEnd )
				)
			)
			( pinPair "@baseboard_fab2_lib.baseboard_fab2(sch_1):\PP1370\"
				( pinRef "@baseboard_fab2_lib.baseboard_fab2(sch_1):page88_i87:DQS1N" )
				( pinRef "@baseboard_fab2_lib.baseboard_fab2(sch_1):page62_i172:DDR5_DQS_DN(1)" )
				( attribute "RELATIVE_PROPAGATION_DELAY_SCOPE" "G"
					( Parent
						( matchGroupRef "@baseboard_fab2_lib.baseboard_fab2(sch_1):\MG_DQ-DQS_NEAR_DIMM_NG_M_M_BYTE1\" )
					)
					( Status sCSetFlattened )
					( Origin gBackEnd )
				)
				( attribute "RELATIVE_PROPAGATION_DELAY" ",5.00 MIL"
					( Parent
						( matchGroupRef "@baseboard_fab2_lib.baseboard_fab2(sch_1):\MG_DQ-DQS_NEAR_DIMM_NG_M_M_BYTE1\" )
					)
					( Units "uMatchProp" "ns" 1.000000)
					( Status sCSetFlattened )
					( Origin gBackEnd )
				)
			)
			( pinPair "@baseboard_fab2_lib.baseboard_fab2(sch_1):\PP1372\"
				( pinRef "@baseboard_fab2_lib.baseboard_fab2(sch_1):page62_i172:DDR5_DQS_DP(1)" )
				( pinRef "@baseboard_fab2_lib.baseboard_fab2(sch_1):page87_i187:DQS1P" )
				( attribute "RELATIVE_PROPAGATION_DELAY_SCOPE" "G"
					( Parent
						( matchGroupRef "@baseboard_fab2_lib.baseboard_fab2(sch_1):\MG_DQ-DQS_FAR_DIMM_NG_M_M_BYTE1\" )
					)
					( Status sCSetFlattened )
					( Origin gBackEnd )
				)
				( attribute "RELATIVE_PROPAGATION_DELAY" ",5.00 MIL"
					( Parent
						( matchGroupRef "@baseboard_fab2_lib.baseboard_fab2(sch_1):\MG_DQ-DQS_FAR_DIMM_NG_M_M_BYTE1\" )
					)
					( Units "uMatchProp" "ns" 1.000000)
					( Status sCSetFlattened )
					( Origin gBackEnd )
				)
			)
			( pinPair "@baseboard_fab2_lib.baseboard_fab2(sch_1):\PP1373\"
				( pinRef "@baseboard_fab2_lib.baseboard_fab2(sch_1):page88_i87:DQS1P" )
				( pinRef "@baseboard_fab2_lib.baseboard_fab2(sch_1):page62_i172:DDR5_DQS_DP(1)" )
				( attribute "RELATIVE_PROPAGATION_DELAY_SCOPE" "G"
					( Parent
						( matchGroupRef "@baseboard_fab2_lib.baseboard_fab2(sch_1):\MG_DQ-DQS_NEAR_DIMM_NG_M_M_BYTE1\" )
					)
					( Status sCSetFlattened )
					( Origin gBackEnd )
				)
				( attribute "RELATIVE_PROPAGATION_DELAY" ",5.00 MIL"
					( Parent
						( matchGroupRef "@baseboard_fab2_lib.baseboard_fab2(sch_1):\MG_DQ-DQS_NEAR_DIMM_NG_M_M_BYTE1\" )
					)
					( Units "uMatchProp" "ns" 1.000000)
					( Status sCSetFlattened )
					( Origin gBackEnd )
				)
			)
			( pinPair "@baseboard_fab2_lib.baseboard_fab2(sch_1):\PP1357\"
				( pinRef "@baseboard_fab2_lib.baseboard_fab2(sch_1):page62_i172:DDR5_DQS_DN(2)" )
				( pinRef "@baseboard_fab2_lib.baseboard_fab2(sch_1):page87_i187:DQS2N" )
				( attribute "RELATIVE_PROPAGATION_DELAY_SCOPE" "G"
					( Parent
						( matchGroupRef "@baseboard_fab2_lib.baseboard_fab2(sch_1):\MG_DQ-DQS_FAR_DIMM_NG_M_M_BYTE2\" )
					)
					( Status sCSetFlattened )
					( Origin gBackEnd )
				)
				( attribute "RELATIVE_PROPAGATION_DELAY" ",5.00 MIL"
					( Parent
						( matchGroupRef "@baseboard_fab2_lib.baseboard_fab2(sch_1):\MG_DQ-DQS_FAR_DIMM_NG_M_M_BYTE2\" )
					)
					( Units "uMatchProp" "ns" 1.000000)
					( Status sCSetFlattened )
					( Origin gBackEnd )
				)
			)
			( pinPair "@baseboard_fab2_lib.baseboard_fab2(sch_1):\PP1358\"
				( pinRef "@baseboard_fab2_lib.baseboard_fab2(sch_1):page88_i87:DQS2N" )
				( pinRef "@baseboard_fab2_lib.baseboard_fab2(sch_1):page62_i172:DDR5_DQS_DN(2)" )
				( attribute "RELATIVE_PROPAGATION_DELAY_SCOPE" "G"
					( Parent
						( matchGroupRef "@baseboard_fab2_lib.baseboard_fab2(sch_1):\MG_DQ-DQS_NEAR_DIMM_NG_M_M_BYTE2\" )
					)
					( Status sCSetFlattened )
					( Origin gBackEnd )
				)
				( attribute "RELATIVE_PROPAGATION_DELAY" ",5.00 MIL"
					( Parent
						( matchGroupRef "@baseboard_fab2_lib.baseboard_fab2(sch_1):\MG_DQ-DQS_NEAR_DIMM_NG_M_M_BYTE2\" )
					)
					( Units "uMatchProp" "ns" 1.000000)
					( Status sCSetFlattened )
					( Origin gBackEnd )
				)
			)
			( pinPair "@baseboard_fab2_lib.baseboard_fab2(sch_1):\PP1360\"
				( pinRef "@baseboard_fab2_lib.baseboard_fab2(sch_1):page62_i172:DDR5_DQS_DP(2)" )
				( pinRef "@baseboard_fab2_lib.baseboard_fab2(sch_1):page87_i187:DQS2P" )
				( attribute "RELATIVE_PROPAGATION_DELAY_SCOPE" "G"
					( Parent
						( matchGroupRef "@baseboard_fab2_lib.baseboard_fab2(sch_1):\MG_DQ-DQS_FAR_DIMM_NG_M_M_BYTE2\" )
					)
					( Status sCSetFlattened )
					( Origin gBackEnd )
				)
				( attribute "RELATIVE_PROPAGATION_DELAY" ",5.00 MIL"
					( Parent
						( matchGroupRef "@baseboard_fab2_lib.baseboard_fab2(sch_1):\MG_DQ-DQS_FAR_DIMM_NG_M_M_BYTE2\" )
					)
					( Units "uMatchProp" "ns" 1.000000)
					( Status sCSetFlattened )
					( Origin gBackEnd )
				)
			)
			( pinPair "@baseboard_fab2_lib.baseboard_fab2(sch_1):\PP1361\"
				( pinRef "@baseboard_fab2_lib.baseboard_fab2(sch_1):page88_i87:DQS2P" )
				( pinRef "@baseboard_fab2_lib.baseboard_fab2(sch_1):page62_i172:DDR5_DQS_DP(2)" )
				( attribute "RELATIVE_PROPAGATION_DELAY_SCOPE" "G"
					( Parent
						( matchGroupRef "@baseboard_fab2_lib.baseboard_fab2(sch_1):\MG_DQ-DQS_NEAR_DIMM_NG_M_M_BYTE2\" )
					)
					( Status sCSetFlattened )
					( Origin gBackEnd )
				)
				( attribute "RELATIVE_PROPAGATION_DELAY" ",5.00 MIL"
					( Parent
						( matchGroupRef "@baseboard_fab2_lib.baseboard_fab2(sch_1):\MG_DQ-DQS_NEAR_DIMM_NG_M_M_BYTE2\" )
					)
					( Units "uMatchProp" "ns" 1.000000)
					( Status sCSetFlattened )
					( Origin gBackEnd )
				)
			)
			( pinPair "@baseboard_fab2_lib.baseboard_fab2(sch_1):\PP1345\"
				( pinRef "@baseboard_fab2_lib.baseboard_fab2(sch_1):page62_i172:DDR5_DQS_DN(3)" )
				( pinRef "@baseboard_fab2_lib.baseboard_fab2(sch_1):page87_i187:DQS3N" )
				( attribute "RELATIVE_PROPAGATION_DELAY_SCOPE" "G"
					( Parent
						( matchGroupRef "@baseboard_fab2_lib.baseboard_fab2(sch_1):\MG_DQ-DQS_FAR_DIMM_NG_M_M_BYTE3\" )
					)
					( Status sCSetFlattened )
					( Origin gBackEnd )
				)
				( attribute "RELATIVE_PROPAGATION_DELAY" ",5.00 MIL"
					( Parent
						( matchGroupRef "@baseboard_fab2_lib.baseboard_fab2(sch_1):\MG_DQ-DQS_FAR_DIMM_NG_M_M_BYTE3\" )
					)
					( Units "uMatchProp" "ns" 1.000000)
					( Status sCSetFlattened )
					( Origin gBackEnd )
				)
			)
			( pinPair "@baseboard_fab2_lib.baseboard_fab2(sch_1):\PP1346\"
				( pinRef "@baseboard_fab2_lib.baseboard_fab2(sch_1):page88_i87:DQS3N" )
				( pinRef "@baseboard_fab2_lib.baseboard_fab2(sch_1):page62_i172:DDR5_DQS_DN(3)" )
				( attribute "RELATIVE_PROPAGATION_DELAY_SCOPE" "G"
					( Parent
						( matchGroupRef "@baseboard_fab2_lib.baseboard_fab2(sch_1):\MG_DQ-DQS_NEAR_DIMM_NG_M_M_BYTE3\" )
					)
					( Status sCSetFlattened )
					( Origin gBackEnd )
				)
				( attribute "RELATIVE_PROPAGATION_DELAY" ",5.00 MIL"
					( Parent
						( matchGroupRef "@baseboard_fab2_lib.baseboard_fab2(sch_1):\MG_DQ-DQS_NEAR_DIMM_NG_M_M_BYTE3\" )
					)
					( Units "uMatchProp" "ns" 1.000000)
					( Status sCSetFlattened )
					( Origin gBackEnd )
				)
			)
			( pinPair "@baseboard_fab2_lib.baseboard_fab2(sch_1):\PP1348\"
				( pinRef "@baseboard_fab2_lib.baseboard_fab2(sch_1):page62_i172:DDR5_DQS_DP(3)" )
				( pinRef "@baseboard_fab2_lib.baseboard_fab2(sch_1):page87_i187:DQS3P" )
				( attribute "RELATIVE_PROPAGATION_DELAY_SCOPE" "G"
					( Parent
						( matchGroupRef "@baseboard_fab2_lib.baseboard_fab2(sch_1):\MG_DQ-DQS_FAR_DIMM_NG_M_M_BYTE3\" )
					)
					( Status sCSetFlattened )
					( Origin gBackEnd )
				)
				( attribute "RELATIVE_PROPAGATION_DELAY" ",5.00 MIL"
					( Parent
						( matchGroupRef "@baseboard_fab2_lib.baseboard_fab2(sch_1):\MG_DQ-DQS_FAR_DIMM_NG_M_M_BYTE3\" )
					)
					( Units "uMatchProp" "ns" 1.000000)
					( Status sCSetFlattened )
					( Origin gBackEnd )
				)
			)
			( pinPair "@baseboard_fab2_lib.baseboard_fab2(sch_1):\PP1349\"
				( pinRef "@baseboard_fab2_lib.baseboard_fab2(sch_1):page88_i87:DQS3P" )
				( pinRef "@baseboard_fab2_lib.baseboard_fab2(sch_1):page62_i172:DDR5_DQS_DP(3)" )
				( attribute "RELATIVE_PROPAGATION_DELAY_SCOPE" "G"
					( Parent
						( matchGroupRef "@baseboard_fab2_lib.baseboard_fab2(sch_1):\MG_DQ-DQS_NEAR_DIMM_NG_M_M_BYTE3\" )
					)
					( Status sCSetFlattened )
					( Origin gBackEnd )
				)
				( attribute "RELATIVE_PROPAGATION_DELAY" ",5.00 MIL"
					( Parent
						( matchGroupRef "@baseboard_fab2_lib.baseboard_fab2(sch_1):\MG_DQ-DQS_NEAR_DIMM_NG_M_M_BYTE3\" )
					)
					( Units "uMatchProp" "ns" 1.000000)
					( Status sCSetFlattened )
					( Origin gBackEnd )
				)
			)
			( pinPair "@baseboard_fab2_lib.baseboard_fab2(sch_1):\PP1333\"
				( pinRef "@baseboard_fab2_lib.baseboard_fab2(sch_1):page62_i172:DDR5_DQS_DN(4)" )
				( pinRef "@baseboard_fab2_lib.baseboard_fab2(sch_1):page87_i187:DQS4N" )
				( attribute "RELATIVE_PROPAGATION_DELAY_SCOPE" "G"
					( Parent
						( matchGroupRef "@baseboard_fab2_lib.baseboard_fab2(sch_1):\MG_DQ-DQS_FAR_DIMM_NG_M_M_BYTE4\" )
					)
					( Status sCSetFlattened )
					( Origin gBackEnd )
				)
				( attribute "RELATIVE_PROPAGATION_DELAY" ",5.00 MIL"
					( Parent
						( matchGroupRef "@baseboard_fab2_lib.baseboard_fab2(sch_1):\MG_DQ-DQS_FAR_DIMM_NG_M_M_BYTE4\" )
					)
					( Units "uMatchProp" "ns" 1.000000)
					( Status sCSetFlattened )
					( Origin gBackEnd )
				)
			)
			( pinPair "@baseboard_fab2_lib.baseboard_fab2(sch_1):\PP1335\"
				( pinRef "@baseboard_fab2_lib.baseboard_fab2(sch_1):page62_i172:DDR5_DQS_DN(4)" )
				( pinRef "@baseboard_fab2_lib.baseboard_fab2(sch_1):page88_i87:DQS4N" )
				( attribute "RELATIVE_PROPAGATION_DELAY_SCOPE" "G"
					( Parent
						( matchGroupRef "@baseboard_fab2_lib.baseboard_fab2(sch_1):\MG_DQ-DQS_NEAR_DIMM_NG_M_M_BYTE4\" )
					)
					( Status sCSetFlattened )
					( Origin gBackEnd )
				)
				( attribute "RELATIVE_PROPAGATION_DELAY" ",5.00 MIL"
					( Parent
						( matchGroupRef "@baseboard_fab2_lib.baseboard_fab2(sch_1):\MG_DQ-DQS_NEAR_DIMM_NG_M_M_BYTE4\" )
					)
					( Units "uMatchProp" "ns" 1.000000)
					( Status sCSetFlattened )
					( Origin gBackEnd )
				)
			)
			( pinPair "@baseboard_fab2_lib.baseboard_fab2(sch_1):\PP1336\"
				( pinRef "@baseboard_fab2_lib.baseboard_fab2(sch_1):page62_i172:DDR5_DQS_DP(4)" )
				( pinRef "@baseboard_fab2_lib.baseboard_fab2(sch_1):page87_i187:DQS4P" )
				( attribute "RELATIVE_PROPAGATION_DELAY_SCOPE" "G"
					( Parent
						( matchGroupRef "@baseboard_fab2_lib.baseboard_fab2(sch_1):\MG_DQ-DQS_FAR_DIMM_NG_M_M_BYTE4\" )
					)
					( Status sCSetFlattened )
					( Origin gBackEnd )
				)
				( attribute "RELATIVE_PROPAGATION_DELAY" ",5.00 MIL"
					( Parent
						( matchGroupRef "@baseboard_fab2_lib.baseboard_fab2(sch_1):\MG_DQ-DQS_FAR_DIMM_NG_M_M_BYTE4\" )
					)
					( Units "uMatchProp" "ns" 1.000000)
					( Status sCSetFlattened )
					( Origin gBackEnd )
				)
			)
			( pinPair "@baseboard_fab2_lib.baseboard_fab2(sch_1):\PP1338\"
				( pinRef "@baseboard_fab2_lib.baseboard_fab2(sch_1):page62_i172:DDR5_DQS_DP(4)" )
				( pinRef "@baseboard_fab2_lib.baseboard_fab2(sch_1):page88_i87:DQS4P" )
				( attribute "RELATIVE_PROPAGATION_DELAY_SCOPE" "G"
					( Parent
						( matchGroupRef "@baseboard_fab2_lib.baseboard_fab2(sch_1):\MG_DQ-DQS_NEAR_DIMM_NG_M_M_BYTE4\" )
					)
					( Status sCSetFlattened )
					( Origin gBackEnd )
				)
				( attribute "RELATIVE_PROPAGATION_DELAY" ",5.00 MIL"
					( Parent
						( matchGroupRef "@baseboard_fab2_lib.baseboard_fab2(sch_1):\MG_DQ-DQS_NEAR_DIMM_NG_M_M_BYTE4\" )
					)
					( Units "uMatchProp" "ns" 1.000000)
					( Status sCSetFlattened )
					( Origin gBackEnd )
				)
			)
			( pinPair "@baseboard_fab2_lib.baseboard_fab2(sch_1):\PP1321\"
				( pinRef "@baseboard_fab2_lib.baseboard_fab2(sch_1):page62_i172:DDR5_DQS_DN(5)" )
				( pinRef "@baseboard_fab2_lib.baseboard_fab2(sch_1):page87_i187:DQS5N" )
				( attribute "RELATIVE_PROPAGATION_DELAY_SCOPE" "G"
					( Parent
						( matchGroupRef "@baseboard_fab2_lib.baseboard_fab2(sch_1):\MG_DQ-DQS_FAR_DIMM_NG_M_M_BYTE5\" )
					)
					( Status sCSetFlattened )
					( Origin gBackEnd )
				)
				( attribute "RELATIVE_PROPAGATION_DELAY" ",5.00 MIL"
					( Parent
						( matchGroupRef "@baseboard_fab2_lib.baseboard_fab2(sch_1):\MG_DQ-DQS_FAR_DIMM_NG_M_M_BYTE5\" )
					)
					( Units "uMatchProp" "ns" 1.000000)
					( Status sCSetFlattened )
					( Origin gBackEnd )
				)
			)
			( pinPair "@baseboard_fab2_lib.baseboard_fab2(sch_1):\PP1323\"
				( pinRef "@baseboard_fab2_lib.baseboard_fab2(sch_1):page62_i172:DDR5_DQS_DN(5)" )
				( pinRef "@baseboard_fab2_lib.baseboard_fab2(sch_1):page88_i87:DQS5N" )
				( attribute "RELATIVE_PROPAGATION_DELAY_SCOPE" "G"
					( Parent
						( matchGroupRef "@baseboard_fab2_lib.baseboard_fab2(sch_1):\MG_DQ-DQS_NEAR_DIMM_NG_M_M_BYTE5\" )
					)
					( Status sCSetFlattened )
					( Origin gBackEnd )
				)
				( attribute "RELATIVE_PROPAGATION_DELAY" ",5.00 MIL"
					( Parent
						( matchGroupRef "@baseboard_fab2_lib.baseboard_fab2(sch_1):\MG_DQ-DQS_NEAR_DIMM_NG_M_M_BYTE5\" )
					)
					( Units "uMatchProp" "ns" 1.000000)
					( Status sCSetFlattened )
					( Origin gBackEnd )
				)
			)
			( pinPair "@baseboard_fab2_lib.baseboard_fab2(sch_1):\PP1324\"
				( pinRef "@baseboard_fab2_lib.baseboard_fab2(sch_1):page62_i172:DDR5_DQS_DP(5)" )
				( pinRef "@baseboard_fab2_lib.baseboard_fab2(sch_1):page87_i187:DQS5P" )
				( attribute "RELATIVE_PROPAGATION_DELAY_SCOPE" "G"
					( Parent
						( matchGroupRef "@baseboard_fab2_lib.baseboard_fab2(sch_1):\MG_DQ-DQS_FAR_DIMM_NG_M_M_BYTE5\" )
					)
					( Status sCSetFlattened )
					( Origin gBackEnd )
				)
				( attribute "RELATIVE_PROPAGATION_DELAY" ",5.00 MIL"
					( Parent
						( matchGroupRef "@baseboard_fab2_lib.baseboard_fab2(sch_1):\MG_DQ-DQS_FAR_DIMM_NG_M_M_BYTE5\" )
					)
					( Units "uMatchProp" "ns" 1.000000)
					( Status sCSetFlattened )
					( Origin gBackEnd )
				)
			)
			( pinPair "@baseboard_fab2_lib.baseboard_fab2(sch_1):\PP1326\"
				( pinRef "@baseboard_fab2_lib.baseboard_fab2(sch_1):page62_i172:DDR5_DQS_DP(5)" )
				( pinRef "@baseboard_fab2_lib.baseboard_fab2(sch_1):page88_i87:DQS5P" )
				( attribute "RELATIVE_PROPAGATION_DELAY_SCOPE" "G"
					( Parent
						( matchGroupRef "@baseboard_fab2_lib.baseboard_fab2(sch_1):\MG_DQ-DQS_NEAR_DIMM_NG_M_M_BYTE5\" )
					)
					( Status sCSetFlattened )
					( Origin gBackEnd )
				)
				( attribute "RELATIVE_PROPAGATION_DELAY" ",5.00 MIL"
					( Parent
						( matchGroupRef "@baseboard_fab2_lib.baseboard_fab2(sch_1):\MG_DQ-DQS_NEAR_DIMM_NG_M_M_BYTE5\" )
					)
					( Units "uMatchProp" "ns" 1.000000)
					( Status sCSetFlattened )
					( Origin gBackEnd )
				)
			)
			( pinPair "@baseboard_fab2_lib.baseboard_fab2(sch_1):\PP1309\"
				( pinRef "@baseboard_fab2_lib.baseboard_fab2(sch_1):page62_i172:DDR5_DQS_DN(6)" )
				( pinRef "@baseboard_fab2_lib.baseboard_fab2(sch_1):page87_i187:DQS6N" )
				( attribute "RELATIVE_PROPAGATION_DELAY_SCOPE" "G"
					( Parent
						( matchGroupRef "@baseboard_fab2_lib.baseboard_fab2(sch_1):\MG_DQ-DQS_FAR_DIMM_NG_M_M_BYTE6\" )
					)
					( Status sCSetFlattened )
					( Origin gBackEnd )
				)
				( attribute "RELATIVE_PROPAGATION_DELAY" ",5.00 MIL"
					( Parent
						( matchGroupRef "@baseboard_fab2_lib.baseboard_fab2(sch_1):\MG_DQ-DQS_FAR_DIMM_NG_M_M_BYTE6\" )
					)
					( Units "uMatchProp" "ns" 1.000000)
					( Status sCSetFlattened )
					( Origin gBackEnd )
				)
			)
			( pinPair "@baseboard_fab2_lib.baseboard_fab2(sch_1):\PP1311\"
				( pinRef "@baseboard_fab2_lib.baseboard_fab2(sch_1):page62_i172:DDR5_DQS_DN(6)" )
				( pinRef "@baseboard_fab2_lib.baseboard_fab2(sch_1):page88_i87:DQS6N" )
				( attribute "RELATIVE_PROPAGATION_DELAY_SCOPE" "G"
					( Parent
						( matchGroupRef "@baseboard_fab2_lib.baseboard_fab2(sch_1):\MG_DQ-DQS_NEAR_DIMM_NG_M_M_BYTE6\" )
					)
					( Status sCSetFlattened )
					( Origin gBackEnd )
				)
				( attribute "RELATIVE_PROPAGATION_DELAY" ",5.00 MIL"
					( Parent
						( matchGroupRef "@baseboard_fab2_lib.baseboard_fab2(sch_1):\MG_DQ-DQS_NEAR_DIMM_NG_M_M_BYTE6\" )
					)
					( Units "uMatchProp" "ns" 1.000000)
					( Status sCSetFlattened )
					( Origin gBackEnd )
				)
			)
			( pinPair "@baseboard_fab2_lib.baseboard_fab2(sch_1):\PP1312\"
				( pinRef "@baseboard_fab2_lib.baseboard_fab2(sch_1):page62_i172:DDR5_DQS_DP(6)" )
				( pinRef "@baseboard_fab2_lib.baseboard_fab2(sch_1):page87_i187:DQS6P" )
				( attribute "RELATIVE_PROPAGATION_DELAY_SCOPE" "G"
					( Parent
						( matchGroupRef "@baseboard_fab2_lib.baseboard_fab2(sch_1):\MG_DQ-DQS_FAR_DIMM_NG_M_M_BYTE6\" )
					)
					( Status sCSetFlattened )
					( Origin gBackEnd )
				)
				( attribute "RELATIVE_PROPAGATION_DELAY" ",5.00 MIL"
					( Parent
						( matchGroupRef "@baseboard_fab2_lib.baseboard_fab2(sch_1):\MG_DQ-DQS_FAR_DIMM_NG_M_M_BYTE6\" )
					)
					( Units "uMatchProp" "ns" 1.000000)
					( Status sCSetFlattened )
					( Origin gBackEnd )
				)
			)
			( pinPair "@baseboard_fab2_lib.baseboard_fab2(sch_1):\PP1314\"
				( pinRef "@baseboard_fab2_lib.baseboard_fab2(sch_1):page62_i172:DDR5_DQS_DP(6)" )
				( pinRef "@baseboard_fab2_lib.baseboard_fab2(sch_1):page88_i87:DQS6P" )
				( attribute "RELATIVE_PROPAGATION_DELAY_SCOPE" "G"
					( Parent
						( matchGroupRef "@baseboard_fab2_lib.baseboard_fab2(sch_1):\MG_DQ-DQS_NEAR_DIMM_NG_M_M_BYTE6\" )
					)
					( Status sCSetFlattened )
					( Origin gBackEnd )
				)
				( attribute "RELATIVE_PROPAGATION_DELAY" ",5.00 MIL"
					( Parent
						( matchGroupRef "@baseboard_fab2_lib.baseboard_fab2(sch_1):\MG_DQ-DQS_NEAR_DIMM_NG_M_M_BYTE6\" )
					)
					( Units "uMatchProp" "ns" 1.000000)
					( Status sCSetFlattened )
					( Origin gBackEnd )
				)
			)
			( pinPair "@baseboard_fab2_lib.baseboard_fab2(sch_1):\PP1297\"
				( pinRef "@baseboard_fab2_lib.baseboard_fab2(sch_1):page62_i172:DDR5_DQS_DN(7)" )
				( pinRef "@baseboard_fab2_lib.baseboard_fab2(sch_1):page87_i187:DQS7N" )
				( attribute "RELATIVE_PROPAGATION_DELAY_SCOPE" "G"
					( Parent
						( matchGroupRef "@baseboard_fab2_lib.baseboard_fab2(sch_1):\MG_DQ-DQS_FAR_DIMM_NG_M_M_BYTE7\" )
					)
					( Status sCSetFlattened )
					( Origin gBackEnd )
				)
				( attribute "RELATIVE_PROPAGATION_DELAY" ",5.00 MIL"
					( Parent
						( matchGroupRef "@baseboard_fab2_lib.baseboard_fab2(sch_1):\MG_DQ-DQS_FAR_DIMM_NG_M_M_BYTE7\" )
					)
					( Units "uMatchProp" "ns" 1.000000)
					( Status sCSetFlattened )
					( Origin gBackEnd )
				)
			)
			( pinPair "@baseboard_fab2_lib.baseboard_fab2(sch_1):\PP1299\"
				( pinRef "@baseboard_fab2_lib.baseboard_fab2(sch_1):page62_i172:DDR5_DQS_DN(7)" )
				( pinRef "@baseboard_fab2_lib.baseboard_fab2(sch_1):page88_i87:DQS7N" )
				( attribute "RELATIVE_PROPAGATION_DELAY_SCOPE" "G"
					( Parent
						( matchGroupRef "@baseboard_fab2_lib.baseboard_fab2(sch_1):\MG_DQ-DQS_NEAR_DIMM_NG_M_M_BYTE7\" )
					)
					( Status sCSetFlattened )
					( Origin gBackEnd )
				)
				( attribute "RELATIVE_PROPAGATION_DELAY" ",5.00 MIL"
					( Parent
						( matchGroupRef "@baseboard_fab2_lib.baseboard_fab2(sch_1):\MG_DQ-DQS_NEAR_DIMM_NG_M_M_BYTE7\" )
					)
					( Units "uMatchProp" "ns" 1.000000)
					( Status sCSetFlattened )
					( Origin gBackEnd )
				)
			)
			( pinPair "@baseboard_fab2_lib.baseboard_fab2(sch_1):\PP1300\"
				( pinRef "@baseboard_fab2_lib.baseboard_fab2(sch_1):page62_i172:DDR5_DQS_DP(7)" )
				( pinRef "@baseboard_fab2_lib.baseboard_fab2(sch_1):page87_i187:DQS7P" )
				( attribute "RELATIVE_PROPAGATION_DELAY_SCOPE" "G"
					( Parent
						( matchGroupRef "@baseboard_fab2_lib.baseboard_fab2(sch_1):\MG_DQ-DQS_FAR_DIMM_NG_M_M_BYTE7\" )
					)
					( Status sCSetFlattened )
					( Origin gBackEnd )
				)
				( attribute "RELATIVE_PROPAGATION_DELAY" ",5.00 MIL"
					( Parent
						( matchGroupRef "@baseboard_fab2_lib.baseboard_fab2(sch_1):\MG_DQ-DQS_FAR_DIMM_NG_M_M_BYTE7\" )
					)
					( Units "uMatchProp" "ns" 1.000000)
					( Status sCSetFlattened )
					( Origin gBackEnd )
				)
			)
			( pinPair "@baseboard_fab2_lib.baseboard_fab2(sch_1):\PP1302\"
				( pinRef "@baseboard_fab2_lib.baseboard_fab2(sch_1):page62_i172:DDR5_DQS_DP(7)" )
				( pinRef "@baseboard_fab2_lib.baseboard_fab2(sch_1):page88_i87:DQS7P" )
				( attribute "RELATIVE_PROPAGATION_DELAY_SCOPE" "G"
					( Parent
						( matchGroupRef "@baseboard_fab2_lib.baseboard_fab2(sch_1):\MG_DQ-DQS_NEAR_DIMM_NG_M_M_BYTE7\" )
					)
					( Status sCSetFlattened )
					( Origin gBackEnd )
				)
				( attribute "RELATIVE_PROPAGATION_DELAY" ",5.00 MIL"
					( Parent
						( matchGroupRef "@baseboard_fab2_lib.baseboard_fab2(sch_1):\MG_DQ-DQS_NEAR_DIMM_NG_M_M_BYTE7\" )
					)
					( Units "uMatchProp" "ns" 1.000000)
					( Status sCSetFlattened )
					( Origin gBackEnd )
				)
			)
			( pinPair "@baseboard_fab2_lib.baseboard_fab2(sch_1):\PP1285\"
				( pinRef "@baseboard_fab2_lib.baseboard_fab2(sch_1):page62_i172:DDR5_DQS_DN(8)" )
				( pinRef "@baseboard_fab2_lib.baseboard_fab2(sch_1):page87_i187:DQS8N" )
				( attribute "RELATIVE_PROPAGATION_DELAY_SCOPE" "G"
					( Parent
						( matchGroupRef "@baseboard_fab2_lib.baseboard_fab2(sch_1):\MG_DQ-DQS_FAR_DIMM_NG_M_M_BYTE-ECC\" )
					)
					( Status sCSetFlattened )
					( Origin gBackEnd )
				)
				( attribute "RELATIVE_PROPAGATION_DELAY" ",5.00 MIL"
					( Parent
						( matchGroupRef "@baseboard_fab2_lib.baseboard_fab2(sch_1):\MG_DQ-DQS_FAR_DIMM_NG_M_M_BYTE-ECC\" )
					)
					( Units "uMatchProp" "ns" 1.000000)
					( Status sCSetFlattened )
					( Origin gBackEnd )
				)
			)
			( pinPair "@baseboard_fab2_lib.baseboard_fab2(sch_1):\PP1286\"
				( pinRef "@baseboard_fab2_lib.baseboard_fab2(sch_1):page88_i87:DQS8N" )
				( pinRef "@baseboard_fab2_lib.baseboard_fab2(sch_1):page62_i172:DDR5_DQS_DN(8)" )
				( attribute "RELATIVE_PROPAGATION_DELAY_SCOPE" "G"
					( Parent
						( matchGroupRef "@baseboard_fab2_lib.baseboard_fab2(sch_1):\MG_DQ-DQS_NEAR_DIMM_NG_M_M_BYTE-ECC\" )
					)
					( Status sCSetFlattened )
					( Origin gBackEnd )
				)
				( attribute "RELATIVE_PROPAGATION_DELAY" ",5.00 MIL"
					( Parent
						( matchGroupRef "@baseboard_fab2_lib.baseboard_fab2(sch_1):\MG_DQ-DQS_NEAR_DIMM_NG_M_M_BYTE-ECC\" )
					)
					( Units "uMatchProp" "ns" 1.000000)
					( Status sCSetFlattened )
					( Origin gBackEnd )
				)
			)
			( pinPair "@baseboard_fab2_lib.baseboard_fab2(sch_1):\PP1288\"
				( pinRef "@baseboard_fab2_lib.baseboard_fab2(sch_1):page62_i172:DDR5_DQS_DP(8)" )
				( pinRef "@baseboard_fab2_lib.baseboard_fab2(sch_1):page87_i187:DQS8P" )
				( attribute "RELATIVE_PROPAGATION_DELAY_SCOPE" "G"
					( Parent
						( matchGroupRef "@baseboard_fab2_lib.baseboard_fab2(sch_1):\MG_DQ-DQS_FAR_DIMM_NG_M_M_BYTE-ECC\" )
					)
					( Status sCSetFlattened )
					( Origin gBackEnd )
				)
				( attribute "RELATIVE_PROPAGATION_DELAY" ",5.00 MIL"
					( Parent
						( matchGroupRef "@baseboard_fab2_lib.baseboard_fab2(sch_1):\MG_DQ-DQS_FAR_DIMM_NG_M_M_BYTE-ECC\" )
					)
					( Units "uMatchProp" "ns" 1.000000)
					( Status sCSetFlattened )
					( Origin gBackEnd )
				)
			)
			( pinPair "@baseboard_fab2_lib.baseboard_fab2(sch_1):\PP1289\"
				( pinRef "@baseboard_fab2_lib.baseboard_fab2(sch_1):page88_i87:DQS8P" )
				( pinRef "@baseboard_fab2_lib.baseboard_fab2(sch_1):page62_i172:DDR5_DQS_DP(8)" )
				( attribute "RELATIVE_PROPAGATION_DELAY_SCOPE" "G"
					( Parent
						( matchGroupRef "@baseboard_fab2_lib.baseboard_fab2(sch_1):\MG_DQ-DQS_NEAR_DIMM_NG_M_M_BYTE-ECC\" )
					)
					( Status sCSetFlattened )
					( Origin gBackEnd )
				)
				( attribute "RELATIVE_PROPAGATION_DELAY" ",5.00 MIL"
					( Parent
						( matchGroupRef "@baseboard_fab2_lib.baseboard_fab2(sch_1):\MG_DQ-DQS_NEAR_DIMM_NG_M_M_BYTE-ECC\" )
					)
					( Units "uMatchProp" "ns" 1.000000)
					( Status sCSetFlattened )
					( Origin gBackEnd )
				)
			)
			( pinPair "@baseboard_fab2_lib.baseboard_fab2(sch_1):\PP1375\"
				( pinRef "@baseboard_fab2_lib.baseboard_fab2(sch_1):page62_i172:DDR5_DQS_DN(9)" )
				( pinRef "@baseboard_fab2_lib.baseboard_fab2(sch_1):page87_i187:DQS9N" )
				( attribute "RELATIVE_PROPAGATION_DELAY_SCOPE" "G"
					( Parent
						( matchGroupRef "@baseboard_fab2_lib.baseboard_fab2(sch_1):\MG_DQ-DQS_FAR_DIMM_NG_M_M_BYTE0\" )
					)
					( Status sCSetFlattened )
					( Origin gBackEnd )
				)
				( attribute "RELATIVE_PROPAGATION_DELAY" ",5.00 MIL"
					( Parent
						( matchGroupRef "@baseboard_fab2_lib.baseboard_fab2(sch_1):\MG_DQ-DQS_FAR_DIMM_NG_M_M_BYTE0\" )
					)
					( Units "uMatchProp" "ns" 1.000000)
					( Status sCSetFlattened )
					( Origin gBackEnd )
				)
			)
			( pinPair "@baseboard_fab2_lib.baseboard_fab2(sch_1):\PP1376\"
				( pinRef "@baseboard_fab2_lib.baseboard_fab2(sch_1):page88_i87:DQS9N" )
				( pinRef "@baseboard_fab2_lib.baseboard_fab2(sch_1):page62_i172:DDR5_DQS_DN(9)" )
				( attribute "RELATIVE_PROPAGATION_DELAY_SCOPE" "G"
					( Parent
						( matchGroupRef "@baseboard_fab2_lib.baseboard_fab2(sch_1):\MG_DQ-DQS_NEAR_DIMM_NG_M_M_BYTE0\" )
					)
					( Status sCSetFlattened )
					( Origin gBackEnd )
				)
				( attribute "RELATIVE_PROPAGATION_DELAY" ",5.00 MIL"
					( Parent
						( matchGroupRef "@baseboard_fab2_lib.baseboard_fab2(sch_1):\MG_DQ-DQS_NEAR_DIMM_NG_M_M_BYTE0\" )
					)
					( Units "uMatchProp" "ns" 1.000000)
					( Status sCSetFlattened )
					( Origin gBackEnd )
				)
			)
			( pinPair "@baseboard_fab2_lib.baseboard_fab2(sch_1):\PP1378\"
				( pinRef "@baseboard_fab2_lib.baseboard_fab2(sch_1):page62_i172:DDR5_DQS_DP(9)" )
				( pinRef "@baseboard_fab2_lib.baseboard_fab2(sch_1):page87_i187:DQS9P" )
				( attribute "RELATIVE_PROPAGATION_DELAY_SCOPE" "G"
					( Parent
						( matchGroupRef "@baseboard_fab2_lib.baseboard_fab2(sch_1):\MG_DQ-DQS_FAR_DIMM_NG_M_M_BYTE0\" )
					)
					( Status sCSetFlattened )
					( Origin gBackEnd )
				)
				( attribute "RELATIVE_PROPAGATION_DELAY" ",5.00 MIL"
					( Parent
						( matchGroupRef "@baseboard_fab2_lib.baseboard_fab2(sch_1):\MG_DQ-DQS_FAR_DIMM_NG_M_M_BYTE0\" )
					)
					( Units "uMatchProp" "ns" 1.000000)
					( Status sCSetFlattened )
					( Origin gBackEnd )
				)
			)
			( pinPair "@baseboard_fab2_lib.baseboard_fab2(sch_1):\PP1379\"
				( pinRef "@baseboard_fab2_lib.baseboard_fab2(sch_1):page88_i87:DQS9P" )
				( pinRef "@baseboard_fab2_lib.baseboard_fab2(sch_1):page62_i172:DDR5_DQS_DP(9)" )
				( attribute "RELATIVE_PROPAGATION_DELAY_SCOPE" "G"
					( Parent
						( matchGroupRef "@baseboard_fab2_lib.baseboard_fab2(sch_1):\MG_DQ-DQS_NEAR_DIMM_NG_M_M_BYTE0\" )
					)
					( Status sCSetFlattened )
					( Origin gBackEnd )
				)
				( attribute "RELATIVE_PROPAGATION_DELAY" ",5.00 MIL"
					( Parent
						( matchGroupRef "@baseboard_fab2_lib.baseboard_fab2(sch_1):\MG_DQ-DQS_NEAR_DIMM_NG_M_M_BYTE0\" )
					)
					( Units "uMatchProp" "ns" 1.000000)
					( Status sCSetFlattened )
					( Origin gBackEnd )
				)
			)
			( pinPair "@baseboard_fab2_lib.baseboard_fab2(sch_1):\PP1363\"
				( pinRef "@baseboard_fab2_lib.baseboard_fab2(sch_1):page62_i172:DDR5_DQS_DN(10)" )
				( pinRef "@baseboard_fab2_lib.baseboard_fab2(sch_1):page87_i187:DQS10N" )
				( attribute "RELATIVE_PROPAGATION_DELAY_SCOPE" "G"
					( Parent
						( matchGroupRef "@baseboard_fab2_lib.baseboard_fab2(sch_1):\MG_DQ-DQS_FAR_DIMM_NG_M_M_BYTE1\" )
					)
					( Status sCSetFlattened )
					( Origin gBackEnd )
				)
				( attribute "RELATIVE_PROPAGATION_DELAY" ",5.00 MIL"
					( Parent
						( matchGroupRef "@baseboard_fab2_lib.baseboard_fab2(sch_1):\MG_DQ-DQS_FAR_DIMM_NG_M_M_BYTE1\" )
					)
					( Units "uMatchProp" "ns" 1.000000)
					( Status sCSetFlattened )
					( Origin gBackEnd )
				)
			)
			( pinPair "@baseboard_fab2_lib.baseboard_fab2(sch_1):\PP1364\"
				( pinRef "@baseboard_fab2_lib.baseboard_fab2(sch_1):page88_i87:DQS10N" )
				( pinRef "@baseboard_fab2_lib.baseboard_fab2(sch_1):page62_i172:DDR5_DQS_DN(10)" )
				( attribute "RELATIVE_PROPAGATION_DELAY_SCOPE" "G"
					( Parent
						( matchGroupRef "@baseboard_fab2_lib.baseboard_fab2(sch_1):\MG_DQ-DQS_NEAR_DIMM_NG_M_M_BYTE1\" )
					)
					( Status sCSetFlattened )
					( Origin gBackEnd )
				)
				( attribute "RELATIVE_PROPAGATION_DELAY" ",5.00 MIL"
					( Parent
						( matchGroupRef "@baseboard_fab2_lib.baseboard_fab2(sch_1):\MG_DQ-DQS_NEAR_DIMM_NG_M_M_BYTE1\" )
					)
					( Units "uMatchProp" "ns" 1.000000)
					( Status sCSetFlattened )
					( Origin gBackEnd )
				)
			)
			( pinPair "@baseboard_fab2_lib.baseboard_fab2(sch_1):\PP1366\"
				( pinRef "@baseboard_fab2_lib.baseboard_fab2(sch_1):page62_i172:DDR5_DQS_DP(10)" )
				( pinRef "@baseboard_fab2_lib.baseboard_fab2(sch_1):page87_i187:DQS10P" )
				( attribute "RELATIVE_PROPAGATION_DELAY_SCOPE" "G"
					( Parent
						( matchGroupRef "@baseboard_fab2_lib.baseboard_fab2(sch_1):\MG_DQ-DQS_FAR_DIMM_NG_M_M_BYTE1\" )
					)
					( Status sCSetFlattened )
					( Origin gBackEnd )
				)
				( attribute "RELATIVE_PROPAGATION_DELAY" ",5.00 MIL"
					( Parent
						( matchGroupRef "@baseboard_fab2_lib.baseboard_fab2(sch_1):\MG_DQ-DQS_FAR_DIMM_NG_M_M_BYTE1\" )
					)
					( Units "uMatchProp" "ns" 1.000000)
					( Status sCSetFlattened )
					( Origin gBackEnd )
				)
			)
			( pinPair "@baseboard_fab2_lib.baseboard_fab2(sch_1):\PP1367\"
				( pinRef "@baseboard_fab2_lib.baseboard_fab2(sch_1):page88_i87:DQS10P" )
				( pinRef "@baseboard_fab2_lib.baseboard_fab2(sch_1):page62_i172:DDR5_DQS_DP(10)" )
				( attribute "RELATIVE_PROPAGATION_DELAY_SCOPE" "G"
					( Parent
						( matchGroupRef "@baseboard_fab2_lib.baseboard_fab2(sch_1):\MG_DQ-DQS_NEAR_DIMM_NG_M_M_BYTE1\" )
					)
					( Status sCSetFlattened )
					( Origin gBackEnd )
				)
				( attribute "RELATIVE_PROPAGATION_DELAY" ",5.00 MIL"
					( Parent
						( matchGroupRef "@baseboard_fab2_lib.baseboard_fab2(sch_1):\MG_DQ-DQS_NEAR_DIMM_NG_M_M_BYTE1\" )
					)
					( Units "uMatchProp" "ns" 1.000000)
					( Status sCSetFlattened )
					( Origin gBackEnd )
				)
			)
			( pinPair "@baseboard_fab2_lib.baseboard_fab2(sch_1):\PP1351\"
				( pinRef "@baseboard_fab2_lib.baseboard_fab2(sch_1):page62_i172:DDR5_DQS_DN(11)" )
				( pinRef "@baseboard_fab2_lib.baseboard_fab2(sch_1):page87_i187:DQS11N" )
				( attribute "RELATIVE_PROPAGATION_DELAY_SCOPE" "G"
					( Parent
						( matchGroupRef "@baseboard_fab2_lib.baseboard_fab2(sch_1):\MG_DQ-DQS_FAR_DIMM_NG_M_M_BYTE2\" )
					)
					( Status sCSetFlattened )
					( Origin gBackEnd )
				)
				( attribute "RELATIVE_PROPAGATION_DELAY" ",5.00 MIL"
					( Parent
						( matchGroupRef "@baseboard_fab2_lib.baseboard_fab2(sch_1):\MG_DQ-DQS_FAR_DIMM_NG_M_M_BYTE2\" )
					)
					( Units "uMatchProp" "ns" 1.000000)
					( Status sCSetFlattened )
					( Origin gBackEnd )
				)
			)
			( pinPair "@baseboard_fab2_lib.baseboard_fab2(sch_1):\PP1352\"
				( pinRef "@baseboard_fab2_lib.baseboard_fab2(sch_1):page88_i87:DQS11N" )
				( pinRef "@baseboard_fab2_lib.baseboard_fab2(sch_1):page62_i172:DDR5_DQS_DN(11)" )
				( attribute "RELATIVE_PROPAGATION_DELAY_SCOPE" "G"
					( Parent
						( matchGroupRef "@baseboard_fab2_lib.baseboard_fab2(sch_1):\MG_DQ-DQS_NEAR_DIMM_NG_M_M_BYTE2\" )
					)
					( Status sCSetFlattened )
					( Origin gBackEnd )
				)
				( attribute "RELATIVE_PROPAGATION_DELAY" ",5.00 MIL"
					( Parent
						( matchGroupRef "@baseboard_fab2_lib.baseboard_fab2(sch_1):\MG_DQ-DQS_NEAR_DIMM_NG_M_M_BYTE2\" )
					)
					( Units "uMatchProp" "ns" 1.000000)
					( Status sCSetFlattened )
					( Origin gBackEnd )
				)
			)
			( pinPair "@baseboard_fab2_lib.baseboard_fab2(sch_1):\PP1354\"
				( pinRef "@baseboard_fab2_lib.baseboard_fab2(sch_1):page62_i172:DDR5_DQS_DP(11)" )
				( pinRef "@baseboard_fab2_lib.baseboard_fab2(sch_1):page87_i187:DQS11P" )
				( attribute "RELATIVE_PROPAGATION_DELAY_SCOPE" "G"
					( Parent
						( matchGroupRef "@baseboard_fab2_lib.baseboard_fab2(sch_1):\MG_DQ-DQS_FAR_DIMM_NG_M_M_BYTE2\" )
					)
					( Status sCSetFlattened )
					( Origin gBackEnd )
				)
				( attribute "RELATIVE_PROPAGATION_DELAY" ",5.00 MIL"
					( Parent
						( matchGroupRef "@baseboard_fab2_lib.baseboard_fab2(sch_1):\MG_DQ-DQS_FAR_DIMM_NG_M_M_BYTE2\" )
					)
					( Units "uMatchProp" "ns" 1.000000)
					( Status sCSetFlattened )
					( Origin gBackEnd )
				)
			)
			( pinPair "@baseboard_fab2_lib.baseboard_fab2(sch_1):\PP1355\"
				( pinRef "@baseboard_fab2_lib.baseboard_fab2(sch_1):page88_i87:DQS11P" )
				( pinRef "@baseboard_fab2_lib.baseboard_fab2(sch_1):page62_i172:DDR5_DQS_DP(11)" )
				( attribute "RELATIVE_PROPAGATION_DELAY_SCOPE" "G"
					( Parent
						( matchGroupRef "@baseboard_fab2_lib.baseboard_fab2(sch_1):\MG_DQ-DQS_NEAR_DIMM_NG_M_M_BYTE2\" )
					)
					( Status sCSetFlattened )
					( Origin gBackEnd )
				)
				( attribute "RELATIVE_PROPAGATION_DELAY" ",5.00 MIL"
					( Parent
						( matchGroupRef "@baseboard_fab2_lib.baseboard_fab2(sch_1):\MG_DQ-DQS_NEAR_DIMM_NG_M_M_BYTE2\" )
					)
					( Units "uMatchProp" "ns" 1.000000)
					( Status sCSetFlattened )
					( Origin gBackEnd )
				)
			)
			( pinPair "@baseboard_fab2_lib.baseboard_fab2(sch_1):\PP1339\"
				( pinRef "@baseboard_fab2_lib.baseboard_fab2(sch_1):page62_i172:DDR5_DQS_DN(12)" )
				( pinRef "@baseboard_fab2_lib.baseboard_fab2(sch_1):page87_i187:DQS12N" )
				( attribute "RELATIVE_PROPAGATION_DELAY_SCOPE" "G"
					( Parent
						( matchGroupRef "@baseboard_fab2_lib.baseboard_fab2(sch_1):\MG_DQ-DQS_FAR_DIMM_NG_M_M_BYTE3\" )
					)
					( Status sCSetFlattened )
					( Origin gBackEnd )
				)
				( attribute "RELATIVE_PROPAGATION_DELAY" ",5.00 MIL"
					( Parent
						( matchGroupRef "@baseboard_fab2_lib.baseboard_fab2(sch_1):\MG_DQ-DQS_FAR_DIMM_NG_M_M_BYTE3\" )
					)
					( Units "uMatchProp" "ns" 1.000000)
					( Status sCSetFlattened )
					( Origin gBackEnd )
				)
			)
			( pinPair "@baseboard_fab2_lib.baseboard_fab2(sch_1):\PP1340\"
				( pinRef "@baseboard_fab2_lib.baseboard_fab2(sch_1):page88_i87:DQS12N" )
				( pinRef "@baseboard_fab2_lib.baseboard_fab2(sch_1):page62_i172:DDR5_DQS_DN(12)" )
				( attribute "RELATIVE_PROPAGATION_DELAY_SCOPE" "G"
					( Parent
						( matchGroupRef "@baseboard_fab2_lib.baseboard_fab2(sch_1):\MG_DQ-DQS_NEAR_DIMM_NG_M_M_BYTE3\" )
					)
					( Status sCSetFlattened )
					( Origin gBackEnd )
				)
				( attribute "RELATIVE_PROPAGATION_DELAY" ",5.00 MIL"
					( Parent
						( matchGroupRef "@baseboard_fab2_lib.baseboard_fab2(sch_1):\MG_DQ-DQS_NEAR_DIMM_NG_M_M_BYTE3\" )
					)
					( Units "uMatchProp" "ns" 1.000000)
					( Status sCSetFlattened )
					( Origin gBackEnd )
				)
			)
			( pinPair "@baseboard_fab2_lib.baseboard_fab2(sch_1):\PP1342\"
				( pinRef "@baseboard_fab2_lib.baseboard_fab2(sch_1):page62_i172:DDR5_DQS_DP(12)" )
				( pinRef "@baseboard_fab2_lib.baseboard_fab2(sch_1):page87_i187:DQS12P" )
				( attribute "RELATIVE_PROPAGATION_DELAY_SCOPE" "G"
					( Parent
						( matchGroupRef "@baseboard_fab2_lib.baseboard_fab2(sch_1):\MG_DQ-DQS_FAR_DIMM_NG_M_M_BYTE3\" )
					)
					( Status sCSetFlattened )
					( Origin gBackEnd )
				)
				( attribute "RELATIVE_PROPAGATION_DELAY" ",5.00 MIL"
					( Parent
						( matchGroupRef "@baseboard_fab2_lib.baseboard_fab2(sch_1):\MG_DQ-DQS_FAR_DIMM_NG_M_M_BYTE3\" )
					)
					( Units "uMatchProp" "ns" 1.000000)
					( Status sCSetFlattened )
					( Origin gBackEnd )
				)
			)
			( pinPair "@baseboard_fab2_lib.baseboard_fab2(sch_1):\PP1343\"
				( pinRef "@baseboard_fab2_lib.baseboard_fab2(sch_1):page88_i87:DQS12P" )
				( pinRef "@baseboard_fab2_lib.baseboard_fab2(sch_1):page62_i172:DDR5_DQS_DP(12)" )
				( attribute "RELATIVE_PROPAGATION_DELAY_SCOPE" "G"
					( Parent
						( matchGroupRef "@baseboard_fab2_lib.baseboard_fab2(sch_1):\MG_DQ-DQS_NEAR_DIMM_NG_M_M_BYTE3\" )
					)
					( Status sCSetFlattened )
					( Origin gBackEnd )
				)
				( attribute "RELATIVE_PROPAGATION_DELAY" ",5.00 MIL"
					( Parent
						( matchGroupRef "@baseboard_fab2_lib.baseboard_fab2(sch_1):\MG_DQ-DQS_NEAR_DIMM_NG_M_M_BYTE3\" )
					)
					( Units "uMatchProp" "ns" 1.000000)
					( Status sCSetFlattened )
					( Origin gBackEnd )
				)
			)
			( pinPair "@baseboard_fab2_lib.baseboard_fab2(sch_1):\PP1327\"
				( pinRef "@baseboard_fab2_lib.baseboard_fab2(sch_1):page62_i172:DDR5_DQS_DN(13)" )
				( pinRef "@baseboard_fab2_lib.baseboard_fab2(sch_1):page87_i187:DQS13N" )
				( attribute "RELATIVE_PROPAGATION_DELAY_SCOPE" "G"
					( Parent
						( matchGroupRef "@baseboard_fab2_lib.baseboard_fab2(sch_1):\MG_DQ-DQS_FAR_DIMM_NG_M_M_BYTE4\" )
					)
					( Status sCSetFlattened )
					( Origin gBackEnd )
				)
				( attribute "RELATIVE_PROPAGATION_DELAY" ",5.00 MIL"
					( Parent
						( matchGroupRef "@baseboard_fab2_lib.baseboard_fab2(sch_1):\MG_DQ-DQS_FAR_DIMM_NG_M_M_BYTE4\" )
					)
					( Units "uMatchProp" "ns" 1.000000)
					( Status sCSetFlattened )
					( Origin gBackEnd )
				)
			)
			( pinPair "@baseboard_fab2_lib.baseboard_fab2(sch_1):\PP1329\"
				( pinRef "@baseboard_fab2_lib.baseboard_fab2(sch_1):page62_i172:DDR5_DQS_DN(13)" )
				( pinRef "@baseboard_fab2_lib.baseboard_fab2(sch_1):page88_i87:DQS13N" )
				( attribute "RELATIVE_PROPAGATION_DELAY_SCOPE" "G"
					( Parent
						( matchGroupRef "@baseboard_fab2_lib.baseboard_fab2(sch_1):\MG_DQ-DQS_NEAR_DIMM_NG_M_M_BYTE4\" )
					)
					( Status sCSetFlattened )
					( Origin gBackEnd )
				)
				( attribute "RELATIVE_PROPAGATION_DELAY" ",5.00 MIL"
					( Parent
						( matchGroupRef "@baseboard_fab2_lib.baseboard_fab2(sch_1):\MG_DQ-DQS_NEAR_DIMM_NG_M_M_BYTE4\" )
					)
					( Units "uMatchProp" "ns" 1.000000)
					( Status sCSetFlattened )
					( Origin gBackEnd )
				)
			)
			( pinPair "@baseboard_fab2_lib.baseboard_fab2(sch_1):\PP1330\"
				( pinRef "@baseboard_fab2_lib.baseboard_fab2(sch_1):page62_i172:DDR5_DQS_DP(13)" )
				( pinRef "@baseboard_fab2_lib.baseboard_fab2(sch_1):page87_i187:DQS13P" )
				( attribute "RELATIVE_PROPAGATION_DELAY_SCOPE" "G"
					( Parent
						( matchGroupRef "@baseboard_fab2_lib.baseboard_fab2(sch_1):\MG_DQ-DQS_FAR_DIMM_NG_M_M_BYTE4\" )
					)
					( Status sCSetFlattened )
					( Origin gBackEnd )
				)
				( attribute "RELATIVE_PROPAGATION_DELAY" ",5.00 MIL"
					( Parent
						( matchGroupRef "@baseboard_fab2_lib.baseboard_fab2(sch_1):\MG_DQ-DQS_FAR_DIMM_NG_M_M_BYTE4\" )
					)
					( Units "uMatchProp" "ns" 1.000000)
					( Status sCSetFlattened )
					( Origin gBackEnd )
				)
			)
			( pinPair "@baseboard_fab2_lib.baseboard_fab2(sch_1):\PP1332\"
				( pinRef "@baseboard_fab2_lib.baseboard_fab2(sch_1):page62_i172:DDR5_DQS_DP(13)" )
				( pinRef "@baseboard_fab2_lib.baseboard_fab2(sch_1):page88_i87:DQS13P" )
				( attribute "RELATIVE_PROPAGATION_DELAY_SCOPE" "G"
					( Parent
						( matchGroupRef "@baseboard_fab2_lib.baseboard_fab2(sch_1):\MG_DQ-DQS_NEAR_DIMM_NG_M_M_BYTE4\" )
					)
					( Status sCSetFlattened )
					( Origin gBackEnd )
				)
				( attribute "RELATIVE_PROPAGATION_DELAY" ",5.00 MIL"
					( Parent
						( matchGroupRef "@baseboard_fab2_lib.baseboard_fab2(sch_1):\MG_DQ-DQS_NEAR_DIMM_NG_M_M_BYTE4\" )
					)
					( Units "uMatchProp" "ns" 1.000000)
					( Status sCSetFlattened )
					( Origin gBackEnd )
				)
			)
			( pinPair "@baseboard_fab2_lib.baseboard_fab2(sch_1):\PP1315\"
				( pinRef "@baseboard_fab2_lib.baseboard_fab2(sch_1):page62_i172:DDR5_DQS_DN(14)" )
				( pinRef "@baseboard_fab2_lib.baseboard_fab2(sch_1):page87_i187:DQS14N" )
				( attribute "RELATIVE_PROPAGATION_DELAY_SCOPE" "G"
					( Parent
						( matchGroupRef "@baseboard_fab2_lib.baseboard_fab2(sch_1):\MG_DQ-DQS_FAR_DIMM_NG_M_M_BYTE5\" )
					)
					( Status sCSetFlattened )
					( Origin gBackEnd )
				)
				( attribute "RELATIVE_PROPAGATION_DELAY" ",5.00 MIL"
					( Parent
						( matchGroupRef "@baseboard_fab2_lib.baseboard_fab2(sch_1):\MG_DQ-DQS_FAR_DIMM_NG_M_M_BYTE5\" )
					)
					( Units "uMatchProp" "ns" 1.000000)
					( Status sCSetFlattened )
					( Origin gBackEnd )
				)
			)
			( pinPair "@baseboard_fab2_lib.baseboard_fab2(sch_1):\PP1317\"
				( pinRef "@baseboard_fab2_lib.baseboard_fab2(sch_1):page62_i172:DDR5_DQS_DN(14)" )
				( pinRef "@baseboard_fab2_lib.baseboard_fab2(sch_1):page88_i87:DQS14N" )
				( attribute "RELATIVE_PROPAGATION_DELAY_SCOPE" "G"
					( Parent
						( matchGroupRef "@baseboard_fab2_lib.baseboard_fab2(sch_1):\MG_DQ-DQS_NEAR_DIMM_NG_M_M_BYTE5\" )
					)
					( Status sCSetFlattened )
					( Origin gBackEnd )
				)
				( attribute "RELATIVE_PROPAGATION_DELAY" ",5.00 MIL"
					( Parent
						( matchGroupRef "@baseboard_fab2_lib.baseboard_fab2(sch_1):\MG_DQ-DQS_NEAR_DIMM_NG_M_M_BYTE5\" )
					)
					( Units "uMatchProp" "ns" 1.000000)
					( Status sCSetFlattened )
					( Origin gBackEnd )
				)
			)
			( pinPair "@baseboard_fab2_lib.baseboard_fab2(sch_1):\PP1318\"
				( pinRef "@baseboard_fab2_lib.baseboard_fab2(sch_1):page62_i172:DDR5_DQS_DP(14)" )
				( pinRef "@baseboard_fab2_lib.baseboard_fab2(sch_1):page87_i187:DQS14P" )
				( attribute "RELATIVE_PROPAGATION_DELAY_SCOPE" "G"
					( Parent
						( matchGroupRef "@baseboard_fab2_lib.baseboard_fab2(sch_1):\MG_DQ-DQS_FAR_DIMM_NG_M_M_BYTE5\" )
					)
					( Status sCSetFlattened )
					( Origin gBackEnd )
				)
				( attribute "RELATIVE_PROPAGATION_DELAY" ",5.00 MIL"
					( Parent
						( matchGroupRef "@baseboard_fab2_lib.baseboard_fab2(sch_1):\MG_DQ-DQS_FAR_DIMM_NG_M_M_BYTE5\" )
					)
					( Units "uMatchProp" "ns" 1.000000)
					( Status sCSetFlattened )
					( Origin gBackEnd )
				)
			)
			( pinPair "@baseboard_fab2_lib.baseboard_fab2(sch_1):\PP1320\"
				( pinRef "@baseboard_fab2_lib.baseboard_fab2(sch_1):page62_i172:DDR5_DQS_DP(14)" )
				( pinRef "@baseboard_fab2_lib.baseboard_fab2(sch_1):page88_i87:DQS14P" )
				( attribute "RELATIVE_PROPAGATION_DELAY_SCOPE" "G"
					( Parent
						( matchGroupRef "@baseboard_fab2_lib.baseboard_fab2(sch_1):\MG_DQ-DQS_NEAR_DIMM_NG_M_M_BYTE5\" )
					)
					( Status sCSetFlattened )
					( Origin gBackEnd )
				)
				( attribute "RELATIVE_PROPAGATION_DELAY" ",5.00 MIL"
					( Parent
						( matchGroupRef "@baseboard_fab2_lib.baseboard_fab2(sch_1):\MG_DQ-DQS_NEAR_DIMM_NG_M_M_BYTE5\" )
					)
					( Units "uMatchProp" "ns" 1.000000)
					( Status sCSetFlattened )
					( Origin gBackEnd )
				)
			)
			( pinPair "@baseboard_fab2_lib.baseboard_fab2(sch_1):\PP1303\"
				( pinRef "@baseboard_fab2_lib.baseboard_fab2(sch_1):page62_i172:DDR5_DQS_DN(15)" )
				( pinRef "@baseboard_fab2_lib.baseboard_fab2(sch_1):page87_i187:DQS15N" )
				( attribute "RELATIVE_PROPAGATION_DELAY_SCOPE" "G"
					( Parent
						( matchGroupRef "@baseboard_fab2_lib.baseboard_fab2(sch_1):\MG_DQ-DQS_FAR_DIMM_NG_M_M_BYTE6\" )
					)
					( Status sCSetFlattened )
					( Origin gBackEnd )
				)
				( attribute "RELATIVE_PROPAGATION_DELAY" ",5.00 MIL"
					( Parent
						( matchGroupRef "@baseboard_fab2_lib.baseboard_fab2(sch_1):\MG_DQ-DQS_FAR_DIMM_NG_M_M_BYTE6\" )
					)
					( Units "uMatchProp" "ns" 1.000000)
					( Status sCSetFlattened )
					( Origin gBackEnd )
				)
			)
			( pinPair "@baseboard_fab2_lib.baseboard_fab2(sch_1):\PP1305\"
				( pinRef "@baseboard_fab2_lib.baseboard_fab2(sch_1):page62_i172:DDR5_DQS_DN(15)" )
				( pinRef "@baseboard_fab2_lib.baseboard_fab2(sch_1):page88_i87:DQS15N" )
				( attribute "RELATIVE_PROPAGATION_DELAY_SCOPE" "G"
					( Parent
						( matchGroupRef "@baseboard_fab2_lib.baseboard_fab2(sch_1):\MG_DQ-DQS_NEAR_DIMM_NG_M_M_BYTE6\" )
					)
					( Status sCSetFlattened )
					( Origin gBackEnd )
				)
				( attribute "RELATIVE_PROPAGATION_DELAY" ",5.00 MIL"
					( Parent
						( matchGroupRef "@baseboard_fab2_lib.baseboard_fab2(sch_1):\MG_DQ-DQS_NEAR_DIMM_NG_M_M_BYTE6\" )
					)
					( Units "uMatchProp" "ns" 1.000000)
					( Status sCSetFlattened )
					( Origin gBackEnd )
				)
			)
			( pinPair "@baseboard_fab2_lib.baseboard_fab2(sch_1):\PP1306\"
				( pinRef "@baseboard_fab2_lib.baseboard_fab2(sch_1):page62_i172:DDR5_DQS_DP(15)" )
				( pinRef "@baseboard_fab2_lib.baseboard_fab2(sch_1):page87_i187:DQS15P" )
				( attribute "RELATIVE_PROPAGATION_DELAY_SCOPE" "G"
					( Parent
						( matchGroupRef "@baseboard_fab2_lib.baseboard_fab2(sch_1):\MG_DQ-DQS_FAR_DIMM_NG_M_M_BYTE6\" )
					)
					( Status sCSetFlattened )
					( Origin gBackEnd )
				)
				( attribute "RELATIVE_PROPAGATION_DELAY" ",5.00 MIL"
					( Parent
						( matchGroupRef "@baseboard_fab2_lib.baseboard_fab2(sch_1):\MG_DQ-DQS_FAR_DIMM_NG_M_M_BYTE6\" )
					)
					( Units "uMatchProp" "ns" 1.000000)
					( Status sCSetFlattened )
					( Origin gBackEnd )
				)
			)
			( pinPair "@baseboard_fab2_lib.baseboard_fab2(sch_1):\PP1308\"
				( pinRef "@baseboard_fab2_lib.baseboard_fab2(sch_1):page62_i172:DDR5_DQS_DP(15)" )
				( pinRef "@baseboard_fab2_lib.baseboard_fab2(sch_1):page88_i87:DQS15P" )
				( attribute "RELATIVE_PROPAGATION_DELAY_SCOPE" "G"
					( Parent
						( matchGroupRef "@baseboard_fab2_lib.baseboard_fab2(sch_1):\MG_DQ-DQS_NEAR_DIMM_NG_M_M_BYTE6\" )
					)
					( Status sCSetFlattened )
					( Origin gBackEnd )
				)
				( attribute "RELATIVE_PROPAGATION_DELAY" ",5.00 MIL"
					( Parent
						( matchGroupRef "@baseboard_fab2_lib.baseboard_fab2(sch_1):\MG_DQ-DQS_NEAR_DIMM_NG_M_M_BYTE6\" )
					)
					( Units "uMatchProp" "ns" 1.000000)
					( Status sCSetFlattened )
					( Origin gBackEnd )
				)
			)
			( pinPair "@baseboard_fab2_lib.baseboard_fab2(sch_1):\PP1291\"
				( pinRef "@baseboard_fab2_lib.baseboard_fab2(sch_1):page62_i172:DDR5_DQS_DN(16)" )
				( pinRef "@baseboard_fab2_lib.baseboard_fab2(sch_1):page87_i187:DQS16N" )
				( attribute "RELATIVE_PROPAGATION_DELAY_SCOPE" "G"
					( Parent
						( matchGroupRef "@baseboard_fab2_lib.baseboard_fab2(sch_1):\MG_DQ-DQS_FAR_DIMM_NG_M_M_BYTE7\" )
					)
					( Status sCSetFlattened )
					( Origin gBackEnd )
				)
				( attribute "RELATIVE_PROPAGATION_DELAY" ",5.00 MIL"
					( Parent
						( matchGroupRef "@baseboard_fab2_lib.baseboard_fab2(sch_1):\MG_DQ-DQS_FAR_DIMM_NG_M_M_BYTE7\" )
					)
					( Units "uMatchProp" "ns" 1.000000)
					( Status sCSetFlattened )
					( Origin gBackEnd )
				)
			)
			( pinPair "@baseboard_fab2_lib.baseboard_fab2(sch_1):\PP1293\"
				( pinRef "@baseboard_fab2_lib.baseboard_fab2(sch_1):page62_i172:DDR5_DQS_DN(16)" )
				( pinRef "@baseboard_fab2_lib.baseboard_fab2(sch_1):page88_i87:DQS16N" )
				( attribute "RELATIVE_PROPAGATION_DELAY_SCOPE" "G"
					( Parent
						( matchGroupRef "@baseboard_fab2_lib.baseboard_fab2(sch_1):\MG_DQ-DQS_NEAR_DIMM_NG_M_M_BYTE7\" )
					)
					( Status sCSetFlattened )
					( Origin gBackEnd )
				)
				( attribute "RELATIVE_PROPAGATION_DELAY" ",5.00 MIL"
					( Parent
						( matchGroupRef "@baseboard_fab2_lib.baseboard_fab2(sch_1):\MG_DQ-DQS_NEAR_DIMM_NG_M_M_BYTE7\" )
					)
					( Units "uMatchProp" "ns" 1.000000)
					( Status sCSetFlattened )
					( Origin gBackEnd )
				)
			)
			( pinPair "@baseboard_fab2_lib.baseboard_fab2(sch_1):\PP1294\"
				( pinRef "@baseboard_fab2_lib.baseboard_fab2(sch_1):page62_i172:DDR5_DQS_DP(16)" )
				( pinRef "@baseboard_fab2_lib.baseboard_fab2(sch_1):page87_i187:DQS16P" )
				( attribute "RELATIVE_PROPAGATION_DELAY_SCOPE" "G"
					( Parent
						( matchGroupRef "@baseboard_fab2_lib.baseboard_fab2(sch_1):\MG_DQ-DQS_FAR_DIMM_NG_M_M_BYTE7\" )
					)
					( Status sCSetFlattened )
					( Origin gBackEnd )
				)
				( attribute "RELATIVE_PROPAGATION_DELAY" ",5.00 MIL"
					( Parent
						( matchGroupRef "@baseboard_fab2_lib.baseboard_fab2(sch_1):\MG_DQ-DQS_FAR_DIMM_NG_M_M_BYTE7\" )
					)
					( Units "uMatchProp" "ns" 1.000000)
					( Status sCSetFlattened )
					( Origin gBackEnd )
				)
			)
			( pinPair "@baseboard_fab2_lib.baseboard_fab2(sch_1):\PP1296\"
				( pinRef "@baseboard_fab2_lib.baseboard_fab2(sch_1):page62_i172:DDR5_DQS_DP(16)" )
				( pinRef "@baseboard_fab2_lib.baseboard_fab2(sch_1):page88_i87:DQS16P" )
				( attribute "RELATIVE_PROPAGATION_DELAY_SCOPE" "G"
					( Parent
						( matchGroupRef "@baseboard_fab2_lib.baseboard_fab2(sch_1):\MG_DQ-DQS_NEAR_DIMM_NG_M_M_BYTE7\" )
					)
					( Status sCSetFlattened )
					( Origin gBackEnd )
				)
				( attribute "RELATIVE_PROPAGATION_DELAY" ",5.00 MIL"
					( Parent
						( matchGroupRef "@baseboard_fab2_lib.baseboard_fab2(sch_1):\MG_DQ-DQS_NEAR_DIMM_NG_M_M_BYTE7\" )
					)
					( Units "uMatchProp" "ns" 1.000000)
					( Status sCSetFlattened )
					( Origin gBackEnd )
				)
			)
			( pinPair "@baseboard_fab2_lib.baseboard_fab2(sch_1):\PP1279\"
				( pinRef "@baseboard_fab2_lib.baseboard_fab2(sch_1):page62_i172:DDR5_DQS_DN(17)" )
				( pinRef "@baseboard_fab2_lib.baseboard_fab2(sch_1):page87_i187:DQS17N" )
				( attribute "RELATIVE_PROPAGATION_DELAY_SCOPE" "G"
					( Parent
						( matchGroupRef "@baseboard_fab2_lib.baseboard_fab2(sch_1):\MG_DQ-DQS_FAR_DIMM_NG_M_M_BYTE-ECC\" )
					)
					( Status sCSetFlattened )
					( Origin gBackEnd )
				)
				( attribute "RELATIVE_PROPAGATION_DELAY" ",5.00 MIL"
					( Parent
						( matchGroupRef "@baseboard_fab2_lib.baseboard_fab2(sch_1):\MG_DQ-DQS_FAR_DIMM_NG_M_M_BYTE-ECC\" )
					)
					( Units "uMatchProp" "ns" 1.000000)
					( Status sCSetFlattened )
					( Origin gBackEnd )
				)
			)
			( pinPair "@baseboard_fab2_lib.baseboard_fab2(sch_1):\PP1280\"
				( pinRef "@baseboard_fab2_lib.baseboard_fab2(sch_1):page88_i87:DQS17N" )
				( pinRef "@baseboard_fab2_lib.baseboard_fab2(sch_1):page62_i172:DDR5_DQS_DN(17)" )
				( attribute "RELATIVE_PROPAGATION_DELAY_SCOPE" "G"
					( Parent
						( matchGroupRef "@baseboard_fab2_lib.baseboard_fab2(sch_1):\MG_DQ-DQS_NEAR_DIMM_NG_M_M_BYTE-ECC\" )
					)
					( Status sCSetFlattened )
					( Origin gBackEnd )
				)
				( attribute "RELATIVE_PROPAGATION_DELAY" ",5.00 MIL"
					( Parent
						( matchGroupRef "@baseboard_fab2_lib.baseboard_fab2(sch_1):\MG_DQ-DQS_NEAR_DIMM_NG_M_M_BYTE-ECC\" )
					)
					( Units "uMatchProp" "ns" 1.000000)
					( Status sCSetFlattened )
					( Origin gBackEnd )
				)
			)
			( pinPair "@baseboard_fab2_lib.baseboard_fab2(sch_1):\PP1282\"
				( pinRef "@baseboard_fab2_lib.baseboard_fab2(sch_1):page62_i172:DDR5_DQS_DP(17)" )
				( pinRef "@baseboard_fab2_lib.baseboard_fab2(sch_1):page87_i187:DQS17P" )
				( attribute "RELATIVE_PROPAGATION_DELAY_SCOPE" "G"
					( Parent
						( matchGroupRef "@baseboard_fab2_lib.baseboard_fab2(sch_1):\MG_DQ-DQS_FAR_DIMM_NG_M_M_BYTE-ECC\" )
					)
					( Status sCSetFlattened )
					( Origin gBackEnd )
				)
				( attribute "RELATIVE_PROPAGATION_DELAY" ",5.00 MIL"
					( Parent
						( matchGroupRef "@baseboard_fab2_lib.baseboard_fab2(sch_1):\MG_DQ-DQS_FAR_DIMM_NG_M_M_BYTE-ECC\" )
					)
					( Units "uMatchProp" "ns" 1.000000)
					( Status sCSetFlattened )
					( Origin gBackEnd )
				)
			)
			( pinPair "@baseboard_fab2_lib.baseboard_fab2(sch_1):\PP1283\"
				( pinRef "@baseboard_fab2_lib.baseboard_fab2(sch_1):page88_i87:DQS17P" )
				( pinRef "@baseboard_fab2_lib.baseboard_fab2(sch_1):page62_i172:DDR5_DQS_DP(17)" )
				( attribute "RELATIVE_PROPAGATION_DELAY_SCOPE" "G"
					( Parent
						( matchGroupRef "@baseboard_fab2_lib.baseboard_fab2(sch_1):\MG_DQ-DQS_NEAR_DIMM_NG_M_M_BYTE-ECC\" )
					)
					( Status sCSetFlattened )
					( Origin gBackEnd )
				)
				( attribute "RELATIVE_PROPAGATION_DELAY" ",5.00 MIL"
					( Parent
						( matchGroupRef "@baseboard_fab2_lib.baseboard_fab2(sch_1):\MG_DQ-DQS_NEAR_DIMM_NG_M_M_BYTE-ECC\" )
					)
					( Units "uMatchProp" "ns" 1.000000)
					( Status sCSetFlattened )
					( Origin gBackEnd )
				)
			)
			( pinPair "@baseboard_fab2_lib.baseboard_fab2(sch_1):\PP973\"
				( pinRef "@baseboard_fab2_lib.baseboard_fab2(sch_1):page57_i172:DDR0_DQS_DN(0)" )
				( pinRef "@baseboard_fab2_lib.baseboard_fab2(sch_1):page77_i66:DQS0N" )
				( attribute "RELATIVE_PROPAGATION_DELAY_SCOPE" "G"
					( Parent
						( matchGroupRef "@baseboard_fab2_lib.baseboard_fab2(sch_1):\MG_DQ-DQS_FAR_DIMM_NG_M_G_BYTE0\" )
					)
					( Status sCSetFlattened )
					( Origin gBackEnd )
				)
				( attribute "RELATIVE_PROPAGATION_DELAY" ",5.00 MIL"
					( Parent
						( matchGroupRef "@baseboard_fab2_lib.baseboard_fab2(sch_1):\MG_DQ-DQS_FAR_DIMM_NG_M_G_BYTE0\" )
					)
					( Units "uMatchProp" "ns" 1.000000)
					( Status sCSetFlattened )
					( Origin gBackEnd )
				)
			)
			( pinPair "@baseboard_fab2_lib.baseboard_fab2(sch_1):\PP974\"
				( pinRef "@baseboard_fab2_lib.baseboard_fab2(sch_1):page78_i120:DQS0N" )
				( pinRef "@baseboard_fab2_lib.baseboard_fab2(sch_1):page57_i172:DDR0_DQS_DN(0)" )
				( attribute "RELATIVE_PROPAGATION_DELAY_SCOPE" "G"
					( Parent
						( matchGroupRef "@baseboard_fab2_lib.baseboard_fab2(sch_1):\MG_DQ-DQS_NEAR_DIMM_NG_M_G_BYTE0\" )
					)
					( Status sCSetFlattened )
					( Origin gBackEnd )
				)
				( attribute "RELATIVE_PROPAGATION_DELAY" ",5.00 MIL"
					( Parent
						( matchGroupRef "@baseboard_fab2_lib.baseboard_fab2(sch_1):\MG_DQ-DQS_NEAR_DIMM_NG_M_G_BYTE0\" )
					)
					( Units "uMatchProp" "ns" 1.000000)
					( Status sCSetFlattened )
					( Origin gBackEnd )
				)
			)
			( pinPair "@baseboard_fab2_lib.baseboard_fab2(sch_1):\PP976\"
				( pinRef "@baseboard_fab2_lib.baseboard_fab2(sch_1):page57_i172:DDR0_DQS_DP(0)" )
				( pinRef "@baseboard_fab2_lib.baseboard_fab2(sch_1):page77_i66:DQS0P" )
				( attribute "RELATIVE_PROPAGATION_DELAY_SCOPE" "G"
					( Parent
						( matchGroupRef "@baseboard_fab2_lib.baseboard_fab2(sch_1):\MG_DQ-DQS_FAR_DIMM_NG_M_G_BYTE0\" )
					)
					( Status sCSetFlattened )
					( Origin gBackEnd )
				)
				( attribute "RELATIVE_PROPAGATION_DELAY" ",5.00 MIL"
					( Parent
						( matchGroupRef "@baseboard_fab2_lib.baseboard_fab2(sch_1):\MG_DQ-DQS_FAR_DIMM_NG_M_G_BYTE0\" )
					)
					( Units "uMatchProp" "ns" 1.000000)
					( Status sCSetFlattened )
					( Origin gBackEnd )
				)
			)
			( pinPair "@baseboard_fab2_lib.baseboard_fab2(sch_1):\PP977\"
				( pinRef "@baseboard_fab2_lib.baseboard_fab2(sch_1):page78_i120:DQS0P" )
				( pinRef "@baseboard_fab2_lib.baseboard_fab2(sch_1):page57_i172:DDR0_DQS_DP(0)" )
				( attribute "RELATIVE_PROPAGATION_DELAY_SCOPE" "G"
					( Parent
						( matchGroupRef "@baseboard_fab2_lib.baseboard_fab2(sch_1):\MG_DQ-DQS_NEAR_DIMM_NG_M_G_BYTE0\" )
					)
					( Status sCSetFlattened )
					( Origin gBackEnd )
				)
				( attribute "RELATIVE_PROPAGATION_DELAY" ",5.00 MIL"
					( Parent
						( matchGroupRef "@baseboard_fab2_lib.baseboard_fab2(sch_1):\MG_DQ-DQS_NEAR_DIMM_NG_M_G_BYTE0\" )
					)
					( Units "uMatchProp" "ns" 1.000000)
					( Status sCSetFlattened )
					( Origin gBackEnd )
				)
			)
			( pinPair "@baseboard_fab2_lib.baseboard_fab2(sch_1):\PP961\"
				( pinRef "@baseboard_fab2_lib.baseboard_fab2(sch_1):page57_i172:DDR0_DQS_DN(1)" )
				( pinRef "@baseboard_fab2_lib.baseboard_fab2(sch_1):page77_i66:DQS1N" )
				( attribute "RELATIVE_PROPAGATION_DELAY_SCOPE" "G"
					( Parent
						( matchGroupRef "@baseboard_fab2_lib.baseboard_fab2(sch_1):\MG_DQ-DQS_FAR_DIMM_NG_M_G_BYTE1\" )
					)
					( Status sCSetFlattened )
					( Origin gBackEnd )
				)
				( attribute "RELATIVE_PROPAGATION_DELAY" ",5.00 MIL"
					( Parent
						( matchGroupRef "@baseboard_fab2_lib.baseboard_fab2(sch_1):\MG_DQ-DQS_FAR_DIMM_NG_M_G_BYTE1\" )
					)
					( Units "uMatchProp" "ns" 1.000000)
					( Status sCSetFlattened )
					( Origin gBackEnd )
				)
			)
			( pinPair "@baseboard_fab2_lib.baseboard_fab2(sch_1):\PP962\"
				( pinRef "@baseboard_fab2_lib.baseboard_fab2(sch_1):page78_i120:DQS1N" )
				( pinRef "@baseboard_fab2_lib.baseboard_fab2(sch_1):page57_i172:DDR0_DQS_DN(1)" )
				( attribute "RELATIVE_PROPAGATION_DELAY_SCOPE" "G"
					( Parent
						( matchGroupRef "@baseboard_fab2_lib.baseboard_fab2(sch_1):\MG_DQ-DQS_NEAR_DIMM_NG_M_G_BYTE1\" )
					)
					( Status sCSetFlattened )
					( Origin gBackEnd )
				)
				( attribute "RELATIVE_PROPAGATION_DELAY" ",5.00 MIL"
					( Parent
						( matchGroupRef "@baseboard_fab2_lib.baseboard_fab2(sch_1):\MG_DQ-DQS_NEAR_DIMM_NG_M_G_BYTE1\" )
					)
					( Units "uMatchProp" "ns" 1.000000)
					( Status sCSetFlattened )
					( Origin gBackEnd )
				)
			)
			( pinPair "@baseboard_fab2_lib.baseboard_fab2(sch_1):\PP964\"
				( pinRef "@baseboard_fab2_lib.baseboard_fab2(sch_1):page57_i172:DDR0_DQS_DP(1)" )
				( pinRef "@baseboard_fab2_lib.baseboard_fab2(sch_1):page77_i66:DQS1P" )
				( attribute "RELATIVE_PROPAGATION_DELAY_SCOPE" "G"
					( Parent
						( matchGroupRef "@baseboard_fab2_lib.baseboard_fab2(sch_1):\MG_DQ-DQS_FAR_DIMM_NG_M_G_BYTE1\" )
					)
					( Status sCSetFlattened )
					( Origin gBackEnd )
				)
				( attribute "RELATIVE_PROPAGATION_DELAY" ",5.00 MIL"
					( Parent
						( matchGroupRef "@baseboard_fab2_lib.baseboard_fab2(sch_1):\MG_DQ-DQS_FAR_DIMM_NG_M_G_BYTE1\" )
					)
					( Units "uMatchProp" "ns" 1.000000)
					( Status sCSetFlattened )
					( Origin gBackEnd )
				)
			)
			( pinPair "@baseboard_fab2_lib.baseboard_fab2(sch_1):\PP965\"
				( pinRef "@baseboard_fab2_lib.baseboard_fab2(sch_1):page78_i120:DQS1P" )
				( pinRef "@baseboard_fab2_lib.baseboard_fab2(sch_1):page57_i172:DDR0_DQS_DP(1)" )
				( attribute "RELATIVE_PROPAGATION_DELAY_SCOPE" "G"
					( Parent
						( matchGroupRef "@baseboard_fab2_lib.baseboard_fab2(sch_1):\MG_DQ-DQS_NEAR_DIMM_NG_M_G_BYTE1\" )
					)
					( Status sCSetFlattened )
					( Origin gBackEnd )
				)
				( attribute "RELATIVE_PROPAGATION_DELAY" ",5.00 MIL"
					( Parent
						( matchGroupRef "@baseboard_fab2_lib.baseboard_fab2(sch_1):\MG_DQ-DQS_NEAR_DIMM_NG_M_G_BYTE1\" )
					)
					( Units "uMatchProp" "ns" 1.000000)
					( Status sCSetFlattened )
					( Origin gBackEnd )
				)
			)
			( pinPair "@baseboard_fab2_lib.baseboard_fab2(sch_1):\PP949\"
				( pinRef "@baseboard_fab2_lib.baseboard_fab2(sch_1):page57_i172:DDR0_DQS_DN(2)" )
				( pinRef "@baseboard_fab2_lib.baseboard_fab2(sch_1):page77_i66:DQS2N" )
				( attribute "RELATIVE_PROPAGATION_DELAY_SCOPE" "G"
					( Parent
						( matchGroupRef "@baseboard_fab2_lib.baseboard_fab2(sch_1):\MG_DQ-DQS_FAR_DIMM_NG_M_G_BYTE2\" )
					)
					( Status sCSetFlattened )
					( Origin gBackEnd )
				)
				( attribute "RELATIVE_PROPAGATION_DELAY" ",5.00 MIL"
					( Parent
						( matchGroupRef "@baseboard_fab2_lib.baseboard_fab2(sch_1):\MG_DQ-DQS_FAR_DIMM_NG_M_G_BYTE2\" )
					)
					( Units "uMatchProp" "ns" 1.000000)
					( Status sCSetFlattened )
					( Origin gBackEnd )
				)
			)
			( pinPair "@baseboard_fab2_lib.baseboard_fab2(sch_1):\PP950\"
				( pinRef "@baseboard_fab2_lib.baseboard_fab2(sch_1):page78_i120:DQS2N" )
				( pinRef "@baseboard_fab2_lib.baseboard_fab2(sch_1):page57_i172:DDR0_DQS_DN(2)" )
				( attribute "RELATIVE_PROPAGATION_DELAY_SCOPE" "G"
					( Parent
						( matchGroupRef "@baseboard_fab2_lib.baseboard_fab2(sch_1):\MG_DQ-DQS_NEAR_DIMM_NG_M_G_BYTE2\" )
					)
					( Status sCSetFlattened )
					( Origin gBackEnd )
				)
				( attribute "RELATIVE_PROPAGATION_DELAY" ",5.00 MIL"
					( Parent
						( matchGroupRef "@baseboard_fab2_lib.baseboard_fab2(sch_1):\MG_DQ-DQS_NEAR_DIMM_NG_M_G_BYTE2\" )
					)
					( Units "uMatchProp" "ns" 1.000000)
					( Status sCSetFlattened )
					( Origin gBackEnd )
				)
			)
			( pinPair "@baseboard_fab2_lib.baseboard_fab2(sch_1):\PP952\"
				( pinRef "@baseboard_fab2_lib.baseboard_fab2(sch_1):page57_i172:DDR0_DQS_DP(2)" )
				( pinRef "@baseboard_fab2_lib.baseboard_fab2(sch_1):page77_i66:DQS2P" )
				( attribute "RELATIVE_PROPAGATION_DELAY_SCOPE" "G"
					( Parent
						( matchGroupRef "@baseboard_fab2_lib.baseboard_fab2(sch_1):\MG_DQ-DQS_FAR_DIMM_NG_M_G_BYTE2\" )
					)
					( Status sCSetFlattened )
					( Origin gBackEnd )
				)
				( attribute "RELATIVE_PROPAGATION_DELAY" ",5.00 MIL"
					( Parent
						( matchGroupRef "@baseboard_fab2_lib.baseboard_fab2(sch_1):\MG_DQ-DQS_FAR_DIMM_NG_M_G_BYTE2\" )
					)
					( Units "uMatchProp" "ns" 1.000000)
					( Status sCSetFlattened )
					( Origin gBackEnd )
				)
			)
			( pinPair "@baseboard_fab2_lib.baseboard_fab2(sch_1):\PP953\"
				( pinRef "@baseboard_fab2_lib.baseboard_fab2(sch_1):page78_i120:DQS2P" )
				( pinRef "@baseboard_fab2_lib.baseboard_fab2(sch_1):page57_i172:DDR0_DQS_DP(2)" )
				( attribute "RELATIVE_PROPAGATION_DELAY_SCOPE" "G"
					( Parent
						( matchGroupRef "@baseboard_fab2_lib.baseboard_fab2(sch_1):\MG_DQ-DQS_NEAR_DIMM_NG_M_G_BYTE2\" )
					)
					( Status sCSetFlattened )
					( Origin gBackEnd )
				)
				( attribute "RELATIVE_PROPAGATION_DELAY" ",5.00 MIL"
					( Parent
						( matchGroupRef "@baseboard_fab2_lib.baseboard_fab2(sch_1):\MG_DQ-DQS_NEAR_DIMM_NG_M_G_BYTE2\" )
					)
					( Units "uMatchProp" "ns" 1.000000)
					( Status sCSetFlattened )
					( Origin gBackEnd )
				)
			)
			( pinPair "@baseboard_fab2_lib.baseboard_fab2(sch_1):\PP937\"
				( pinRef "@baseboard_fab2_lib.baseboard_fab2(sch_1):page57_i172:DDR0_DQS_DN(3)" )
				( pinRef "@baseboard_fab2_lib.baseboard_fab2(sch_1):page77_i66:DQS3N" )
				( attribute "RELATIVE_PROPAGATION_DELAY_SCOPE" "G"
					( Parent
						( matchGroupRef "@baseboard_fab2_lib.baseboard_fab2(sch_1):\MG_DQ-DQS_FAR_DIMM_NG_M_G_BYTE3\" )
					)
					( Status sCSetFlattened )
					( Origin gBackEnd )
				)
				( attribute "RELATIVE_PROPAGATION_DELAY" ",5.00 MIL"
					( Parent
						( matchGroupRef "@baseboard_fab2_lib.baseboard_fab2(sch_1):\MG_DQ-DQS_FAR_DIMM_NG_M_G_BYTE3\" )
					)
					( Units "uMatchProp" "ns" 1.000000)
					( Status sCSetFlattened )
					( Origin gBackEnd )
				)
			)
			( pinPair "@baseboard_fab2_lib.baseboard_fab2(sch_1):\PP938\"
				( pinRef "@baseboard_fab2_lib.baseboard_fab2(sch_1):page78_i120:DQS3N" )
				( pinRef "@baseboard_fab2_lib.baseboard_fab2(sch_1):page57_i172:DDR0_DQS_DN(3)" )
				( attribute "RELATIVE_PROPAGATION_DELAY_SCOPE" "G"
					( Parent
						( matchGroupRef "@baseboard_fab2_lib.baseboard_fab2(sch_1):\MG_DQ-DQS_NEAR_DIMM_NG_M_G_BYTE3\" )
					)
					( Status sCSetFlattened )
					( Origin gBackEnd )
				)
				( attribute "RELATIVE_PROPAGATION_DELAY" ",5.00 MIL"
					( Parent
						( matchGroupRef "@baseboard_fab2_lib.baseboard_fab2(sch_1):\MG_DQ-DQS_NEAR_DIMM_NG_M_G_BYTE3\" )
					)
					( Units "uMatchProp" "ns" 1.000000)
					( Status sCSetFlattened )
					( Origin gBackEnd )
				)
			)
			( pinPair "@baseboard_fab2_lib.baseboard_fab2(sch_1):\PP940\"
				( pinRef "@baseboard_fab2_lib.baseboard_fab2(sch_1):page57_i172:DDR0_DQS_DP(3)" )
				( pinRef "@baseboard_fab2_lib.baseboard_fab2(sch_1):page77_i66:DQS3P" )
				( attribute "RELATIVE_PROPAGATION_DELAY_SCOPE" "G"
					( Parent
						( matchGroupRef "@baseboard_fab2_lib.baseboard_fab2(sch_1):\MG_DQ-DQS_FAR_DIMM_NG_M_G_BYTE3\" )
					)
					( Status sCSetFlattened )
					( Origin gBackEnd )
				)
				( attribute "RELATIVE_PROPAGATION_DELAY" ",5.00 MIL"
					( Parent
						( matchGroupRef "@baseboard_fab2_lib.baseboard_fab2(sch_1):\MG_DQ-DQS_FAR_DIMM_NG_M_G_BYTE3\" )
					)
					( Units "uMatchProp" "ns" 1.000000)
					( Status sCSetFlattened )
					( Origin gBackEnd )
				)
			)
			( pinPair "@baseboard_fab2_lib.baseboard_fab2(sch_1):\PP941\"
				( pinRef "@baseboard_fab2_lib.baseboard_fab2(sch_1):page78_i120:DQS3P" )
				( pinRef "@baseboard_fab2_lib.baseboard_fab2(sch_1):page57_i172:DDR0_DQS_DP(3)" )
				( attribute "RELATIVE_PROPAGATION_DELAY_SCOPE" "G"
					( Parent
						( matchGroupRef "@baseboard_fab2_lib.baseboard_fab2(sch_1):\MG_DQ-DQS_NEAR_DIMM_NG_M_G_BYTE3\" )
					)
					( Status sCSetFlattened )
					( Origin gBackEnd )
				)
				( attribute "RELATIVE_PROPAGATION_DELAY" ",5.00 MIL"
					( Parent
						( matchGroupRef "@baseboard_fab2_lib.baseboard_fab2(sch_1):\MG_DQ-DQS_NEAR_DIMM_NG_M_G_BYTE3\" )
					)
					( Units "uMatchProp" "ns" 1.000000)
					( Status sCSetFlattened )
					( Origin gBackEnd )
				)
			)
			( pinPair "@baseboard_fab2_lib.baseboard_fab2(sch_1):\PP925\"
				( pinRef "@baseboard_fab2_lib.baseboard_fab2(sch_1):page57_i172:DDR0_DQS_DN(4)" )
				( pinRef "@baseboard_fab2_lib.baseboard_fab2(sch_1):page77_i66:DQS4N" )
				( attribute "RELATIVE_PROPAGATION_DELAY_SCOPE" "G"
					( Parent
						( matchGroupRef "@baseboard_fab2_lib.baseboard_fab2(sch_1):\MG_DQ-DQS_FAR_DIMM_NG_M_G_BYTE4\" )
					)
					( Status sCSetFlattened )
					( Origin gBackEnd )
				)
				( attribute "RELATIVE_PROPAGATION_DELAY" ",5.00 MIL"
					( Parent
						( matchGroupRef "@baseboard_fab2_lib.baseboard_fab2(sch_1):\MG_DQ-DQS_FAR_DIMM_NG_M_G_BYTE4\" )
					)
					( Units "uMatchProp" "ns" 1.000000)
					( Status sCSetFlattened )
					( Origin gBackEnd )
				)
			)
			( pinPair "@baseboard_fab2_lib.baseboard_fab2(sch_1):\PP927\"
				( pinRef "@baseboard_fab2_lib.baseboard_fab2(sch_1):page78_i120:DQS4N" )
				( pinRef "@baseboard_fab2_lib.baseboard_fab2(sch_1):page57_i172:DDR0_DQS_DN(4)" )
				( attribute "RELATIVE_PROPAGATION_DELAY_SCOPE" "G"
					( Parent
						( matchGroupRef "@baseboard_fab2_lib.baseboard_fab2(sch_1):\MG_DQ-DQS_NEAR_DIMM_NG_M_G_BYTE4\" )
					)
					( Status sCSetFlattened )
					( Origin gBackEnd )
				)
				( attribute "RELATIVE_PROPAGATION_DELAY" ",5.00 MIL"
					( Parent
						( matchGroupRef "@baseboard_fab2_lib.baseboard_fab2(sch_1):\MG_DQ-DQS_NEAR_DIMM_NG_M_G_BYTE4\" )
					)
					( Units "uMatchProp" "ns" 1.000000)
					( Status sCSetFlattened )
					( Origin gBackEnd )
				)
			)
			( pinPair "@baseboard_fab2_lib.baseboard_fab2(sch_1):\PP928\"
				( pinRef "@baseboard_fab2_lib.baseboard_fab2(sch_1):page57_i172:DDR0_DQS_DP(4)" )
				( pinRef "@baseboard_fab2_lib.baseboard_fab2(sch_1):page77_i66:DQS4P" )
				( attribute "RELATIVE_PROPAGATION_DELAY_SCOPE" "G"
					( Parent
						( matchGroupRef "@baseboard_fab2_lib.baseboard_fab2(sch_1):\MG_DQ-DQS_FAR_DIMM_NG_M_G_BYTE4\" )
					)
					( Status sCSetFlattened )
					( Origin gBackEnd )
				)
				( attribute "RELATIVE_PROPAGATION_DELAY" ",5.00 MIL"
					( Parent
						( matchGroupRef "@baseboard_fab2_lib.baseboard_fab2(sch_1):\MG_DQ-DQS_FAR_DIMM_NG_M_G_BYTE4\" )
					)
					( Units "uMatchProp" "ns" 1.000000)
					( Status sCSetFlattened )
					( Origin gBackEnd )
				)
			)
			( pinPair "@baseboard_fab2_lib.baseboard_fab2(sch_1):\PP930\"
				( pinRef "@baseboard_fab2_lib.baseboard_fab2(sch_1):page78_i120:DQS4P" )
				( pinRef "@baseboard_fab2_lib.baseboard_fab2(sch_1):page57_i172:DDR0_DQS_DP(4)" )
				( attribute "RELATIVE_PROPAGATION_DELAY_SCOPE" "G"
					( Parent
						( matchGroupRef "@baseboard_fab2_lib.baseboard_fab2(sch_1):\MG_DQ-DQS_NEAR_DIMM_NG_M_G_BYTE4\" )
					)
					( Status sCSetFlattened )
					( Origin gBackEnd )
				)
				( attribute "RELATIVE_PROPAGATION_DELAY" ",5.00 MIL"
					( Parent
						( matchGroupRef "@baseboard_fab2_lib.baseboard_fab2(sch_1):\MG_DQ-DQS_NEAR_DIMM_NG_M_G_BYTE4\" )
					)
					( Units "uMatchProp" "ns" 1.000000)
					( Status sCSetFlattened )
					( Origin gBackEnd )
				)
			)
			( pinPair "@baseboard_fab2_lib.baseboard_fab2(sch_1):\PP913\"
				( pinRef "@baseboard_fab2_lib.baseboard_fab2(sch_1):page57_i172:DDR0_DQS_DN(5)" )
				( pinRef "@baseboard_fab2_lib.baseboard_fab2(sch_1):page77_i66:DQS5N" )
				( attribute "RELATIVE_PROPAGATION_DELAY_SCOPE" "G"
					( Parent
						( matchGroupRef "@baseboard_fab2_lib.baseboard_fab2(sch_1):\MG_DQ-DQS_FAR_DIMM_NG_M_G_BYTE5\" )
					)
					( Status sCSetFlattened )
					( Origin gBackEnd )
				)
				( attribute "RELATIVE_PROPAGATION_DELAY" ",5.00 MIL"
					( Parent
						( matchGroupRef "@baseboard_fab2_lib.baseboard_fab2(sch_1):\MG_DQ-DQS_FAR_DIMM_NG_M_G_BYTE5\" )
					)
					( Units "uMatchProp" "ns" 1.000000)
					( Status sCSetFlattened )
					( Origin gBackEnd )
				)
			)
			( pinPair "@baseboard_fab2_lib.baseboard_fab2(sch_1):\PP915\"
				( pinRef "@baseboard_fab2_lib.baseboard_fab2(sch_1):page78_i120:DQS5N" )
				( pinRef "@baseboard_fab2_lib.baseboard_fab2(sch_1):page57_i172:DDR0_DQS_DN(5)" )
				( attribute "RELATIVE_PROPAGATION_DELAY_SCOPE" "G"
					( Parent
						( matchGroupRef "@baseboard_fab2_lib.baseboard_fab2(sch_1):\MG_DQ-DQS_NEAR_DIMM_NG_M_G_BYTE5\" )
					)
					( Status sCSetFlattened )
					( Origin gBackEnd )
				)
				( attribute "RELATIVE_PROPAGATION_DELAY" ",5.00 MIL"
					( Parent
						( matchGroupRef "@baseboard_fab2_lib.baseboard_fab2(sch_1):\MG_DQ-DQS_NEAR_DIMM_NG_M_G_BYTE5\" )
					)
					( Units "uMatchProp" "ns" 1.000000)
					( Status sCSetFlattened )
					( Origin gBackEnd )
				)
			)
			( pinPair "@baseboard_fab2_lib.baseboard_fab2(sch_1):\PP916\"
				( pinRef "@baseboard_fab2_lib.baseboard_fab2(sch_1):page57_i172:DDR0_DQS_DP(5)" )
				( pinRef "@baseboard_fab2_lib.baseboard_fab2(sch_1):page77_i66:DQS5P" )
				( attribute "RELATIVE_PROPAGATION_DELAY_SCOPE" "G"
					( Parent
						( matchGroupRef "@baseboard_fab2_lib.baseboard_fab2(sch_1):\MG_DQ-DQS_FAR_DIMM_NG_M_G_BYTE5\" )
					)
					( Status sCSetFlattened )
					( Origin gBackEnd )
				)
				( attribute "RELATIVE_PROPAGATION_DELAY" ",5.00 MIL"
					( Parent
						( matchGroupRef "@baseboard_fab2_lib.baseboard_fab2(sch_1):\MG_DQ-DQS_FAR_DIMM_NG_M_G_BYTE5\" )
					)
					( Units "uMatchProp" "ns" 1.000000)
					( Status sCSetFlattened )
					( Origin gBackEnd )
				)
			)
			( pinPair "@baseboard_fab2_lib.baseboard_fab2(sch_1):\PP918\"
				( pinRef "@baseboard_fab2_lib.baseboard_fab2(sch_1):page78_i120:DQS5P" )
				( pinRef "@baseboard_fab2_lib.baseboard_fab2(sch_1):page57_i172:DDR0_DQS_DP(5)" )
				( attribute "RELATIVE_PROPAGATION_DELAY_SCOPE" "G"
					( Parent
						( matchGroupRef "@baseboard_fab2_lib.baseboard_fab2(sch_1):\MG_DQ-DQS_NEAR_DIMM_NG_M_G_BYTE5\" )
					)
					( Status sCSetFlattened )
					( Origin gBackEnd )
				)
				( attribute "RELATIVE_PROPAGATION_DELAY" ",5.00 MIL"
					( Parent
						( matchGroupRef "@baseboard_fab2_lib.baseboard_fab2(sch_1):\MG_DQ-DQS_NEAR_DIMM_NG_M_G_BYTE5\" )
					)
					( Units "uMatchProp" "ns" 1.000000)
					( Status sCSetFlattened )
					( Origin gBackEnd )
				)
			)
			( pinPair "@baseboard_fab2_lib.baseboard_fab2(sch_1):\PP901\"
				( pinRef "@baseboard_fab2_lib.baseboard_fab2(sch_1):page57_i172:DDR0_DQS_DN(6)" )
				( pinRef "@baseboard_fab2_lib.baseboard_fab2(sch_1):page77_i66:DQS6N" )
				( attribute "RELATIVE_PROPAGATION_DELAY_SCOPE" "G"
					( Parent
						( matchGroupRef "@baseboard_fab2_lib.baseboard_fab2(sch_1):\MG_DQ-DQS_FAR_DIMM_NG_M_G_BYTE6\" )
					)
					( Status sCSetFlattened )
					( Origin gBackEnd )
				)
				( attribute "RELATIVE_PROPAGATION_DELAY" ",5.00 MIL"
					( Parent
						( matchGroupRef "@baseboard_fab2_lib.baseboard_fab2(sch_1):\MG_DQ-DQS_FAR_DIMM_NG_M_G_BYTE6\" )
					)
					( Units "uMatchProp" "ns" 1.000000)
					( Status sCSetFlattened )
					( Origin gBackEnd )
				)
			)
			( pinPair "@baseboard_fab2_lib.baseboard_fab2(sch_1):\PP903\"
				( pinRef "@baseboard_fab2_lib.baseboard_fab2(sch_1):page78_i120:DQS6N" )
				( pinRef "@baseboard_fab2_lib.baseboard_fab2(sch_1):page57_i172:DDR0_DQS_DN(6)" )
				( attribute "RELATIVE_PROPAGATION_DELAY_SCOPE" "G"
					( Parent
						( matchGroupRef "@baseboard_fab2_lib.baseboard_fab2(sch_1):\MG_DQ-DQS_NEAR_DIMM_NG_M_G_BYTE6\" )
					)
					( Status sCSetFlattened )
					( Origin gBackEnd )
				)
				( attribute "RELATIVE_PROPAGATION_DELAY" ",5.00 MIL"
					( Parent
						( matchGroupRef "@baseboard_fab2_lib.baseboard_fab2(sch_1):\MG_DQ-DQS_NEAR_DIMM_NG_M_G_BYTE6\" )
					)
					( Units "uMatchProp" "ns" 1.000000)
					( Status sCSetFlattened )
					( Origin gBackEnd )
				)
			)
			( pinPair "@baseboard_fab2_lib.baseboard_fab2(sch_1):\PP904\"
				( pinRef "@baseboard_fab2_lib.baseboard_fab2(sch_1):page57_i172:DDR0_DQS_DP(6)" )
				( pinRef "@baseboard_fab2_lib.baseboard_fab2(sch_1):page77_i66:DQS6P" )
				( attribute "RELATIVE_PROPAGATION_DELAY_SCOPE" "G"
					( Parent
						( matchGroupRef "@baseboard_fab2_lib.baseboard_fab2(sch_1):\MG_DQ-DQS_FAR_DIMM_NG_M_G_BYTE6\" )
					)
					( Status sCSetFlattened )
					( Origin gBackEnd )
				)
				( attribute "RELATIVE_PROPAGATION_DELAY" ",5.00 MIL"
					( Parent
						( matchGroupRef "@baseboard_fab2_lib.baseboard_fab2(sch_1):\MG_DQ-DQS_FAR_DIMM_NG_M_G_BYTE6\" )
					)
					( Units "uMatchProp" "ns" 1.000000)
					( Status sCSetFlattened )
					( Origin gBackEnd )
				)
			)
			( pinPair "@baseboard_fab2_lib.baseboard_fab2(sch_1):\PP906\"
				( pinRef "@baseboard_fab2_lib.baseboard_fab2(sch_1):page78_i120:DQS6P" )
				( pinRef "@baseboard_fab2_lib.baseboard_fab2(sch_1):page57_i172:DDR0_DQS_DP(6)" )
				( attribute "RELATIVE_PROPAGATION_DELAY_SCOPE" "G"
					( Parent
						( matchGroupRef "@baseboard_fab2_lib.baseboard_fab2(sch_1):\MG_DQ-DQS_NEAR_DIMM_NG_M_G_BYTE6\" )
					)
					( Status sCSetFlattened )
					( Origin gBackEnd )
				)
				( attribute "RELATIVE_PROPAGATION_DELAY" ",5.00 MIL"
					( Parent
						( matchGroupRef "@baseboard_fab2_lib.baseboard_fab2(sch_1):\MG_DQ-DQS_NEAR_DIMM_NG_M_G_BYTE6\" )
					)
					( Units "uMatchProp" "ns" 1.000000)
					( Status sCSetFlattened )
					( Origin gBackEnd )
				)
			)
			( pinPair "@baseboard_fab2_lib.baseboard_fab2(sch_1):\PP889\"
				( pinRef "@baseboard_fab2_lib.baseboard_fab2(sch_1):page57_i172:DDR0_DQS_DN(7)" )
				( pinRef "@baseboard_fab2_lib.baseboard_fab2(sch_1):page77_i66:DQS7N" )
				( attribute "RELATIVE_PROPAGATION_DELAY_SCOPE" "G"
					( Parent
						( matchGroupRef "@baseboard_fab2_lib.baseboard_fab2(sch_1):\MG_DQ-DQS_FAR_DIMM_NG_M_G_BYTE7\" )
					)
					( Status sCSetFlattened )
					( Origin gBackEnd )
				)
				( attribute "RELATIVE_PROPAGATION_DELAY" ",5.00 MIL"
					( Parent
						( matchGroupRef "@baseboard_fab2_lib.baseboard_fab2(sch_1):\MG_DQ-DQS_FAR_DIMM_NG_M_G_BYTE7\" )
					)
					( Units "uMatchProp" "ns" 1.000000)
					( Status sCSetFlattened )
					( Origin gBackEnd )
				)
			)
			( pinPair "@baseboard_fab2_lib.baseboard_fab2(sch_1):\PP891\"
				( pinRef "@baseboard_fab2_lib.baseboard_fab2(sch_1):page78_i120:DQS7N" )
				( pinRef "@baseboard_fab2_lib.baseboard_fab2(sch_1):page57_i172:DDR0_DQS_DN(7)" )
				( attribute "RELATIVE_PROPAGATION_DELAY_SCOPE" "G"
					( Parent
						( matchGroupRef "@baseboard_fab2_lib.baseboard_fab2(sch_1):\MG_DQ-DQS_NEAR_DIMM_NG_M_G_BYTE7\" )
					)
					( Status sCSetFlattened )
					( Origin gBackEnd )
				)
				( attribute "RELATIVE_PROPAGATION_DELAY" ",5.00 MIL"
					( Parent
						( matchGroupRef "@baseboard_fab2_lib.baseboard_fab2(sch_1):\MG_DQ-DQS_NEAR_DIMM_NG_M_G_BYTE7\" )
					)
					( Units "uMatchProp" "ns" 1.000000)
					( Status sCSetFlattened )
					( Origin gBackEnd )
				)
			)
			( pinPair "@baseboard_fab2_lib.baseboard_fab2(sch_1):\PP892\"
				( pinRef "@baseboard_fab2_lib.baseboard_fab2(sch_1):page57_i172:DDR0_DQS_DP(7)" )
				( pinRef "@baseboard_fab2_lib.baseboard_fab2(sch_1):page77_i66:DQS7P" )
				( attribute "RELATIVE_PROPAGATION_DELAY_SCOPE" "G"
					( Parent
						( matchGroupRef "@baseboard_fab2_lib.baseboard_fab2(sch_1):\MG_DQ-DQS_FAR_DIMM_NG_M_G_BYTE7\" )
					)
					( Status sCSetFlattened )
					( Origin gBackEnd )
				)
				( attribute "RELATIVE_PROPAGATION_DELAY" ",5.00 MIL"
					( Parent
						( matchGroupRef "@baseboard_fab2_lib.baseboard_fab2(sch_1):\MG_DQ-DQS_FAR_DIMM_NG_M_G_BYTE7\" )
					)
					( Units "uMatchProp" "ns" 1.000000)
					( Status sCSetFlattened )
					( Origin gBackEnd )
				)
			)
			( pinPair "@baseboard_fab2_lib.baseboard_fab2(sch_1):\PP894\"
				( pinRef "@baseboard_fab2_lib.baseboard_fab2(sch_1):page78_i120:DQS7P" )
				( pinRef "@baseboard_fab2_lib.baseboard_fab2(sch_1):page57_i172:DDR0_DQS_DP(7)" )
				( attribute "RELATIVE_PROPAGATION_DELAY_SCOPE" "G"
					( Parent
						( matchGroupRef "@baseboard_fab2_lib.baseboard_fab2(sch_1):\MG_DQ-DQS_NEAR_DIMM_NG_M_G_BYTE7\" )
					)
					( Status sCSetFlattened )
					( Origin gBackEnd )
				)
				( attribute "RELATIVE_PROPAGATION_DELAY" ",5.00 MIL"
					( Parent
						( matchGroupRef "@baseboard_fab2_lib.baseboard_fab2(sch_1):\MG_DQ-DQS_NEAR_DIMM_NG_M_G_BYTE7\" )
					)
					( Units "uMatchProp" "ns" 1.000000)
					( Status sCSetFlattened )
					( Origin gBackEnd )
				)
			)
			( pinPair "@baseboard_fab2_lib.baseboard_fab2(sch_1):\PP877\"
				( pinRef "@baseboard_fab2_lib.baseboard_fab2(sch_1):page57_i172:DDR0_DQS_DN(8)" )
				( pinRef "@baseboard_fab2_lib.baseboard_fab2(sch_1):page77_i66:DQS8N" )
				( attribute "RELATIVE_PROPAGATION_DELAY_SCOPE" "G"
					( Parent
						( matchGroupRef "@baseboard_fab2_lib.baseboard_fab2(sch_1):\MG_DQ-DQS_FAR_DIMM_NG_M_G_BYTE-ECC\" )
					)
					( Status sCSetFlattened )
					( Origin gBackEnd )
				)
				( attribute "RELATIVE_PROPAGATION_DELAY" ",5.00 MIL"
					( Parent
						( matchGroupRef "@baseboard_fab2_lib.baseboard_fab2(sch_1):\MG_DQ-DQS_FAR_DIMM_NG_M_G_BYTE-ECC\" )
					)
					( Units "uMatchProp" "ns" 1.000000)
					( Status sCSetFlattened )
					( Origin gBackEnd )
				)
			)
			( pinPair "@baseboard_fab2_lib.baseboard_fab2(sch_1):\PP878\"
				( pinRef "@baseboard_fab2_lib.baseboard_fab2(sch_1):page78_i120:DQS8N" )
				( pinRef "@baseboard_fab2_lib.baseboard_fab2(sch_1):page57_i172:DDR0_DQS_DN(8)" )
				( attribute "RELATIVE_PROPAGATION_DELAY_SCOPE" "G"
					( Parent
						( matchGroupRef "@baseboard_fab2_lib.baseboard_fab2(sch_1):\MG_DQ-DQS_NEAR_DIMM_NG_M_G_BYTE-ECC\" )
					)
					( Status sCSetFlattened )
					( Origin gBackEnd )
				)
				( attribute "RELATIVE_PROPAGATION_DELAY" ",5.00 MIL"
					( Parent
						( matchGroupRef "@baseboard_fab2_lib.baseboard_fab2(sch_1):\MG_DQ-DQS_NEAR_DIMM_NG_M_G_BYTE-ECC\" )
					)
					( Units "uMatchProp" "ns" 1.000000)
					( Status sCSetFlattened )
					( Origin gBackEnd )
				)
			)
			( pinPair "@baseboard_fab2_lib.baseboard_fab2(sch_1):\PP880\"
				( pinRef "@baseboard_fab2_lib.baseboard_fab2(sch_1):page57_i172:DDR0_DQS_DP(8)" )
				( pinRef "@baseboard_fab2_lib.baseboard_fab2(sch_1):page77_i66:DQS8P" )
				( attribute "RELATIVE_PROPAGATION_DELAY_SCOPE" "G"
					( Parent
						( matchGroupRef "@baseboard_fab2_lib.baseboard_fab2(sch_1):\MG_DQ-DQS_FAR_DIMM_NG_M_G_BYTE-ECC\" )
					)
					( Status sCSetFlattened )
					( Origin gBackEnd )
				)
				( attribute "RELATIVE_PROPAGATION_DELAY" ",5.00 MIL"
					( Parent
						( matchGroupRef "@baseboard_fab2_lib.baseboard_fab2(sch_1):\MG_DQ-DQS_FAR_DIMM_NG_M_G_BYTE-ECC\" )
					)
					( Units "uMatchProp" "ns" 1.000000)
					( Status sCSetFlattened )
					( Origin gBackEnd )
				)
			)
			( pinPair "@baseboard_fab2_lib.baseboard_fab2(sch_1):\PP881\"
				( pinRef "@baseboard_fab2_lib.baseboard_fab2(sch_1):page78_i120:DQS8P" )
				( pinRef "@baseboard_fab2_lib.baseboard_fab2(sch_1):page57_i172:DDR0_DQS_DP(8)" )
				( attribute "RELATIVE_PROPAGATION_DELAY_SCOPE" "G"
					( Parent
						( matchGroupRef "@baseboard_fab2_lib.baseboard_fab2(sch_1):\MG_DQ-DQS_NEAR_DIMM_NG_M_G_BYTE-ECC\" )
					)
					( Status sCSetFlattened )
					( Origin gBackEnd )
				)
				( attribute "RELATIVE_PROPAGATION_DELAY" ",5.00 MIL"
					( Parent
						( matchGroupRef "@baseboard_fab2_lib.baseboard_fab2(sch_1):\MG_DQ-DQS_NEAR_DIMM_NG_M_G_BYTE-ECC\" )
					)
					( Units "uMatchProp" "ns" 1.000000)
					( Status sCSetFlattened )
					( Origin gBackEnd )
				)
			)
			( pinPair "@baseboard_fab2_lib.baseboard_fab2(sch_1):\PP967\"
				( pinRef "@baseboard_fab2_lib.baseboard_fab2(sch_1):page57_i172:DDR0_DQS_DN(9)" )
				( pinRef "@baseboard_fab2_lib.baseboard_fab2(sch_1):page77_i66:DQS9N" )
				( attribute "RELATIVE_PROPAGATION_DELAY_SCOPE" "G"
					( Parent
						( matchGroupRef "@baseboard_fab2_lib.baseboard_fab2(sch_1):\MG_DQ-DQS_FAR_DIMM_NG_M_G_BYTE0\" )
					)
					( Status sCSetFlattened )
					( Origin gBackEnd )
				)
				( attribute "RELATIVE_PROPAGATION_DELAY" ",5.00 MIL"
					( Parent
						( matchGroupRef "@baseboard_fab2_lib.baseboard_fab2(sch_1):\MG_DQ-DQS_FAR_DIMM_NG_M_G_BYTE0\" )
					)
					( Units "uMatchProp" "ns" 1.000000)
					( Status sCSetFlattened )
					( Origin gBackEnd )
				)
			)
			( pinPair "@baseboard_fab2_lib.baseboard_fab2(sch_1):\PP968\"
				( pinRef "@baseboard_fab2_lib.baseboard_fab2(sch_1):page78_i120:DQS9N" )
				( pinRef "@baseboard_fab2_lib.baseboard_fab2(sch_1):page57_i172:DDR0_DQS_DN(9)" )
				( attribute "RELATIVE_PROPAGATION_DELAY_SCOPE" "G"
					( Parent
						( matchGroupRef "@baseboard_fab2_lib.baseboard_fab2(sch_1):\MG_DQ-DQS_NEAR_DIMM_NG_M_G_BYTE0\" )
					)
					( Status sCSetFlattened )
					( Origin gBackEnd )
				)
				( attribute "RELATIVE_PROPAGATION_DELAY" ",5.00 MIL"
					( Parent
						( matchGroupRef "@baseboard_fab2_lib.baseboard_fab2(sch_1):\MG_DQ-DQS_NEAR_DIMM_NG_M_G_BYTE0\" )
					)
					( Units "uMatchProp" "ns" 1.000000)
					( Status sCSetFlattened )
					( Origin gBackEnd )
				)
			)
			( pinPair "@baseboard_fab2_lib.baseboard_fab2(sch_1):\PP970\"
				( pinRef "@baseboard_fab2_lib.baseboard_fab2(sch_1):page57_i172:DDR0_DQS_DP(9)" )
				( pinRef "@baseboard_fab2_lib.baseboard_fab2(sch_1):page77_i66:DQS9P" )
				( attribute "RELATIVE_PROPAGATION_DELAY_SCOPE" "G"
					( Parent
						( matchGroupRef "@baseboard_fab2_lib.baseboard_fab2(sch_1):\MG_DQ-DQS_FAR_DIMM_NG_M_G_BYTE0\" )
					)
					( Status sCSetFlattened )
					( Origin gBackEnd )
				)
				( attribute "RELATIVE_PROPAGATION_DELAY" ",5.00 MIL"
					( Parent
						( matchGroupRef "@baseboard_fab2_lib.baseboard_fab2(sch_1):\MG_DQ-DQS_FAR_DIMM_NG_M_G_BYTE0\" )
					)
					( Units "uMatchProp" "ns" 1.000000)
					( Status sCSetFlattened )
					( Origin gBackEnd )
				)
			)
			( pinPair "@baseboard_fab2_lib.baseboard_fab2(sch_1):\PP971\"
				( pinRef "@baseboard_fab2_lib.baseboard_fab2(sch_1):page78_i120:DQS9P" )
				( pinRef "@baseboard_fab2_lib.baseboard_fab2(sch_1):page57_i172:DDR0_DQS_DP(9)" )
				( attribute "RELATIVE_PROPAGATION_DELAY_SCOPE" "G"
					( Parent
						( matchGroupRef "@baseboard_fab2_lib.baseboard_fab2(sch_1):\MG_DQ-DQS_NEAR_DIMM_NG_M_G_BYTE0\" )
					)
					( Status sCSetFlattened )
					( Origin gBackEnd )
				)
				( attribute "RELATIVE_PROPAGATION_DELAY" ",5.00 MIL"
					( Parent
						( matchGroupRef "@baseboard_fab2_lib.baseboard_fab2(sch_1):\MG_DQ-DQS_NEAR_DIMM_NG_M_G_BYTE0\" )
					)
					( Units "uMatchProp" "ns" 1.000000)
					( Status sCSetFlattened )
					( Origin gBackEnd )
				)
			)
			( pinPair "@baseboard_fab2_lib.baseboard_fab2(sch_1):\PP955\"
				( pinRef "@baseboard_fab2_lib.baseboard_fab2(sch_1):page57_i172:DDR0_DQS_DN(10)" )
				( pinRef "@baseboard_fab2_lib.baseboard_fab2(sch_1):page77_i66:DQS10N" )
				( attribute "RELATIVE_PROPAGATION_DELAY_SCOPE" "G"
					( Parent
						( matchGroupRef "@baseboard_fab2_lib.baseboard_fab2(sch_1):\MG_DQ-DQS_FAR_DIMM_NG_M_G_BYTE1\" )
					)
					( Status sCSetFlattened )
					( Origin gBackEnd )
				)
				( attribute "RELATIVE_PROPAGATION_DELAY" ",5.00 MIL"
					( Parent
						( matchGroupRef "@baseboard_fab2_lib.baseboard_fab2(sch_1):\MG_DQ-DQS_FAR_DIMM_NG_M_G_BYTE1\" )
					)
					( Units "uMatchProp" "ns" 1.000000)
					( Status sCSetFlattened )
					( Origin gBackEnd )
				)
			)
			( pinPair "@baseboard_fab2_lib.baseboard_fab2(sch_1):\PP956\"
				( pinRef "@baseboard_fab2_lib.baseboard_fab2(sch_1):page78_i120:DQS10N" )
				( pinRef "@baseboard_fab2_lib.baseboard_fab2(sch_1):page57_i172:DDR0_DQS_DN(10)" )
				( attribute "RELATIVE_PROPAGATION_DELAY_SCOPE" "G"
					( Parent
						( matchGroupRef "@baseboard_fab2_lib.baseboard_fab2(sch_1):\MG_DQ-DQS_NEAR_DIMM_NG_M_G_BYTE1\" )
					)
					( Status sCSetFlattened )
					( Origin gBackEnd )
				)
				( attribute "RELATIVE_PROPAGATION_DELAY" ",5.00 MIL"
					( Parent
						( matchGroupRef "@baseboard_fab2_lib.baseboard_fab2(sch_1):\MG_DQ-DQS_NEAR_DIMM_NG_M_G_BYTE1\" )
					)
					( Units "uMatchProp" "ns" 1.000000)
					( Status sCSetFlattened )
					( Origin gBackEnd )
				)
			)
			( pinPair "@baseboard_fab2_lib.baseboard_fab2(sch_1):\PP958\"
				( pinRef "@baseboard_fab2_lib.baseboard_fab2(sch_1):page57_i172:DDR0_DQS_DP(10)" )
				( pinRef "@baseboard_fab2_lib.baseboard_fab2(sch_1):page77_i66:DQS10P" )
				( attribute "RELATIVE_PROPAGATION_DELAY_SCOPE" "G"
					( Parent
						( matchGroupRef "@baseboard_fab2_lib.baseboard_fab2(sch_1):\MG_DQ-DQS_FAR_DIMM_NG_M_G_BYTE1\" )
					)
					( Status sCSetFlattened )
					( Origin gBackEnd )
				)
				( attribute "RELATIVE_PROPAGATION_DELAY" ",5.00 MIL"
					( Parent
						( matchGroupRef "@baseboard_fab2_lib.baseboard_fab2(sch_1):\MG_DQ-DQS_FAR_DIMM_NG_M_G_BYTE1\" )
					)
					( Units "uMatchProp" "ns" 1.000000)
					( Status sCSetFlattened )
					( Origin gBackEnd )
				)
			)
			( pinPair "@baseboard_fab2_lib.baseboard_fab2(sch_1):\PP959\"
				( pinRef "@baseboard_fab2_lib.baseboard_fab2(sch_1):page78_i120:DQS10P" )
				( pinRef "@baseboard_fab2_lib.baseboard_fab2(sch_1):page57_i172:DDR0_DQS_DP(10)" )
				( attribute "RELATIVE_PROPAGATION_DELAY_SCOPE" "G"
					( Parent
						( matchGroupRef "@baseboard_fab2_lib.baseboard_fab2(sch_1):\MG_DQ-DQS_NEAR_DIMM_NG_M_G_BYTE1\" )
					)
					( Status sCSetFlattened )
					( Origin gBackEnd )
				)
				( attribute "RELATIVE_PROPAGATION_DELAY" ",5.00 MIL"
					( Parent
						( matchGroupRef "@baseboard_fab2_lib.baseboard_fab2(sch_1):\MG_DQ-DQS_NEAR_DIMM_NG_M_G_BYTE1\" )
					)
					( Units "uMatchProp" "ns" 1.000000)
					( Status sCSetFlattened )
					( Origin gBackEnd )
				)
			)
			( pinPair "@baseboard_fab2_lib.baseboard_fab2(sch_1):\PP943\"
				( pinRef "@baseboard_fab2_lib.baseboard_fab2(sch_1):page57_i172:DDR0_DQS_DN(11)" )
				( pinRef "@baseboard_fab2_lib.baseboard_fab2(sch_1):page77_i66:DQS11N" )
				( attribute "RELATIVE_PROPAGATION_DELAY_SCOPE" "G"
					( Parent
						( matchGroupRef "@baseboard_fab2_lib.baseboard_fab2(sch_1):\MG_DQ-DQS_FAR_DIMM_NG_M_G_BYTE2\" )
					)
					( Status sCSetFlattened )
					( Origin gBackEnd )
				)
				( attribute "RELATIVE_PROPAGATION_DELAY" ",5.00 MIL"
					( Parent
						( matchGroupRef "@baseboard_fab2_lib.baseboard_fab2(sch_1):\MG_DQ-DQS_FAR_DIMM_NG_M_G_BYTE2\" )
					)
					( Units "uMatchProp" "ns" 1.000000)
					( Status sCSetFlattened )
					( Origin gBackEnd )
				)
			)
			( pinPair "@baseboard_fab2_lib.baseboard_fab2(sch_1):\PP944\"
				( pinRef "@baseboard_fab2_lib.baseboard_fab2(sch_1):page78_i120:DQS11N" )
				( pinRef "@baseboard_fab2_lib.baseboard_fab2(sch_1):page57_i172:DDR0_DQS_DN(11)" )
				( attribute "RELATIVE_PROPAGATION_DELAY_SCOPE" "G"
					( Parent
						( matchGroupRef "@baseboard_fab2_lib.baseboard_fab2(sch_1):\MG_DQ-DQS_NEAR_DIMM_NG_M_G_BYTE2\" )
					)
					( Status sCSetFlattened )
					( Origin gBackEnd )
				)
				( attribute "RELATIVE_PROPAGATION_DELAY" ",5.00 MIL"
					( Parent
						( matchGroupRef "@baseboard_fab2_lib.baseboard_fab2(sch_1):\MG_DQ-DQS_NEAR_DIMM_NG_M_G_BYTE2\" )
					)
					( Units "uMatchProp" "ns" 1.000000)
					( Status sCSetFlattened )
					( Origin gBackEnd )
				)
			)
			( pinPair "@baseboard_fab2_lib.baseboard_fab2(sch_1):\PP946\"
				( pinRef "@baseboard_fab2_lib.baseboard_fab2(sch_1):page57_i172:DDR0_DQS_DP(11)" )
				( pinRef "@baseboard_fab2_lib.baseboard_fab2(sch_1):page77_i66:DQS11P" )
				( attribute "RELATIVE_PROPAGATION_DELAY_SCOPE" "G"
					( Parent
						( matchGroupRef "@baseboard_fab2_lib.baseboard_fab2(sch_1):\MG_DQ-DQS_FAR_DIMM_NG_M_G_BYTE2\" )
					)
					( Status sCSetFlattened )
					( Origin gBackEnd )
				)
				( attribute "RELATIVE_PROPAGATION_DELAY" ",5.00 MIL"
					( Parent
						( matchGroupRef "@baseboard_fab2_lib.baseboard_fab2(sch_1):\MG_DQ-DQS_FAR_DIMM_NG_M_G_BYTE2\" )
					)
					( Units "uMatchProp" "ns" 1.000000)
					( Status sCSetFlattened )
					( Origin gBackEnd )
				)
			)
			( pinPair "@baseboard_fab2_lib.baseboard_fab2(sch_1):\PP947\"
				( pinRef "@baseboard_fab2_lib.baseboard_fab2(sch_1):page78_i120:DQS11P" )
				( pinRef "@baseboard_fab2_lib.baseboard_fab2(sch_1):page57_i172:DDR0_DQS_DP(11)" )
				( attribute "RELATIVE_PROPAGATION_DELAY_SCOPE" "G"
					( Parent
						( matchGroupRef "@baseboard_fab2_lib.baseboard_fab2(sch_1):\MG_DQ-DQS_NEAR_DIMM_NG_M_G_BYTE2\" )
					)
					( Status sCSetFlattened )
					( Origin gBackEnd )
				)
				( attribute "RELATIVE_PROPAGATION_DELAY" ",5.00 MIL"
					( Parent
						( matchGroupRef "@baseboard_fab2_lib.baseboard_fab2(sch_1):\MG_DQ-DQS_NEAR_DIMM_NG_M_G_BYTE2\" )
					)
					( Units "uMatchProp" "ns" 1.000000)
					( Status sCSetFlattened )
					( Origin gBackEnd )
				)
			)
			( pinPair "@baseboard_fab2_lib.baseboard_fab2(sch_1):\PP931\"
				( pinRef "@baseboard_fab2_lib.baseboard_fab2(sch_1):page57_i172:DDR0_DQS_DN(12)" )
				( pinRef "@baseboard_fab2_lib.baseboard_fab2(sch_1):page77_i66:DQS12N" )
				( attribute "RELATIVE_PROPAGATION_DELAY_SCOPE" "G"
					( Parent
						( matchGroupRef "@baseboard_fab2_lib.baseboard_fab2(sch_1):\MG_DQ-DQS_FAR_DIMM_NG_M_G_BYTE3\" )
					)
					( Status sCSetFlattened )
					( Origin gBackEnd )
				)
				( attribute "RELATIVE_PROPAGATION_DELAY" ",5.00 MIL"
					( Parent
						( matchGroupRef "@baseboard_fab2_lib.baseboard_fab2(sch_1):\MG_DQ-DQS_FAR_DIMM_NG_M_G_BYTE3\" )
					)
					( Units "uMatchProp" "ns" 1.000000)
					( Status sCSetFlattened )
					( Origin gBackEnd )
				)
			)
			( pinPair "@baseboard_fab2_lib.baseboard_fab2(sch_1):\PP932\"
				( pinRef "@baseboard_fab2_lib.baseboard_fab2(sch_1):page78_i120:DQS12N" )
				( pinRef "@baseboard_fab2_lib.baseboard_fab2(sch_1):page57_i172:DDR0_DQS_DN(12)" )
				( attribute "RELATIVE_PROPAGATION_DELAY_SCOPE" "G"
					( Parent
						( matchGroupRef "@baseboard_fab2_lib.baseboard_fab2(sch_1):\MG_DQ-DQS_NEAR_DIMM_NG_M_G_BYTE3\" )
					)
					( Status sCSetFlattened )
					( Origin gBackEnd )
				)
				( attribute "RELATIVE_PROPAGATION_DELAY" ",5.00 MIL"
					( Parent
						( matchGroupRef "@baseboard_fab2_lib.baseboard_fab2(sch_1):\MG_DQ-DQS_NEAR_DIMM_NG_M_G_BYTE3\" )
					)
					( Units "uMatchProp" "ns" 1.000000)
					( Status sCSetFlattened )
					( Origin gBackEnd )
				)
			)
			( pinPair "@baseboard_fab2_lib.baseboard_fab2(sch_1):\PP934\"
				( pinRef "@baseboard_fab2_lib.baseboard_fab2(sch_1):page57_i172:DDR0_DQS_DP(12)" )
				( pinRef "@baseboard_fab2_lib.baseboard_fab2(sch_1):page77_i66:DQS12P" )
				( attribute "RELATIVE_PROPAGATION_DELAY_SCOPE" "G"
					( Parent
						( matchGroupRef "@baseboard_fab2_lib.baseboard_fab2(sch_1):\MG_DQ-DQS_FAR_DIMM_NG_M_G_BYTE3\" )
					)
					( Status sCSetFlattened )
					( Origin gBackEnd )
				)
				( attribute "RELATIVE_PROPAGATION_DELAY" ",5.00 MIL"
					( Parent
						( matchGroupRef "@baseboard_fab2_lib.baseboard_fab2(sch_1):\MG_DQ-DQS_FAR_DIMM_NG_M_G_BYTE3\" )
					)
					( Units "uMatchProp" "ns" 1.000000)
					( Status sCSetFlattened )
					( Origin gBackEnd )
				)
			)
			( pinPair "@baseboard_fab2_lib.baseboard_fab2(sch_1):\PP935\"
				( pinRef "@baseboard_fab2_lib.baseboard_fab2(sch_1):page78_i120:DQS12P" )
				( pinRef "@baseboard_fab2_lib.baseboard_fab2(sch_1):page57_i172:DDR0_DQS_DP(12)" )
				( attribute "RELATIVE_PROPAGATION_DELAY_SCOPE" "G"
					( Parent
						( matchGroupRef "@baseboard_fab2_lib.baseboard_fab2(sch_1):\MG_DQ-DQS_NEAR_DIMM_NG_M_G_BYTE3\" )
					)
					( Status sCSetFlattened )
					( Origin gBackEnd )
				)
				( attribute "RELATIVE_PROPAGATION_DELAY" ",5.00 MIL"
					( Parent
						( matchGroupRef "@baseboard_fab2_lib.baseboard_fab2(sch_1):\MG_DQ-DQS_NEAR_DIMM_NG_M_G_BYTE3\" )
					)
					( Units "uMatchProp" "ns" 1.000000)
					( Status sCSetFlattened )
					( Origin gBackEnd )
				)
			)
			( pinPair "@baseboard_fab2_lib.baseboard_fab2(sch_1):\PP919\"
				( pinRef "@baseboard_fab2_lib.baseboard_fab2(sch_1):page57_i172:DDR0_DQS_DN(13)" )
				( pinRef "@baseboard_fab2_lib.baseboard_fab2(sch_1):page77_i66:DQS13N" )
				( attribute "RELATIVE_PROPAGATION_DELAY_SCOPE" "G"
					( Parent
						( matchGroupRef "@baseboard_fab2_lib.baseboard_fab2(sch_1):\MG_DQ-DQS_FAR_DIMM_NG_M_G_BYTE4\" )
					)
					( Status sCSetFlattened )
					( Origin gBackEnd )
				)
				( attribute "RELATIVE_PROPAGATION_DELAY" ",5.00 MIL"
					( Parent
						( matchGroupRef "@baseboard_fab2_lib.baseboard_fab2(sch_1):\MG_DQ-DQS_FAR_DIMM_NG_M_G_BYTE4\" )
					)
					( Units "uMatchProp" "ns" 1.000000)
					( Status sCSetFlattened )
					( Origin gBackEnd )
				)
			)
			( pinPair "@baseboard_fab2_lib.baseboard_fab2(sch_1):\PP921\"
				( pinRef "@baseboard_fab2_lib.baseboard_fab2(sch_1):page78_i120:DQS13N" )
				( pinRef "@baseboard_fab2_lib.baseboard_fab2(sch_1):page57_i172:DDR0_DQS_DN(13)" )
				( attribute "RELATIVE_PROPAGATION_DELAY_SCOPE" "G"
					( Parent
						( matchGroupRef "@baseboard_fab2_lib.baseboard_fab2(sch_1):\MG_DQ-DQS_NEAR_DIMM_NG_M_G_BYTE4\" )
					)
					( Status sCSetFlattened )
					( Origin gBackEnd )
				)
				( attribute "RELATIVE_PROPAGATION_DELAY" ",5.00 MIL"
					( Parent
						( matchGroupRef "@baseboard_fab2_lib.baseboard_fab2(sch_1):\MG_DQ-DQS_NEAR_DIMM_NG_M_G_BYTE4\" )
					)
					( Units "uMatchProp" "ns" 1.000000)
					( Status sCSetFlattened )
					( Origin gBackEnd )
				)
			)
			( pinPair "@baseboard_fab2_lib.baseboard_fab2(sch_1):\PP922\"
				( pinRef "@baseboard_fab2_lib.baseboard_fab2(sch_1):page57_i172:DDR0_DQS_DP(13)" )
				( pinRef "@baseboard_fab2_lib.baseboard_fab2(sch_1):page77_i66:DQS13P" )
				( attribute "RELATIVE_PROPAGATION_DELAY_SCOPE" "G"
					( Parent
						( matchGroupRef "@baseboard_fab2_lib.baseboard_fab2(sch_1):\MG_DQ-DQS_FAR_DIMM_NG_M_G_BYTE4\" )
					)
					( Status sCSetFlattened )
					( Origin gBackEnd )
				)
				( attribute "RELATIVE_PROPAGATION_DELAY" ",5.00 MIL"
					( Parent
						( matchGroupRef "@baseboard_fab2_lib.baseboard_fab2(sch_1):\MG_DQ-DQS_FAR_DIMM_NG_M_G_BYTE4\" )
					)
					( Units "uMatchProp" "ns" 1.000000)
					( Status sCSetFlattened )
					( Origin gBackEnd )
				)
			)
			( pinPair "@baseboard_fab2_lib.baseboard_fab2(sch_1):\PP924\"
				( pinRef "@baseboard_fab2_lib.baseboard_fab2(sch_1):page78_i120:DQS13P" )
				( pinRef "@baseboard_fab2_lib.baseboard_fab2(sch_1):page57_i172:DDR0_DQS_DP(13)" )
				( attribute "RELATIVE_PROPAGATION_DELAY_SCOPE" "G"
					( Parent
						( matchGroupRef "@baseboard_fab2_lib.baseboard_fab2(sch_1):\MG_DQ-DQS_NEAR_DIMM_NG_M_G_BYTE4\" )
					)
					( Status sCSetFlattened )
					( Origin gBackEnd )
				)
				( attribute "RELATIVE_PROPAGATION_DELAY" ",5.00 MIL"
					( Parent
						( matchGroupRef "@baseboard_fab2_lib.baseboard_fab2(sch_1):\MG_DQ-DQS_NEAR_DIMM_NG_M_G_BYTE4\" )
					)
					( Units "uMatchProp" "ns" 1.000000)
					( Status sCSetFlattened )
					( Origin gBackEnd )
				)
			)
			( pinPair "@baseboard_fab2_lib.baseboard_fab2(sch_1):\PP907\"
				( pinRef "@baseboard_fab2_lib.baseboard_fab2(sch_1):page57_i172:DDR0_DQS_DN(14)" )
				( pinRef "@baseboard_fab2_lib.baseboard_fab2(sch_1):page77_i66:DQS14N" )
				( attribute "RELATIVE_PROPAGATION_DELAY_SCOPE" "G"
					( Parent
						( matchGroupRef "@baseboard_fab2_lib.baseboard_fab2(sch_1):\MG_DQ-DQS_FAR_DIMM_NG_M_G_BYTE5\" )
					)
					( Status sCSetFlattened )
					( Origin gBackEnd )
				)
				( attribute "RELATIVE_PROPAGATION_DELAY" ",5.00 MIL"
					( Parent
						( matchGroupRef "@baseboard_fab2_lib.baseboard_fab2(sch_1):\MG_DQ-DQS_FAR_DIMM_NG_M_G_BYTE5\" )
					)
					( Units "uMatchProp" "ns" 1.000000)
					( Status sCSetFlattened )
					( Origin gBackEnd )
				)
			)
			( pinPair "@baseboard_fab2_lib.baseboard_fab2(sch_1):\PP909\"
				( pinRef "@baseboard_fab2_lib.baseboard_fab2(sch_1):page78_i120:DQS14N" )
				( pinRef "@baseboard_fab2_lib.baseboard_fab2(sch_1):page57_i172:DDR0_DQS_DN(14)" )
				( attribute "RELATIVE_PROPAGATION_DELAY_SCOPE" "G"
					( Parent
						( matchGroupRef "@baseboard_fab2_lib.baseboard_fab2(sch_1):\MG_DQ-DQS_NEAR_DIMM_NG_M_G_BYTE5\" )
					)
					( Status sCSetFlattened )
					( Origin gBackEnd )
				)
				( attribute "RELATIVE_PROPAGATION_DELAY" ",5.00 MIL"
					( Parent
						( matchGroupRef "@baseboard_fab2_lib.baseboard_fab2(sch_1):\MG_DQ-DQS_NEAR_DIMM_NG_M_G_BYTE5\" )
					)
					( Units "uMatchProp" "ns" 1.000000)
					( Status sCSetFlattened )
					( Origin gBackEnd )
				)
			)
			( pinPair "@baseboard_fab2_lib.baseboard_fab2(sch_1):\PP910\"
				( pinRef "@baseboard_fab2_lib.baseboard_fab2(sch_1):page57_i172:DDR0_DQS_DP(14)" )
				( pinRef "@baseboard_fab2_lib.baseboard_fab2(sch_1):page77_i66:DQS14P" )
				( attribute "RELATIVE_PROPAGATION_DELAY_SCOPE" "G"
					( Parent
						( matchGroupRef "@baseboard_fab2_lib.baseboard_fab2(sch_1):\MG_DQ-DQS_FAR_DIMM_NG_M_G_BYTE5\" )
					)
					( Status sCSetFlattened )
					( Origin gBackEnd )
				)
				( attribute "RELATIVE_PROPAGATION_DELAY" ",5.00 MIL"
					( Parent
						( matchGroupRef "@baseboard_fab2_lib.baseboard_fab2(sch_1):\MG_DQ-DQS_FAR_DIMM_NG_M_G_BYTE5\" )
					)
					( Units "uMatchProp" "ns" 1.000000)
					( Status sCSetFlattened )
					( Origin gBackEnd )
				)
			)
			( pinPair "@baseboard_fab2_lib.baseboard_fab2(sch_1):\PP912\"
				( pinRef "@baseboard_fab2_lib.baseboard_fab2(sch_1):page78_i120:DQS14P" )
				( pinRef "@baseboard_fab2_lib.baseboard_fab2(sch_1):page57_i172:DDR0_DQS_DP(14)" )
				( attribute "RELATIVE_PROPAGATION_DELAY_SCOPE" "G"
					( Parent
						( matchGroupRef "@baseboard_fab2_lib.baseboard_fab2(sch_1):\MG_DQ-DQS_NEAR_DIMM_NG_M_G_BYTE5\" )
					)
					( Status sCSetFlattened )
					( Origin gBackEnd )
				)
				( attribute "RELATIVE_PROPAGATION_DELAY" ",5.00 MIL"
					( Parent
						( matchGroupRef "@baseboard_fab2_lib.baseboard_fab2(sch_1):\MG_DQ-DQS_NEAR_DIMM_NG_M_G_BYTE5\" )
					)
					( Units "uMatchProp" "ns" 1.000000)
					( Status sCSetFlattened )
					( Origin gBackEnd )
				)
			)
			( pinPair "@baseboard_fab2_lib.baseboard_fab2(sch_1):\PP895\"
				( pinRef "@baseboard_fab2_lib.baseboard_fab2(sch_1):page57_i172:DDR0_DQS_DN(15)" )
				( pinRef "@baseboard_fab2_lib.baseboard_fab2(sch_1):page77_i66:DQS15N" )
				( attribute "RELATIVE_PROPAGATION_DELAY_SCOPE" "G"
					( Parent
						( matchGroupRef "@baseboard_fab2_lib.baseboard_fab2(sch_1):\MG_DQ-DQS_FAR_DIMM_NG_M_G_BYTE6\" )
					)
					( Status sCSetFlattened )
					( Origin gBackEnd )
				)
				( attribute "RELATIVE_PROPAGATION_DELAY" ",5.00 MIL"
					( Parent
						( matchGroupRef "@baseboard_fab2_lib.baseboard_fab2(sch_1):\MG_DQ-DQS_FAR_DIMM_NG_M_G_BYTE6\" )
					)
					( Units "uMatchProp" "ns" 1.000000)
					( Status sCSetFlattened )
					( Origin gBackEnd )
				)
			)
			( pinPair "@baseboard_fab2_lib.baseboard_fab2(sch_1):\PP897\"
				( pinRef "@baseboard_fab2_lib.baseboard_fab2(sch_1):page78_i120:DQS15N" )
				( pinRef "@baseboard_fab2_lib.baseboard_fab2(sch_1):page57_i172:DDR0_DQS_DN(15)" )
				( attribute "RELATIVE_PROPAGATION_DELAY_SCOPE" "G"
					( Parent
						( matchGroupRef "@baseboard_fab2_lib.baseboard_fab2(sch_1):\MG_DQ-DQS_NEAR_DIMM_NG_M_G_BYTE6\" )
					)
					( Status sCSetFlattened )
					( Origin gBackEnd )
				)
				( attribute "RELATIVE_PROPAGATION_DELAY" ",5.00 MIL"
					( Parent
						( matchGroupRef "@baseboard_fab2_lib.baseboard_fab2(sch_1):\MG_DQ-DQS_NEAR_DIMM_NG_M_G_BYTE6\" )
					)
					( Units "uMatchProp" "ns" 1.000000)
					( Status sCSetFlattened )
					( Origin gBackEnd )
				)
			)
			( pinPair "@baseboard_fab2_lib.baseboard_fab2(sch_1):\PP898\"
				( pinRef "@baseboard_fab2_lib.baseboard_fab2(sch_1):page57_i172:DDR0_DQS_DP(15)" )
				( pinRef "@baseboard_fab2_lib.baseboard_fab2(sch_1):page77_i66:DQS15P" )
				( attribute "RELATIVE_PROPAGATION_DELAY_SCOPE" "G"
					( Parent
						( matchGroupRef "@baseboard_fab2_lib.baseboard_fab2(sch_1):\MG_DQ-DQS_FAR_DIMM_NG_M_G_BYTE6\" )
					)
					( Status sCSetFlattened )
					( Origin gBackEnd )
				)
				( attribute "RELATIVE_PROPAGATION_DELAY" ",5.00 MIL"
					( Parent
						( matchGroupRef "@baseboard_fab2_lib.baseboard_fab2(sch_1):\MG_DQ-DQS_FAR_DIMM_NG_M_G_BYTE6\" )
					)
					( Units "uMatchProp" "ns" 1.000000)
					( Status sCSetFlattened )
					( Origin gBackEnd )
				)
			)
			( pinPair "@baseboard_fab2_lib.baseboard_fab2(sch_1):\PP900\"
				( pinRef "@baseboard_fab2_lib.baseboard_fab2(sch_1):page78_i120:DQS15P" )
				( pinRef "@baseboard_fab2_lib.baseboard_fab2(sch_1):page57_i172:DDR0_DQS_DP(15)" )
				( attribute "RELATIVE_PROPAGATION_DELAY_SCOPE" "G"
					( Parent
						( matchGroupRef "@baseboard_fab2_lib.baseboard_fab2(sch_1):\MG_DQ-DQS_NEAR_DIMM_NG_M_G_BYTE6\" )
					)
					( Status sCSetFlattened )
					( Origin gBackEnd )
				)
				( attribute "RELATIVE_PROPAGATION_DELAY" ",5.00 MIL"
					( Parent
						( matchGroupRef "@baseboard_fab2_lib.baseboard_fab2(sch_1):\MG_DQ-DQS_NEAR_DIMM_NG_M_G_BYTE6\" )
					)
					( Units "uMatchProp" "ns" 1.000000)
					( Status sCSetFlattened )
					( Origin gBackEnd )
				)
			)
			( pinPair "@baseboard_fab2_lib.baseboard_fab2(sch_1):\PP883\"
				( pinRef "@baseboard_fab2_lib.baseboard_fab2(sch_1):page57_i172:DDR0_DQS_DN(16)" )
				( pinRef "@baseboard_fab2_lib.baseboard_fab2(sch_1):page77_i66:DQS16N" )
				( attribute "RELATIVE_PROPAGATION_DELAY_SCOPE" "G"
					( Parent
						( matchGroupRef "@baseboard_fab2_lib.baseboard_fab2(sch_1):\MG_DQ-DQS_FAR_DIMM_NG_M_G_BYTE7\" )
					)
					( Status sCSetFlattened )
					( Origin gBackEnd )
				)
				( attribute "RELATIVE_PROPAGATION_DELAY" ",5.00 MIL"
					( Parent
						( matchGroupRef "@baseboard_fab2_lib.baseboard_fab2(sch_1):\MG_DQ-DQS_FAR_DIMM_NG_M_G_BYTE7\" )
					)
					( Units "uMatchProp" "ns" 1.000000)
					( Status sCSetFlattened )
					( Origin gBackEnd )
				)
			)
			( pinPair "@baseboard_fab2_lib.baseboard_fab2(sch_1):\PP885\"
				( pinRef "@baseboard_fab2_lib.baseboard_fab2(sch_1):page78_i120:DQS16N" )
				( pinRef "@baseboard_fab2_lib.baseboard_fab2(sch_1):page57_i172:DDR0_DQS_DN(16)" )
				( attribute "RELATIVE_PROPAGATION_DELAY_SCOPE" "G"
					( Parent
						( matchGroupRef "@baseboard_fab2_lib.baseboard_fab2(sch_1):\MG_DQ-DQS_NEAR_DIMM_NG_M_G_BYTE7\" )
					)
					( Status sCSetFlattened )
					( Origin gBackEnd )
				)
				( attribute "RELATIVE_PROPAGATION_DELAY" ",5.00 MIL"
					( Parent
						( matchGroupRef "@baseboard_fab2_lib.baseboard_fab2(sch_1):\MG_DQ-DQS_NEAR_DIMM_NG_M_G_BYTE7\" )
					)
					( Units "uMatchProp" "ns" 1.000000)
					( Status sCSetFlattened )
					( Origin gBackEnd )
				)
			)
			( pinPair "@baseboard_fab2_lib.baseboard_fab2(sch_1):\PP886\"
				( pinRef "@baseboard_fab2_lib.baseboard_fab2(sch_1):page57_i172:DDR0_DQS_DP(16)" )
				( pinRef "@baseboard_fab2_lib.baseboard_fab2(sch_1):page77_i66:DQS16P" )
				( attribute "RELATIVE_PROPAGATION_DELAY_SCOPE" "G"
					( Parent
						( matchGroupRef "@baseboard_fab2_lib.baseboard_fab2(sch_1):\MG_DQ-DQS_FAR_DIMM_NG_M_G_BYTE7\" )
					)
					( Status sCSetFlattened )
					( Origin gBackEnd )
				)
				( attribute "RELATIVE_PROPAGATION_DELAY" ",5.00 MIL"
					( Parent
						( matchGroupRef "@baseboard_fab2_lib.baseboard_fab2(sch_1):\MG_DQ-DQS_FAR_DIMM_NG_M_G_BYTE7\" )
					)
					( Units "uMatchProp" "ns" 1.000000)
					( Status sCSetFlattened )
					( Origin gBackEnd )
				)
			)
			( pinPair "@baseboard_fab2_lib.baseboard_fab2(sch_1):\PP888\"
				( pinRef "@baseboard_fab2_lib.baseboard_fab2(sch_1):page78_i120:DQS16P" )
				( pinRef "@baseboard_fab2_lib.baseboard_fab2(sch_1):page57_i172:DDR0_DQS_DP(16)" )
				( attribute "RELATIVE_PROPAGATION_DELAY_SCOPE" "G"
					( Parent
						( matchGroupRef "@baseboard_fab2_lib.baseboard_fab2(sch_1):\MG_DQ-DQS_NEAR_DIMM_NG_M_G_BYTE7\" )
					)
					( Status sCSetFlattened )
					( Origin gBackEnd )
				)
				( attribute "RELATIVE_PROPAGATION_DELAY" ",5.00 MIL"
					( Parent
						( matchGroupRef "@baseboard_fab2_lib.baseboard_fab2(sch_1):\MG_DQ-DQS_NEAR_DIMM_NG_M_G_BYTE7\" )
					)
					( Units "uMatchProp" "ns" 1.000000)
					( Status sCSetFlattened )
					( Origin gBackEnd )
				)
			)
			( pinPair "@baseboard_fab2_lib.baseboard_fab2(sch_1):\PP871\"
				( pinRef "@baseboard_fab2_lib.baseboard_fab2(sch_1):page57_i172:DDR0_DQS_DN(17)" )
				( pinRef "@baseboard_fab2_lib.baseboard_fab2(sch_1):page77_i66:DQS17N" )
				( attribute "RELATIVE_PROPAGATION_DELAY_SCOPE" "G"
					( Parent
						( matchGroupRef "@baseboard_fab2_lib.baseboard_fab2(sch_1):\MG_DQ-DQS_FAR_DIMM_NG_M_G_BYTE-ECC\" )
					)
					( Status sCSetFlattened )
					( Origin gBackEnd )
				)
				( attribute "RELATIVE_PROPAGATION_DELAY" ",5.00 MIL"
					( Parent
						( matchGroupRef "@baseboard_fab2_lib.baseboard_fab2(sch_1):\MG_DQ-DQS_FAR_DIMM_NG_M_G_BYTE-ECC\" )
					)
					( Units "uMatchProp" "ns" 1.000000)
					( Status sCSetFlattened )
					( Origin gBackEnd )
				)
			)
			( pinPair "@baseboard_fab2_lib.baseboard_fab2(sch_1):\PP872\"
				( pinRef "@baseboard_fab2_lib.baseboard_fab2(sch_1):page78_i120:DQS17N" )
				( pinRef "@baseboard_fab2_lib.baseboard_fab2(sch_1):page57_i172:DDR0_DQS_DN(17)" )
				( attribute "RELATIVE_PROPAGATION_DELAY_SCOPE" "G"
					( Parent
						( matchGroupRef "@baseboard_fab2_lib.baseboard_fab2(sch_1):\MG_DQ-DQS_NEAR_DIMM_NG_M_G_BYTE-ECC\" )
					)
					( Status sCSetFlattened )
					( Origin gBackEnd )
				)
				( attribute "RELATIVE_PROPAGATION_DELAY" ",5.00 MIL"
					( Parent
						( matchGroupRef "@baseboard_fab2_lib.baseboard_fab2(sch_1):\MG_DQ-DQS_NEAR_DIMM_NG_M_G_BYTE-ECC\" )
					)
					( Units "uMatchProp" "ns" 1.000000)
					( Status sCSetFlattened )
					( Origin gBackEnd )
				)
			)
			( pinPair "@baseboard_fab2_lib.baseboard_fab2(sch_1):\PP874\"
				( pinRef "@baseboard_fab2_lib.baseboard_fab2(sch_1):page57_i172:DDR0_DQS_DP(17)" )
				( pinRef "@baseboard_fab2_lib.baseboard_fab2(sch_1):page77_i66:DQS17P" )
				( attribute "RELATIVE_PROPAGATION_DELAY_SCOPE" "G"
					( Parent
						( matchGroupRef "@baseboard_fab2_lib.baseboard_fab2(sch_1):\MG_DQ-DQS_FAR_DIMM_NG_M_G_BYTE-ECC\" )
					)
					( Status sCSetFlattened )
					( Origin gBackEnd )
				)
				( attribute "RELATIVE_PROPAGATION_DELAY" ",5.00 MIL"
					( Parent
						( matchGroupRef "@baseboard_fab2_lib.baseboard_fab2(sch_1):\MG_DQ-DQS_FAR_DIMM_NG_M_G_BYTE-ECC\" )
					)
					( Units "uMatchProp" "ns" 1.000000)
					( Status sCSetFlattened )
					( Origin gBackEnd )
				)
			)
			( pinPair "@baseboard_fab2_lib.baseboard_fab2(sch_1):\PP875\"
				( pinRef "@baseboard_fab2_lib.baseboard_fab2(sch_1):page78_i120:DQS17P" )
				( pinRef "@baseboard_fab2_lib.baseboard_fab2(sch_1):page57_i172:DDR0_DQS_DP(17)" )
				( attribute "RELATIVE_PROPAGATION_DELAY_SCOPE" "G"
					( Parent
						( matchGroupRef "@baseboard_fab2_lib.baseboard_fab2(sch_1):\MG_DQ-DQS_NEAR_DIMM_NG_M_G_BYTE-ECC\" )
					)
					( Status sCSetFlattened )
					( Origin gBackEnd )
				)
				( attribute "RELATIVE_PROPAGATION_DELAY" ",5.00 MIL"
					( Parent
						( matchGroupRef "@baseboard_fab2_lib.baseboard_fab2(sch_1):\MG_DQ-DQS_NEAR_DIMM_NG_M_G_BYTE-ECC\" )
					)
					( Units "uMatchProp" "ns" 1.000000)
					( Status sCSetFlattened )
					( Origin gBackEnd )
				)
			)
			( pinPair "@baseboard_fab2_lib.baseboard_fab2(sch_1):\PP865\"
				( pinRef "@baseboard_fab2_lib.baseboard_fab2(sch_1):page58_i172:DDR1_DQS_DN(0)" )
				( pinRef "@baseboard_fab2_lib.baseboard_fab2(sch_1):page79_i64:DQS0N" )
				( attribute "RELATIVE_PROPAGATION_DELAY_SCOPE" "G"
					( Parent
						( matchGroupRef "@baseboard_fab2_lib.baseboard_fab2(sch_1):\MG_DQ-DQS_FAR_DIMM_NG_M_H_BYTE0\" )
					)
					( Status sCSetFlattened )
					( Origin gBackEnd )
				)
				( attribute "RELATIVE_PROPAGATION_DELAY" ",5.00 MIL"
					( Parent
						( matchGroupRef "@baseboard_fab2_lib.baseboard_fab2(sch_1):\MG_DQ-DQS_FAR_DIMM_NG_M_H_BYTE0\" )
					)
					( Units "uMatchProp" "ns" 1.000000)
					( Status sCSetFlattened )
					( Origin gBackEnd )
				)
			)
			( pinPair "@baseboard_fab2_lib.baseboard_fab2(sch_1):\PP866\"
				( pinRef "@baseboard_fab2_lib.baseboard_fab2(sch_1):page80_i101:DQS0N" )
				( pinRef "@baseboard_fab2_lib.baseboard_fab2(sch_1):page58_i172:DDR1_DQS_DN(0)" )
				( attribute "RELATIVE_PROPAGATION_DELAY_SCOPE" "G"
					( Parent
						( matchGroupRef "@baseboard_fab2_lib.baseboard_fab2(sch_1):\MG_DQ-DQS_NEAR_DIMM_NG_M_H_BYTE0\" )
					)
					( Status sCSetFlattened )
					( Origin gBackEnd )
				)
				( attribute "RELATIVE_PROPAGATION_DELAY" ",5.00 MIL"
					( Parent
						( matchGroupRef "@baseboard_fab2_lib.baseboard_fab2(sch_1):\MG_DQ-DQS_NEAR_DIMM_NG_M_H_BYTE0\" )
					)
					( Units "uMatchProp" "ns" 1.000000)
					( Status sCSetFlattened )
					( Origin gBackEnd )
				)
			)
			( pinPair "@baseboard_fab2_lib.baseboard_fab2(sch_1):\PP868\"
				( pinRef "@baseboard_fab2_lib.baseboard_fab2(sch_1):page58_i172:DDR1_DQS_DP(0)" )
				( pinRef "@baseboard_fab2_lib.baseboard_fab2(sch_1):page79_i64:DQS0P" )
				( attribute "RELATIVE_PROPAGATION_DELAY_SCOPE" "G"
					( Parent
						( matchGroupRef "@baseboard_fab2_lib.baseboard_fab2(sch_1):\MG_DQ-DQS_FAR_DIMM_NG_M_H_BYTE0\" )
					)
					( Status sCSetFlattened )
					( Origin gBackEnd )
				)
				( attribute "RELATIVE_PROPAGATION_DELAY" ",5.00 MIL"
					( Parent
						( matchGroupRef "@baseboard_fab2_lib.baseboard_fab2(sch_1):\MG_DQ-DQS_FAR_DIMM_NG_M_H_BYTE0\" )
					)
					( Units "uMatchProp" "ns" 1.000000)
					( Status sCSetFlattened )
					( Origin gBackEnd )
				)
			)
			( pinPair "@baseboard_fab2_lib.baseboard_fab2(sch_1):\PP869\"
				( pinRef "@baseboard_fab2_lib.baseboard_fab2(sch_1):page80_i101:DQS0P" )
				( pinRef "@baseboard_fab2_lib.baseboard_fab2(sch_1):page58_i172:DDR1_DQS_DP(0)" )
				( attribute "RELATIVE_PROPAGATION_DELAY_SCOPE" "G"
					( Parent
						( matchGroupRef "@baseboard_fab2_lib.baseboard_fab2(sch_1):\MG_DQ-DQS_NEAR_DIMM_NG_M_H_BYTE0\" )
					)
					( Status sCSetFlattened )
					( Origin gBackEnd )
				)
				( attribute "RELATIVE_PROPAGATION_DELAY" ",5.00 MIL"
					( Parent
						( matchGroupRef "@baseboard_fab2_lib.baseboard_fab2(sch_1):\MG_DQ-DQS_NEAR_DIMM_NG_M_H_BYTE0\" )
					)
					( Units "uMatchProp" "ns" 1.000000)
					( Status sCSetFlattened )
					( Origin gBackEnd )
				)
			)
			( pinPair "@baseboard_fab2_lib.baseboard_fab2(sch_1):\PP853\"
				( pinRef "@baseboard_fab2_lib.baseboard_fab2(sch_1):page58_i172:DDR1_DQS_DN(1)" )
				( pinRef "@baseboard_fab2_lib.baseboard_fab2(sch_1):page79_i64:DQS1N" )
				( attribute "RELATIVE_PROPAGATION_DELAY_SCOPE" "G"
					( Parent
						( matchGroupRef "@baseboard_fab2_lib.baseboard_fab2(sch_1):\MG_DQ-DQS_FAR_DIMM_NG_M_H_BYTE1\" )
					)
					( Status sCSetFlattened )
					( Origin gBackEnd )
				)
				( attribute "RELATIVE_PROPAGATION_DELAY" ",5.00 MIL"
					( Parent
						( matchGroupRef "@baseboard_fab2_lib.baseboard_fab2(sch_1):\MG_DQ-DQS_FAR_DIMM_NG_M_H_BYTE1\" )
					)
					( Units "uMatchProp" "ns" 1.000000)
					( Status sCSetFlattened )
					( Origin gBackEnd )
				)
			)
			( pinPair "@baseboard_fab2_lib.baseboard_fab2(sch_1):\PP854\"
				( pinRef "@baseboard_fab2_lib.baseboard_fab2(sch_1):page80_i101:DQS1N" )
				( pinRef "@baseboard_fab2_lib.baseboard_fab2(sch_1):page58_i172:DDR1_DQS_DN(1)" )
				( attribute "RELATIVE_PROPAGATION_DELAY_SCOPE" "G"
					( Parent
						( matchGroupRef "@baseboard_fab2_lib.baseboard_fab2(sch_1):\MG_DQ-DQS_NEAR_DIMM_NG_M_H_BYTE1\" )
					)
					( Status sCSetFlattened )
					( Origin gBackEnd )
				)
				( attribute "RELATIVE_PROPAGATION_DELAY" ",5.00 MIL"
					( Parent
						( matchGroupRef "@baseboard_fab2_lib.baseboard_fab2(sch_1):\MG_DQ-DQS_NEAR_DIMM_NG_M_H_BYTE1\" )
					)
					( Units "uMatchProp" "ns" 1.000000)
					( Status sCSetFlattened )
					( Origin gBackEnd )
				)
			)
			( pinPair "@baseboard_fab2_lib.baseboard_fab2(sch_1):\PP856\"
				( pinRef "@baseboard_fab2_lib.baseboard_fab2(sch_1):page58_i172:DDR1_DQS_DP(1)" )
				( pinRef "@baseboard_fab2_lib.baseboard_fab2(sch_1):page79_i64:DQS1P" )
				( attribute "RELATIVE_PROPAGATION_DELAY_SCOPE" "G"
					( Parent
						( matchGroupRef "@baseboard_fab2_lib.baseboard_fab2(sch_1):\MG_DQ-DQS_FAR_DIMM_NG_M_H_BYTE1\" )
					)
					( Status sCSetFlattened )
					( Origin gBackEnd )
				)
				( attribute "RELATIVE_PROPAGATION_DELAY" ",5.00 MIL"
					( Parent
						( matchGroupRef "@baseboard_fab2_lib.baseboard_fab2(sch_1):\MG_DQ-DQS_FAR_DIMM_NG_M_H_BYTE1\" )
					)
					( Units "uMatchProp" "ns" 1.000000)
					( Status sCSetFlattened )
					( Origin gBackEnd )
				)
			)
			( pinPair "@baseboard_fab2_lib.baseboard_fab2(sch_1):\PP857\"
				( pinRef "@baseboard_fab2_lib.baseboard_fab2(sch_1):page80_i101:DQS1P" )
				( pinRef "@baseboard_fab2_lib.baseboard_fab2(sch_1):page58_i172:DDR1_DQS_DP(1)" )
				( attribute "RELATIVE_PROPAGATION_DELAY_SCOPE" "G"
					( Parent
						( matchGroupRef "@baseboard_fab2_lib.baseboard_fab2(sch_1):\MG_DQ-DQS_NEAR_DIMM_NG_M_H_BYTE1\" )
					)
					( Status sCSetFlattened )
					( Origin gBackEnd )
				)
				( attribute "RELATIVE_PROPAGATION_DELAY" ",5.00 MIL"
					( Parent
						( matchGroupRef "@baseboard_fab2_lib.baseboard_fab2(sch_1):\MG_DQ-DQS_NEAR_DIMM_NG_M_H_BYTE1\" )
					)
					( Units "uMatchProp" "ns" 1.000000)
					( Status sCSetFlattened )
					( Origin gBackEnd )
				)
			)
			( pinPair "@baseboard_fab2_lib.baseboard_fab2(sch_1):\PP1204\"
				( pinRef "@baseboard_fab2_lib.baseboard_fab2(sch_1):page26_i172:DDR3_DQS_DP(8)" )
				( pinRef "@baseboard_fab2_lib.baseboard_fab2(sch_1):page49_i66:DQS8P" )
				( attribute "RELATIVE_PROPAGATION_DELAY_SCOPE" "G"
					( Parent
						( matchGroupRef "@baseboard_fab2_lib.baseboard_fab2(sch_1):\MG_DQ-DQS_FAR_DIMM_NG_M_D_BYTE-ECC\" )
					)
					( Status sCSetFlattened )
					( Origin gBackEnd )
				)
				( attribute "RELATIVE_PROPAGATION_DELAY" ",5.00 MIL"
					( Parent
						( matchGroupRef "@baseboard_fab2_lib.baseboard_fab2(sch_1):\MG_DQ-DQS_FAR_DIMM_NG_M_D_BYTE-ECC\" )
					)
					( Units "uMatchProp" "ns" 1.000000)
					( Status sCSetFlattened )
					( Origin gBackEnd )
				)
			)
			( pinPair "@baseboard_fab2_lib.baseboard_fab2(sch_1):\PP1205\"
				( pinRef "@baseboard_fab2_lib.baseboard_fab2(sch_1):page50_i46:DQS8P" )
				( pinRef "@baseboard_fab2_lib.baseboard_fab2(sch_1):page26_i172:DDR3_DQS_DP(8)" )
				( attribute "RELATIVE_PROPAGATION_DELAY_SCOPE" "G"
					( Parent
						( matchGroupRef "@baseboard_fab2_lib.baseboard_fab2(sch_1):\MG_DQ-DQS_NEAR_DIMM_NG_M_D_BYTE-ECC\" )
					)
					( Status sCSetFlattened )
					( Origin gBackEnd )
				)
				( attribute "RELATIVE_PROPAGATION_DELAY" ",5.00 MIL"
					( Parent
						( matchGroupRef "@baseboard_fab2_lib.baseboard_fab2(sch_1):\MG_DQ-DQS_NEAR_DIMM_NG_M_D_BYTE-ECC\" )
					)
					( Units "uMatchProp" "ns" 1.000000)
					( Status sCSetFlattened )
					( Origin gBackEnd )
				)
			)
			( pinPair "@baseboard_fab2_lib.baseboard_fab2(sch_1):\PP670\"
				( pinRef "@baseboard_fab2_lib.baseboard_fab2(sch_1):page26_i172:DDR3_DQS_DP(9)" )
				( pinRef "@baseboard_fab2_lib.baseboard_fab2(sch_1):page49_i66:DQS9P" )
				( attribute "RELATIVE_PROPAGATION_DELAY_SCOPE" "G"
					( Parent
						( matchGroupRef "@baseboard_fab2_lib.baseboard_fab2(sch_1):\MG_DQ-DQS_FAR_DIMM_NG_M_D_BYTE0\" )
					)
					( Status sCSetFlattened )
					( Origin gBackEnd )
				)
				( attribute "RELATIVE_PROPAGATION_DELAY" ",5.00 MIL"
					( Parent
						( matchGroupRef "@baseboard_fab2_lib.baseboard_fab2(sch_1):\MG_DQ-DQS_FAR_DIMM_NG_M_D_BYTE0\" )
					)
					( Units "uMatchProp" "ns" 1.000000)
					( Status sCSetFlattened )
					( Origin gBackEnd )
				)
			)
			( pinPair "@baseboard_fab2_lib.baseboard_fab2(sch_1):\PP671\"
				( pinRef "@baseboard_fab2_lib.baseboard_fab2(sch_1):page50_i46:DQS9P" )
				( pinRef "@baseboard_fab2_lib.baseboard_fab2(sch_1):page26_i172:DDR3_DQS_DP(9)" )
				( attribute "RELATIVE_PROPAGATION_DELAY_SCOPE" "G"
					( Parent
						( matchGroupRef "@baseboard_fab2_lib.baseboard_fab2(sch_1):\MG_DQ-DQS_NEAR_DIMM_NG_M_D_BYTE0\" )
					)
					( Status sCSetFlattened )
					( Origin gBackEnd )
				)
				( attribute "RELATIVE_PROPAGATION_DELAY" ",5.00 MIL"
					( Parent
						( matchGroupRef "@baseboard_fab2_lib.baseboard_fab2(sch_1):\MG_DQ-DQS_NEAR_DIMM_NG_M_D_BYTE0\" )
					)
					( Units "uMatchProp" "ns" 1.000000)
					( Status sCSetFlattened )
					( Origin gBackEnd )
				)
			)
			( pinPair "@baseboard_fab2_lib.baseboard_fab2(sch_1):\PP682\"
				( pinRef "@baseboard_fab2_lib.baseboard_fab2(sch_1):page26_i172:DDR3_DQS_DP(10)" )
				( pinRef "@baseboard_fab2_lib.baseboard_fab2(sch_1):page49_i66:DQS10P" )
				( attribute "RELATIVE_PROPAGATION_DELAY_SCOPE" "G"
					( Parent
						( matchGroupRef "@baseboard_fab2_lib.baseboard_fab2(sch_1):\MG_DQ-DQS_FAR_DIMM_NG_M_D_BYTE1\" )
					)
					( Status sCSetFlattened )
					( Origin gBackEnd )
				)
				( attribute "RELATIVE_PROPAGATION_DELAY" ",5.00 MIL"
					( Parent
						( matchGroupRef "@baseboard_fab2_lib.baseboard_fab2(sch_1):\MG_DQ-DQS_FAR_DIMM_NG_M_D_BYTE1\" )
					)
					( Units "uMatchProp" "ns" 1.000000)
					( Status sCSetFlattened )
					( Origin gBackEnd )
				)
			)
			( pinPair "@baseboard_fab2_lib.baseboard_fab2(sch_1):\PP683\"
				( pinRef "@baseboard_fab2_lib.baseboard_fab2(sch_1):page50_i46:DQS10P" )
				( pinRef "@baseboard_fab2_lib.baseboard_fab2(sch_1):page26_i172:DDR3_DQS_DP(10)" )
				( attribute "RELATIVE_PROPAGATION_DELAY_SCOPE" "G"
					( Parent
						( matchGroupRef "@baseboard_fab2_lib.baseboard_fab2(sch_1):\MG_DQ-DQS_NEAR_DIMM_NG_M_D_BYTE1\" )
					)
					( Status sCSetFlattened )
					( Origin gBackEnd )
				)
				( attribute "RELATIVE_PROPAGATION_DELAY" ",5.00 MIL"
					( Parent
						( matchGroupRef "@baseboard_fab2_lib.baseboard_fab2(sch_1):\MG_DQ-DQS_NEAR_DIMM_NG_M_D_BYTE1\" )
					)
					( Units "uMatchProp" "ns" 1.000000)
					( Status sCSetFlattened )
					( Origin gBackEnd )
				)
			)
			( pinPair "@baseboard_fab2_lib.baseboard_fab2(sch_1):\PP694\"
				( pinRef "@baseboard_fab2_lib.baseboard_fab2(sch_1):page26_i172:DDR3_DQS_DP(11)" )
				( pinRef "@baseboard_fab2_lib.baseboard_fab2(sch_1):page49_i66:DQS11P" )
				( attribute "RELATIVE_PROPAGATION_DELAY_SCOPE" "G"
					( Parent
						( matchGroupRef "@baseboard_fab2_lib.baseboard_fab2(sch_1):\MG_DQ-DQS_FAR_DIMM_NG_M_D_BYTE2\" )
					)
					( Status sCSetFlattened )
					( Origin gBackEnd )
				)
				( attribute "RELATIVE_PROPAGATION_DELAY" ",5.00 MIL"
					( Parent
						( matchGroupRef "@baseboard_fab2_lib.baseboard_fab2(sch_1):\MG_DQ-DQS_FAR_DIMM_NG_M_D_BYTE2\" )
					)
					( Units "uMatchProp" "ns" 1.000000)
					( Status sCSetFlattened )
					( Origin gBackEnd )
				)
			)
			( pinPair "@baseboard_fab2_lib.baseboard_fab2(sch_1):\PP695\"
				( pinRef "@baseboard_fab2_lib.baseboard_fab2(sch_1):page26_i172:DDR3_DQS_DP(11)" )
				( pinRef "@baseboard_fab2_lib.baseboard_fab2(sch_1):page50_i46:DQS11P" )
				( attribute "RELATIVE_PROPAGATION_DELAY_SCOPE" "G"
					( Parent
						( matchGroupRef "@baseboard_fab2_lib.baseboard_fab2(sch_1):\MG_DQ-DQS_NEAR_DIMM_NG_M_D_BYTE2\" )
					)
					( Status sCSetFlattened )
					( Origin gBackEnd )
				)
				( attribute "RELATIVE_PROPAGATION_DELAY" ",5.00 MIL"
					( Parent
						( matchGroupRef "@baseboard_fab2_lib.baseboard_fab2(sch_1):\MG_DQ-DQS_NEAR_DIMM_NG_M_D_BYTE2\" )
					)
					( Units "uMatchProp" "ns" 1.000000)
					( Status sCSetFlattened )
					( Origin gBackEnd )
				)
			)
			( pinPair "@baseboard_fab2_lib.baseboard_fab2(sch_1):\PP706\"
				( pinRef "@baseboard_fab2_lib.baseboard_fab2(sch_1):page26_i172:DDR3_DQS_DP(12)" )
				( pinRef "@baseboard_fab2_lib.baseboard_fab2(sch_1):page49_i66:DQS12P" )
				( attribute "RELATIVE_PROPAGATION_DELAY_SCOPE" "G"
					( Parent
						( matchGroupRef "@baseboard_fab2_lib.baseboard_fab2(sch_1):\MG_DQ-DQS_FAR_DIMM_NG_M_D_BYTE3\" )
					)
					( Status sCSetFlattened )
					( Origin gBackEnd )
				)
				( attribute "RELATIVE_PROPAGATION_DELAY" ",5.00 MIL"
					( Parent
						( matchGroupRef "@baseboard_fab2_lib.baseboard_fab2(sch_1):\MG_DQ-DQS_FAR_DIMM_NG_M_D_BYTE3\" )
					)
					( Units "uMatchProp" "ns" 1.000000)
					( Status sCSetFlattened )
					( Origin gBackEnd )
				)
			)
			( pinPair "@baseboard_fab2_lib.baseboard_fab2(sch_1):\PP707\"
				( pinRef "@baseboard_fab2_lib.baseboard_fab2(sch_1):page50_i46:DQS12P" )
				( pinRef "@baseboard_fab2_lib.baseboard_fab2(sch_1):page26_i172:DDR3_DQS_DP(12)" )
				( attribute "RELATIVE_PROPAGATION_DELAY_SCOPE" "G"
					( Parent
						( matchGroupRef "@baseboard_fab2_lib.baseboard_fab2(sch_1):\MG_DQ-DQS_NEAR_DIMM_NG_M_D_BYTE3\" )
					)
					( Status sCSetFlattened )
					( Origin gBackEnd )
				)
				( attribute "RELATIVE_PROPAGATION_DELAY" ",5.00 MIL"
					( Parent
						( matchGroupRef "@baseboard_fab2_lib.baseboard_fab2(sch_1):\MG_DQ-DQS_NEAR_DIMM_NG_M_D_BYTE3\" )
					)
					( Units "uMatchProp" "ns" 1.000000)
					( Status sCSetFlattened )
					( Origin gBackEnd )
				)
			)
			( pinPair "@baseboard_fab2_lib.baseboard_fab2(sch_1):\PP718\"
				( pinRef "@baseboard_fab2_lib.baseboard_fab2(sch_1):page26_i172:DDR3_DQS_DP(13)" )
				( pinRef "@baseboard_fab2_lib.baseboard_fab2(sch_1):page49_i66:DQS13P" )
				( attribute "RELATIVE_PROPAGATION_DELAY_SCOPE" "G"
					( Parent
						( matchGroupRef "@baseboard_fab2_lib.baseboard_fab2(sch_1):\MG_DQ-DQS_FAR_DIMM_NG_M_D_BYTE4\" )
					)
					( Status sCSetFlattened )
					( Origin gBackEnd )
				)
				( attribute "RELATIVE_PROPAGATION_DELAY" ",5.00 MIL"
					( Parent
						( matchGroupRef "@baseboard_fab2_lib.baseboard_fab2(sch_1):\MG_DQ-DQS_FAR_DIMM_NG_M_D_BYTE4\" )
					)
					( Units "uMatchProp" "ns" 1.000000)
					( Status sCSetFlattened )
					( Origin gBackEnd )
				)
			)
			( pinPair "@baseboard_fab2_lib.baseboard_fab2(sch_1):\PP720\"
				( pinRef "@baseboard_fab2_lib.baseboard_fab2(sch_1):page50_i46:DQS13P" )
				( pinRef "@baseboard_fab2_lib.baseboard_fab2(sch_1):page26_i172:DDR3_DQS_DP(13)" )
				( attribute "RELATIVE_PROPAGATION_DELAY_SCOPE" "G"
					( Parent
						( matchGroupRef "@baseboard_fab2_lib.baseboard_fab2(sch_1):\MG_DQ-DQS_NEAR_DIMM_NG_M_D_BYTE4\" )
					)
					( Status sCSetFlattened )
					( Origin gBackEnd )
				)
				( attribute "RELATIVE_PROPAGATION_DELAY" ",5.00 MIL"
					( Parent
						( matchGroupRef "@baseboard_fab2_lib.baseboard_fab2(sch_1):\MG_DQ-DQS_NEAR_DIMM_NG_M_D_BYTE4\" )
					)
					( Units "uMatchProp" "ns" 1.000000)
					( Status sCSetFlattened )
					( Origin gBackEnd )
				)
			)
			( pinPair "@baseboard_fab2_lib.baseboard_fab2(sch_1):\PP730\"
				( pinRef "@baseboard_fab2_lib.baseboard_fab2(sch_1):page26_i172:DDR3_DQS_DP(14)" )
				( pinRef "@baseboard_fab2_lib.baseboard_fab2(sch_1):page49_i66:DQS14P" )
				( attribute "RELATIVE_PROPAGATION_DELAY_SCOPE" "G"
					( Parent
						( matchGroupRef "@baseboard_fab2_lib.baseboard_fab2(sch_1):\MG_DQ-DQS_FAR_DIMM_NG_M_D_BYTE5\" )
					)
					( Status sCSetFlattened )
					( Origin gBackEnd )
				)
				( attribute "RELATIVE_PROPAGATION_DELAY" ",5.00 MIL"
					( Parent
						( matchGroupRef "@baseboard_fab2_lib.baseboard_fab2(sch_1):\MG_DQ-DQS_FAR_DIMM_NG_M_D_BYTE5\" )
					)
					( Units "uMatchProp" "ns" 1.000000)
					( Status sCSetFlattened )
					( Origin gBackEnd )
				)
			)
			( pinPair "@baseboard_fab2_lib.baseboard_fab2(sch_1):\PP732\"
				( pinRef "@baseboard_fab2_lib.baseboard_fab2(sch_1):page26_i172:DDR3_DQS_DP(14)" )
				( pinRef "@baseboard_fab2_lib.baseboard_fab2(sch_1):page50_i46:DQS14P" )
				( attribute "RELATIVE_PROPAGATION_DELAY_SCOPE" "G"
					( Parent
						( matchGroupRef "@baseboard_fab2_lib.baseboard_fab2(sch_1):\MG_DQ-DQS_NEAR_DIMM_NG_M_D_BYTE5\" )
					)
					( Status sCSetFlattened )
					( Origin gBackEnd )
				)
				( attribute "RELATIVE_PROPAGATION_DELAY" ",5.00 MIL"
					( Parent
						( matchGroupRef "@baseboard_fab2_lib.baseboard_fab2(sch_1):\MG_DQ-DQS_NEAR_DIMM_NG_M_D_BYTE5\" )
					)
					( Units "uMatchProp" "ns" 1.000000)
					( Status sCSetFlattened )
					( Origin gBackEnd )
				)
			)
			( pinPair "@baseboard_fab2_lib.baseboard_fab2(sch_1):\PP742\"
				( pinRef "@baseboard_fab2_lib.baseboard_fab2(sch_1):page26_i172:DDR3_DQS_DP(15)" )
				( pinRef "@baseboard_fab2_lib.baseboard_fab2(sch_1):page49_i66:DQS15P" )
				( attribute "RELATIVE_PROPAGATION_DELAY_SCOPE" "G"
					( Parent
						( matchGroupRef "@baseboard_fab2_lib.baseboard_fab2(sch_1):\MG_DQ-DQS_FAR_DIMM_NG_M_D_BYTE6\" )
					)
					( Status sCSetFlattened )
					( Origin gBackEnd )
				)
				( attribute "RELATIVE_PROPAGATION_DELAY" ",5.00 MIL"
					( Parent
						( matchGroupRef "@baseboard_fab2_lib.baseboard_fab2(sch_1):\MG_DQ-DQS_FAR_DIMM_NG_M_D_BYTE6\" )
					)
					( Units "uMatchProp" "ns" 1.000000)
					( Status sCSetFlattened )
					( Origin gBackEnd )
				)
			)
			( pinPair "@baseboard_fab2_lib.baseboard_fab2(sch_1):\PP744\"
				( pinRef "@baseboard_fab2_lib.baseboard_fab2(sch_1):page26_i172:DDR3_DQS_DP(15)" )
				( pinRef "@baseboard_fab2_lib.baseboard_fab2(sch_1):page50_i46:DQS15P" )
				( attribute "RELATIVE_PROPAGATION_DELAY_SCOPE" "G"
					( Parent
						( matchGroupRef "@baseboard_fab2_lib.baseboard_fab2(sch_1):\MG_DQ-DQS_NEAR_DIMM_NG_M_D_BYTE6\" )
					)
					( Status sCSetFlattened )
					( Origin gBackEnd )
				)
				( attribute "RELATIVE_PROPAGATION_DELAY" ",5.00 MIL"
					( Parent
						( matchGroupRef "@baseboard_fab2_lib.baseboard_fab2(sch_1):\MG_DQ-DQS_NEAR_DIMM_NG_M_D_BYTE6\" )
					)
					( Units "uMatchProp" "ns" 1.000000)
					( Status sCSetFlattened )
					( Origin gBackEnd )
				)
			)
			( pinPair "@baseboard_fab2_lib.baseboard_fab2(sch_1):\PP754\"
				( pinRef "@baseboard_fab2_lib.baseboard_fab2(sch_1):page26_i172:DDR3_DQS_DP(16)" )
				( pinRef "@baseboard_fab2_lib.baseboard_fab2(sch_1):page49_i66:DQS16P" )
				( attribute "RELATIVE_PROPAGATION_DELAY_SCOPE" "G"
					( Parent
						( matchGroupRef "@baseboard_fab2_lib.baseboard_fab2(sch_1):\MG_DQ-DQS_FAR_DIMM_NG_M_D_BYTE7\" )
					)
					( Status sCSetFlattened )
					( Origin gBackEnd )
				)
				( attribute "RELATIVE_PROPAGATION_DELAY" ",5.00 MIL"
					( Parent
						( matchGroupRef "@baseboard_fab2_lib.baseboard_fab2(sch_1):\MG_DQ-DQS_FAR_DIMM_NG_M_D_BYTE7\" )
					)
					( Units "uMatchProp" "ns" 1.000000)
					( Status sCSetFlattened )
					( Origin gBackEnd )
				)
			)
			( pinPair "@baseboard_fab2_lib.baseboard_fab2(sch_1):\PP756\"
				( pinRef "@baseboard_fab2_lib.baseboard_fab2(sch_1):page26_i172:DDR3_DQS_DP(16)" )
				( pinRef "@baseboard_fab2_lib.baseboard_fab2(sch_1):page50_i46:DQS16P" )
				( attribute "RELATIVE_PROPAGATION_DELAY_SCOPE" "G"
					( Parent
						( matchGroupRef "@baseboard_fab2_lib.baseboard_fab2(sch_1):\MG_DQ-DQS_NEAR_DIMM_NG_M_D_BYTE7\" )
					)
					( Status sCSetFlattened )
					( Origin gBackEnd )
				)
				( attribute "RELATIVE_PROPAGATION_DELAY" ",5.00 MIL"
					( Parent
						( matchGroupRef "@baseboard_fab2_lib.baseboard_fab2(sch_1):\MG_DQ-DQS_NEAR_DIMM_NG_M_D_BYTE7\" )
					)
					( Units "uMatchProp" "ns" 1.000000)
					( Status sCSetFlattened )
					( Origin gBackEnd )
				)
			)
			( pinPair "@baseboard_fab2_lib.baseboard_fab2(sch_1):\PP1198\"
				( pinRef "@baseboard_fab2_lib.baseboard_fab2(sch_1):page26_i172:DDR3_DQS_DP(17)" )
				( pinRef "@baseboard_fab2_lib.baseboard_fab2(sch_1):page49_i66:DQS17P" )
				( attribute "RELATIVE_PROPAGATION_DELAY_SCOPE" "G"
					( Parent
						( matchGroupRef "@baseboard_fab2_lib.baseboard_fab2(sch_1):\MG_DQ-DQS_FAR_DIMM_NG_M_D_BYTE-ECC\" )
					)
					( Status sCSetFlattened )
					( Origin gBackEnd )
				)
				( attribute "RELATIVE_PROPAGATION_DELAY" ",5.00 MIL"
					( Parent
						( matchGroupRef "@baseboard_fab2_lib.baseboard_fab2(sch_1):\MG_DQ-DQS_FAR_DIMM_NG_M_D_BYTE-ECC\" )
					)
					( Units "uMatchProp" "ns" 1.000000)
					( Status sCSetFlattened )
					( Origin gBackEnd )
				)
			)
			( pinPair "@baseboard_fab2_lib.baseboard_fab2(sch_1):\PP1199\"
				( pinRef "@baseboard_fab2_lib.baseboard_fab2(sch_1):page50_i46:DQS17P" )
				( pinRef "@baseboard_fab2_lib.baseboard_fab2(sch_1):page26_i172:DDR3_DQS_DP(17)" )
				( attribute "RELATIVE_PROPAGATION_DELAY_SCOPE" "G"
					( Parent
						( matchGroupRef "@baseboard_fab2_lib.baseboard_fab2(sch_1):\MG_DQ-DQS_NEAR_DIMM_NG_M_D_BYTE-ECC\" )
					)
					( Status sCSetFlattened )
					( Origin gBackEnd )
				)
				( attribute "RELATIVE_PROPAGATION_DELAY" ",5.00 MIL"
					( Parent
						( matchGroupRef "@baseboard_fab2_lib.baseboard_fab2(sch_1):\MG_DQ-DQS_NEAR_DIMM_NG_M_D_BYTE-ECC\" )
					)
					( Units "uMatchProp" "ns" 1.000000)
					( Status sCSetFlattened )
					( Origin gBackEnd )
				)
			)
			( pinPair "@baseboard_fab2_lib.baseboard_fab2(sch_1):\PP1192\"
				( pinRef "@baseboard_fab2_lib.baseboard_fab2(sch_1):page27_i172:DDR4_DQS_DP(0)" )
				( pinRef "@baseboard_fab2_lib.baseboard_fab2(sch_1):page51_i66:DQS0P" )
				( attribute "RELATIVE_PROPAGATION_DELAY_SCOPE" "G"
					( Parent
						( matchGroupRef "@baseboard_fab2_lib.baseboard_fab2(sch_1):\MG_DQ-DQS_FAR_DIMM_NG_M_E_BYTE0\" )
					)
					( Status sCSetFlattened )
					( Origin gBackEnd )
				)
				( attribute "RELATIVE_PROPAGATION_DELAY" ",5.00 MIL"
					( Parent
						( matchGroupRef "@baseboard_fab2_lib.baseboard_fab2(sch_1):\MG_DQ-DQS_FAR_DIMM_NG_M_E_BYTE0\" )
					)
					( Units "uMatchProp" "ns" 1.000000)
					( Status sCSetFlattened )
					( Origin gBackEnd )
				)
			)
			( pinPair "@baseboard_fab2_lib.baseboard_fab2(sch_1):\PP1193\"
				( pinRef "@baseboard_fab2_lib.baseboard_fab2(sch_1):page27_i172:DDR4_DQS_DP(0)" )
				( pinRef "@baseboard_fab2_lib.baseboard_fab2(sch_1):page52_i100:DQS0P" )
				( attribute "RELATIVE_PROPAGATION_DELAY_SCOPE" "G"
					( Parent
						( matchGroupRef "@baseboard_fab2_lib.baseboard_fab2(sch_1):\MG_DQ-DQS_NEAR_DIMM_NG_M_E_BYTE0\" )
					)
					( Status sCSetFlattened )
					( Origin gBackEnd )
				)
				( attribute "RELATIVE_PROPAGATION_DELAY" ",5.00 MIL"
					( Parent
						( matchGroupRef "@baseboard_fab2_lib.baseboard_fab2(sch_1):\MG_DQ-DQS_NEAR_DIMM_NG_M_E_BYTE0\" )
					)
					( Units "uMatchProp" "ns" 1.000000)
					( Status sCSetFlattened )
					( Origin gBackEnd )
				)
			)
			( pinPair "@baseboard_fab2_lib.baseboard_fab2(sch_1):\PP1180\"
				( pinRef "@baseboard_fab2_lib.baseboard_fab2(sch_1):page27_i172:DDR4_DQS_DP(1)" )
				( pinRef "@baseboard_fab2_lib.baseboard_fab2(sch_1):page51_i66:DQS1P" )
				( attribute "RELATIVE_PROPAGATION_DELAY_SCOPE" "G"
					( Parent
						( matchGroupRef "@baseboard_fab2_lib.baseboard_fab2(sch_1):\MG_DQ-DQS_FAR_DIMM_NG_M_E_BYTE1\" )
					)
					( Status sCSetFlattened )
					( Origin gBackEnd )
				)
				( attribute "RELATIVE_PROPAGATION_DELAY" ",5.00 MIL"
					( Parent
						( matchGroupRef "@baseboard_fab2_lib.baseboard_fab2(sch_1):\MG_DQ-DQS_FAR_DIMM_NG_M_E_BYTE1\" )
					)
					( Units "uMatchProp" "ns" 1.000000)
					( Status sCSetFlattened )
					( Origin gBackEnd )
				)
			)
			( pinPair "@baseboard_fab2_lib.baseboard_fab2(sch_1):\PP1181\"
				( pinRef "@baseboard_fab2_lib.baseboard_fab2(sch_1):page27_i172:DDR4_DQS_DP(1)" )
				( pinRef "@baseboard_fab2_lib.baseboard_fab2(sch_1):page52_i100:DQS1P" )
				( attribute "RELATIVE_PROPAGATION_DELAY_SCOPE" "G"
					( Parent
						( matchGroupRef "@baseboard_fab2_lib.baseboard_fab2(sch_1):\MG_DQ-DQS_NEAR_DIMM_NG_M_E_BYTE1\" )
					)
					( Status sCSetFlattened )
					( Origin gBackEnd )
				)
				( attribute "RELATIVE_PROPAGATION_DELAY" ",5.00 MIL"
					( Parent
						( matchGroupRef "@baseboard_fab2_lib.baseboard_fab2(sch_1):\MG_DQ-DQS_NEAR_DIMM_NG_M_E_BYTE1\" )
					)
					( Units "uMatchProp" "ns" 1.000000)
					( Status sCSetFlattened )
					( Origin gBackEnd )
				)
			)
			( pinPair "@baseboard_fab2_lib.baseboard_fab2(sch_1):\PP1168\"
				( pinRef "@baseboard_fab2_lib.baseboard_fab2(sch_1):page27_i172:DDR4_DQS_DP(2)" )
				( pinRef "@baseboard_fab2_lib.baseboard_fab2(sch_1):page51_i66:DQS2P" )
				( attribute "RELATIVE_PROPAGATION_DELAY_SCOPE" "G"
					( Parent
						( matchGroupRef "@baseboard_fab2_lib.baseboard_fab2(sch_1):\MG_DQ-DQS_FAR_DIMM_NG_M_E_BYTE2\" )
					)
					( Status sCSetFlattened )
					( Origin gBackEnd )
				)
				( attribute "RELATIVE_PROPAGATION_DELAY" ",5.00 MIL"
					( Parent
						( matchGroupRef "@baseboard_fab2_lib.baseboard_fab2(sch_1):\MG_DQ-DQS_FAR_DIMM_NG_M_E_BYTE2\" )
					)
					( Units "uMatchProp" "ns" 1.000000)
					( Status sCSetFlattened )
					( Origin gBackEnd )
				)
			)
			( pinPair "@baseboard_fab2_lib.baseboard_fab2(sch_1):\PP1169\"
				( pinRef "@baseboard_fab2_lib.baseboard_fab2(sch_1):page52_i100:DQS2P" )
				( pinRef "@baseboard_fab2_lib.baseboard_fab2(sch_1):page27_i172:DDR4_DQS_DP(2)" )
				( attribute "RELATIVE_PROPAGATION_DELAY_SCOPE" "G"
					( Parent
						( matchGroupRef "@baseboard_fab2_lib.baseboard_fab2(sch_1):\MG_DQ-DQS_NEAR_DIMM_NG_M_E_BYTE2\" )
					)
					( Status sCSetFlattened )
					( Origin gBackEnd )
				)
				( attribute "RELATIVE_PROPAGATION_DELAY" ",5.00 MIL"
					( Parent
						( matchGroupRef "@baseboard_fab2_lib.baseboard_fab2(sch_1):\MG_DQ-DQS_NEAR_DIMM_NG_M_E_BYTE2\" )
					)
					( Units "uMatchProp" "ns" 1.000000)
					( Status sCSetFlattened )
					( Origin gBackEnd )
				)
			)
			( pinPair "@baseboard_fab2_lib.baseboard_fab2(sch_1):\PP1156\"
				( pinRef "@baseboard_fab2_lib.baseboard_fab2(sch_1):page27_i172:DDR4_DQS_DP(3)" )
				( pinRef "@baseboard_fab2_lib.baseboard_fab2(sch_1):page51_i66:DQS3P" )
				( attribute "RELATIVE_PROPAGATION_DELAY_SCOPE" "G"
					( Parent
						( matchGroupRef "@baseboard_fab2_lib.baseboard_fab2(sch_1):\MG_DQ-DQS_FAR_DIMM_NG_M_E_BYTE3\" )
					)
					( Status sCSetFlattened )
					( Origin gBackEnd )
				)
				( attribute "RELATIVE_PROPAGATION_DELAY" ",5.00 MIL"
					( Parent
						( matchGroupRef "@baseboard_fab2_lib.baseboard_fab2(sch_1):\MG_DQ-DQS_FAR_DIMM_NG_M_E_BYTE3\" )
					)
					( Units "uMatchProp" "ns" 1.000000)
					( Status sCSetFlattened )
					( Origin gBackEnd )
				)
			)
			( pinPair "@baseboard_fab2_lib.baseboard_fab2(sch_1):\PP1157\"
				( pinRef "@baseboard_fab2_lib.baseboard_fab2(sch_1):page27_i172:DDR4_DQS_DP(3)" )
				( pinRef "@baseboard_fab2_lib.baseboard_fab2(sch_1):page52_i100:DQS3P" )
				( attribute "RELATIVE_PROPAGATION_DELAY_SCOPE" "G"
					( Parent
						( matchGroupRef "@baseboard_fab2_lib.baseboard_fab2(sch_1):\MG_DQ-DQS_NEAR_DIMM_NG_M_E_BYTE3\" )
					)
					( Status sCSetFlattened )
					( Origin gBackEnd )
				)
				( attribute "RELATIVE_PROPAGATION_DELAY" ",5.00 MIL"
					( Parent
						( matchGroupRef "@baseboard_fab2_lib.baseboard_fab2(sch_1):\MG_DQ-DQS_NEAR_DIMM_NG_M_E_BYTE3\" )
					)
					( Units "uMatchProp" "ns" 1.000000)
					( Status sCSetFlattened )
					( Origin gBackEnd )
				)
			)
			( pinPair "@baseboard_fab2_lib.baseboard_fab2(sch_1):\PP1144\"
				( pinRef "@baseboard_fab2_lib.baseboard_fab2(sch_1):page27_i172:DDR4_DQS_DP(4)" )
				( pinRef "@baseboard_fab2_lib.baseboard_fab2(sch_1):page51_i66:DQS4P" )
				( attribute "RELATIVE_PROPAGATION_DELAY_SCOPE" "G"
					( Parent
						( matchGroupRef "@baseboard_fab2_lib.baseboard_fab2(sch_1):\MG_DQ-DQS_FAR_DIMM_NG_M_E_BYTE4\" )
					)
					( Status sCSetFlattened )
					( Origin gBackEnd )
				)
				( attribute "RELATIVE_PROPAGATION_DELAY" ",5.00 MIL"
					( Parent
						( matchGroupRef "@baseboard_fab2_lib.baseboard_fab2(sch_1):\MG_DQ-DQS_FAR_DIMM_NG_M_E_BYTE4\" )
					)
					( Units "uMatchProp" "ns" 1.000000)
					( Status sCSetFlattened )
					( Origin gBackEnd )
				)
			)
			( pinPair "@baseboard_fab2_lib.baseboard_fab2(sch_1):\PP1146\"
				( pinRef "@baseboard_fab2_lib.baseboard_fab2(sch_1):page27_i172:DDR4_DQS_DP(4)" )
				( pinRef "@baseboard_fab2_lib.baseboard_fab2(sch_1):page52_i100:DQS4P" )
				( attribute "RELATIVE_PROPAGATION_DELAY_SCOPE" "G"
					( Parent
						( matchGroupRef "@baseboard_fab2_lib.baseboard_fab2(sch_1):\MG_DQ-DQS_NEAR_DIMM_NG_M_E_BYTE4\" )
					)
					( Status sCSetFlattened )
					( Origin gBackEnd )
				)
				( attribute "RELATIVE_PROPAGATION_DELAY" ",5.00 MIL"
					( Parent
						( matchGroupRef "@baseboard_fab2_lib.baseboard_fab2(sch_1):\MG_DQ-DQS_NEAR_DIMM_NG_M_E_BYTE4\" )
					)
					( Units "uMatchProp" "ns" 1.000000)
					( Status sCSetFlattened )
					( Origin gBackEnd )
				)
			)
			( pinPair "@baseboard_fab2_lib.baseboard_fab2(sch_1):\PP1132\"
				( pinRef "@baseboard_fab2_lib.baseboard_fab2(sch_1):page27_i172:DDR4_DQS_DP(5)" )
				( pinRef "@baseboard_fab2_lib.baseboard_fab2(sch_1):page51_i66:DQS5P" )
				( attribute "RELATIVE_PROPAGATION_DELAY_SCOPE" "G"
					( Parent
						( matchGroupRef "@baseboard_fab2_lib.baseboard_fab2(sch_1):\MG_DQ-DQS_FAR_DIMM_NG_M_E_BYTE5\" )
					)
					( Status sCSetFlattened )
					( Origin gBackEnd )
				)
				( attribute "RELATIVE_PROPAGATION_DELAY" ",5.00 MIL"
					( Parent
						( matchGroupRef "@baseboard_fab2_lib.baseboard_fab2(sch_1):\MG_DQ-DQS_FAR_DIMM_NG_M_E_BYTE5\" )
					)
					( Units "uMatchProp" "ns" 1.000000)
					( Status sCSetFlattened )
					( Origin gBackEnd )
				)
			)
			( pinPair "@baseboard_fab2_lib.baseboard_fab2(sch_1):\PP1134\"
				( pinRef "@baseboard_fab2_lib.baseboard_fab2(sch_1):page52_i100:DQS5P" )
				( pinRef "@baseboard_fab2_lib.baseboard_fab2(sch_1):page27_i172:DDR4_DQS_DP(5)" )
				( attribute "RELATIVE_PROPAGATION_DELAY_SCOPE" "G"
					( Parent
						( matchGroupRef "@baseboard_fab2_lib.baseboard_fab2(sch_1):\MG_DQ-DQS_NEAR_DIMM_NG_M_E_BYTE5\" )
					)
					( Status sCSetFlattened )
					( Origin gBackEnd )
				)
				( attribute "RELATIVE_PROPAGATION_DELAY" ",5.00 MIL"
					( Parent
						( matchGroupRef "@baseboard_fab2_lib.baseboard_fab2(sch_1):\MG_DQ-DQS_NEAR_DIMM_NG_M_E_BYTE5\" )
					)
					( Units "uMatchProp" "ns" 1.000000)
					( Status sCSetFlattened )
					( Origin gBackEnd )
				)
			)
			( pinPair "@baseboard_fab2_lib.baseboard_fab2(sch_1):\PP1120\"
				( pinRef "@baseboard_fab2_lib.baseboard_fab2(sch_1):page27_i172:DDR4_DQS_DP(6)" )
				( pinRef "@baseboard_fab2_lib.baseboard_fab2(sch_1):page51_i66:DQS6P" )
				( attribute "RELATIVE_PROPAGATION_DELAY_SCOPE" "G"
					( Parent
						( matchGroupRef "@baseboard_fab2_lib.baseboard_fab2(sch_1):\MG_DQ-DQS_FAR_DIMM_NG_M_E_BYTE6\" )
					)
					( Status sCSetFlattened )
					( Origin gBackEnd )
				)
				( attribute "RELATIVE_PROPAGATION_DELAY" ",5.00 MIL"
					( Parent
						( matchGroupRef "@baseboard_fab2_lib.baseboard_fab2(sch_1):\MG_DQ-DQS_FAR_DIMM_NG_M_E_BYTE6\" )
					)
					( Units "uMatchProp" "ns" 1.000000)
					( Status sCSetFlattened )
					( Origin gBackEnd )
				)
			)
			( pinPair "@baseboard_fab2_lib.baseboard_fab2(sch_1):\PP1122\"
				( pinRef "@baseboard_fab2_lib.baseboard_fab2(sch_1):page27_i172:DDR4_DQS_DP(6)" )
				( pinRef "@baseboard_fab2_lib.baseboard_fab2(sch_1):page52_i100:DQS6P" )
				( attribute "RELATIVE_PROPAGATION_DELAY_SCOPE" "G"
					( Parent
						( matchGroupRef "@baseboard_fab2_lib.baseboard_fab2(sch_1):\MG_DQ-DQS_NEAR_DIMM_NG_M_E_BYTE6\" )
					)
					( Status sCSetFlattened )
					( Origin gBackEnd )
				)
				( attribute "RELATIVE_PROPAGATION_DELAY" ",5.00 MIL"
					( Parent
						( matchGroupRef "@baseboard_fab2_lib.baseboard_fab2(sch_1):\MG_DQ-DQS_NEAR_DIMM_NG_M_E_BYTE6\" )
					)
					( Units "uMatchProp" "ns" 1.000000)
					( Status sCSetFlattened )
					( Origin gBackEnd )
				)
			)
			( pinPair "@baseboard_fab2_lib.baseboard_fab2(sch_1):\PP1108\"
				( pinRef "@baseboard_fab2_lib.baseboard_fab2(sch_1):page27_i172:DDR4_DQS_DP(7)" )
				( pinRef "@baseboard_fab2_lib.baseboard_fab2(sch_1):page51_i66:DQS7P" )
				( attribute "RELATIVE_PROPAGATION_DELAY_SCOPE" "G"
					( Parent
						( matchGroupRef "@baseboard_fab2_lib.baseboard_fab2(sch_1):\MG_DQ-DQS_FAR_DIMM_NG_M_E_BYTE7\" )
					)
					( Status sCSetFlattened )
					( Origin gBackEnd )
				)
				( attribute "RELATIVE_PROPAGATION_DELAY" ",5.00 MIL"
					( Parent
						( matchGroupRef "@baseboard_fab2_lib.baseboard_fab2(sch_1):\MG_DQ-DQS_FAR_DIMM_NG_M_E_BYTE7\" )
					)
					( Units "uMatchProp" "ns" 1.000000)
					( Status sCSetFlattened )
					( Origin gBackEnd )
				)
			)
			( pinPair "@baseboard_fab2_lib.baseboard_fab2(sch_1):\PP1110\"
				( pinRef "@baseboard_fab2_lib.baseboard_fab2(sch_1):page52_i100:DQS7P" )
				( pinRef "@baseboard_fab2_lib.baseboard_fab2(sch_1):page27_i172:DDR4_DQS_DP(7)" )
				( attribute "RELATIVE_PROPAGATION_DELAY_SCOPE" "G"
					( Parent
						( matchGroupRef "@baseboard_fab2_lib.baseboard_fab2(sch_1):\MG_DQ-DQS_NEAR_DIMM_NG_M_E_BYTE7\" )
					)
					( Status sCSetFlattened )
					( Origin gBackEnd )
				)
				( attribute "RELATIVE_PROPAGATION_DELAY" ",5.00 MIL"
					( Parent
						( matchGroupRef "@baseboard_fab2_lib.baseboard_fab2(sch_1):\MG_DQ-DQS_NEAR_DIMM_NG_M_E_BYTE7\" )
					)
					( Units "uMatchProp" "ns" 1.000000)
					( Status sCSetFlattened )
					( Origin gBackEnd )
				)
			)
			( pinPair "@baseboard_fab2_lib.baseboard_fab2(sch_1):\PP1096\"
				( pinRef "@baseboard_fab2_lib.baseboard_fab2(sch_1):page27_i172:DDR4_DQS_DP(8)" )
				( pinRef "@baseboard_fab2_lib.baseboard_fab2(sch_1):page51_i66:DQS8P" )
				( attribute "RELATIVE_PROPAGATION_DELAY_SCOPE" "G"
					( Parent
						( matchGroupRef "@baseboard_fab2_lib.baseboard_fab2(sch_1):\MG_DQ-DQS_FAR_DIMM_NG_M_E_BYTE-ECC\" )
					)
					( Status sCSetFlattened )
					( Origin gBackEnd )
				)
				( attribute "RELATIVE_PROPAGATION_DELAY" ",5.00 MIL"
					( Parent
						( matchGroupRef "@baseboard_fab2_lib.baseboard_fab2(sch_1):\MG_DQ-DQS_FAR_DIMM_NG_M_E_BYTE-ECC\" )
					)
					( Units "uMatchProp" "ns" 1.000000)
					( Status sCSetFlattened )
					( Origin gBackEnd )
				)
			)
			( pinPair "@baseboard_fab2_lib.baseboard_fab2(sch_1):\PP1097\"
				( pinRef "@baseboard_fab2_lib.baseboard_fab2(sch_1):page52_i100:DQS8P" )
				( pinRef "@baseboard_fab2_lib.baseboard_fab2(sch_1):page27_i172:DDR4_DQS_DP(8)" )
				( attribute "RELATIVE_PROPAGATION_DELAY_SCOPE" "G"
					( Parent
						( matchGroupRef "@baseboard_fab2_lib.baseboard_fab2(sch_1):\MG_DQ-DQS_NEAR_DIMM_NG_M_E_BYTE-ECC\" )
					)
					( Status sCSetFlattened )
					( Origin gBackEnd )
				)
				( attribute "RELATIVE_PROPAGATION_DELAY" ",5.00 MIL"
					( Parent
						( matchGroupRef "@baseboard_fab2_lib.baseboard_fab2(sch_1):\MG_DQ-DQS_NEAR_DIMM_NG_M_E_BYTE-ECC\" )
					)
					( Units "uMatchProp" "ns" 1.000000)
					( Status sCSetFlattened )
					( Origin gBackEnd )
				)
			)
			( pinPair "@baseboard_fab2_lib.baseboard_fab2(sch_1):\PP1186\"
				( pinRef "@baseboard_fab2_lib.baseboard_fab2(sch_1):page27_i172:DDR4_DQS_DP(9)" )
				( pinRef "@baseboard_fab2_lib.baseboard_fab2(sch_1):page51_i66:DQS9P" )
				( attribute "RELATIVE_PROPAGATION_DELAY_SCOPE" "G"
					( Parent
						( matchGroupRef "@baseboard_fab2_lib.baseboard_fab2(sch_1):\MG_DQ-DQS_FAR_DIMM_NG_M_E_BYTE0\" )
					)
					( Status sCSetFlattened )
					( Origin gBackEnd )
				)
				( attribute "RELATIVE_PROPAGATION_DELAY" ",5.00 MIL"
					( Parent
						( matchGroupRef "@baseboard_fab2_lib.baseboard_fab2(sch_1):\MG_DQ-DQS_FAR_DIMM_NG_M_E_BYTE0\" )
					)
					( Units "uMatchProp" "ns" 1.000000)
					( Status sCSetFlattened )
					( Origin gBackEnd )
				)
			)
			( pinPair "@baseboard_fab2_lib.baseboard_fab2(sch_1):\PP1187\"
				( pinRef "@baseboard_fab2_lib.baseboard_fab2(sch_1):page27_i172:DDR4_DQS_DP(9)" )
				( pinRef "@baseboard_fab2_lib.baseboard_fab2(sch_1):page52_i100:DQS9P" )
				( attribute "RELATIVE_PROPAGATION_DELAY_SCOPE" "G"
					( Parent
						( matchGroupRef "@baseboard_fab2_lib.baseboard_fab2(sch_1):\MG_DQ-DQS_NEAR_DIMM_NG_M_E_BYTE0\" )
					)
					( Status sCSetFlattened )
					( Origin gBackEnd )
				)
				( attribute "RELATIVE_PROPAGATION_DELAY" ",5.00 MIL"
					( Parent
						( matchGroupRef "@baseboard_fab2_lib.baseboard_fab2(sch_1):\MG_DQ-DQS_NEAR_DIMM_NG_M_E_BYTE0\" )
					)
					( Units "uMatchProp" "ns" 1.000000)
					( Status sCSetFlattened )
					( Origin gBackEnd )
				)
			)
			( pinPair "@baseboard_fab2_lib.baseboard_fab2(sch_1):\PP1174\"
				( pinRef "@baseboard_fab2_lib.baseboard_fab2(sch_1):page27_i172:DDR4_DQS_DP(10)" )
				( pinRef "@baseboard_fab2_lib.baseboard_fab2(sch_1):page51_i66:DQS10P" )
				( attribute "RELATIVE_PROPAGATION_DELAY_SCOPE" "G"
					( Parent
						( matchGroupRef "@baseboard_fab2_lib.baseboard_fab2(sch_1):\MG_DQ-DQS_FAR_DIMM_NG_M_E_BYTE1\" )
					)
					( Status sCSetFlattened )
					( Origin gBackEnd )
				)
				( attribute "RELATIVE_PROPAGATION_DELAY" ",5.00 MIL"
					( Parent
						( matchGroupRef "@baseboard_fab2_lib.baseboard_fab2(sch_1):\MG_DQ-DQS_FAR_DIMM_NG_M_E_BYTE1\" )
					)
					( Units "uMatchProp" "ns" 1.000000)
					( Status sCSetFlattened )
					( Origin gBackEnd )
				)
			)
			( pinPair "@baseboard_fab2_lib.baseboard_fab2(sch_1):\PP1175\"
				( pinRef "@baseboard_fab2_lib.baseboard_fab2(sch_1):page52_i100:DQS10P" )
				( pinRef "@baseboard_fab2_lib.baseboard_fab2(sch_1):page27_i172:DDR4_DQS_DP(10)" )
				( attribute "RELATIVE_PROPAGATION_DELAY_SCOPE" "G"
					( Parent
						( matchGroupRef "@baseboard_fab2_lib.baseboard_fab2(sch_1):\MG_DQ-DQS_NEAR_DIMM_NG_M_E_BYTE1\" )
					)
					( Status sCSetFlattened )
					( Origin gBackEnd )
				)
				( attribute "RELATIVE_PROPAGATION_DELAY" ",5.00 MIL"
					( Parent
						( matchGroupRef "@baseboard_fab2_lib.baseboard_fab2(sch_1):\MG_DQ-DQS_NEAR_DIMM_NG_M_E_BYTE1\" )
					)
					( Units "uMatchProp" "ns" 1.000000)
					( Status sCSetFlattened )
					( Origin gBackEnd )
				)
			)
			( pinPair "@baseboard_fab2_lib.baseboard_fab2(sch_1):\PP1162\"
				( pinRef "@baseboard_fab2_lib.baseboard_fab2(sch_1):page27_i172:DDR4_DQS_DP(11)" )
				( pinRef "@baseboard_fab2_lib.baseboard_fab2(sch_1):page51_i66:DQS11P" )
				( attribute "RELATIVE_PROPAGATION_DELAY_SCOPE" "G"
					( Parent
						( matchGroupRef "@baseboard_fab2_lib.baseboard_fab2(sch_1):\MG_DQ-DQS_FAR_DIMM_NG_M_E_BYTE2\" )
					)
					( Status sCSetFlattened )
					( Origin gBackEnd )
				)
				( attribute "RELATIVE_PROPAGATION_DELAY" ",5.00 MIL"
					( Parent
						( matchGroupRef "@baseboard_fab2_lib.baseboard_fab2(sch_1):\MG_DQ-DQS_FAR_DIMM_NG_M_E_BYTE2\" )
					)
					( Units "uMatchProp" "ns" 1.000000)
					( Status sCSetFlattened )
					( Origin gBackEnd )
				)
			)
			( pinPair "@baseboard_fab2_lib.baseboard_fab2(sch_1):\PP1163\"
				( pinRef "@baseboard_fab2_lib.baseboard_fab2(sch_1):page27_i172:DDR4_DQS_DP(11)" )
				( pinRef "@baseboard_fab2_lib.baseboard_fab2(sch_1):page52_i100:DQS11P" )
				( attribute "RELATIVE_PROPAGATION_DELAY_SCOPE" "G"
					( Parent
						( matchGroupRef "@baseboard_fab2_lib.baseboard_fab2(sch_1):\MG_DQ-DQS_NEAR_DIMM_NG_M_E_BYTE2\" )
					)
					( Status sCSetFlattened )
					( Origin gBackEnd )
				)
				( attribute "RELATIVE_PROPAGATION_DELAY" ",5.00 MIL"
					( Parent
						( matchGroupRef "@baseboard_fab2_lib.baseboard_fab2(sch_1):\MG_DQ-DQS_NEAR_DIMM_NG_M_E_BYTE2\" )
					)
					( Units "uMatchProp" "ns" 1.000000)
					( Status sCSetFlattened )
					( Origin gBackEnd )
				)
			)
			( pinPair "@baseboard_fab2_lib.baseboard_fab2(sch_1):\PP1150\"
				( pinRef "@baseboard_fab2_lib.baseboard_fab2(sch_1):page27_i172:DDR4_DQS_DP(12)" )
				( pinRef "@baseboard_fab2_lib.baseboard_fab2(sch_1):page51_i66:DQS12P" )
				( attribute "RELATIVE_PROPAGATION_DELAY_SCOPE" "G"
					( Parent
						( matchGroupRef "@baseboard_fab2_lib.baseboard_fab2(sch_1):\MG_DQ-DQS_FAR_DIMM_NG_M_E_BYTE3\" )
					)
					( Status sCSetFlattened )
					( Origin gBackEnd )
				)
				( attribute "RELATIVE_PROPAGATION_DELAY" ",5.00 MIL"
					( Parent
						( matchGroupRef "@baseboard_fab2_lib.baseboard_fab2(sch_1):\MG_DQ-DQS_FAR_DIMM_NG_M_E_BYTE3\" )
					)
					( Units "uMatchProp" "ns" 1.000000)
					( Status sCSetFlattened )
					( Origin gBackEnd )
				)
			)
			( pinPair "@baseboard_fab2_lib.baseboard_fab2(sch_1):\PP1151\"
				( pinRef "@baseboard_fab2_lib.baseboard_fab2(sch_1):page27_i172:DDR4_DQS_DP(12)" )
				( pinRef "@baseboard_fab2_lib.baseboard_fab2(sch_1):page52_i100:DQS12P" )
				( attribute "RELATIVE_PROPAGATION_DELAY_SCOPE" "G"
					( Parent
						( matchGroupRef "@baseboard_fab2_lib.baseboard_fab2(sch_1):\MG_DQ-DQS_NEAR_DIMM_NG_M_E_BYTE3\" )
					)
					( Status sCSetFlattened )
					( Origin gBackEnd )
				)
				( attribute "RELATIVE_PROPAGATION_DELAY" ",5.00 MIL"
					( Parent
						( matchGroupRef "@baseboard_fab2_lib.baseboard_fab2(sch_1):\MG_DQ-DQS_NEAR_DIMM_NG_M_E_BYTE3\" )
					)
					( Units "uMatchProp" "ns" 1.000000)
					( Status sCSetFlattened )
					( Origin gBackEnd )
				)
			)
			( pinPair "@baseboard_fab2_lib.baseboard_fab2(sch_1):\PP1138\"
				( pinRef "@baseboard_fab2_lib.baseboard_fab2(sch_1):page27_i172:DDR4_DQS_DP(13)" )
				( pinRef "@baseboard_fab2_lib.baseboard_fab2(sch_1):page51_i66:DQS13P" )
				( attribute "RELATIVE_PROPAGATION_DELAY_SCOPE" "G"
					( Parent
						( matchGroupRef "@baseboard_fab2_lib.baseboard_fab2(sch_1):\MG_DQ-DQS_FAR_DIMM_NG_M_E_BYTE4\" )
					)
					( Status sCSetFlattened )
					( Origin gBackEnd )
				)
				( attribute "RELATIVE_PROPAGATION_DELAY" ",5.00 MIL"
					( Parent
						( matchGroupRef "@baseboard_fab2_lib.baseboard_fab2(sch_1):\MG_DQ-DQS_FAR_DIMM_NG_M_E_BYTE4\" )
					)
					( Units "uMatchProp" "ns" 1.000000)
					( Status sCSetFlattened )
					( Origin gBackEnd )
				)
			)
			( pinPair "@baseboard_fab2_lib.baseboard_fab2(sch_1):\PP1140\"
				( pinRef "@baseboard_fab2_lib.baseboard_fab2(sch_1):page27_i172:DDR4_DQS_DP(13)" )
				( pinRef "@baseboard_fab2_lib.baseboard_fab2(sch_1):page52_i100:DQS13P" )
				( attribute "RELATIVE_PROPAGATION_DELAY_SCOPE" "G"
					( Parent
						( matchGroupRef "@baseboard_fab2_lib.baseboard_fab2(sch_1):\MG_DQ-DQS_NEAR_DIMM_NG_M_E_BYTE4\" )
					)
					( Status sCSetFlattened )
					( Origin gBackEnd )
				)
				( attribute "RELATIVE_PROPAGATION_DELAY" ",5.00 MIL"
					( Parent
						( matchGroupRef "@baseboard_fab2_lib.baseboard_fab2(sch_1):\MG_DQ-DQS_NEAR_DIMM_NG_M_E_BYTE4\" )
					)
					( Units "uMatchProp" "ns" 1.000000)
					( Status sCSetFlattened )
					( Origin gBackEnd )
				)
			)
			( pinPair "@baseboard_fab2_lib.baseboard_fab2(sch_1):\PP1126\"
				( pinRef "@baseboard_fab2_lib.baseboard_fab2(sch_1):page27_i172:DDR4_DQS_DP(14)" )
				( pinRef "@baseboard_fab2_lib.baseboard_fab2(sch_1):page51_i66:DQS14P" )
				( attribute "RELATIVE_PROPAGATION_DELAY_SCOPE" "G"
					( Parent
						( matchGroupRef "@baseboard_fab2_lib.baseboard_fab2(sch_1):\MG_DQ-DQS_FAR_DIMM_NG_M_E_BYTE5\" )
					)
					( Status sCSetFlattened )
					( Origin gBackEnd )
				)
				( attribute "RELATIVE_PROPAGATION_DELAY" ",5.00 MIL"
					( Parent
						( matchGroupRef "@baseboard_fab2_lib.baseboard_fab2(sch_1):\MG_DQ-DQS_FAR_DIMM_NG_M_E_BYTE5\" )
					)
					( Units "uMatchProp" "ns" 1.000000)
					( Status sCSetFlattened )
					( Origin gBackEnd )
				)
			)
			( pinPair "@baseboard_fab2_lib.baseboard_fab2(sch_1):\PP1128\"
				( pinRef "@baseboard_fab2_lib.baseboard_fab2(sch_1):page52_i100:DQS14P" )
				( pinRef "@baseboard_fab2_lib.baseboard_fab2(sch_1):page27_i172:DDR4_DQS_DP(14)" )
				( attribute "RELATIVE_PROPAGATION_DELAY_SCOPE" "G"
					( Parent
						( matchGroupRef "@baseboard_fab2_lib.baseboard_fab2(sch_1):\MG_DQ-DQS_NEAR_DIMM_NG_M_E_BYTE5\" )
					)
					( Status sCSetFlattened )
					( Origin gBackEnd )
				)
				( attribute "RELATIVE_PROPAGATION_DELAY" ",5.00 MIL"
					( Parent
						( matchGroupRef "@baseboard_fab2_lib.baseboard_fab2(sch_1):\MG_DQ-DQS_NEAR_DIMM_NG_M_E_BYTE5\" )
					)
					( Units "uMatchProp" "ns" 1.000000)
					( Status sCSetFlattened )
					( Origin gBackEnd )
				)
			)
			( pinPair "@baseboard_fab2_lib.baseboard_fab2(sch_1):\PP1114\"
				( pinRef "@baseboard_fab2_lib.baseboard_fab2(sch_1):page27_i172:DDR4_DQS_DP(15)" )
				( pinRef "@baseboard_fab2_lib.baseboard_fab2(sch_1):page51_i66:DQS15P" )
				( attribute "RELATIVE_PROPAGATION_DELAY_SCOPE" "G"
					( Parent
						( matchGroupRef "@baseboard_fab2_lib.baseboard_fab2(sch_1):\MG_DQ-DQS_FAR_DIMM_NG_M_E_BYTE6\" )
					)
					( Status sCSetFlattened )
					( Origin gBackEnd )
				)
				( attribute "RELATIVE_PROPAGATION_DELAY" ",5.00 MIL"
					( Parent
						( matchGroupRef "@baseboard_fab2_lib.baseboard_fab2(sch_1):\MG_DQ-DQS_FAR_DIMM_NG_M_E_BYTE6\" )
					)
					( Units "uMatchProp" "ns" 1.000000)
					( Status sCSetFlattened )
					( Origin gBackEnd )
				)
			)
			( pinPair "@baseboard_fab2_lib.baseboard_fab2(sch_1):\PP1116\"
				( pinRef "@baseboard_fab2_lib.baseboard_fab2(sch_1):page27_i172:DDR4_DQS_DP(15)" )
				( pinRef "@baseboard_fab2_lib.baseboard_fab2(sch_1):page52_i100:DQS15P" )
				( attribute "RELATIVE_PROPAGATION_DELAY_SCOPE" "G"
					( Parent
						( matchGroupRef "@baseboard_fab2_lib.baseboard_fab2(sch_1):\MG_DQ-DQS_NEAR_DIMM_NG_M_E_BYTE6\" )
					)
					( Status sCSetFlattened )
					( Origin gBackEnd )
				)
				( attribute "RELATIVE_PROPAGATION_DELAY" ",5.00 MIL"
					( Parent
						( matchGroupRef "@baseboard_fab2_lib.baseboard_fab2(sch_1):\MG_DQ-DQS_NEAR_DIMM_NG_M_E_BYTE6\" )
					)
					( Units "uMatchProp" "ns" 1.000000)
					( Status sCSetFlattened )
					( Origin gBackEnd )
				)
			)
			( pinPair "@baseboard_fab2_lib.baseboard_fab2(sch_1):\PP1102\"
				( pinRef "@baseboard_fab2_lib.baseboard_fab2(sch_1):page27_i172:DDR4_DQS_DP(16)" )
				( pinRef "@baseboard_fab2_lib.baseboard_fab2(sch_1):page51_i66:DQS16P" )
				( attribute "RELATIVE_PROPAGATION_DELAY_SCOPE" "G"
					( Parent
						( matchGroupRef "@baseboard_fab2_lib.baseboard_fab2(sch_1):\MG_DQ-DQS_FAR_DIMM_NG_M_E_BYTE7\" )
					)
					( Status sCSetFlattened )
					( Origin gBackEnd )
				)
				( attribute "RELATIVE_PROPAGATION_DELAY" ",5.00 MIL"
					( Parent
						( matchGroupRef "@baseboard_fab2_lib.baseboard_fab2(sch_1):\MG_DQ-DQS_FAR_DIMM_NG_M_E_BYTE7\" )
					)
					( Units "uMatchProp" "ns" 1.000000)
					( Status sCSetFlattened )
					( Origin gBackEnd )
				)
			)
			( pinPair "@baseboard_fab2_lib.baseboard_fab2(sch_1):\PP1104\"
				( pinRef "@baseboard_fab2_lib.baseboard_fab2(sch_1):page27_i172:DDR4_DQS_DP(16)" )
				( pinRef "@baseboard_fab2_lib.baseboard_fab2(sch_1):page52_i100:DQS16P" )
				( attribute "RELATIVE_PROPAGATION_DELAY_SCOPE" "G"
					( Parent
						( matchGroupRef "@baseboard_fab2_lib.baseboard_fab2(sch_1):\MG_DQ-DQS_NEAR_DIMM_NG_M_E_BYTE7\" )
					)
					( Status sCSetFlattened )
					( Origin gBackEnd )
				)
				( attribute "RELATIVE_PROPAGATION_DELAY" ",5.00 MIL"
					( Parent
						( matchGroupRef "@baseboard_fab2_lib.baseboard_fab2(sch_1):\MG_DQ-DQS_NEAR_DIMM_NG_M_E_BYTE7\" )
					)
					( Units "uMatchProp" "ns" 1.000000)
					( Status sCSetFlattened )
					( Origin gBackEnd )
				)
			)
			( pinPair "@baseboard_fab2_lib.baseboard_fab2(sch_1):\PP1090\"
				( pinRef "@baseboard_fab2_lib.baseboard_fab2(sch_1):page27_i172:DDR4_DQS_DP(17)" )
				( pinRef "@baseboard_fab2_lib.baseboard_fab2(sch_1):page51_i66:DQS17P" )
				( attribute "RELATIVE_PROPAGATION_DELAY_SCOPE" "G"
					( Parent
						( matchGroupRef "@baseboard_fab2_lib.baseboard_fab2(sch_1):\MG_DQ-DQS_FAR_DIMM_NG_M_E_BYTE-ECC\" )
					)
					( Status sCSetFlattened )
					( Origin gBackEnd )
				)
				( attribute "RELATIVE_PROPAGATION_DELAY" ",5.00 MIL"
					( Parent
						( matchGroupRef "@baseboard_fab2_lib.baseboard_fab2(sch_1):\MG_DQ-DQS_FAR_DIMM_NG_M_E_BYTE-ECC\" )
					)
					( Units "uMatchProp" "ns" 1.000000)
					( Status sCSetFlattened )
					( Origin gBackEnd )
				)
			)
			( pinPair "@baseboard_fab2_lib.baseboard_fab2(sch_1):\PP1091\"
				( pinRef "@baseboard_fab2_lib.baseboard_fab2(sch_1):page27_i172:DDR4_DQS_DP(17)" )
				( pinRef "@baseboard_fab2_lib.baseboard_fab2(sch_1):page52_i100:DQS17P" )
				( attribute "RELATIVE_PROPAGATION_DELAY_SCOPE" "G"
					( Parent
						( matchGroupRef "@baseboard_fab2_lib.baseboard_fab2(sch_1):\MG_DQ-DQS_NEAR_DIMM_NG_M_E_BYTE-ECC\" )
					)
					( Status sCSetFlattened )
					( Origin gBackEnd )
				)
				( attribute "RELATIVE_PROPAGATION_DELAY" ",5.00 MIL"
					( Parent
						( matchGroupRef "@baseboard_fab2_lib.baseboard_fab2(sch_1):\MG_DQ-DQS_NEAR_DIMM_NG_M_E_BYTE-ECC\" )
					)
					( Units "uMatchProp" "ns" 1.000000)
					( Status sCSetFlattened )
					( Origin gBackEnd )
				)
			)
			( pinPair "@baseboard_fab2_lib.baseboard_fab2(sch_1):\PP1081\"
				( pinRef "@baseboard_fab2_lib.baseboard_fab2(sch_1):page28_i172:DDR5_DQS_DN(0)" )
				( pinRef "@baseboard_fab2_lib.baseboard_fab2(sch_1):page53_i66:DQS0N" )
				( attribute "RELATIVE_PROPAGATION_DELAY_SCOPE" "G"
					( Parent
						( matchGroupRef "@baseboard_fab2_lib.baseboard_fab2(sch_1):\MG_DQ-DQS_FAR_DIMM_NG_M_F_BYTE0\" )
					)
					( Status sCSetFlattened )
					( Origin gBackEnd )
				)
				( attribute "RELATIVE_PROPAGATION_DELAY" ",5.00 MIL"
					( Parent
						( matchGroupRef "@baseboard_fab2_lib.baseboard_fab2(sch_1):\MG_DQ-DQS_FAR_DIMM_NG_M_F_BYTE0\" )
					)
					( Units "uMatchProp" "ns" 1.000000)
					( Status sCSetFlattened )
					( Origin gBackEnd )
				)
			)
			( pinPair "@baseboard_fab2_lib.baseboard_fab2(sch_1):\PP1082\"
				( pinRef "@baseboard_fab2_lib.baseboard_fab2(sch_1):page54_i66:DQS0N" )
				( pinRef "@baseboard_fab2_lib.baseboard_fab2(sch_1):page28_i172:DDR5_DQS_DN(0)" )
				( attribute "RELATIVE_PROPAGATION_DELAY_SCOPE" "G"
					( Parent
						( matchGroupRef "@baseboard_fab2_lib.baseboard_fab2(sch_1):\MG_DQ-DQS_NEAR_DIMM_NG_M_F_BYTE0\" )
					)
					( Status sCSetFlattened )
					( Origin gBackEnd )
				)
				( attribute "RELATIVE_PROPAGATION_DELAY" ",5.00 MIL"
					( Parent
						( matchGroupRef "@baseboard_fab2_lib.baseboard_fab2(sch_1):\MG_DQ-DQS_NEAR_DIMM_NG_M_F_BYTE0\" )
					)
					( Units "uMatchProp" "ns" 1.000000)
					( Status sCSetFlattened )
					( Origin gBackEnd )
				)
			)
			( pinPair "@baseboard_fab2_lib.baseboard_fab2(sch_1):\PP1069\"
				( pinRef "@baseboard_fab2_lib.baseboard_fab2(sch_1):page28_i172:DDR5_DQS_DN(1)" )
				( pinRef "@baseboard_fab2_lib.baseboard_fab2(sch_1):page53_i66:DQS1N" )
				( attribute "RELATIVE_PROPAGATION_DELAY_SCOPE" "G"
					( Parent
						( matchGroupRef "@baseboard_fab2_lib.baseboard_fab2(sch_1):\MG_DQ-DQS_FAR_DIMM_NG_M_F_BYTE1\" )
					)
					( Status sCSetFlattened )
					( Origin gBackEnd )
				)
				( attribute "RELATIVE_PROPAGATION_DELAY" ",5.00 MIL"
					( Parent
						( matchGroupRef "@baseboard_fab2_lib.baseboard_fab2(sch_1):\MG_DQ-DQS_FAR_DIMM_NG_M_F_BYTE1\" )
					)
					( Units "uMatchProp" "ns" 1.000000)
					( Status sCSetFlattened )
					( Origin gBackEnd )
				)
			)
			( pinPair "@baseboard_fab2_lib.baseboard_fab2(sch_1):\PP1070\"
				( pinRef "@baseboard_fab2_lib.baseboard_fab2(sch_1):page54_i66:DQS1N" )
				( pinRef "@baseboard_fab2_lib.baseboard_fab2(sch_1):page28_i172:DDR5_DQS_DN(1)" )
				( attribute "RELATIVE_PROPAGATION_DELAY_SCOPE" "G"
					( Parent
						( matchGroupRef "@baseboard_fab2_lib.baseboard_fab2(sch_1):\MG_DQ-DQS_NEAR_DIMM_NG_M_F_BYTE1\" )
					)
					( Status sCSetFlattened )
					( Origin gBackEnd )
				)
				( attribute "RELATIVE_PROPAGATION_DELAY" ",5.00 MIL"
					( Parent
						( matchGroupRef "@baseboard_fab2_lib.baseboard_fab2(sch_1):\MG_DQ-DQS_NEAR_DIMM_NG_M_F_BYTE1\" )
					)
					( Units "uMatchProp" "ns" 1.000000)
					( Status sCSetFlattened )
					( Origin gBackEnd )
				)
			)
			( pinPair "@baseboard_fab2_lib.baseboard_fab2(sch_1):\PP1057\"
				( pinRef "@baseboard_fab2_lib.baseboard_fab2(sch_1):page28_i172:DDR5_DQS_DN(2)" )
				( pinRef "@baseboard_fab2_lib.baseboard_fab2(sch_1):page53_i66:DQS2N" )
				( attribute "RELATIVE_PROPAGATION_DELAY_SCOPE" "G"
					( Parent
						( matchGroupRef "@baseboard_fab2_lib.baseboard_fab2(sch_1):\MG_DQ-DQS_FAR_DIMM_NG_M_F_BYTE2\" )
					)
					( Status sCSetFlattened )
					( Origin gBackEnd )
				)
				( attribute "RELATIVE_PROPAGATION_DELAY" ",5.00 MIL"
					( Parent
						( matchGroupRef "@baseboard_fab2_lib.baseboard_fab2(sch_1):\MG_DQ-DQS_FAR_DIMM_NG_M_F_BYTE2\" )
					)
					( Units "uMatchProp" "ns" 1.000000)
					( Status sCSetFlattened )
					( Origin gBackEnd )
				)
			)
			( pinPair "@baseboard_fab2_lib.baseboard_fab2(sch_1):\PP1058\"
				( pinRef "@baseboard_fab2_lib.baseboard_fab2(sch_1):page54_i66:DQS2N" )
				( pinRef "@baseboard_fab2_lib.baseboard_fab2(sch_1):page28_i172:DDR5_DQS_DN(2)" )
				( attribute "RELATIVE_PROPAGATION_DELAY_SCOPE" "G"
					( Parent
						( matchGroupRef "@baseboard_fab2_lib.baseboard_fab2(sch_1):\MG_DQ-DQS_NEAR_DIMM_NG_M_F_BYTE2\" )
					)
					( Status sCSetFlattened )
					( Origin gBackEnd )
				)
				( attribute "RELATIVE_PROPAGATION_DELAY" ",5.00 MIL"
					( Parent
						( matchGroupRef "@baseboard_fab2_lib.baseboard_fab2(sch_1):\MG_DQ-DQS_NEAR_DIMM_NG_M_F_BYTE2\" )
					)
					( Units "uMatchProp" "ns" 1.000000)
					( Status sCSetFlattened )
					( Origin gBackEnd )
				)
			)
			( pinPair "@baseboard_fab2_lib.baseboard_fab2(sch_1):\PP1045\"
				( pinRef "@baseboard_fab2_lib.baseboard_fab2(sch_1):page28_i172:DDR5_DQS_DN(3)" )
				( pinRef "@baseboard_fab2_lib.baseboard_fab2(sch_1):page53_i66:DQS3N" )
				( attribute "RELATIVE_PROPAGATION_DELAY_SCOPE" "G"
					( Parent
						( matchGroupRef "@baseboard_fab2_lib.baseboard_fab2(sch_1):\MG_DQ-DQS_FAR_DIMM_NG_M_F_BYTE3\" )
					)
					( Status sCSetFlattened )
					( Origin gBackEnd )
				)
				( attribute "RELATIVE_PROPAGATION_DELAY" ",5.00 MIL"
					( Parent
						( matchGroupRef "@baseboard_fab2_lib.baseboard_fab2(sch_1):\MG_DQ-DQS_FAR_DIMM_NG_M_F_BYTE3\" )
					)
					( Units "uMatchProp" "ns" 1.000000)
					( Status sCSetFlattened )
					( Origin gBackEnd )
				)
			)
			( pinPair "@baseboard_fab2_lib.baseboard_fab2(sch_1):\PP1046\"
				( pinRef "@baseboard_fab2_lib.baseboard_fab2(sch_1):page54_i66:DQS3N" )
				( pinRef "@baseboard_fab2_lib.baseboard_fab2(sch_1):page28_i172:DDR5_DQS_DN(3)" )
				( attribute "RELATIVE_PROPAGATION_DELAY_SCOPE" "G"
					( Parent
						( matchGroupRef "@baseboard_fab2_lib.baseboard_fab2(sch_1):\MG_DQ-DQS_NEAR_DIMM_NG_M_F_BYTE3\" )
					)
					( Status sCSetFlattened )
					( Origin gBackEnd )
				)
				( attribute "RELATIVE_PROPAGATION_DELAY" ",5.00 MIL"
					( Parent
						( matchGroupRef "@baseboard_fab2_lib.baseboard_fab2(sch_1):\MG_DQ-DQS_NEAR_DIMM_NG_M_F_BYTE3\" )
					)
					( Units "uMatchProp" "ns" 1.000000)
					( Status sCSetFlattened )
					( Origin gBackEnd )
				)
			)
			( pinPair "@baseboard_fab2_lib.baseboard_fab2(sch_1):\PP1033\"
				( pinRef "@baseboard_fab2_lib.baseboard_fab2(sch_1):page28_i172:DDR5_DQS_DN(4)" )
				( pinRef "@baseboard_fab2_lib.baseboard_fab2(sch_1):page53_i66:DQS4N" )
				( attribute "RELATIVE_PROPAGATION_DELAY_SCOPE" "G"
					( Parent
						( matchGroupRef "@baseboard_fab2_lib.baseboard_fab2(sch_1):\MG_DQ-DQS_FAR_DIMM_NG_M_F_BYTE4\" )
					)
					( Status sCSetFlattened )
					( Origin gBackEnd )
				)
				( attribute "RELATIVE_PROPAGATION_DELAY" ",5.00 MIL"
					( Parent
						( matchGroupRef "@baseboard_fab2_lib.baseboard_fab2(sch_1):\MG_DQ-DQS_FAR_DIMM_NG_M_F_BYTE4\" )
					)
					( Units "uMatchProp" "ns" 1.000000)
					( Status sCSetFlattened )
					( Origin gBackEnd )
				)
			)
			( pinPair "@baseboard_fab2_lib.baseboard_fab2(sch_1):\PP1035\"
				( pinRef "@baseboard_fab2_lib.baseboard_fab2(sch_1):page28_i172:DDR5_DQS_DN(4)" )
				( pinRef "@baseboard_fab2_lib.baseboard_fab2(sch_1):page54_i66:DQS4N" )
				( attribute "RELATIVE_PROPAGATION_DELAY_SCOPE" "G"
					( Parent
						( matchGroupRef "@baseboard_fab2_lib.baseboard_fab2(sch_1):\MG_DQ-DQS_NEAR_DIMM_NG_M_F_BYTE4\" )
					)
					( Status sCSetFlattened )
					( Origin gBackEnd )
				)
				( attribute "RELATIVE_PROPAGATION_DELAY" ",5.00 MIL"
					( Parent
						( matchGroupRef "@baseboard_fab2_lib.baseboard_fab2(sch_1):\MG_DQ-DQS_NEAR_DIMM_NG_M_F_BYTE4\" )
					)
					( Units "uMatchProp" "ns" 1.000000)
					( Status sCSetFlattened )
					( Origin gBackEnd )
				)
			)
			( pinPair "@baseboard_fab2_lib.baseboard_fab2(sch_1):\PP1021\"
				( pinRef "@baseboard_fab2_lib.baseboard_fab2(sch_1):page28_i172:DDR5_DQS_DN(5)" )
				( pinRef "@baseboard_fab2_lib.baseboard_fab2(sch_1):page53_i66:DQS5N" )
				( attribute "RELATIVE_PROPAGATION_DELAY_SCOPE" "G"
					( Parent
						( matchGroupRef "@baseboard_fab2_lib.baseboard_fab2(sch_1):\MG_DQ-DQS_FAR_DIMM_NG_M_F_BYTE5\" )
					)
					( Status sCSetFlattened )
					( Origin gBackEnd )
				)
				( attribute "RELATIVE_PROPAGATION_DELAY" ",5.00 MIL"
					( Parent
						( matchGroupRef "@baseboard_fab2_lib.baseboard_fab2(sch_1):\MG_DQ-DQS_FAR_DIMM_NG_M_F_BYTE5\" )
					)
					( Units "uMatchProp" "ns" 1.000000)
					( Status sCSetFlattened )
					( Origin gBackEnd )
				)
			)
			( pinPair "@baseboard_fab2_lib.baseboard_fab2(sch_1):\PP1023\"
				( pinRef "@baseboard_fab2_lib.baseboard_fab2(sch_1):page28_i172:DDR5_DQS_DN(5)" )
				( pinRef "@baseboard_fab2_lib.baseboard_fab2(sch_1):page54_i66:DQS5N" )
				( attribute "RELATIVE_PROPAGATION_DELAY_SCOPE" "G"
					( Parent
						( matchGroupRef "@baseboard_fab2_lib.baseboard_fab2(sch_1):\MG_DQ-DQS_NEAR_DIMM_NG_M_F_BYTE5\" )
					)
					( Status sCSetFlattened )
					( Origin gBackEnd )
				)
				( attribute "RELATIVE_PROPAGATION_DELAY" ",5.00 MIL"
					( Parent
						( matchGroupRef "@baseboard_fab2_lib.baseboard_fab2(sch_1):\MG_DQ-DQS_NEAR_DIMM_NG_M_F_BYTE5\" )
					)
					( Units "uMatchProp" "ns" 1.000000)
					( Status sCSetFlattened )
					( Origin gBackEnd )
				)
			)
			( pinPair "@baseboard_fab2_lib.baseboard_fab2(sch_1):\PP1009\"
				( pinRef "@baseboard_fab2_lib.baseboard_fab2(sch_1):page28_i172:DDR5_DQS_DN(6)" )
				( pinRef "@baseboard_fab2_lib.baseboard_fab2(sch_1):page53_i66:DQS6N" )
				( attribute "RELATIVE_PROPAGATION_DELAY_SCOPE" "G"
					( Parent
						( matchGroupRef "@baseboard_fab2_lib.baseboard_fab2(sch_1):\MG_DQ-DQS_FAR_DIMM_NG_M_F_BYTE6\" )
					)
					( Status sCSetFlattened )
					( Origin gBackEnd )
				)
				( attribute "RELATIVE_PROPAGATION_DELAY" ",5.00 MIL"
					( Parent
						( matchGroupRef "@baseboard_fab2_lib.baseboard_fab2(sch_1):\MG_DQ-DQS_FAR_DIMM_NG_M_F_BYTE6\" )
					)
					( Units "uMatchProp" "ns" 1.000000)
					( Status sCSetFlattened )
					( Origin gBackEnd )
				)
			)
			( pinPair "@baseboard_fab2_lib.baseboard_fab2(sch_1):\PP1011\"
				( pinRef "@baseboard_fab2_lib.baseboard_fab2(sch_1):page28_i172:DDR5_DQS_DN(6)" )
				( pinRef "@baseboard_fab2_lib.baseboard_fab2(sch_1):page54_i66:DQS6N" )
				( attribute "RELATIVE_PROPAGATION_DELAY_SCOPE" "G"
					( Parent
						( matchGroupRef "@baseboard_fab2_lib.baseboard_fab2(sch_1):\MG_DQ-DQS_NEAR_DIMM_NG_M_F_BYTE6\" )
					)
					( Status sCSetFlattened )
					( Origin gBackEnd )
				)
				( attribute "RELATIVE_PROPAGATION_DELAY" ",5.00 MIL"
					( Parent
						( matchGroupRef "@baseboard_fab2_lib.baseboard_fab2(sch_1):\MG_DQ-DQS_NEAR_DIMM_NG_M_F_BYTE6\" )
					)
					( Units "uMatchProp" "ns" 1.000000)
					( Status sCSetFlattened )
					( Origin gBackEnd )
				)
			)
			( pinPair "@baseboard_fab2_lib.baseboard_fab2(sch_1):\PP997\"
				( pinRef "@baseboard_fab2_lib.baseboard_fab2(sch_1):page28_i172:DDR5_DQS_DN(7)" )
				( pinRef "@baseboard_fab2_lib.baseboard_fab2(sch_1):page53_i66:DQS7N" )
				( attribute "RELATIVE_PROPAGATION_DELAY_SCOPE" "G"
					( Parent
						( matchGroupRef "@baseboard_fab2_lib.baseboard_fab2(sch_1):\MG_DQ-DQS_FAR_DIMM_NG_M_F_BYTE7\" )
					)
					( Status sCSetFlattened )
					( Origin gBackEnd )
				)
				( attribute "RELATIVE_PROPAGATION_DELAY" ",5.00 MIL"
					( Parent
						( matchGroupRef "@baseboard_fab2_lib.baseboard_fab2(sch_1):\MG_DQ-DQS_FAR_DIMM_NG_M_F_BYTE7\" )
					)
					( Units "uMatchProp" "ns" 1.000000)
					( Status sCSetFlattened )
					( Origin gBackEnd )
				)
			)
			( pinPair "@baseboard_fab2_lib.baseboard_fab2(sch_1):\PP999\"
				( pinRef "@baseboard_fab2_lib.baseboard_fab2(sch_1):page28_i172:DDR5_DQS_DN(7)" )
				( pinRef "@baseboard_fab2_lib.baseboard_fab2(sch_1):page54_i66:DQS7N" )
				( attribute "RELATIVE_PROPAGATION_DELAY_SCOPE" "G"
					( Parent
						( matchGroupRef "@baseboard_fab2_lib.baseboard_fab2(sch_1):\MG_DQ-DQS_NEAR_DIMM_NG_M_F_BYTE7\" )
					)
					( Status sCSetFlattened )
					( Origin gBackEnd )
				)
				( attribute "RELATIVE_PROPAGATION_DELAY" ",5.00 MIL"
					( Parent
						( matchGroupRef "@baseboard_fab2_lib.baseboard_fab2(sch_1):\MG_DQ-DQS_NEAR_DIMM_NG_M_F_BYTE7\" )
					)
					( Units "uMatchProp" "ns" 1.000000)
					( Status sCSetFlattened )
					( Origin gBackEnd )
				)
			)
			( pinPair "@baseboard_fab2_lib.baseboard_fab2(sch_1):\PP985\"
				( pinRef "@baseboard_fab2_lib.baseboard_fab2(sch_1):page28_i172:DDR5_DQS_DN(8)" )
				( pinRef "@baseboard_fab2_lib.baseboard_fab2(sch_1):page53_i66:DQS8N" )
				( attribute "RELATIVE_PROPAGATION_DELAY_SCOPE" "G"
					( Parent
						( matchGroupRef "@baseboard_fab2_lib.baseboard_fab2(sch_1):\MG_DQ-DQS_FAR_DIMM_NG_M_F_BYTE-ECC\" )
					)
					( Status sCSetFlattened )
					( Origin gBackEnd )
				)
				( attribute "RELATIVE_PROPAGATION_DELAY" ",5.00 MIL"
					( Parent
						( matchGroupRef "@baseboard_fab2_lib.baseboard_fab2(sch_1):\MG_DQ-DQS_FAR_DIMM_NG_M_F_BYTE-ECC\" )
					)
					( Units "uMatchProp" "ns" 1.000000)
					( Status sCSetFlattened )
					( Origin gBackEnd )
				)
			)
			( pinPair "@baseboard_fab2_lib.baseboard_fab2(sch_1):\PP986\"
				( pinRef "@baseboard_fab2_lib.baseboard_fab2(sch_1):page54_i66:DQS8N" )
				( pinRef "@baseboard_fab2_lib.baseboard_fab2(sch_1):page28_i172:DDR5_DQS_DN(8)" )
				( attribute "RELATIVE_PROPAGATION_DELAY_SCOPE" "G"
					( Parent
						( matchGroupRef "@baseboard_fab2_lib.baseboard_fab2(sch_1):\MG_DQ-DQS_NEAR_DIMM_NG_M_F_BYTE-ECC\" )
					)
					( Status sCSetFlattened )
					( Origin gBackEnd )
				)
				( attribute "RELATIVE_PROPAGATION_DELAY" ",5.00 MIL"
					( Parent
						( matchGroupRef "@baseboard_fab2_lib.baseboard_fab2(sch_1):\MG_DQ-DQS_NEAR_DIMM_NG_M_F_BYTE-ECC\" )
					)
					( Units "uMatchProp" "ns" 1.000000)
					( Status sCSetFlattened )
					( Origin gBackEnd )
				)
			)
			( pinPair "@baseboard_fab2_lib.baseboard_fab2(sch_1):\PP1075\"
				( pinRef "@baseboard_fab2_lib.baseboard_fab2(sch_1):page28_i172:DDR5_DQS_DN(9)" )
				( pinRef "@baseboard_fab2_lib.baseboard_fab2(sch_1):page53_i66:DQS9N" )
				( attribute "RELATIVE_PROPAGATION_DELAY_SCOPE" "G"
					( Parent
						( matchGroupRef "@baseboard_fab2_lib.baseboard_fab2(sch_1):\MG_DQ-DQS_FAR_DIMM_NG_M_F_BYTE0\" )
					)
					( Status sCSetFlattened )
					( Origin gBackEnd )
				)
				( attribute "RELATIVE_PROPAGATION_DELAY" ",5.00 MIL"
					( Parent
						( matchGroupRef "@baseboard_fab2_lib.baseboard_fab2(sch_1):\MG_DQ-DQS_FAR_DIMM_NG_M_F_BYTE0\" )
					)
					( Units "uMatchProp" "ns" 1.000000)
					( Status sCSetFlattened )
					( Origin gBackEnd )
				)
			)
			( pinPair "@baseboard_fab2_lib.baseboard_fab2(sch_1):\PP1076\"
				( pinRef "@baseboard_fab2_lib.baseboard_fab2(sch_1):page54_i66:DQS9N" )
				( pinRef "@baseboard_fab2_lib.baseboard_fab2(sch_1):page28_i172:DDR5_DQS_DN(9)" )
				( attribute "RELATIVE_PROPAGATION_DELAY_SCOPE" "G"
					( Parent
						( matchGroupRef "@baseboard_fab2_lib.baseboard_fab2(sch_1):\MG_DQ-DQS_NEAR_DIMM_NG_M_F_BYTE0\" )
					)
					( Status sCSetFlattened )
					( Origin gBackEnd )
				)
				( attribute "RELATIVE_PROPAGATION_DELAY" ",5.00 MIL"
					( Parent
						( matchGroupRef "@baseboard_fab2_lib.baseboard_fab2(sch_1):\MG_DQ-DQS_NEAR_DIMM_NG_M_F_BYTE0\" )
					)
					( Units "uMatchProp" "ns" 1.000000)
					( Status sCSetFlattened )
					( Origin gBackEnd )
				)
			)
			( pinPair "@baseboard_fab2_lib.baseboard_fab2(sch_1):\PP1063\"
				( pinRef "@baseboard_fab2_lib.baseboard_fab2(sch_1):page28_i172:DDR5_DQS_DN(10)" )
				( pinRef "@baseboard_fab2_lib.baseboard_fab2(sch_1):page53_i66:DQS10N" )
				( attribute "RELATIVE_PROPAGATION_DELAY_SCOPE" "G"
					( Parent
						( matchGroupRef "@baseboard_fab2_lib.baseboard_fab2(sch_1):\MG_DQ-DQS_FAR_DIMM_NG_M_F_BYTE1\" )
					)
					( Status sCSetFlattened )
					( Origin gBackEnd )
				)
				( attribute "RELATIVE_PROPAGATION_DELAY" ",5.00 MIL"
					( Parent
						( matchGroupRef "@baseboard_fab2_lib.baseboard_fab2(sch_1):\MG_DQ-DQS_FAR_DIMM_NG_M_F_BYTE1\" )
					)
					( Units "uMatchProp" "ns" 1.000000)
					( Status sCSetFlattened )
					( Origin gBackEnd )
				)
			)
			( pinPair "@baseboard_fab2_lib.baseboard_fab2(sch_1):\PP1064\"
				( pinRef "@baseboard_fab2_lib.baseboard_fab2(sch_1):page54_i66:DQS10N" )
				( pinRef "@baseboard_fab2_lib.baseboard_fab2(sch_1):page28_i172:DDR5_DQS_DN(10)" )
				( attribute "RELATIVE_PROPAGATION_DELAY_SCOPE" "G"
					( Parent
						( matchGroupRef "@baseboard_fab2_lib.baseboard_fab2(sch_1):\MG_DQ-DQS_NEAR_DIMM_NG_M_F_BYTE1\" )
					)
					( Status sCSetFlattened )
					( Origin gBackEnd )
				)
				( attribute "RELATIVE_PROPAGATION_DELAY" ",5.00 MIL"
					( Parent
						( matchGroupRef "@baseboard_fab2_lib.baseboard_fab2(sch_1):\MG_DQ-DQS_NEAR_DIMM_NG_M_F_BYTE1\" )
					)
					( Units "uMatchProp" "ns" 1.000000)
					( Status sCSetFlattened )
					( Origin gBackEnd )
				)
			)
			( pinPair "@baseboard_fab2_lib.baseboard_fab2(sch_1):\PP1051\"
				( pinRef "@baseboard_fab2_lib.baseboard_fab2(sch_1):page28_i172:DDR5_DQS_DN(11)" )
				( pinRef "@baseboard_fab2_lib.baseboard_fab2(sch_1):page53_i66:DQS11N" )
				( attribute "RELATIVE_PROPAGATION_DELAY_SCOPE" "G"
					( Parent
						( matchGroupRef "@baseboard_fab2_lib.baseboard_fab2(sch_1):\MG_DQ-DQS_FAR_DIMM_NG_M_F_BYTE2\" )
					)
					( Status sCSetFlattened )
					( Origin gBackEnd )
				)
				( attribute "RELATIVE_PROPAGATION_DELAY" ",5.00 MIL"
					( Parent
						( matchGroupRef "@baseboard_fab2_lib.baseboard_fab2(sch_1):\MG_DQ-DQS_FAR_DIMM_NG_M_F_BYTE2\" )
					)
					( Units "uMatchProp" "ns" 1.000000)
					( Status sCSetFlattened )
					( Origin gBackEnd )
				)
			)
			( pinPair "@baseboard_fab2_lib.baseboard_fab2(sch_1):\PP1052\"
				( pinRef "@baseboard_fab2_lib.baseboard_fab2(sch_1):page54_i66:DQS11N" )
				( pinRef "@baseboard_fab2_lib.baseboard_fab2(sch_1):page28_i172:DDR5_DQS_DN(11)" )
				( attribute "RELATIVE_PROPAGATION_DELAY_SCOPE" "G"
					( Parent
						( matchGroupRef "@baseboard_fab2_lib.baseboard_fab2(sch_1):\MG_DQ-DQS_NEAR_DIMM_NG_M_F_BYTE2\" )
					)
					( Status sCSetFlattened )
					( Origin gBackEnd )
				)
				( attribute "RELATIVE_PROPAGATION_DELAY" ",5.00 MIL"
					( Parent
						( matchGroupRef "@baseboard_fab2_lib.baseboard_fab2(sch_1):\MG_DQ-DQS_NEAR_DIMM_NG_M_F_BYTE2\" )
					)
					( Units "uMatchProp" "ns" 1.000000)
					( Status sCSetFlattened )
					( Origin gBackEnd )
				)
			)
			( pinPair "@baseboard_fab2_lib.baseboard_fab2(sch_1):\PP1039\"
				( pinRef "@baseboard_fab2_lib.baseboard_fab2(sch_1):page28_i172:DDR5_DQS_DN(12)" )
				( pinRef "@baseboard_fab2_lib.baseboard_fab2(sch_1):page53_i66:DQS12N" )
				( attribute "RELATIVE_PROPAGATION_DELAY_SCOPE" "G"
					( Parent
						( matchGroupRef "@baseboard_fab2_lib.baseboard_fab2(sch_1):\MG_DQ-DQS_FAR_DIMM_NG_M_F_BYTE3\" )
					)
					( Status sCSetFlattened )
					( Origin gBackEnd )
				)
				( attribute "RELATIVE_PROPAGATION_DELAY" ",5.00 MIL"
					( Parent
						( matchGroupRef "@baseboard_fab2_lib.baseboard_fab2(sch_1):\MG_DQ-DQS_FAR_DIMM_NG_M_F_BYTE3\" )
					)
					( Units "uMatchProp" "ns" 1.000000)
					( Status sCSetFlattened )
					( Origin gBackEnd )
				)
			)
			( pinPair "@baseboard_fab2_lib.baseboard_fab2(sch_1):\PP1040\"
				( pinRef "@baseboard_fab2_lib.baseboard_fab2(sch_1):page28_i172:DDR5_DQS_DN(12)" )
				( pinRef "@baseboard_fab2_lib.baseboard_fab2(sch_1):page54_i66:DQS12N" )
				( attribute "RELATIVE_PROPAGATION_DELAY_SCOPE" "G"
					( Parent
						( matchGroupRef "@baseboard_fab2_lib.baseboard_fab2(sch_1):\MG_DQ-DQS_NEAR_DIMM_NG_M_F_BYTE3\" )
					)
					( Status sCSetFlattened )
					( Origin gBackEnd )
				)
				( attribute "RELATIVE_PROPAGATION_DELAY" ",5.00 MIL"
					( Parent
						( matchGroupRef "@baseboard_fab2_lib.baseboard_fab2(sch_1):\MG_DQ-DQS_NEAR_DIMM_NG_M_F_BYTE3\" )
					)
					( Units "uMatchProp" "ns" 1.000000)
					( Status sCSetFlattened )
					( Origin gBackEnd )
				)
			)
			( pinPair "@baseboard_fab2_lib.baseboard_fab2(sch_1):\PP1027\"
				( pinRef "@baseboard_fab2_lib.baseboard_fab2(sch_1):page28_i172:DDR5_DQS_DN(13)" )
				( pinRef "@baseboard_fab2_lib.baseboard_fab2(sch_1):page53_i66:DQS13N" )
				( attribute "RELATIVE_PROPAGATION_DELAY_SCOPE" "G"
					( Parent
						( matchGroupRef "@baseboard_fab2_lib.baseboard_fab2(sch_1):\MG_DQ-DQS_FAR_DIMM_NG_M_F_BYTE4\" )
					)
					( Status sCSetFlattened )
					( Origin gBackEnd )
				)
				( attribute "RELATIVE_PROPAGATION_DELAY" ",5.00 MIL"
					( Parent
						( matchGroupRef "@baseboard_fab2_lib.baseboard_fab2(sch_1):\MG_DQ-DQS_FAR_DIMM_NG_M_F_BYTE4\" )
					)
					( Units "uMatchProp" "ns" 1.000000)
					( Status sCSetFlattened )
					( Origin gBackEnd )
				)
			)
			( pinPair "@baseboard_fab2_lib.baseboard_fab2(sch_1):\PP1029\"
				( pinRef "@baseboard_fab2_lib.baseboard_fab2(sch_1):page28_i172:DDR5_DQS_DN(13)" )
				( pinRef "@baseboard_fab2_lib.baseboard_fab2(sch_1):page54_i66:DQS13N" )
				( attribute "RELATIVE_PROPAGATION_DELAY_SCOPE" "G"
					( Parent
						( matchGroupRef "@baseboard_fab2_lib.baseboard_fab2(sch_1):\MG_DQ-DQS_NEAR_DIMM_NG_M_F_BYTE4\" )
					)
					( Status sCSetFlattened )
					( Origin gBackEnd )
				)
				( attribute "RELATIVE_PROPAGATION_DELAY" ",5.00 MIL"
					( Parent
						( matchGroupRef "@baseboard_fab2_lib.baseboard_fab2(sch_1):\MG_DQ-DQS_NEAR_DIMM_NG_M_F_BYTE4\" )
					)
					( Units "uMatchProp" "ns" 1.000000)
					( Status sCSetFlattened )
					( Origin gBackEnd )
				)
			)
			( pinPair "@baseboard_fab2_lib.baseboard_fab2(sch_1):\PP1015\"
				( pinRef "@baseboard_fab2_lib.baseboard_fab2(sch_1):page28_i172:DDR5_DQS_DN(14)" )
				( pinRef "@baseboard_fab2_lib.baseboard_fab2(sch_1):page53_i66:DQS14N" )
				( attribute "RELATIVE_PROPAGATION_DELAY_SCOPE" "G"
					( Parent
						( matchGroupRef "@baseboard_fab2_lib.baseboard_fab2(sch_1):\MG_DQ-DQS_FAR_DIMM_NG_M_F_BYTE5\" )
					)
					( Status sCSetFlattened )
					( Origin gBackEnd )
				)
				( attribute "RELATIVE_PROPAGATION_DELAY" ",5.00 MIL"
					( Parent
						( matchGroupRef "@baseboard_fab2_lib.baseboard_fab2(sch_1):\MG_DQ-DQS_FAR_DIMM_NG_M_F_BYTE5\" )
					)
					( Units "uMatchProp" "ns" 1.000000)
					( Status sCSetFlattened )
					( Origin gBackEnd )
				)
			)
			( pinPair "@baseboard_fab2_lib.baseboard_fab2(sch_1):\PP1017\"
				( pinRef "@baseboard_fab2_lib.baseboard_fab2(sch_1):page28_i172:DDR5_DQS_DN(14)" )
				( pinRef "@baseboard_fab2_lib.baseboard_fab2(sch_1):page54_i66:DQS14N" )
				( attribute "RELATIVE_PROPAGATION_DELAY_SCOPE" "G"
					( Parent
						( matchGroupRef "@baseboard_fab2_lib.baseboard_fab2(sch_1):\MG_DQ-DQS_NEAR_DIMM_NG_M_F_BYTE5\" )
					)
					( Status sCSetFlattened )
					( Origin gBackEnd )
				)
				( attribute "RELATIVE_PROPAGATION_DELAY" ",5.00 MIL"
					( Parent
						( matchGroupRef "@baseboard_fab2_lib.baseboard_fab2(sch_1):\MG_DQ-DQS_NEAR_DIMM_NG_M_F_BYTE5\" )
					)
					( Units "uMatchProp" "ns" 1.000000)
					( Status sCSetFlattened )
					( Origin gBackEnd )
				)
			)
			( pinPair "@baseboard_fab2_lib.baseboard_fab2(sch_1):\PP1003\"
				( pinRef "@baseboard_fab2_lib.baseboard_fab2(sch_1):page28_i172:DDR5_DQS_DN(15)" )
				( pinRef "@baseboard_fab2_lib.baseboard_fab2(sch_1):page53_i66:DQS15N" )
				( attribute "RELATIVE_PROPAGATION_DELAY_SCOPE" "G"
					( Parent
						( matchGroupRef "@baseboard_fab2_lib.baseboard_fab2(sch_1):\MG_DQ-DQS_FAR_DIMM_NG_M_F_BYTE6\" )
					)
					( Status sCSetFlattened )
					( Origin gBackEnd )
				)
				( attribute "RELATIVE_PROPAGATION_DELAY" ",5.00 MIL"
					( Parent
						( matchGroupRef "@baseboard_fab2_lib.baseboard_fab2(sch_1):\MG_DQ-DQS_FAR_DIMM_NG_M_F_BYTE6\" )
					)
					( Units "uMatchProp" "ns" 1.000000)
					( Status sCSetFlattened )
					( Origin gBackEnd )
				)
			)
			( pinPair "@baseboard_fab2_lib.baseboard_fab2(sch_1):\PP1005\"
				( pinRef "@baseboard_fab2_lib.baseboard_fab2(sch_1):page28_i172:DDR5_DQS_DN(15)" )
				( pinRef "@baseboard_fab2_lib.baseboard_fab2(sch_1):page54_i66:DQS15N" )
				( attribute "RELATIVE_PROPAGATION_DELAY_SCOPE" "G"
					( Parent
						( matchGroupRef "@baseboard_fab2_lib.baseboard_fab2(sch_1):\MG_DQ-DQS_NEAR_DIMM_NG_M_F_BYTE6\" )
					)
					( Status sCSetFlattened )
					( Origin gBackEnd )
				)
				( attribute "RELATIVE_PROPAGATION_DELAY" ",5.00 MIL"
					( Parent
						( matchGroupRef "@baseboard_fab2_lib.baseboard_fab2(sch_1):\MG_DQ-DQS_NEAR_DIMM_NG_M_F_BYTE6\" )
					)
					( Units "uMatchProp" "ns" 1.000000)
					( Status sCSetFlattened )
					( Origin gBackEnd )
				)
			)
			( pinPair "@baseboard_fab2_lib.baseboard_fab2(sch_1):\PP991\"
				( pinRef "@baseboard_fab2_lib.baseboard_fab2(sch_1):page28_i172:DDR5_DQS_DN(16)" )
				( pinRef "@baseboard_fab2_lib.baseboard_fab2(sch_1):page53_i66:DQS16N" )
				( attribute "RELATIVE_PROPAGATION_DELAY_SCOPE" "G"
					( Parent
						( matchGroupRef "@baseboard_fab2_lib.baseboard_fab2(sch_1):\MG_DQ-DQS_FAR_DIMM_NG_M_F_BYTE7\" )
					)
					( Status sCSetFlattened )
					( Origin gBackEnd )
				)
				( attribute "RELATIVE_PROPAGATION_DELAY" ",5.00 MIL"
					( Parent
						( matchGroupRef "@baseboard_fab2_lib.baseboard_fab2(sch_1):\MG_DQ-DQS_FAR_DIMM_NG_M_F_BYTE7\" )
					)
					( Units "uMatchProp" "ns" 1.000000)
					( Status sCSetFlattened )
					( Origin gBackEnd )
				)
			)
			( pinPair "@baseboard_fab2_lib.baseboard_fab2(sch_1):\PP993\"
				( pinRef "@baseboard_fab2_lib.baseboard_fab2(sch_1):page28_i172:DDR5_DQS_DN(16)" )
				( pinRef "@baseboard_fab2_lib.baseboard_fab2(sch_1):page54_i66:DQS16N" )
				( attribute "RELATIVE_PROPAGATION_DELAY_SCOPE" "G"
					( Parent
						( matchGroupRef "@baseboard_fab2_lib.baseboard_fab2(sch_1):\MG_DQ-DQS_NEAR_DIMM_NG_M_F_BYTE7\" )
					)
					( Status sCSetFlattened )
					( Origin gBackEnd )
				)
				( attribute "RELATIVE_PROPAGATION_DELAY" ",5.00 MIL"
					( Parent
						( matchGroupRef "@baseboard_fab2_lib.baseboard_fab2(sch_1):\MG_DQ-DQS_NEAR_DIMM_NG_M_F_BYTE7\" )
					)
					( Units "uMatchProp" "ns" 1.000000)
					( Status sCSetFlattened )
					( Origin gBackEnd )
				)
			)
			( pinPair "@baseboard_fab2_lib.baseboard_fab2(sch_1):\PP979\"
				( pinRef "@baseboard_fab2_lib.baseboard_fab2(sch_1):page28_i172:DDR5_DQS_DN(17)" )
				( pinRef "@baseboard_fab2_lib.baseboard_fab2(sch_1):page53_i66:DQS17N" )
				( attribute "RELATIVE_PROPAGATION_DELAY_SCOPE" "G"
					( Parent
						( matchGroupRef "@baseboard_fab2_lib.baseboard_fab2(sch_1):\MG_DQ-DQS_FAR_DIMM_NG_M_F_BYTE-ECC\" )
					)
					( Status sCSetFlattened )
					( Origin gBackEnd )
				)
				( attribute "RELATIVE_PROPAGATION_DELAY" ",5.00 MIL"
					( Parent
						( matchGroupRef "@baseboard_fab2_lib.baseboard_fab2(sch_1):\MG_DQ-DQS_FAR_DIMM_NG_M_F_BYTE-ECC\" )
					)
					( Units "uMatchProp" "ns" 1.000000)
					( Status sCSetFlattened )
					( Origin gBackEnd )
				)
			)
			( pinPair "@baseboard_fab2_lib.baseboard_fab2(sch_1):\PP980\"
				( pinRef "@baseboard_fab2_lib.baseboard_fab2(sch_1):page54_i66:DQS17N" )
				( pinRef "@baseboard_fab2_lib.baseboard_fab2(sch_1):page28_i172:DDR5_DQS_DN(17)" )
				( attribute "RELATIVE_PROPAGATION_DELAY_SCOPE" "G"
					( Parent
						( matchGroupRef "@baseboard_fab2_lib.baseboard_fab2(sch_1):\MG_DQ-DQS_NEAR_DIMM_NG_M_F_BYTE-ECC\" )
					)
					( Status sCSetFlattened )
					( Origin gBackEnd )
				)
				( attribute "RELATIVE_PROPAGATION_DELAY" ",5.00 MIL"
					( Parent
						( matchGroupRef "@baseboard_fab2_lib.baseboard_fab2(sch_1):\MG_DQ-DQS_NEAR_DIMM_NG_M_F_BYTE-ECC\" )
					)
					( Units "uMatchProp" "ns" 1.000000)
					( Status sCSetFlattened )
					( Origin gBackEnd )
				)
			)
			( pinPair "@baseboard_fab2_lib.baseboard_fab2(sch_1):\PP1084\"
				( pinRef "@baseboard_fab2_lib.baseboard_fab2(sch_1):page28_i172:DDR5_DQS_DP(0)" )
				( pinRef "@baseboard_fab2_lib.baseboard_fab2(sch_1):page53_i66:DQS0P" )
				( attribute "RELATIVE_PROPAGATION_DELAY_SCOPE" "G"
					( Parent
						( matchGroupRef "@baseboard_fab2_lib.baseboard_fab2(sch_1):\MG_DQ-DQS_FAR_DIMM_NG_M_F_BYTE0\" )
					)
					( Status sCSetFlattened )
					( Origin gBackEnd )
				)
				( attribute "RELATIVE_PROPAGATION_DELAY" ",5.00 MIL"
					( Parent
						( matchGroupRef "@baseboard_fab2_lib.baseboard_fab2(sch_1):\MG_DQ-DQS_FAR_DIMM_NG_M_F_BYTE0\" )
					)
					( Units "uMatchProp" "ns" 1.000000)
					( Status sCSetFlattened )
					( Origin gBackEnd )
				)
			)
			( pinPair "@baseboard_fab2_lib.baseboard_fab2(sch_1):\PP1085\"
				( pinRef "@baseboard_fab2_lib.baseboard_fab2(sch_1):page54_i66:DQS0P" )
				( pinRef "@baseboard_fab2_lib.baseboard_fab2(sch_1):page28_i172:DDR5_DQS_DP(0)" )
				( attribute "RELATIVE_PROPAGATION_DELAY_SCOPE" "G"
					( Parent
						( matchGroupRef "@baseboard_fab2_lib.baseboard_fab2(sch_1):\MG_DQ-DQS_NEAR_DIMM_NG_M_F_BYTE0\" )
					)
					( Status sCSetFlattened )
					( Origin gBackEnd )
				)
				( attribute "RELATIVE_PROPAGATION_DELAY" ",5.00 MIL"
					( Parent
						( matchGroupRef "@baseboard_fab2_lib.baseboard_fab2(sch_1):\MG_DQ-DQS_NEAR_DIMM_NG_M_F_BYTE0\" )
					)
					( Units "uMatchProp" "ns" 1.000000)
					( Status sCSetFlattened )
					( Origin gBackEnd )
				)
			)
			( pinPair "@baseboard_fab2_lib.baseboard_fab2(sch_1):\PP1072\"
				( pinRef "@baseboard_fab2_lib.baseboard_fab2(sch_1):page28_i172:DDR5_DQS_DP(1)" )
				( pinRef "@baseboard_fab2_lib.baseboard_fab2(sch_1):page53_i66:DQS1P" )
				( attribute "RELATIVE_PROPAGATION_DELAY_SCOPE" "G"
					( Parent
						( matchGroupRef "@baseboard_fab2_lib.baseboard_fab2(sch_1):\MG_DQ-DQS_FAR_DIMM_NG_M_F_BYTE1\" )
					)
					( Status sCSetFlattened )
					( Origin gBackEnd )
				)
				( attribute "RELATIVE_PROPAGATION_DELAY" ",5.00 MIL"
					( Parent
						( matchGroupRef "@baseboard_fab2_lib.baseboard_fab2(sch_1):\MG_DQ-DQS_FAR_DIMM_NG_M_F_BYTE1\" )
					)
					( Units "uMatchProp" "ns" 1.000000)
					( Status sCSetFlattened )
					( Origin gBackEnd )
				)
			)
			( pinPair "@baseboard_fab2_lib.baseboard_fab2(sch_1):\PP1073\"
				( pinRef "@baseboard_fab2_lib.baseboard_fab2(sch_1):page28_i172:DDR5_DQS_DP(1)" )
				( pinRef "@baseboard_fab2_lib.baseboard_fab2(sch_1):page54_i66:DQS1P" )
				( attribute "RELATIVE_PROPAGATION_DELAY_SCOPE" "G"
					( Parent
						( matchGroupRef "@baseboard_fab2_lib.baseboard_fab2(sch_1):\MG_DQ-DQS_NEAR_DIMM_NG_M_F_BYTE1\" )
					)
					( Status sCSetFlattened )
					( Origin gBackEnd )
				)
				( attribute "RELATIVE_PROPAGATION_DELAY" ",5.00 MIL"
					( Parent
						( matchGroupRef "@baseboard_fab2_lib.baseboard_fab2(sch_1):\MG_DQ-DQS_NEAR_DIMM_NG_M_F_BYTE1\" )
					)
					( Units "uMatchProp" "ns" 1.000000)
					( Status sCSetFlattened )
					( Origin gBackEnd )
				)
			)
			( pinPair "@baseboard_fab2_lib.baseboard_fab2(sch_1):\PP1060\"
				( pinRef "@baseboard_fab2_lib.baseboard_fab2(sch_1):page28_i172:DDR5_DQS_DP(2)" )
				( pinRef "@baseboard_fab2_lib.baseboard_fab2(sch_1):page53_i66:DQS2P" )
				( attribute "RELATIVE_PROPAGATION_DELAY_SCOPE" "G"
					( Parent
						( matchGroupRef "@baseboard_fab2_lib.baseboard_fab2(sch_1):\MG_DQ-DQS_FAR_DIMM_NG_M_F_BYTE2\" )
					)
					( Status sCSetFlattened )
					( Origin gBackEnd )
				)
				( attribute "RELATIVE_PROPAGATION_DELAY" ",5.00 MIL"
					( Parent
						( matchGroupRef "@baseboard_fab2_lib.baseboard_fab2(sch_1):\MG_DQ-DQS_FAR_DIMM_NG_M_F_BYTE2\" )
					)
					( Units "uMatchProp" "ns" 1.000000)
					( Status sCSetFlattened )
					( Origin gBackEnd )
				)
			)
			( pinPair "@baseboard_fab2_lib.baseboard_fab2(sch_1):\PP1061\"
				( pinRef "@baseboard_fab2_lib.baseboard_fab2(sch_1):page28_i172:DDR5_DQS_DP(2)" )
				( pinRef "@baseboard_fab2_lib.baseboard_fab2(sch_1):page54_i66:DQS2P" )
				( attribute "RELATIVE_PROPAGATION_DELAY_SCOPE" "G"
					( Parent
						( matchGroupRef "@baseboard_fab2_lib.baseboard_fab2(sch_1):\MG_DQ-DQS_NEAR_DIMM_NG_M_F_BYTE2\" )
					)
					( Status sCSetFlattened )
					( Origin gBackEnd )
				)
				( attribute "RELATIVE_PROPAGATION_DELAY" ",5.00 MIL"
					( Parent
						( matchGroupRef "@baseboard_fab2_lib.baseboard_fab2(sch_1):\MG_DQ-DQS_NEAR_DIMM_NG_M_F_BYTE2\" )
					)
					( Units "uMatchProp" "ns" 1.000000)
					( Status sCSetFlattened )
					( Origin gBackEnd )
				)
			)
			( pinPair "@baseboard_fab2_lib.baseboard_fab2(sch_1):\PP1048\"
				( pinRef "@baseboard_fab2_lib.baseboard_fab2(sch_1):page28_i172:DDR5_DQS_DP(3)" )
				( pinRef "@baseboard_fab2_lib.baseboard_fab2(sch_1):page53_i66:DQS3P" )
				( attribute "RELATIVE_PROPAGATION_DELAY_SCOPE" "G"
					( Parent
						( matchGroupRef "@baseboard_fab2_lib.baseboard_fab2(sch_1):\MG_DQ-DQS_FAR_DIMM_NG_M_F_BYTE3\" )
					)
					( Status sCSetFlattened )
					( Origin gBackEnd )
				)
				( attribute "RELATIVE_PROPAGATION_DELAY" ",5.00 MIL"
					( Parent
						( matchGroupRef "@baseboard_fab2_lib.baseboard_fab2(sch_1):\MG_DQ-DQS_FAR_DIMM_NG_M_F_BYTE3\" )
					)
					( Units "uMatchProp" "ns" 1.000000)
					( Status sCSetFlattened )
					( Origin gBackEnd )
				)
			)
			( pinPair "@baseboard_fab2_lib.baseboard_fab2(sch_1):\PP1049\"
				( pinRef "@baseboard_fab2_lib.baseboard_fab2(sch_1):page54_i66:DQS3P" )
				( pinRef "@baseboard_fab2_lib.baseboard_fab2(sch_1):page28_i172:DDR5_DQS_DP(3)" )
				( attribute "RELATIVE_PROPAGATION_DELAY_SCOPE" "G"
					( Parent
						( matchGroupRef "@baseboard_fab2_lib.baseboard_fab2(sch_1):\MG_DQ-DQS_NEAR_DIMM_NG_M_F_BYTE3\" )
					)
					( Status sCSetFlattened )
					( Origin gBackEnd )
				)
				( attribute "RELATIVE_PROPAGATION_DELAY" ",5.00 MIL"
					( Parent
						( matchGroupRef "@baseboard_fab2_lib.baseboard_fab2(sch_1):\MG_DQ-DQS_NEAR_DIMM_NG_M_F_BYTE3\" )
					)
					( Units "uMatchProp" "ns" 1.000000)
					( Status sCSetFlattened )
					( Origin gBackEnd )
				)
			)
			( pinPair "@baseboard_fab2_lib.baseboard_fab2(sch_1):\PP1036\"
				( pinRef "@baseboard_fab2_lib.baseboard_fab2(sch_1):page28_i172:DDR5_DQS_DP(4)" )
				( pinRef "@baseboard_fab2_lib.baseboard_fab2(sch_1):page53_i66:DQS4P" )
				( attribute "RELATIVE_PROPAGATION_DELAY_SCOPE" "G"
					( Parent
						( matchGroupRef "@baseboard_fab2_lib.baseboard_fab2(sch_1):\MG_DQ-DQS_FAR_DIMM_NG_M_F_BYTE4\" )
					)
					( Status sCSetFlattened )
					( Origin gBackEnd )
				)
				( attribute "RELATIVE_PROPAGATION_DELAY" ",5.00 MIL"
					( Parent
						( matchGroupRef "@baseboard_fab2_lib.baseboard_fab2(sch_1):\MG_DQ-DQS_FAR_DIMM_NG_M_F_BYTE4\" )
					)
					( Units "uMatchProp" "ns" 1.000000)
					( Status sCSetFlattened )
					( Origin gBackEnd )
				)
			)
			( pinPair "@baseboard_fab2_lib.baseboard_fab2(sch_1):\PP1038\"
				( pinRef "@baseboard_fab2_lib.baseboard_fab2(sch_1):page28_i172:DDR5_DQS_DP(4)" )
				( pinRef "@baseboard_fab2_lib.baseboard_fab2(sch_1):page54_i66:DQS4P" )
				( attribute "RELATIVE_PROPAGATION_DELAY_SCOPE" "G"
					( Parent
						( matchGroupRef "@baseboard_fab2_lib.baseboard_fab2(sch_1):\MG_DQ-DQS_NEAR_DIMM_NG_M_F_BYTE4\" )
					)
					( Status sCSetFlattened )
					( Origin gBackEnd )
				)
				( attribute "RELATIVE_PROPAGATION_DELAY" ",5.00 MIL"
					( Parent
						( matchGroupRef "@baseboard_fab2_lib.baseboard_fab2(sch_1):\MG_DQ-DQS_NEAR_DIMM_NG_M_F_BYTE4\" )
					)
					( Units "uMatchProp" "ns" 1.000000)
					( Status sCSetFlattened )
					( Origin gBackEnd )
				)
			)
			( pinPair "@baseboard_fab2_lib.baseboard_fab2(sch_1):\PP1024\"
				( pinRef "@baseboard_fab2_lib.baseboard_fab2(sch_1):page28_i172:DDR5_DQS_DP(5)" )
				( pinRef "@baseboard_fab2_lib.baseboard_fab2(sch_1):page53_i66:DQS5P" )
				( attribute "RELATIVE_PROPAGATION_DELAY_SCOPE" "G"
					( Parent
						( matchGroupRef "@baseboard_fab2_lib.baseboard_fab2(sch_1):\MG_DQ-DQS_FAR_DIMM_NG_M_F_BYTE5\" )
					)
					( Status sCSetFlattened )
					( Origin gBackEnd )
				)
				( attribute "RELATIVE_PROPAGATION_DELAY" ",5.00 MIL"
					( Parent
						( matchGroupRef "@baseboard_fab2_lib.baseboard_fab2(sch_1):\MG_DQ-DQS_FAR_DIMM_NG_M_F_BYTE5\" )
					)
					( Units "uMatchProp" "ns" 1.000000)
					( Status sCSetFlattened )
					( Origin gBackEnd )
				)
			)
			( pinPair "@baseboard_fab2_lib.baseboard_fab2(sch_1):\PP1026\"
				( pinRef "@baseboard_fab2_lib.baseboard_fab2(sch_1):page28_i172:DDR5_DQS_DP(5)" )
				( pinRef "@baseboard_fab2_lib.baseboard_fab2(sch_1):page54_i66:DQS5P" )
				( attribute "RELATIVE_PROPAGATION_DELAY_SCOPE" "G"
					( Parent
						( matchGroupRef "@baseboard_fab2_lib.baseboard_fab2(sch_1):\MG_DQ-DQS_NEAR_DIMM_NG_M_F_BYTE5\" )
					)
					( Status sCSetFlattened )
					( Origin gBackEnd )
				)
				( attribute "RELATIVE_PROPAGATION_DELAY" ",5.00 MIL"
					( Parent
						( matchGroupRef "@baseboard_fab2_lib.baseboard_fab2(sch_1):\MG_DQ-DQS_NEAR_DIMM_NG_M_F_BYTE5\" )
					)
					( Units "uMatchProp" "ns" 1.000000)
					( Status sCSetFlattened )
					( Origin gBackEnd )
				)
			)
			( pinPair "@baseboard_fab2_lib.baseboard_fab2(sch_1):\PP1012\"
				( pinRef "@baseboard_fab2_lib.baseboard_fab2(sch_1):page28_i172:DDR5_DQS_DP(6)" )
				( pinRef "@baseboard_fab2_lib.baseboard_fab2(sch_1):page53_i66:DQS6P" )
				( attribute "RELATIVE_PROPAGATION_DELAY_SCOPE" "G"
					( Parent
						( matchGroupRef "@baseboard_fab2_lib.baseboard_fab2(sch_1):\MG_DQ-DQS_FAR_DIMM_NG_M_F_BYTE6\" )
					)
					( Status sCSetFlattened )
					( Origin gBackEnd )
				)
				( attribute "RELATIVE_PROPAGATION_DELAY" ",5.00 MIL"
					( Parent
						( matchGroupRef "@baseboard_fab2_lib.baseboard_fab2(sch_1):\MG_DQ-DQS_FAR_DIMM_NG_M_F_BYTE6\" )
					)
					( Units "uMatchProp" "ns" 1.000000)
					( Status sCSetFlattened )
					( Origin gBackEnd )
				)
			)
			( pinPair "@baseboard_fab2_lib.baseboard_fab2(sch_1):\PP1014\"
				( pinRef "@baseboard_fab2_lib.baseboard_fab2(sch_1):page54_i66:DQS6P" )
				( pinRef "@baseboard_fab2_lib.baseboard_fab2(sch_1):page28_i172:DDR5_DQS_DP(6)" )
				( attribute "RELATIVE_PROPAGATION_DELAY_SCOPE" "G"
					( Parent
						( matchGroupRef "@baseboard_fab2_lib.baseboard_fab2(sch_1):\MG_DQ-DQS_NEAR_DIMM_NG_M_F_BYTE6\" )
					)
					( Status sCSetFlattened )
					( Origin gBackEnd )
				)
				( attribute "RELATIVE_PROPAGATION_DELAY" ",5.00 MIL"
					( Parent
						( matchGroupRef "@baseboard_fab2_lib.baseboard_fab2(sch_1):\MG_DQ-DQS_NEAR_DIMM_NG_M_F_BYTE6\" )
					)
					( Units "uMatchProp" "ns" 1.000000)
					( Status sCSetFlattened )
					( Origin gBackEnd )
				)
			)
			( pinPair "@baseboard_fab2_lib.baseboard_fab2(sch_1):\PP1000\"
				( pinRef "@baseboard_fab2_lib.baseboard_fab2(sch_1):page28_i172:DDR5_DQS_DP(7)" )
				( pinRef "@baseboard_fab2_lib.baseboard_fab2(sch_1):page53_i66:DQS7P" )
				( attribute "RELATIVE_PROPAGATION_DELAY_SCOPE" "G"
					( Parent
						( matchGroupRef "@baseboard_fab2_lib.baseboard_fab2(sch_1):\MG_DQ-DQS_FAR_DIMM_NG_M_F_BYTE7\" )
					)
					( Status sCSetFlattened )
					( Origin gBackEnd )
				)
				( attribute "RELATIVE_PROPAGATION_DELAY" ",5.00 MIL"
					( Parent
						( matchGroupRef "@baseboard_fab2_lib.baseboard_fab2(sch_1):\MG_DQ-DQS_FAR_DIMM_NG_M_F_BYTE7\" )
					)
					( Units "uMatchProp" "ns" 1.000000)
					( Status sCSetFlattened )
					( Origin gBackEnd )
				)
			)
			( pinPair "@baseboard_fab2_lib.baseboard_fab2(sch_1):\PP1002\"
				( pinRef "@baseboard_fab2_lib.baseboard_fab2(sch_1):page54_i66:DQS7P" )
				( pinRef "@baseboard_fab2_lib.baseboard_fab2(sch_1):page28_i172:DDR5_DQS_DP(7)" )
				( attribute "RELATIVE_PROPAGATION_DELAY_SCOPE" "G"
					( Parent
						( matchGroupRef "@baseboard_fab2_lib.baseboard_fab2(sch_1):\MG_DQ-DQS_NEAR_DIMM_NG_M_F_BYTE7\" )
					)
					( Status sCSetFlattened )
					( Origin gBackEnd )
				)
				( attribute "RELATIVE_PROPAGATION_DELAY" ",5.00 MIL"
					( Parent
						( matchGroupRef "@baseboard_fab2_lib.baseboard_fab2(sch_1):\MG_DQ-DQS_NEAR_DIMM_NG_M_F_BYTE7\" )
					)
					( Units "uMatchProp" "ns" 1.000000)
					( Status sCSetFlattened )
					( Origin gBackEnd )
				)
			)
			( pinPair "@baseboard_fab2_lib.baseboard_fab2(sch_1):\PP988\"
				( pinRef "@baseboard_fab2_lib.baseboard_fab2(sch_1):page28_i172:DDR5_DQS_DP(8)" )
				( pinRef "@baseboard_fab2_lib.baseboard_fab2(sch_1):page53_i66:DQS8P" )
				( attribute "RELATIVE_PROPAGATION_DELAY_SCOPE" "G"
					( Parent
						( matchGroupRef "@baseboard_fab2_lib.baseboard_fab2(sch_1):\MG_DQ-DQS_FAR_DIMM_NG_M_F_BYTE-ECC\" )
					)
					( Status sCSetFlattened )
					( Origin gBackEnd )
				)
				( attribute "RELATIVE_PROPAGATION_DELAY" ",5.00 MIL"
					( Parent
						( matchGroupRef "@baseboard_fab2_lib.baseboard_fab2(sch_1):\MG_DQ-DQS_FAR_DIMM_NG_M_F_BYTE-ECC\" )
					)
					( Units "uMatchProp" "ns" 1.000000)
					( Status sCSetFlattened )
					( Origin gBackEnd )
				)
			)
			( pinPair "@baseboard_fab2_lib.baseboard_fab2(sch_1):\PP989\"
				( pinRef "@baseboard_fab2_lib.baseboard_fab2(sch_1):page54_i66:DQS8P" )
				( pinRef "@baseboard_fab2_lib.baseboard_fab2(sch_1):page28_i172:DDR5_DQS_DP(8)" )
				( attribute "RELATIVE_PROPAGATION_DELAY_SCOPE" "G"
					( Parent
						( matchGroupRef "@baseboard_fab2_lib.baseboard_fab2(sch_1):\MG_DQ-DQS_NEAR_DIMM_NG_M_F_BYTE-ECC\" )
					)
					( Status sCSetFlattened )
					( Origin gBackEnd )
				)
				( attribute "RELATIVE_PROPAGATION_DELAY" ",5.00 MIL"
					( Parent
						( matchGroupRef "@baseboard_fab2_lib.baseboard_fab2(sch_1):\MG_DQ-DQS_NEAR_DIMM_NG_M_F_BYTE-ECC\" )
					)
					( Units "uMatchProp" "ns" 1.000000)
					( Status sCSetFlattened )
					( Origin gBackEnd )
				)
			)
			( pinPair "@baseboard_fab2_lib.baseboard_fab2(sch_1):\PP1078\"
				( pinRef "@baseboard_fab2_lib.baseboard_fab2(sch_1):page28_i172:DDR5_DQS_DP(9)" )
				( pinRef "@baseboard_fab2_lib.baseboard_fab2(sch_1):page53_i66:DQS9P" )
				( attribute "RELATIVE_PROPAGATION_DELAY_SCOPE" "G"
					( Parent
						( matchGroupRef "@baseboard_fab2_lib.baseboard_fab2(sch_1):\MG_DQ-DQS_FAR_DIMM_NG_M_F_BYTE0\" )
					)
					( Status sCSetFlattened )
					( Origin gBackEnd )
				)
				( attribute "RELATIVE_PROPAGATION_DELAY" ",5.00 MIL"
					( Parent
						( matchGroupRef "@baseboard_fab2_lib.baseboard_fab2(sch_1):\MG_DQ-DQS_FAR_DIMM_NG_M_F_BYTE0\" )
					)
					( Units "uMatchProp" "ns" 1.000000)
					( Status sCSetFlattened )
					( Origin gBackEnd )
				)
			)
			( pinPair "@baseboard_fab2_lib.baseboard_fab2(sch_1):\PP1079\"
				( pinRef "@baseboard_fab2_lib.baseboard_fab2(sch_1):page54_i66:DQS9P" )
				( pinRef "@baseboard_fab2_lib.baseboard_fab2(sch_1):page28_i172:DDR5_DQS_DP(9)" )
				( attribute "RELATIVE_PROPAGATION_DELAY_SCOPE" "G"
					( Parent
						( matchGroupRef "@baseboard_fab2_lib.baseboard_fab2(sch_1):\MG_DQ-DQS_NEAR_DIMM_NG_M_F_BYTE0\" )
					)
					( Status sCSetFlattened )
					( Origin gBackEnd )
				)
				( attribute "RELATIVE_PROPAGATION_DELAY" ",5.00 MIL"
					( Parent
						( matchGroupRef "@baseboard_fab2_lib.baseboard_fab2(sch_1):\MG_DQ-DQS_NEAR_DIMM_NG_M_F_BYTE0\" )
					)
					( Units "uMatchProp" "ns" 1.000000)
					( Status sCSetFlattened )
					( Origin gBackEnd )
				)
			)
			( pinPair "@baseboard_fab2_lib.baseboard_fab2(sch_1):\PP1066\"
				( pinRef "@baseboard_fab2_lib.baseboard_fab2(sch_1):page28_i172:DDR5_DQS_DP(10)" )
				( pinRef "@baseboard_fab2_lib.baseboard_fab2(sch_1):page53_i66:DQS10P" )
				( attribute "RELATIVE_PROPAGATION_DELAY_SCOPE" "G"
					( Parent
						( matchGroupRef "@baseboard_fab2_lib.baseboard_fab2(sch_1):\MG_DQ-DQS_FAR_DIMM_NG_M_F_BYTE1\" )
					)
					( Status sCSetFlattened )
					( Origin gBackEnd )
				)
				( attribute "RELATIVE_PROPAGATION_DELAY" ",5.00 MIL"
					( Parent
						( matchGroupRef "@baseboard_fab2_lib.baseboard_fab2(sch_1):\MG_DQ-DQS_FAR_DIMM_NG_M_F_BYTE1\" )
					)
					( Units "uMatchProp" "ns" 1.000000)
					( Status sCSetFlattened )
					( Origin gBackEnd )
				)
			)
			( pinPair "@baseboard_fab2_lib.baseboard_fab2(sch_1):\PP1067\"
				( pinRef "@baseboard_fab2_lib.baseboard_fab2(sch_1):page54_i66:DQS10P" )
				( pinRef "@baseboard_fab2_lib.baseboard_fab2(sch_1):page28_i172:DDR5_DQS_DP(10)" )
				( attribute "RELATIVE_PROPAGATION_DELAY_SCOPE" "G"
					( Parent
						( matchGroupRef "@baseboard_fab2_lib.baseboard_fab2(sch_1):\MG_DQ-DQS_NEAR_DIMM_NG_M_F_BYTE1\" )
					)
					( Status sCSetFlattened )
					( Origin gBackEnd )
				)
				( attribute "RELATIVE_PROPAGATION_DELAY" ",5.00 MIL"
					( Parent
						( matchGroupRef "@baseboard_fab2_lib.baseboard_fab2(sch_1):\MG_DQ-DQS_NEAR_DIMM_NG_M_F_BYTE1\" )
					)
					( Units "uMatchProp" "ns" 1.000000)
					( Status sCSetFlattened )
					( Origin gBackEnd )
				)
			)
			( pinPair "@baseboard_fab2_lib.baseboard_fab2(sch_1):\PP1054\"
				( pinRef "@baseboard_fab2_lib.baseboard_fab2(sch_1):page28_i172:DDR5_DQS_DP(11)" )
				( pinRef "@baseboard_fab2_lib.baseboard_fab2(sch_1):page53_i66:DQS11P" )
				( attribute "RELATIVE_PROPAGATION_DELAY_SCOPE" "G"
					( Parent
						( matchGroupRef "@baseboard_fab2_lib.baseboard_fab2(sch_1):\MG_DQ-DQS_FAR_DIMM_NG_M_F_BYTE2\" )
					)
					( Status sCSetFlattened )
					( Origin gBackEnd )
				)
				( attribute "RELATIVE_PROPAGATION_DELAY" ",5.00 MIL"
					( Parent
						( matchGroupRef "@baseboard_fab2_lib.baseboard_fab2(sch_1):\MG_DQ-DQS_FAR_DIMM_NG_M_F_BYTE2\" )
					)
					( Units "uMatchProp" "ns" 1.000000)
					( Status sCSetFlattened )
					( Origin gBackEnd )
				)
			)
			( pinPair "@baseboard_fab2_lib.baseboard_fab2(sch_1):\PP1055\"
				( pinRef "@baseboard_fab2_lib.baseboard_fab2(sch_1):page54_i66:DQS11P" )
				( pinRef "@baseboard_fab2_lib.baseboard_fab2(sch_1):page28_i172:DDR5_DQS_DP(11)" )
				( attribute "RELATIVE_PROPAGATION_DELAY_SCOPE" "G"
					( Parent
						( matchGroupRef "@baseboard_fab2_lib.baseboard_fab2(sch_1):\MG_DQ-DQS_NEAR_DIMM_NG_M_F_BYTE2\" )
					)
					( Status sCSetFlattened )
					( Origin gBackEnd )
				)
				( attribute "RELATIVE_PROPAGATION_DELAY" ",5.00 MIL"
					( Parent
						( matchGroupRef "@baseboard_fab2_lib.baseboard_fab2(sch_1):\MG_DQ-DQS_NEAR_DIMM_NG_M_F_BYTE2\" )
					)
					( Units "uMatchProp" "ns" 1.000000)
					( Status sCSetFlattened )
					( Origin gBackEnd )
				)
			)
			( pinPair "@baseboard_fab2_lib.baseboard_fab2(sch_1):\PP1042\"
				( pinRef "@baseboard_fab2_lib.baseboard_fab2(sch_1):page28_i172:DDR5_DQS_DP(12)" )
				( pinRef "@baseboard_fab2_lib.baseboard_fab2(sch_1):page53_i66:DQS12P" )
				( attribute "RELATIVE_PROPAGATION_DELAY_SCOPE" "G"
					( Parent
						( matchGroupRef "@baseboard_fab2_lib.baseboard_fab2(sch_1):\MG_DQ-DQS_FAR_DIMM_NG_M_F_BYTE3\" )
					)
					( Status sCSetFlattened )
					( Origin gBackEnd )
				)
				( attribute "RELATIVE_PROPAGATION_DELAY" ",5.00 MIL"
					( Parent
						( matchGroupRef "@baseboard_fab2_lib.baseboard_fab2(sch_1):\MG_DQ-DQS_FAR_DIMM_NG_M_F_BYTE3\" )
					)
					( Units "uMatchProp" "ns" 1.000000)
					( Status sCSetFlattened )
					( Origin gBackEnd )
				)
			)
			( pinPair "@baseboard_fab2_lib.baseboard_fab2(sch_1):\PP1043\"
				( pinRef "@baseboard_fab2_lib.baseboard_fab2(sch_1):page54_i66:DQS12P" )
				( pinRef "@baseboard_fab2_lib.baseboard_fab2(sch_1):page28_i172:DDR5_DQS_DP(12)" )
				( attribute "RELATIVE_PROPAGATION_DELAY_SCOPE" "G"
					( Parent
						( matchGroupRef "@baseboard_fab2_lib.baseboard_fab2(sch_1):\MG_DQ-DQS_NEAR_DIMM_NG_M_F_BYTE3\" )
					)
					( Status sCSetFlattened )
					( Origin gBackEnd )
				)
				( attribute "RELATIVE_PROPAGATION_DELAY" ",5.00 MIL"
					( Parent
						( matchGroupRef "@baseboard_fab2_lib.baseboard_fab2(sch_1):\MG_DQ-DQS_NEAR_DIMM_NG_M_F_BYTE3\" )
					)
					( Units "uMatchProp" "ns" 1.000000)
					( Status sCSetFlattened )
					( Origin gBackEnd )
				)
			)
			( pinPair "@baseboard_fab2_lib.baseboard_fab2(sch_1):\PP1030\"
				( pinRef "@baseboard_fab2_lib.baseboard_fab2(sch_1):page28_i172:DDR5_DQS_DP(13)" )
				( pinRef "@baseboard_fab2_lib.baseboard_fab2(sch_1):page53_i66:DQS13P" )
				( attribute "RELATIVE_PROPAGATION_DELAY_SCOPE" "G"
					( Parent
						( matchGroupRef "@baseboard_fab2_lib.baseboard_fab2(sch_1):\MG_DQ-DQS_FAR_DIMM_NG_M_F_BYTE4\" )
					)
					( Status sCSetFlattened )
					( Origin gBackEnd )
				)
				( attribute "RELATIVE_PROPAGATION_DELAY" ",5.00 MIL"
					( Parent
						( matchGroupRef "@baseboard_fab2_lib.baseboard_fab2(sch_1):\MG_DQ-DQS_FAR_DIMM_NG_M_F_BYTE4\" )
					)
					( Units "uMatchProp" "ns" 1.000000)
					( Status sCSetFlattened )
					( Origin gBackEnd )
				)
			)
			( pinPair "@baseboard_fab2_lib.baseboard_fab2(sch_1):\PP1032\"
				( pinRef "@baseboard_fab2_lib.baseboard_fab2(sch_1):page28_i172:DDR5_DQS_DP(13)" )
				( pinRef "@baseboard_fab2_lib.baseboard_fab2(sch_1):page54_i66:DQS13P" )
				( attribute "RELATIVE_PROPAGATION_DELAY_SCOPE" "G"
					( Parent
						( matchGroupRef "@baseboard_fab2_lib.baseboard_fab2(sch_1):\MG_DQ-DQS_NEAR_DIMM_NG_M_F_BYTE4\" )
					)
					( Status sCSetFlattened )
					( Origin gBackEnd )
				)
				( attribute "RELATIVE_PROPAGATION_DELAY" ",5.00 MIL"
					( Parent
						( matchGroupRef "@baseboard_fab2_lib.baseboard_fab2(sch_1):\MG_DQ-DQS_NEAR_DIMM_NG_M_F_BYTE4\" )
					)
					( Units "uMatchProp" "ns" 1.000000)
					( Status sCSetFlattened )
					( Origin gBackEnd )
				)
			)
			( pinPair "@baseboard_fab2_lib.baseboard_fab2(sch_1):\PP1018\"
				( pinRef "@baseboard_fab2_lib.baseboard_fab2(sch_1):page28_i172:DDR5_DQS_DP(14)" )
				( pinRef "@baseboard_fab2_lib.baseboard_fab2(sch_1):page53_i66:DQS14P" )
				( attribute "RELATIVE_PROPAGATION_DELAY_SCOPE" "G"
					( Parent
						( matchGroupRef "@baseboard_fab2_lib.baseboard_fab2(sch_1):\MG_DQ-DQS_FAR_DIMM_NG_M_F_BYTE5\" )
					)
					( Status sCSetFlattened )
					( Origin gBackEnd )
				)
				( attribute "RELATIVE_PROPAGATION_DELAY" ",5.00 MIL"
					( Parent
						( matchGroupRef "@baseboard_fab2_lib.baseboard_fab2(sch_1):\MG_DQ-DQS_FAR_DIMM_NG_M_F_BYTE5\" )
					)
					( Units "uMatchProp" "ns" 1.000000)
					( Status sCSetFlattened )
					( Origin gBackEnd )
				)
			)
			( pinPair "@baseboard_fab2_lib.baseboard_fab2(sch_1):\PP1020\"
				( pinRef "@baseboard_fab2_lib.baseboard_fab2(sch_1):page28_i172:DDR5_DQS_DP(14)" )
				( pinRef "@baseboard_fab2_lib.baseboard_fab2(sch_1):page54_i66:DQS14P" )
				( attribute "RELATIVE_PROPAGATION_DELAY_SCOPE" "G"
					( Parent
						( matchGroupRef "@baseboard_fab2_lib.baseboard_fab2(sch_1):\MG_DQ-DQS_NEAR_DIMM_NG_M_F_BYTE5\" )
					)
					( Status sCSetFlattened )
					( Origin gBackEnd )
				)
				( attribute "RELATIVE_PROPAGATION_DELAY" ",5.00 MIL"
					( Parent
						( matchGroupRef "@baseboard_fab2_lib.baseboard_fab2(sch_1):\MG_DQ-DQS_NEAR_DIMM_NG_M_F_BYTE5\" )
					)
					( Units "uMatchProp" "ns" 1.000000)
					( Status sCSetFlattened )
					( Origin gBackEnd )
				)
			)
			( pinPair "@baseboard_fab2_lib.baseboard_fab2(sch_1):\PP1006\"
				( pinRef "@baseboard_fab2_lib.baseboard_fab2(sch_1):page28_i172:DDR5_DQS_DP(15)" )
				( pinRef "@baseboard_fab2_lib.baseboard_fab2(sch_1):page53_i66:DQS15P" )
				( attribute "RELATIVE_PROPAGATION_DELAY_SCOPE" "G"
					( Parent
						( matchGroupRef "@baseboard_fab2_lib.baseboard_fab2(sch_1):\MG_DQ-DQS_FAR_DIMM_NG_M_F_BYTE6\" )
					)
					( Status sCSetFlattened )
					( Origin gBackEnd )
				)
				( attribute "RELATIVE_PROPAGATION_DELAY" ",5.00 MIL"
					( Parent
						( matchGroupRef "@baseboard_fab2_lib.baseboard_fab2(sch_1):\MG_DQ-DQS_FAR_DIMM_NG_M_F_BYTE6\" )
					)
					( Units "uMatchProp" "ns" 1.000000)
					( Status sCSetFlattened )
					( Origin gBackEnd )
				)
			)
			( pinPair "@baseboard_fab2_lib.baseboard_fab2(sch_1):\PP1008\"
				( pinRef "@baseboard_fab2_lib.baseboard_fab2(sch_1):page28_i172:DDR5_DQS_DP(15)" )
				( pinRef "@baseboard_fab2_lib.baseboard_fab2(sch_1):page54_i66:DQS15P" )
				( attribute "RELATIVE_PROPAGATION_DELAY_SCOPE" "G"
					( Parent
						( matchGroupRef "@baseboard_fab2_lib.baseboard_fab2(sch_1):\MG_DQ-DQS_NEAR_DIMM_NG_M_F_BYTE6\" )
					)
					( Status sCSetFlattened )
					( Origin gBackEnd )
				)
				( attribute "RELATIVE_PROPAGATION_DELAY" ",5.00 MIL"
					( Parent
						( matchGroupRef "@baseboard_fab2_lib.baseboard_fab2(sch_1):\MG_DQ-DQS_NEAR_DIMM_NG_M_F_BYTE6\" )
					)
					( Units "uMatchProp" "ns" 1.000000)
					( Status sCSetFlattened )
					( Origin gBackEnd )
				)
			)
			( pinPair "@baseboard_fab2_lib.baseboard_fab2(sch_1):\PP994\"
				( pinRef "@baseboard_fab2_lib.baseboard_fab2(sch_1):page28_i172:DDR5_DQS_DP(16)" )
				( pinRef "@baseboard_fab2_lib.baseboard_fab2(sch_1):page53_i66:DQS16P" )
				( attribute "RELATIVE_PROPAGATION_DELAY_SCOPE" "G"
					( Parent
						( matchGroupRef "@baseboard_fab2_lib.baseboard_fab2(sch_1):\MG_DQ-DQS_FAR_DIMM_NG_M_F_BYTE7\" )
					)
					( Status sCSetFlattened )
					( Origin gBackEnd )
				)
				( attribute "RELATIVE_PROPAGATION_DELAY" ",5.00 MIL"
					( Parent
						( matchGroupRef "@baseboard_fab2_lib.baseboard_fab2(sch_1):\MG_DQ-DQS_FAR_DIMM_NG_M_F_BYTE7\" )
					)
					( Units "uMatchProp" "ns" 1.000000)
					( Status sCSetFlattened )
					( Origin gBackEnd )
				)
			)
			( pinPair "@baseboard_fab2_lib.baseboard_fab2(sch_1):\PP996\"
				( pinRef "@baseboard_fab2_lib.baseboard_fab2(sch_1):page28_i172:DDR5_DQS_DP(16)" )
				( pinRef "@baseboard_fab2_lib.baseboard_fab2(sch_1):page54_i66:DQS16P" )
				( attribute "RELATIVE_PROPAGATION_DELAY_SCOPE" "G"
					( Parent
						( matchGroupRef "@baseboard_fab2_lib.baseboard_fab2(sch_1):\MG_DQ-DQS_NEAR_DIMM_NG_M_F_BYTE7\" )
					)
					( Status sCSetFlattened )
					( Origin gBackEnd )
				)
				( attribute "RELATIVE_PROPAGATION_DELAY" ",5.00 MIL"
					( Parent
						( matchGroupRef "@baseboard_fab2_lib.baseboard_fab2(sch_1):\MG_DQ-DQS_NEAR_DIMM_NG_M_F_BYTE7\" )
					)
					( Units "uMatchProp" "ns" 1.000000)
					( Status sCSetFlattened )
					( Origin gBackEnd )
				)
			)
			( pinPair "@baseboard_fab2_lib.baseboard_fab2(sch_1):\PP982\"
				( pinRef "@baseboard_fab2_lib.baseboard_fab2(sch_1):page28_i172:DDR5_DQS_DP(17)" )
				( pinRef "@baseboard_fab2_lib.baseboard_fab2(sch_1):page53_i66:DQS17P" )
				( attribute "RELATIVE_PROPAGATION_DELAY_SCOPE" "G"
					( Parent
						( matchGroupRef "@baseboard_fab2_lib.baseboard_fab2(sch_1):\MG_DQ-DQS_FAR_DIMM_NG_M_F_BYTE-ECC\" )
					)
					( Status sCSetFlattened )
					( Origin gBackEnd )
				)
				( attribute "RELATIVE_PROPAGATION_DELAY" ",5.00 MIL"
					( Parent
						( matchGroupRef "@baseboard_fab2_lib.baseboard_fab2(sch_1):\MG_DQ-DQS_FAR_DIMM_NG_M_F_BYTE-ECC\" )
					)
					( Units "uMatchProp" "ns" 1.000000)
					( Status sCSetFlattened )
					( Origin gBackEnd )
				)
			)
			( pinPair "@baseboard_fab2_lib.baseboard_fab2(sch_1):\PP983\"
				( pinRef "@baseboard_fab2_lib.baseboard_fab2(sch_1):page54_i66:DQS17P" )
				( pinRef "@baseboard_fab2_lib.baseboard_fab2(sch_1):page28_i172:DDR5_DQS_DP(17)" )
				( attribute "RELATIVE_PROPAGATION_DELAY_SCOPE" "G"
					( Parent
						( matchGroupRef "@baseboard_fab2_lib.baseboard_fab2(sch_1):\MG_DQ-DQS_NEAR_DIMM_NG_M_F_BYTE-ECC\" )
					)
					( Status sCSetFlattened )
					( Origin gBackEnd )
				)
				( attribute "RELATIVE_PROPAGATION_DELAY" ",5.00 MIL"
					( Parent
						( matchGroupRef "@baseboard_fab2_lib.baseboard_fab2(sch_1):\MG_DQ-DQS_NEAR_DIMM_NG_M_F_BYTE-ECC\" )
					)
					( Units "uMatchProp" "ns" 1.000000)
					( Status sCSetFlattened )
					( Origin gBackEnd )
				)
			)
			( pinPair "@baseboard_fab2_lib.baseboard_fab2(sch_1):\PP475\"
				( pinRef "@baseboard_fab2_lib.baseboard_fab2(sch_1):page24_i172:DDR1_DQS_DN(16)" )
				( pinRef "@baseboard_fab2_lib.baseboard_fab2(sch_1):page45_i61:DQS16N" )
				( attribute "RELATIVE_PROPAGATION_DELAY_SCOPE" "G"
					( Parent
						( matchGroupRef "@baseboard_fab2_lib.baseboard_fab2(sch_1):\MG_DQ-DQS_FAR_DIMM_NG_M_B_BYTE7\" )
					)
					( Status sCSetFlattened )
					( Origin gBackEnd )
				)
				( attribute "RELATIVE_PROPAGATION_DELAY" ",5.00 MIL"
					( Parent
						( matchGroupRef "@baseboard_fab2_lib.baseboard_fab2(sch_1):\MG_DQ-DQS_FAR_DIMM_NG_M_B_BYTE7\" )
					)
					( Units "uMatchProp" "ns" 1.000000)
					( Status sCSetFlattened )
					( Origin gBackEnd )
				)
			)
			( pinPair "@baseboard_fab2_lib.baseboard_fab2(sch_1):\PP477\"
				( pinRef "@baseboard_fab2_lib.baseboard_fab2(sch_1):page24_i172:DDR1_DQS_DN(16)" )
				( pinRef "@baseboard_fab2_lib.baseboard_fab2(sch_1):page46_i112:DQS16N" )
				( attribute "RELATIVE_PROPAGATION_DELAY_SCOPE" "G"
					( Parent
						( matchGroupRef "@baseboard_fab2_lib.baseboard_fab2(sch_1):\MG_DQ-DQS_NEAR_DIMM_NG_M_B_BYTE7\" )
					)
					( Status sCSetFlattened )
					( Origin gBackEnd )
				)
				( attribute "RELATIVE_PROPAGATION_DELAY" ",5.00 MIL"
					( Parent
						( matchGroupRef "@baseboard_fab2_lib.baseboard_fab2(sch_1):\MG_DQ-DQS_NEAR_DIMM_NG_M_B_BYTE7\" )
					)
					( Units "uMatchProp" "ns" 1.000000)
					( Status sCSetFlattened )
					( Origin gBackEnd )
				)
			)
			( pinPair "@baseboard_fab2_lib.baseboard_fab2(sch_1):\PP1219\"
				( pinRef "@baseboard_fab2_lib.baseboard_fab2(sch_1):page24_i172:DDR1_DQS_DN(17)" )
				( pinRef "@baseboard_fab2_lib.baseboard_fab2(sch_1):page45_i61:DQS17N" )
				( attribute "RELATIVE_PROPAGATION_DELAY_SCOPE" "G"
					( Parent
						( matchGroupRef "@baseboard_fab2_lib.baseboard_fab2(sch_1):\MG_DQ-DQS_FAR_DIMM_NG_M_B_BYTE-ECC\" )
					)
					( Status sCSetFlattened )
					( Origin gBackEnd )
				)
				( attribute "RELATIVE_PROPAGATION_DELAY" ",5.00 MIL"
					( Parent
						( matchGroupRef "@baseboard_fab2_lib.baseboard_fab2(sch_1):\MG_DQ-DQS_FAR_DIMM_NG_M_B_BYTE-ECC\" )
					)
					( Units "uMatchProp" "ns" 1.000000)
					( Status sCSetFlattened )
					( Origin gBackEnd )
				)
			)
			( pinPair "@baseboard_fab2_lib.baseboard_fab2(sch_1):\PP1220\"
				( pinRef "@baseboard_fab2_lib.baseboard_fab2(sch_1):page24_i172:DDR1_DQS_DN(17)" )
				( pinRef "@baseboard_fab2_lib.baseboard_fab2(sch_1):page46_i112:DQS17N" )
				( attribute "RELATIVE_PROPAGATION_DELAY_SCOPE" "G"
					( Parent
						( matchGroupRef "@baseboard_fab2_lib.baseboard_fab2(sch_1):\MG_DQ-DQS_NEAR_DIMM_NG_M_B_BYTE-ECC\" )
					)
					( Status sCSetFlattened )
					( Origin gBackEnd )
				)
				( attribute "RELATIVE_PROPAGATION_DELAY" ",5.00 MIL"
					( Parent
						( matchGroupRef "@baseboard_fab2_lib.baseboard_fab2(sch_1):\MG_DQ-DQS_NEAR_DIMM_NG_M_B_BYTE-ECC\" )
					)
					( Units "uMatchProp" "ns" 1.000000)
					( Status sCSetFlattened )
					( Origin gBackEnd )
				)
			)
			( pinPair "@baseboard_fab2_lib.baseboard_fab2(sch_1):\PP568\"
				( pinRef "@baseboard_fab2_lib.baseboard_fab2(sch_1):page24_i172:DDR1_DQS_DP(0)" )
				( pinRef "@baseboard_fab2_lib.baseboard_fab2(sch_1):page45_i61:DQS0P" )
				( attribute "RELATIVE_PROPAGATION_DELAY_SCOPE" "G"
					( Parent
						( matchGroupRef "@baseboard_fab2_lib.baseboard_fab2(sch_1):\MG_DQ-DQS_FAR_DIMM_NG_M_B_BYTE0\" )
					)
					( Status sCSetFlattened )
					( Origin gBackEnd )
				)
				( attribute "RELATIVE_PROPAGATION_DELAY" ",5.00 MIL"
					( Parent
						( matchGroupRef "@baseboard_fab2_lib.baseboard_fab2(sch_1):\MG_DQ-DQS_FAR_DIMM_NG_M_B_BYTE0\" )
					)
					( Units "uMatchProp" "ns" 1.000000)
					( Status sCSetFlattened )
					( Origin gBackEnd )
				)
			)
			( pinPair "@baseboard_fab2_lib.baseboard_fab2(sch_1):\PP569\"
				( pinRef "@baseboard_fab2_lib.baseboard_fab2(sch_1):page24_i172:DDR1_DQS_DP(0)" )
				( pinRef "@baseboard_fab2_lib.baseboard_fab2(sch_1):page46_i112:DQS0P" )
				( attribute "RELATIVE_PROPAGATION_DELAY_SCOPE" "G"
					( Parent
						( matchGroupRef "@baseboard_fab2_lib.baseboard_fab2(sch_1):\MG_DQ-DQS_NEAR_DIMM_NG_M_B_BYTE0\" )
					)
					( Status sCSetFlattened )
					( Origin gBackEnd )
				)
				( attribute "RELATIVE_PROPAGATION_DELAY" ",5.00 MIL"
					( Parent
						( matchGroupRef "@baseboard_fab2_lib.baseboard_fab2(sch_1):\MG_DQ-DQS_NEAR_DIMM_NG_M_B_BYTE0\" )
					)
					( Units "uMatchProp" "ns" 1.000000)
					( Status sCSetFlattened )
					( Origin gBackEnd )
				)
			)
			( pinPair "@baseboard_fab2_lib.baseboard_fab2(sch_1):\PP556\"
				( pinRef "@baseboard_fab2_lib.baseboard_fab2(sch_1):page24_i172:DDR1_DQS_DP(1)" )
				( pinRef "@baseboard_fab2_lib.baseboard_fab2(sch_1):page45_i61:DQS1P" )
				( attribute "RELATIVE_PROPAGATION_DELAY_SCOPE" "G"
					( Parent
						( matchGroupRef "@baseboard_fab2_lib.baseboard_fab2(sch_1):\MG_DQ-DQS_FAR_DIMM_NG_M_B_BYTE1\" )
					)
					( Status sCSetFlattened )
					( Origin gBackEnd )
				)
				( attribute "RELATIVE_PROPAGATION_DELAY" ",5.00 MIL"
					( Parent
						( matchGroupRef "@baseboard_fab2_lib.baseboard_fab2(sch_1):\MG_DQ-DQS_FAR_DIMM_NG_M_B_BYTE1\" )
					)
					( Units "uMatchProp" "ns" 1.000000)
					( Status sCSetFlattened )
					( Origin gBackEnd )
				)
			)
			( pinPair "@baseboard_fab2_lib.baseboard_fab2(sch_1):\PP557\"
				( pinRef "@baseboard_fab2_lib.baseboard_fab2(sch_1):page24_i172:DDR1_DQS_DP(1)" )
				( pinRef "@baseboard_fab2_lib.baseboard_fab2(sch_1):page46_i112:DQS1P" )
				( attribute "RELATIVE_PROPAGATION_DELAY_SCOPE" "G"
					( Parent
						( matchGroupRef "@baseboard_fab2_lib.baseboard_fab2(sch_1):\MG_DQ-DQS_NEAR_DIMM_NG_M_B_BYTE1\" )
					)
					( Status sCSetFlattened )
					( Origin gBackEnd )
				)
				( attribute "RELATIVE_PROPAGATION_DELAY" ",5.00 MIL"
					( Parent
						( matchGroupRef "@baseboard_fab2_lib.baseboard_fab2(sch_1):\MG_DQ-DQS_NEAR_DIMM_NG_M_B_BYTE1\" )
					)
					( Units "uMatchProp" "ns" 1.000000)
					( Status sCSetFlattened )
					( Origin gBackEnd )
				)
			)
			( pinPair "@baseboard_fab2_lib.baseboard_fab2(sch_1):\PP544\"
				( pinRef "@baseboard_fab2_lib.baseboard_fab2(sch_1):page24_i172:DDR1_DQS_DP(2)" )
				( pinRef "@baseboard_fab2_lib.baseboard_fab2(sch_1):page45_i61:DQS2P" )
				( attribute "RELATIVE_PROPAGATION_DELAY_SCOPE" "G"
					( Parent
						( matchGroupRef "@baseboard_fab2_lib.baseboard_fab2(sch_1):\MG_DQ-DQS_FAR_DIMM_NG_M_B_BYTE2\" )
					)
					( Status sCSetFlattened )
					( Origin gBackEnd )
				)
				( attribute "RELATIVE_PROPAGATION_DELAY" ",5.00 MIL"
					( Parent
						( matchGroupRef "@baseboard_fab2_lib.baseboard_fab2(sch_1):\MG_DQ-DQS_FAR_DIMM_NG_M_B_BYTE2\" )
					)
					( Units "uMatchProp" "ns" 1.000000)
					( Status sCSetFlattened )
					( Origin gBackEnd )
				)
			)
			( pinPair "@baseboard_fab2_lib.baseboard_fab2(sch_1):\PP545\"
				( pinRef "@baseboard_fab2_lib.baseboard_fab2(sch_1):page24_i172:DDR1_DQS_DP(2)" )
				( pinRef "@baseboard_fab2_lib.baseboard_fab2(sch_1):page46_i112:DQS2P" )
				( attribute "RELATIVE_PROPAGATION_DELAY_SCOPE" "G"
					( Parent
						( matchGroupRef "@baseboard_fab2_lib.baseboard_fab2(sch_1):\MG_DQ-DQS_NEAR_DIMM_NG_M_B_BYTE2\" )
					)
					( Status sCSetFlattened )
					( Origin gBackEnd )
				)
				( attribute "RELATIVE_PROPAGATION_DELAY" ",5.00 MIL"
					( Parent
						( matchGroupRef "@baseboard_fab2_lib.baseboard_fab2(sch_1):\MG_DQ-DQS_NEAR_DIMM_NG_M_B_BYTE2\" )
					)
					( Units "uMatchProp" "ns" 1.000000)
					( Status sCSetFlattened )
					( Origin gBackEnd )
				)
			)
			( pinPair "@baseboard_fab2_lib.baseboard_fab2(sch_1):\PP532\"
				( pinRef "@baseboard_fab2_lib.baseboard_fab2(sch_1):page24_i172:DDR1_DQS_DP(3)" )
				( pinRef "@baseboard_fab2_lib.baseboard_fab2(sch_1):page45_i61:DQS3P" )
				( attribute "RELATIVE_PROPAGATION_DELAY_SCOPE" "G"
					( Parent
						( matchGroupRef "@baseboard_fab2_lib.baseboard_fab2(sch_1):\MG_DQ-DQS_FAR_DIMM_NG_M_B_BYTE3\" )
					)
					( Status sCSetFlattened )
					( Origin gBackEnd )
				)
				( attribute "RELATIVE_PROPAGATION_DELAY" ",5.00 MIL"
					( Parent
						( matchGroupRef "@baseboard_fab2_lib.baseboard_fab2(sch_1):\MG_DQ-DQS_FAR_DIMM_NG_M_B_BYTE3\" )
					)
					( Units "uMatchProp" "ns" 1.000000)
					( Status sCSetFlattened )
					( Origin gBackEnd )
				)
			)
			( pinPair "@baseboard_fab2_lib.baseboard_fab2(sch_1):\PP533\"
				( pinRef "@baseboard_fab2_lib.baseboard_fab2(sch_1):page24_i172:DDR1_DQS_DP(3)" )
				( pinRef "@baseboard_fab2_lib.baseboard_fab2(sch_1):page46_i112:DQS3P" )
				( attribute "RELATIVE_PROPAGATION_DELAY_SCOPE" "G"
					( Parent
						( matchGroupRef "@baseboard_fab2_lib.baseboard_fab2(sch_1):\MG_DQ-DQS_NEAR_DIMM_NG_M_B_BYTE3\" )
					)
					( Status sCSetFlattened )
					( Origin gBackEnd )
				)
				( attribute "RELATIVE_PROPAGATION_DELAY" ",5.00 MIL"
					( Parent
						( matchGroupRef "@baseboard_fab2_lib.baseboard_fab2(sch_1):\MG_DQ-DQS_NEAR_DIMM_NG_M_B_BYTE3\" )
					)
					( Units "uMatchProp" "ns" 1.000000)
					( Status sCSetFlattened )
					( Origin gBackEnd )
				)
			)
			( pinPair "@baseboard_fab2_lib.baseboard_fab2(sch_1):\PP520\"
				( pinRef "@baseboard_fab2_lib.baseboard_fab2(sch_1):page24_i172:DDR1_DQS_DP(4)" )
				( pinRef "@baseboard_fab2_lib.baseboard_fab2(sch_1):page45_i61:DQS4P" )
				( attribute "RELATIVE_PROPAGATION_DELAY_SCOPE" "G"
					( Parent
						( matchGroupRef "@baseboard_fab2_lib.baseboard_fab2(sch_1):\MG_DQ-DQS_FAR_DIMM_NG_M_B_BYTE4\" )
					)
					( Status sCSetFlattened )
					( Origin gBackEnd )
				)
				( attribute "RELATIVE_PROPAGATION_DELAY" ",5.00 MIL"
					( Parent
						( matchGroupRef "@baseboard_fab2_lib.baseboard_fab2(sch_1):\MG_DQ-DQS_FAR_DIMM_NG_M_B_BYTE4\" )
					)
					( Units "uMatchProp" "ns" 1.000000)
					( Status sCSetFlattened )
					( Origin gBackEnd )
				)
			)
			( pinPair "@baseboard_fab2_lib.baseboard_fab2(sch_1):\PP522\"
				( pinRef "@baseboard_fab2_lib.baseboard_fab2(sch_1):page24_i172:DDR1_DQS_DP(4)" )
				( pinRef "@baseboard_fab2_lib.baseboard_fab2(sch_1):page46_i112:DQS4P" )
				( attribute "RELATIVE_PROPAGATION_DELAY_SCOPE" "G"
					( Parent
						( matchGroupRef "@baseboard_fab2_lib.baseboard_fab2(sch_1):\MG_DQ-DQS_NEAR_DIMM_NG_M_B_BYTE4\" )
					)
					( Status sCSetFlattened )
					( Origin gBackEnd )
				)
				( attribute "RELATIVE_PROPAGATION_DELAY" ",5.00 MIL"
					( Parent
						( matchGroupRef "@baseboard_fab2_lib.baseboard_fab2(sch_1):\MG_DQ-DQS_NEAR_DIMM_NG_M_B_BYTE4\" )
					)
					( Units "uMatchProp" "ns" 1.000000)
					( Status sCSetFlattened )
					( Origin gBackEnd )
				)
			)
			( pinPair "@baseboard_fab2_lib.baseboard_fab2(sch_1):\PP508\"
				( pinRef "@baseboard_fab2_lib.baseboard_fab2(sch_1):page24_i172:DDR1_DQS_DP(5)" )
				( pinRef "@baseboard_fab2_lib.baseboard_fab2(sch_1):page45_i61:DQS5P" )
				( attribute "RELATIVE_PROPAGATION_DELAY_SCOPE" "G"
					( Parent
						( matchGroupRef "@baseboard_fab2_lib.baseboard_fab2(sch_1):\MG_DQ-DQS_FAR_DIMM_NG_M_B_BYTE5\" )
					)
					( Status sCSetFlattened )
					( Origin gBackEnd )
				)
				( attribute "RELATIVE_PROPAGATION_DELAY" ",5.00 MIL"
					( Parent
						( matchGroupRef "@baseboard_fab2_lib.baseboard_fab2(sch_1):\MG_DQ-DQS_FAR_DIMM_NG_M_B_BYTE5\" )
					)
					( Units "uMatchProp" "ns" 1.000000)
					( Status sCSetFlattened )
					( Origin gBackEnd )
				)
			)
			( pinPair "@baseboard_fab2_lib.baseboard_fab2(sch_1):\PP509\"
				( pinRef "@baseboard_fab2_lib.baseboard_fab2(sch_1):page24_i172:DDR1_DQS_DP(5)" )
				( pinRef "@baseboard_fab2_lib.baseboard_fab2(sch_1):page46_i112:DQS5P" )
				( attribute "RELATIVE_PROPAGATION_DELAY_SCOPE" "G"
					( Parent
						( matchGroupRef "@baseboard_fab2_lib.baseboard_fab2(sch_1):\MG_DQ-DQS_NEAR_DIMM_NG_M_B_BYTE5\" )
					)
					( Status sCSetFlattened )
					( Origin gBackEnd )
				)
				( attribute "RELATIVE_PROPAGATION_DELAY" ",5.00 MIL"
					( Parent
						( matchGroupRef "@baseboard_fab2_lib.baseboard_fab2(sch_1):\MG_DQ-DQS_NEAR_DIMM_NG_M_B_BYTE5\" )
					)
					( Units "uMatchProp" "ns" 1.000000)
					( Status sCSetFlattened )
					( Origin gBackEnd )
				)
			)
			( pinPair "@baseboard_fab2_lib.baseboard_fab2(sch_1):\PP496\"
				( pinRef "@baseboard_fab2_lib.baseboard_fab2(sch_1):page24_i172:DDR1_DQS_DP(6)" )
				( pinRef "@baseboard_fab2_lib.baseboard_fab2(sch_1):page45_i61:DQS6P" )
				( attribute "RELATIVE_PROPAGATION_DELAY_SCOPE" "G"
					( Parent
						( matchGroupRef "@baseboard_fab2_lib.baseboard_fab2(sch_1):\MG_DQ-DQS_FAR_DIMM_NG_M_B_BYTE6\" )
					)
					( Status sCSetFlattened )
					( Origin gBackEnd )
				)
				( attribute "RELATIVE_PROPAGATION_DELAY" ",5.00 MIL"
					( Parent
						( matchGroupRef "@baseboard_fab2_lib.baseboard_fab2(sch_1):\MG_DQ-DQS_FAR_DIMM_NG_M_B_BYTE6\" )
					)
					( Units "uMatchProp" "ns" 1.000000)
					( Status sCSetFlattened )
					( Origin gBackEnd )
				)
			)
			( pinPair "@baseboard_fab2_lib.baseboard_fab2(sch_1):\PP497\"
				( pinRef "@baseboard_fab2_lib.baseboard_fab2(sch_1):page24_i172:DDR1_DQS_DP(6)" )
				( pinRef "@baseboard_fab2_lib.baseboard_fab2(sch_1):page46_i112:DQS6P" )
				( attribute "RELATIVE_PROPAGATION_DELAY_SCOPE" "G"
					( Parent
						( matchGroupRef "@baseboard_fab2_lib.baseboard_fab2(sch_1):\MG_DQ-DQS_NEAR_DIMM_NG_M_B_BYTE6\" )
					)
					( Status sCSetFlattened )
					( Origin gBackEnd )
				)
				( attribute "RELATIVE_PROPAGATION_DELAY" ",5.00 MIL"
					( Parent
						( matchGroupRef "@baseboard_fab2_lib.baseboard_fab2(sch_1):\MG_DQ-DQS_NEAR_DIMM_NG_M_B_BYTE6\" )
					)
					( Units "uMatchProp" "ns" 1.000000)
					( Status sCSetFlattened )
					( Origin gBackEnd )
				)
			)
			( pinPair "@baseboard_fab2_lib.baseboard_fab2(sch_1):\PP484\"
				( pinRef "@baseboard_fab2_lib.baseboard_fab2(sch_1):page24_i172:DDR1_DQS_DP(7)" )
				( pinRef "@baseboard_fab2_lib.baseboard_fab2(sch_1):page45_i61:DQS7P" )
				( attribute "RELATIVE_PROPAGATION_DELAY_SCOPE" "G"
					( Parent
						( matchGroupRef "@baseboard_fab2_lib.baseboard_fab2(sch_1):\MG_DQ-DQS_FAR_DIMM_NG_M_B_BYTE7\" )
					)
					( Status sCSetFlattened )
					( Origin gBackEnd )
				)
				( attribute "RELATIVE_PROPAGATION_DELAY" ",5.00 MIL"
					( Parent
						( matchGroupRef "@baseboard_fab2_lib.baseboard_fab2(sch_1):\MG_DQ-DQS_FAR_DIMM_NG_M_B_BYTE7\" )
					)
					( Units "uMatchProp" "ns" 1.000000)
					( Status sCSetFlattened )
					( Origin gBackEnd )
				)
			)
			( pinPair "@baseboard_fab2_lib.baseboard_fab2(sch_1):\PP486\"
				( pinRef "@baseboard_fab2_lib.baseboard_fab2(sch_1):page24_i172:DDR1_DQS_DP(7)" )
				( pinRef "@baseboard_fab2_lib.baseboard_fab2(sch_1):page46_i112:DQS7P" )
				( attribute "RELATIVE_PROPAGATION_DELAY_SCOPE" "G"
					( Parent
						( matchGroupRef "@baseboard_fab2_lib.baseboard_fab2(sch_1):\MG_DQ-DQS_NEAR_DIMM_NG_M_B_BYTE7\" )
					)
					( Status sCSetFlattened )
					( Origin gBackEnd )
				)
				( attribute "RELATIVE_PROPAGATION_DELAY" ",5.00 MIL"
					( Parent
						( matchGroupRef "@baseboard_fab2_lib.baseboard_fab2(sch_1):\MG_DQ-DQS_NEAR_DIMM_NG_M_B_BYTE7\" )
					)
					( Units "uMatchProp" "ns" 1.000000)
					( Status sCSetFlattened )
					( Origin gBackEnd )
				)
			)
			( pinPair "@baseboard_fab2_lib.baseboard_fab2(sch_1):\PP1228\"
				( pinRef "@baseboard_fab2_lib.baseboard_fab2(sch_1):page24_i172:DDR1_DQS_DP(8)" )
				( pinRef "@baseboard_fab2_lib.baseboard_fab2(sch_1):page45_i61:DQS8P" )
				( attribute "RELATIVE_PROPAGATION_DELAY_SCOPE" "G"
					( Parent
						( matchGroupRef "@baseboard_fab2_lib.baseboard_fab2(sch_1):\MG_DQ-DQS_FAR_DIMM_NG_M_B_BYTE-ECC\" )
					)
					( Status sCSetFlattened )
					( Origin gBackEnd )
				)
				( attribute "RELATIVE_PROPAGATION_DELAY" ",5.00 MIL"
					( Parent
						( matchGroupRef "@baseboard_fab2_lib.baseboard_fab2(sch_1):\MG_DQ-DQS_FAR_DIMM_NG_M_B_BYTE-ECC\" )
					)
					( Units "uMatchProp" "ns" 1.000000)
					( Status sCSetFlattened )
					( Origin gBackEnd )
				)
			)
			( pinPair "@baseboard_fab2_lib.baseboard_fab2(sch_1):\PP1229\"
				( pinRef "@baseboard_fab2_lib.baseboard_fab2(sch_1):page24_i172:DDR1_DQS_DP(8)" )
				( pinRef "@baseboard_fab2_lib.baseboard_fab2(sch_1):page46_i112:DQS8P" )
				( attribute "RELATIVE_PROPAGATION_DELAY_SCOPE" "G"
					( Parent
						( matchGroupRef "@baseboard_fab2_lib.baseboard_fab2(sch_1):\MG_DQ-DQS_NEAR_DIMM_NG_M_B_BYTE-ECC\" )
					)
					( Status sCSetFlattened )
					( Origin gBackEnd )
				)
				( attribute "RELATIVE_PROPAGATION_DELAY" ",5.00 MIL"
					( Parent
						( matchGroupRef "@baseboard_fab2_lib.baseboard_fab2(sch_1):\MG_DQ-DQS_NEAR_DIMM_NG_M_B_BYTE-ECC\" )
					)
					( Units "uMatchProp" "ns" 1.000000)
					( Status sCSetFlattened )
					( Origin gBackEnd )
				)
			)
			( pinPair "@baseboard_fab2_lib.baseboard_fab2(sch_1):\PP562\"
				( pinRef "@baseboard_fab2_lib.baseboard_fab2(sch_1):page24_i172:DDR1_DQS_DP(9)" )
				( pinRef "@baseboard_fab2_lib.baseboard_fab2(sch_1):page45_i61:DQS9P" )
				( attribute "RELATIVE_PROPAGATION_DELAY_SCOPE" "G"
					( Parent
						( matchGroupRef "@baseboard_fab2_lib.baseboard_fab2(sch_1):\MG_DQ-DQS_FAR_DIMM_NG_M_B_BYTE0\" )
					)
					( Status sCSetFlattened )
					( Origin gBackEnd )
				)
				( attribute "RELATIVE_PROPAGATION_DELAY" ",5.00 MIL"
					( Parent
						( matchGroupRef "@baseboard_fab2_lib.baseboard_fab2(sch_1):\MG_DQ-DQS_FAR_DIMM_NG_M_B_BYTE0\" )
					)
					( Units "uMatchProp" "ns" 1.000000)
					( Status sCSetFlattened )
					( Origin gBackEnd )
				)
			)
			( pinPair "@baseboard_fab2_lib.baseboard_fab2(sch_1):\PP563\"
				( pinRef "@baseboard_fab2_lib.baseboard_fab2(sch_1):page24_i172:DDR1_DQS_DP(9)" )
				( pinRef "@baseboard_fab2_lib.baseboard_fab2(sch_1):page46_i112:DQS9P" )
				( attribute "RELATIVE_PROPAGATION_DELAY_SCOPE" "G"
					( Parent
						( matchGroupRef "@baseboard_fab2_lib.baseboard_fab2(sch_1):\MG_DQ-DQS_NEAR_DIMM_NG_M_B_BYTE0\" )
					)
					( Status sCSetFlattened )
					( Origin gBackEnd )
				)
				( attribute "RELATIVE_PROPAGATION_DELAY" ",5.00 MIL"
					( Parent
						( matchGroupRef "@baseboard_fab2_lib.baseboard_fab2(sch_1):\MG_DQ-DQS_NEAR_DIMM_NG_M_B_BYTE0\" )
					)
					( Units "uMatchProp" "ns" 1.000000)
					( Status sCSetFlattened )
					( Origin gBackEnd )
				)
			)
			( pinPair "@baseboard_fab2_lib.baseboard_fab2(sch_1):\PP550\"
				( pinRef "@baseboard_fab2_lib.baseboard_fab2(sch_1):page24_i172:DDR1_DQS_DP(10)" )
				( pinRef "@baseboard_fab2_lib.baseboard_fab2(sch_1):page45_i61:DQS10P" )
				( attribute "RELATIVE_PROPAGATION_DELAY_SCOPE" "G"
					( Parent
						( matchGroupRef "@baseboard_fab2_lib.baseboard_fab2(sch_1):\MG_DQ-DQS_FAR_DIMM_NG_M_B_BYTE1\" )
					)
					( Status sCSetFlattened )
					( Origin gBackEnd )
				)
				( attribute "RELATIVE_PROPAGATION_DELAY" ",5.00 MIL"
					( Parent
						( matchGroupRef "@baseboard_fab2_lib.baseboard_fab2(sch_1):\MG_DQ-DQS_FAR_DIMM_NG_M_B_BYTE1\" )
					)
					( Units "uMatchProp" "ns" 1.000000)
					( Status sCSetFlattened )
					( Origin gBackEnd )
				)
			)
			( pinPair "@baseboard_fab2_lib.baseboard_fab2(sch_1):\PP551\"
				( pinRef "@baseboard_fab2_lib.baseboard_fab2(sch_1):page24_i172:DDR1_DQS_DP(10)" )
				( pinRef "@baseboard_fab2_lib.baseboard_fab2(sch_1):page46_i112:DQS10P" )
				( attribute "RELATIVE_PROPAGATION_DELAY_SCOPE" "G"
					( Parent
						( matchGroupRef "@baseboard_fab2_lib.baseboard_fab2(sch_1):\MG_DQ-DQS_NEAR_DIMM_NG_M_B_BYTE1\" )
					)
					( Status sCSetFlattened )
					( Origin gBackEnd )
				)
				( attribute "RELATIVE_PROPAGATION_DELAY" ",5.00 MIL"
					( Parent
						( matchGroupRef "@baseboard_fab2_lib.baseboard_fab2(sch_1):\MG_DQ-DQS_NEAR_DIMM_NG_M_B_BYTE1\" )
					)
					( Units "uMatchProp" "ns" 1.000000)
					( Status sCSetFlattened )
					( Origin gBackEnd )
				)
			)
			( pinPair "@baseboard_fab2_lib.baseboard_fab2(sch_1):\PP538\"
				( pinRef "@baseboard_fab2_lib.baseboard_fab2(sch_1):page24_i172:DDR1_DQS_DP(11)" )
				( pinRef "@baseboard_fab2_lib.baseboard_fab2(sch_1):page45_i61:DQS11P" )
				( attribute "RELATIVE_PROPAGATION_DELAY_SCOPE" "G"
					( Parent
						( matchGroupRef "@baseboard_fab2_lib.baseboard_fab2(sch_1):\MG_DQ-DQS_FAR_DIMM_NG_M_B_BYTE2\" )
					)
					( Status sCSetFlattened )
					( Origin gBackEnd )
				)
				( attribute "RELATIVE_PROPAGATION_DELAY" ",5.00 MIL"
					( Parent
						( matchGroupRef "@baseboard_fab2_lib.baseboard_fab2(sch_1):\MG_DQ-DQS_FAR_DIMM_NG_M_B_BYTE2\" )
					)
					( Units "uMatchProp" "ns" 1.000000)
					( Status sCSetFlattened )
					( Origin gBackEnd )
				)
			)
			( pinPair "@baseboard_fab2_lib.baseboard_fab2(sch_1):\PP539\"
				( pinRef "@baseboard_fab2_lib.baseboard_fab2(sch_1):page24_i172:DDR1_DQS_DP(11)" )
				( pinRef "@baseboard_fab2_lib.baseboard_fab2(sch_1):page46_i112:DQS11P" )
				( attribute "RELATIVE_PROPAGATION_DELAY_SCOPE" "G"
					( Parent
						( matchGroupRef "@baseboard_fab2_lib.baseboard_fab2(sch_1):\MG_DQ-DQS_NEAR_DIMM_NG_M_B_BYTE2\" )
					)
					( Status sCSetFlattened )
					( Origin gBackEnd )
				)
				( attribute "RELATIVE_PROPAGATION_DELAY" ",5.00 MIL"
					( Parent
						( matchGroupRef "@baseboard_fab2_lib.baseboard_fab2(sch_1):\MG_DQ-DQS_NEAR_DIMM_NG_M_B_BYTE2\" )
					)
					( Units "uMatchProp" "ns" 1.000000)
					( Status sCSetFlattened )
					( Origin gBackEnd )
				)
			)
			( pinPair "@baseboard_fab2_lib.baseboard_fab2(sch_1):\PP526\"
				( pinRef "@baseboard_fab2_lib.baseboard_fab2(sch_1):page24_i172:DDR1_DQS_DP(12)" )
				( pinRef "@baseboard_fab2_lib.baseboard_fab2(sch_1):page45_i61:DQS12P" )
				( attribute "RELATIVE_PROPAGATION_DELAY_SCOPE" "G"
					( Parent
						( matchGroupRef "@baseboard_fab2_lib.baseboard_fab2(sch_1):\MG_DQ-DQS_FAR_DIMM_NG_M_B_BYTE3\" )
					)
					( Status sCSetFlattened )
					( Origin gBackEnd )
				)
				( attribute "RELATIVE_PROPAGATION_DELAY" ",5.00 MIL"
					( Parent
						( matchGroupRef "@baseboard_fab2_lib.baseboard_fab2(sch_1):\MG_DQ-DQS_FAR_DIMM_NG_M_B_BYTE3\" )
					)
					( Units "uMatchProp" "ns" 1.000000)
					( Status sCSetFlattened )
					( Origin gBackEnd )
				)
			)
			( pinPair "@baseboard_fab2_lib.baseboard_fab2(sch_1):\PP527\"
				( pinRef "@baseboard_fab2_lib.baseboard_fab2(sch_1):page24_i172:DDR1_DQS_DP(12)" )
				( pinRef "@baseboard_fab2_lib.baseboard_fab2(sch_1):page46_i112:DQS12P" )
				( attribute "RELATIVE_PROPAGATION_DELAY_SCOPE" "G"
					( Parent
						( matchGroupRef "@baseboard_fab2_lib.baseboard_fab2(sch_1):\MG_DQ-DQS_NEAR_DIMM_NG_M_B_BYTE3\" )
					)
					( Status sCSetFlattened )
					( Origin gBackEnd )
				)
				( attribute "RELATIVE_PROPAGATION_DELAY" ",5.00 MIL"
					( Parent
						( matchGroupRef "@baseboard_fab2_lib.baseboard_fab2(sch_1):\MG_DQ-DQS_NEAR_DIMM_NG_M_B_BYTE3\" )
					)
					( Units "uMatchProp" "ns" 1.000000)
					( Status sCSetFlattened )
					( Origin gBackEnd )
				)
			)
			( pinPair "@baseboard_fab2_lib.baseboard_fab2(sch_1):\PP514\"
				( pinRef "@baseboard_fab2_lib.baseboard_fab2(sch_1):page24_i172:DDR1_DQS_DP(13)" )
				( pinRef "@baseboard_fab2_lib.baseboard_fab2(sch_1):page45_i61:DQS13P" )
				( attribute "RELATIVE_PROPAGATION_DELAY_SCOPE" "G"
					( Parent
						( matchGroupRef "@baseboard_fab2_lib.baseboard_fab2(sch_1):\MG_DQ-DQS_FAR_DIMM_NG_M_B_BYTE4\" )
					)
					( Status sCSetFlattened )
					( Origin gBackEnd )
				)
				( attribute "RELATIVE_PROPAGATION_DELAY" ",5.00 MIL"
					( Parent
						( matchGroupRef "@baseboard_fab2_lib.baseboard_fab2(sch_1):\MG_DQ-DQS_FAR_DIMM_NG_M_B_BYTE4\" )
					)
					( Units "uMatchProp" "ns" 1.000000)
					( Status sCSetFlattened )
					( Origin gBackEnd )
				)
			)
			( pinPair "@baseboard_fab2_lib.baseboard_fab2(sch_1):\PP516\"
				( pinRef "@baseboard_fab2_lib.baseboard_fab2(sch_1):page24_i172:DDR1_DQS_DP(13)" )
				( pinRef "@baseboard_fab2_lib.baseboard_fab2(sch_1):page46_i112:DQS13P" )
				( attribute "RELATIVE_PROPAGATION_DELAY_SCOPE" "G"
					( Parent
						( matchGroupRef "@baseboard_fab2_lib.baseboard_fab2(sch_1):\MG_DQ-DQS_NEAR_DIMM_NG_M_B_BYTE4\" )
					)
					( Status sCSetFlattened )
					( Origin gBackEnd )
				)
				( attribute "RELATIVE_PROPAGATION_DELAY" ",5.00 MIL"
					( Parent
						( matchGroupRef "@baseboard_fab2_lib.baseboard_fab2(sch_1):\MG_DQ-DQS_NEAR_DIMM_NG_M_B_BYTE4\" )
					)
					( Units "uMatchProp" "ns" 1.000000)
					( Status sCSetFlattened )
					( Origin gBackEnd )
				)
			)
			( pinPair "@baseboard_fab2_lib.baseboard_fab2(sch_1):\PP502\"
				( pinRef "@baseboard_fab2_lib.baseboard_fab2(sch_1):page24_i172:DDR1_DQS_DP(14)" )
				( pinRef "@baseboard_fab2_lib.baseboard_fab2(sch_1):page45_i61:DQS14P" )
				( attribute "RELATIVE_PROPAGATION_DELAY_SCOPE" "G"
					( Parent
						( matchGroupRef "@baseboard_fab2_lib.baseboard_fab2(sch_1):\MG_DQ-DQS_FAR_DIMM_NG_M_B_BYTE5\" )
					)
					( Status sCSetFlattened )
					( Origin gBackEnd )
				)
				( attribute "RELATIVE_PROPAGATION_DELAY" ",5.00 MIL"
					( Parent
						( matchGroupRef "@baseboard_fab2_lib.baseboard_fab2(sch_1):\MG_DQ-DQS_FAR_DIMM_NG_M_B_BYTE5\" )
					)
					( Units "uMatchProp" "ns" 1.000000)
					( Status sCSetFlattened )
					( Origin gBackEnd )
				)
			)
			( pinPair "@baseboard_fab2_lib.baseboard_fab2(sch_1):\PP503\"
				( pinRef "@baseboard_fab2_lib.baseboard_fab2(sch_1):page24_i172:DDR1_DQS_DP(14)" )
				( pinRef "@baseboard_fab2_lib.baseboard_fab2(sch_1):page46_i112:DQS14P" )
				( attribute "RELATIVE_PROPAGATION_DELAY_SCOPE" "G"
					( Parent
						( matchGroupRef "@baseboard_fab2_lib.baseboard_fab2(sch_1):\MG_DQ-DQS_NEAR_DIMM_NG_M_B_BYTE5\" )
					)
					( Status sCSetFlattened )
					( Origin gBackEnd )
				)
				( attribute "RELATIVE_PROPAGATION_DELAY" ",5.00 MIL"
					( Parent
						( matchGroupRef "@baseboard_fab2_lib.baseboard_fab2(sch_1):\MG_DQ-DQS_NEAR_DIMM_NG_M_B_BYTE5\" )
					)
					( Units "uMatchProp" "ns" 1.000000)
					( Status sCSetFlattened )
					( Origin gBackEnd )
				)
			)
			( pinPair "@baseboard_fab2_lib.baseboard_fab2(sch_1):\PP490\"
				( pinRef "@baseboard_fab2_lib.baseboard_fab2(sch_1):page24_i172:DDR1_DQS_DP(15)" )
				( pinRef "@baseboard_fab2_lib.baseboard_fab2(sch_1):page45_i61:DQS15P" )
				( attribute "RELATIVE_PROPAGATION_DELAY_SCOPE" "G"
					( Parent
						( matchGroupRef "@baseboard_fab2_lib.baseboard_fab2(sch_1):\MG_DQ-DQS_FAR_DIMM_NG_M_B_BYTE6\" )
					)
					( Status sCSetFlattened )
					( Origin gBackEnd )
				)
				( attribute "RELATIVE_PROPAGATION_DELAY" ",5.00 MIL"
					( Parent
						( matchGroupRef "@baseboard_fab2_lib.baseboard_fab2(sch_1):\MG_DQ-DQS_FAR_DIMM_NG_M_B_BYTE6\" )
					)
					( Units "uMatchProp" "ns" 1.000000)
					( Status sCSetFlattened )
					( Origin gBackEnd )
				)
			)
			( pinPair "@baseboard_fab2_lib.baseboard_fab2(sch_1):\PP491\"
				( pinRef "@baseboard_fab2_lib.baseboard_fab2(sch_1):page24_i172:DDR1_DQS_DP(15)" )
				( pinRef "@baseboard_fab2_lib.baseboard_fab2(sch_1):page46_i112:DQS15P" )
				( attribute "RELATIVE_PROPAGATION_DELAY_SCOPE" "G"
					( Parent
						( matchGroupRef "@baseboard_fab2_lib.baseboard_fab2(sch_1):\MG_DQ-DQS_NEAR_DIMM_NG_M_B_BYTE6\" )
					)
					( Status sCSetFlattened )
					( Origin gBackEnd )
				)
				( attribute "RELATIVE_PROPAGATION_DELAY" ",5.00 MIL"
					( Parent
						( matchGroupRef "@baseboard_fab2_lib.baseboard_fab2(sch_1):\MG_DQ-DQS_NEAR_DIMM_NG_M_B_BYTE6\" )
					)
					( Units "uMatchProp" "ns" 1.000000)
					( Status sCSetFlattened )
					( Origin gBackEnd )
				)
			)
			( pinPair "@baseboard_fab2_lib.baseboard_fab2(sch_1):\PP478\"
				( pinRef "@baseboard_fab2_lib.baseboard_fab2(sch_1):page24_i172:DDR1_DQS_DP(16)" )
				( pinRef "@baseboard_fab2_lib.baseboard_fab2(sch_1):page45_i61:DQS16P" )
				( attribute "RELATIVE_PROPAGATION_DELAY_SCOPE" "G"
					( Parent
						( matchGroupRef "@baseboard_fab2_lib.baseboard_fab2(sch_1):\MG_DQ-DQS_FAR_DIMM_NG_M_B_BYTE7\" )
					)
					( Status sCSetFlattened )
					( Origin gBackEnd )
				)
				( attribute "RELATIVE_PROPAGATION_DELAY" ",5.00 MIL"
					( Parent
						( matchGroupRef "@baseboard_fab2_lib.baseboard_fab2(sch_1):\MG_DQ-DQS_FAR_DIMM_NG_M_B_BYTE7\" )
					)
					( Units "uMatchProp" "ns" 1.000000)
					( Status sCSetFlattened )
					( Origin gBackEnd )
				)
			)
			( pinPair "@baseboard_fab2_lib.baseboard_fab2(sch_1):\PP480\"
				( pinRef "@baseboard_fab2_lib.baseboard_fab2(sch_1):page24_i172:DDR1_DQS_DP(16)" )
				( pinRef "@baseboard_fab2_lib.baseboard_fab2(sch_1):page46_i112:DQS16P" )
				( attribute "RELATIVE_PROPAGATION_DELAY_SCOPE" "G"
					( Parent
						( matchGroupRef "@baseboard_fab2_lib.baseboard_fab2(sch_1):\MG_DQ-DQS_NEAR_DIMM_NG_M_B_BYTE7\" )
					)
					( Status sCSetFlattened )
					( Origin gBackEnd )
				)
				( attribute "RELATIVE_PROPAGATION_DELAY" ",5.00 MIL"
					( Parent
						( matchGroupRef "@baseboard_fab2_lib.baseboard_fab2(sch_1):\MG_DQ-DQS_NEAR_DIMM_NG_M_B_BYTE7\" )
					)
					( Units "uMatchProp" "ns" 1.000000)
					( Status sCSetFlattened )
					( Origin gBackEnd )
				)
			)
			( pinPair "@baseboard_fab2_lib.baseboard_fab2(sch_1):\PP1222\"
				( pinRef "@baseboard_fab2_lib.baseboard_fab2(sch_1):page24_i172:DDR1_DQS_DP(17)" )
				( pinRef "@baseboard_fab2_lib.baseboard_fab2(sch_1):page45_i61:DQS17P" )
				( attribute "RELATIVE_PROPAGATION_DELAY_SCOPE" "G"
					( Parent
						( matchGroupRef "@baseboard_fab2_lib.baseboard_fab2(sch_1):\MG_DQ-DQS_FAR_DIMM_NG_M_B_BYTE-ECC\" )
					)
					( Status sCSetFlattened )
					( Origin gBackEnd )
				)
				( attribute "RELATIVE_PROPAGATION_DELAY" ",5.00 MIL"
					( Parent
						( matchGroupRef "@baseboard_fab2_lib.baseboard_fab2(sch_1):\MG_DQ-DQS_FAR_DIMM_NG_M_B_BYTE-ECC\" )
					)
					( Units "uMatchProp" "ns" 1.000000)
					( Status sCSetFlattened )
					( Origin gBackEnd )
				)
			)
			( pinPair "@baseboard_fab2_lib.baseboard_fab2(sch_1):\PP1223\"
				( pinRef "@baseboard_fab2_lib.baseboard_fab2(sch_1):page24_i172:DDR1_DQS_DP(17)" )
				( pinRef "@baseboard_fab2_lib.baseboard_fab2(sch_1):page46_i112:DQS17P" )
				( attribute "RELATIVE_PROPAGATION_DELAY_SCOPE" "G"
					( Parent
						( matchGroupRef "@baseboard_fab2_lib.baseboard_fab2(sch_1):\MG_DQ-DQS_NEAR_DIMM_NG_M_B_BYTE-ECC\" )
					)
					( Status sCSetFlattened )
					( Origin gBackEnd )
				)
				( attribute "RELATIVE_PROPAGATION_DELAY" ",5.00 MIL"
					( Parent
						( matchGroupRef "@baseboard_fab2_lib.baseboard_fab2(sch_1):\MG_DQ-DQS_NEAR_DIMM_NG_M_B_BYTE-ECC\" )
					)
					( Units "uMatchProp" "ns" 1.000000)
					( Status sCSetFlattened )
					( Origin gBackEnd )
				)
			)
			( pinPair "@baseboard_fab2_lib.baseboard_fab2(sch_1):\PP661\"
				( pinRef "@baseboard_fab2_lib.baseboard_fab2(sch_1):page25_i172:DDR2_DQS_DN(0)" )
				( pinRef "@baseboard_fab2_lib.baseboard_fab2(sch_1):page47_i61:DQS0N" )
				( attribute "RELATIVE_PROPAGATION_DELAY_SCOPE" "G"
					( Parent
						( matchGroupRef "@baseboard_fab2_lib.baseboard_fab2(sch_1):\MG_DQ-DQS_FAR_DIMM_NG_M_C_BYTE0\" )
					)
					( Status sCSetFlattened )
					( Origin gBackEnd )
				)
				( attribute "RELATIVE_PROPAGATION_DELAY" ",5.00 MIL"
					( Parent
						( matchGroupRef "@baseboard_fab2_lib.baseboard_fab2(sch_1):\MG_DQ-DQS_FAR_DIMM_NG_M_C_BYTE0\" )
					)
					( Units "uMatchProp" "ns" 1.000000)
					( Status sCSetFlattened )
					( Origin gBackEnd )
				)
			)
			( pinPair "@baseboard_fab2_lib.baseboard_fab2(sch_1):\PP662\"
				( pinRef "@baseboard_fab2_lib.baseboard_fab2(sch_1):page25_i172:DDR2_DQS_DN(0)" )
				( pinRef "@baseboard_fab2_lib.baseboard_fab2(sch_1):page48_i61:DQS0N" )
				( attribute "RELATIVE_PROPAGATION_DELAY_SCOPE" "G"
					( Parent
						( matchGroupRef "@baseboard_fab2_lib.baseboard_fab2(sch_1):\MG_DQ-DQS_NEAR_DIMM_NG_M_C_BYTE0\" )
					)
					( Status sCSetFlattened )
					( Origin gBackEnd )
				)
				( attribute "RELATIVE_PROPAGATION_DELAY" ",5.00 MIL"
					( Parent
						( matchGroupRef "@baseboard_fab2_lib.baseboard_fab2(sch_1):\MG_DQ-DQS_NEAR_DIMM_NG_M_C_BYTE0\" )
					)
					( Units "uMatchProp" "ns" 1.000000)
					( Status sCSetFlattened )
					( Origin gBackEnd )
				)
			)
			( pinPair "@baseboard_fab2_lib.baseboard_fab2(sch_1):\PP649\"
				( pinRef "@baseboard_fab2_lib.baseboard_fab2(sch_1):page25_i172:DDR2_DQS_DN(1)" )
				( pinRef "@baseboard_fab2_lib.baseboard_fab2(sch_1):page47_i61:DQS1N" )
				( attribute "RELATIVE_PROPAGATION_DELAY_SCOPE" "G"
					( Parent
						( matchGroupRef "@baseboard_fab2_lib.baseboard_fab2(sch_1):\MG_DQ-DQS_FAR_DIMM_NG_M_C_BYTE1\" )
					)
					( Status sCSetFlattened )
					( Origin gBackEnd )
				)
				( attribute "RELATIVE_PROPAGATION_DELAY" ",5.00 MIL"
					( Parent
						( matchGroupRef "@baseboard_fab2_lib.baseboard_fab2(sch_1):\MG_DQ-DQS_FAR_DIMM_NG_M_C_BYTE1\" )
					)
					( Units "uMatchProp" "ns" 1.000000)
					( Status sCSetFlattened )
					( Origin gBackEnd )
				)
			)
			( pinPair "@baseboard_fab2_lib.baseboard_fab2(sch_1):\PP650\"
				( pinRef "@baseboard_fab2_lib.baseboard_fab2(sch_1):page25_i172:DDR2_DQS_DN(1)" )
				( pinRef "@baseboard_fab2_lib.baseboard_fab2(sch_1):page48_i61:DQS1N" )
				( attribute "RELATIVE_PROPAGATION_DELAY_SCOPE" "G"
					( Parent
						( matchGroupRef "@baseboard_fab2_lib.baseboard_fab2(sch_1):\MG_DQ-DQS_NEAR_DIMM_NG_M_C_BYTE1\" )
					)
					( Status sCSetFlattened )
					( Origin gBackEnd )
				)
				( attribute "RELATIVE_PROPAGATION_DELAY" ",5.00 MIL"
					( Parent
						( matchGroupRef "@baseboard_fab2_lib.baseboard_fab2(sch_1):\MG_DQ-DQS_NEAR_DIMM_NG_M_C_BYTE1\" )
					)
					( Units "uMatchProp" "ns" 1.000000)
					( Status sCSetFlattened )
					( Origin gBackEnd )
				)
			)
			( pinPair "@baseboard_fab2_lib.baseboard_fab2(sch_1):\PP637\"
				( pinRef "@baseboard_fab2_lib.baseboard_fab2(sch_1):page25_i172:DDR2_DQS_DN(2)" )
				( pinRef "@baseboard_fab2_lib.baseboard_fab2(sch_1):page47_i61:DQS2N" )
				( attribute "RELATIVE_PROPAGATION_DELAY_SCOPE" "G"
					( Parent
						( matchGroupRef "@baseboard_fab2_lib.baseboard_fab2(sch_1):\MG_DQ-DQS_FAR_DIMM_NG_M_C_BYTE2\" )
					)
					( Status sCSetFlattened )
					( Origin gBackEnd )
				)
				( attribute "RELATIVE_PROPAGATION_DELAY" ",5.00 MIL"
					( Parent
						( matchGroupRef "@baseboard_fab2_lib.baseboard_fab2(sch_1):\MG_DQ-DQS_FAR_DIMM_NG_M_C_BYTE2\" )
					)
					( Units "uMatchProp" "ns" 1.000000)
					( Status sCSetFlattened )
					( Origin gBackEnd )
				)
			)
			( pinPair "@baseboard_fab2_lib.baseboard_fab2(sch_1):\PP638\"
				( pinRef "@baseboard_fab2_lib.baseboard_fab2(sch_1):page25_i172:DDR2_DQS_DN(2)" )
				( pinRef "@baseboard_fab2_lib.baseboard_fab2(sch_1):page48_i61:DQS2N" )
				( attribute "RELATIVE_PROPAGATION_DELAY_SCOPE" "G"
					( Parent
						( matchGroupRef "@baseboard_fab2_lib.baseboard_fab2(sch_1):\MG_DQ-DQS_NEAR_DIMM_NG_M_C_BYTE2\" )
					)
					( Status sCSetFlattened )
					( Origin gBackEnd )
				)
				( attribute "RELATIVE_PROPAGATION_DELAY" ",5.00 MIL"
					( Parent
						( matchGroupRef "@baseboard_fab2_lib.baseboard_fab2(sch_1):\MG_DQ-DQS_NEAR_DIMM_NG_M_C_BYTE2\" )
					)
					( Units "uMatchProp" "ns" 1.000000)
					( Status sCSetFlattened )
					( Origin gBackEnd )
				)
			)
			( pinPair "@baseboard_fab2_lib.baseboard_fab2(sch_1):\PP625\"
				( pinRef "@baseboard_fab2_lib.baseboard_fab2(sch_1):page25_i172:DDR2_DQS_DN(3)" )
				( pinRef "@baseboard_fab2_lib.baseboard_fab2(sch_1):page47_i61:DQS3N" )
				( attribute "RELATIVE_PROPAGATION_DELAY_SCOPE" "G"
					( Parent
						( matchGroupRef "@baseboard_fab2_lib.baseboard_fab2(sch_1):\MG_DQ-DQS_FAR_DIMM_NG_M_C_BYTE3\" )
					)
					( Status sCSetFlattened )
					( Origin gBackEnd )
				)
				( attribute "RELATIVE_PROPAGATION_DELAY" ",5.00 MIL"
					( Parent
						( matchGroupRef "@baseboard_fab2_lib.baseboard_fab2(sch_1):\MG_DQ-DQS_FAR_DIMM_NG_M_C_BYTE3\" )
					)
					( Units "uMatchProp" "ns" 1.000000)
					( Status sCSetFlattened )
					( Origin gBackEnd )
				)
			)
			( pinPair "@baseboard_fab2_lib.baseboard_fab2(sch_1):\PP626\"
				( pinRef "@baseboard_fab2_lib.baseboard_fab2(sch_1):page25_i172:DDR2_DQS_DN(3)" )
				( pinRef "@baseboard_fab2_lib.baseboard_fab2(sch_1):page48_i61:DQS3N" )
				( attribute "RELATIVE_PROPAGATION_DELAY_SCOPE" "G"
					( Parent
						( matchGroupRef "@baseboard_fab2_lib.baseboard_fab2(sch_1):\MG_DQ-DQS_NEAR_DIMM_NG_M_C_BYTE3\" )
					)
					( Status sCSetFlattened )
					( Origin gBackEnd )
				)
				( attribute "RELATIVE_PROPAGATION_DELAY" ",5.00 MIL"
					( Parent
						( matchGroupRef "@baseboard_fab2_lib.baseboard_fab2(sch_1):\MG_DQ-DQS_NEAR_DIMM_NG_M_C_BYTE3\" )
					)
					( Units "uMatchProp" "ns" 1.000000)
					( Status sCSetFlattened )
					( Origin gBackEnd )
				)
			)
			( pinPair "@baseboard_fab2_lib.baseboard_fab2(sch_1):\PP613\"
				( pinRef "@baseboard_fab2_lib.baseboard_fab2(sch_1):page25_i172:DDR2_DQS_DN(4)" )
				( pinRef "@baseboard_fab2_lib.baseboard_fab2(sch_1):page47_i61:DQS4N" )
				( attribute "RELATIVE_PROPAGATION_DELAY_SCOPE" "G"
					( Parent
						( matchGroupRef "@baseboard_fab2_lib.baseboard_fab2(sch_1):\MG_DQ-DQS_FAR_DIMM_NG_M_C_BYTE4\" )
					)
					( Status sCSetFlattened )
					( Origin gBackEnd )
				)
				( attribute "RELATIVE_PROPAGATION_DELAY" ",5.00 MIL"
					( Parent
						( matchGroupRef "@baseboard_fab2_lib.baseboard_fab2(sch_1):\MG_DQ-DQS_FAR_DIMM_NG_M_C_BYTE4\" )
					)
					( Units "uMatchProp" "ns" 1.000000)
					( Status sCSetFlattened )
					( Origin gBackEnd )
				)
			)
			( pinPair "@baseboard_fab2_lib.baseboard_fab2(sch_1):\PP615\"
				( pinRef "@baseboard_fab2_lib.baseboard_fab2(sch_1):page25_i172:DDR2_DQS_DN(4)" )
				( pinRef "@baseboard_fab2_lib.baseboard_fab2(sch_1):page48_i61:DQS4N" )
				( attribute "RELATIVE_PROPAGATION_DELAY_SCOPE" "G"
					( Parent
						( matchGroupRef "@baseboard_fab2_lib.baseboard_fab2(sch_1):\MG_DQ-DQS_NEAR_DIMM_NG_M_C_BYTE4\" )
					)
					( Status sCSetFlattened )
					( Origin gBackEnd )
				)
				( attribute "RELATIVE_PROPAGATION_DELAY" ",5.00 MIL"
					( Parent
						( matchGroupRef "@baseboard_fab2_lib.baseboard_fab2(sch_1):\MG_DQ-DQS_NEAR_DIMM_NG_M_C_BYTE4\" )
					)
					( Units "uMatchProp" "ns" 1.000000)
					( Status sCSetFlattened )
					( Origin gBackEnd )
				)
			)
			( pinPair "@baseboard_fab2_lib.baseboard_fab2(sch_1):\PP601\"
				( pinRef "@baseboard_fab2_lib.baseboard_fab2(sch_1):page25_i172:DDR2_DQS_DN(5)" )
				( pinRef "@baseboard_fab2_lib.baseboard_fab2(sch_1):page47_i61:DQS5N" )
				( attribute "RELATIVE_PROPAGATION_DELAY_SCOPE" "G"
					( Parent
						( matchGroupRef "@baseboard_fab2_lib.baseboard_fab2(sch_1):\MG_DQ-DQS_FAR_DIMM_NG_M_C_BYTE5\" )
					)
					( Status sCSetFlattened )
					( Origin gBackEnd )
				)
				( attribute "RELATIVE_PROPAGATION_DELAY" ",5.00 MIL"
					( Parent
						( matchGroupRef "@baseboard_fab2_lib.baseboard_fab2(sch_1):\MG_DQ-DQS_FAR_DIMM_NG_M_C_BYTE5\" )
					)
					( Units "uMatchProp" "ns" 1.000000)
					( Status sCSetFlattened )
					( Origin gBackEnd )
				)
			)
			( pinPair "@baseboard_fab2_lib.baseboard_fab2(sch_1):\PP603\"
				( pinRef "@baseboard_fab2_lib.baseboard_fab2(sch_1):page25_i172:DDR2_DQS_DN(5)" )
				( pinRef "@baseboard_fab2_lib.baseboard_fab2(sch_1):page48_i61:DQS5N" )
				( attribute "RELATIVE_PROPAGATION_DELAY_SCOPE" "G"
					( Parent
						( matchGroupRef "@baseboard_fab2_lib.baseboard_fab2(sch_1):\MG_DQ-DQS_NEAR_DIMM_NG_M_C_BYTE5\" )
					)
					( Status sCSetFlattened )
					( Origin gBackEnd )
				)
				( attribute "RELATIVE_PROPAGATION_DELAY" ",5.00 MIL"
					( Parent
						( matchGroupRef "@baseboard_fab2_lib.baseboard_fab2(sch_1):\MG_DQ-DQS_NEAR_DIMM_NG_M_C_BYTE5\" )
					)
					( Units "uMatchProp" "ns" 1.000000)
					( Status sCSetFlattened )
					( Origin gBackEnd )
				)
			)
			( pinPair "@baseboard_fab2_lib.baseboard_fab2(sch_1):\PP589\"
				( pinRef "@baseboard_fab2_lib.baseboard_fab2(sch_1):page25_i172:DDR2_DQS_DN(6)" )
				( pinRef "@baseboard_fab2_lib.baseboard_fab2(sch_1):page47_i61:DQS6N" )
				( attribute "RELATIVE_PROPAGATION_DELAY_SCOPE" "G"
					( Parent
						( matchGroupRef "@baseboard_fab2_lib.baseboard_fab2(sch_1):\MG_DQ-DQS_FAR_DIMM_NG_M_C_BYTE6\" )
					)
					( Status sCSetFlattened )
					( Origin gBackEnd )
				)
				( attribute "RELATIVE_PROPAGATION_DELAY" ",5.00 MIL"
					( Parent
						( matchGroupRef "@baseboard_fab2_lib.baseboard_fab2(sch_1):\MG_DQ-DQS_FAR_DIMM_NG_M_C_BYTE6\" )
					)
					( Units "uMatchProp" "ns" 1.000000)
					( Status sCSetFlattened )
					( Origin gBackEnd )
				)
			)
			( pinPair "@baseboard_fab2_lib.baseboard_fab2(sch_1):\PP591\"
				( pinRef "@baseboard_fab2_lib.baseboard_fab2(sch_1):page25_i172:DDR2_DQS_DN(6)" )
				( pinRef "@baseboard_fab2_lib.baseboard_fab2(sch_1):page48_i61:DQS6N" )
				( attribute "RELATIVE_PROPAGATION_DELAY_SCOPE" "G"
					( Parent
						( matchGroupRef "@baseboard_fab2_lib.baseboard_fab2(sch_1):\MG_DQ-DQS_NEAR_DIMM_NG_M_C_BYTE6\" )
					)
					( Status sCSetFlattened )
					( Origin gBackEnd )
				)
				( attribute "RELATIVE_PROPAGATION_DELAY" ",5.00 MIL"
					( Parent
						( matchGroupRef "@baseboard_fab2_lib.baseboard_fab2(sch_1):\MG_DQ-DQS_NEAR_DIMM_NG_M_C_BYTE6\" )
					)
					( Units "uMatchProp" "ns" 1.000000)
					( Status sCSetFlattened )
					( Origin gBackEnd )
				)
			)
			( pinPair "@baseboard_fab2_lib.baseboard_fab2(sch_1):\PP577\"
				( pinRef "@baseboard_fab2_lib.baseboard_fab2(sch_1):page25_i172:DDR2_DQS_DN(7)" )
				( pinRef "@baseboard_fab2_lib.baseboard_fab2(sch_1):page47_i61:DQS7N" )
				( attribute "RELATIVE_PROPAGATION_DELAY_SCOPE" "G"
					( Parent
						( matchGroupRef "@baseboard_fab2_lib.baseboard_fab2(sch_1):\MG_DQ-DQS_FAR_DIMM_NG_M_C_BYTE7\" )
					)
					( Status sCSetFlattened )
					( Origin gBackEnd )
				)
				( attribute "RELATIVE_PROPAGATION_DELAY" ",5.00 MIL"
					( Parent
						( matchGroupRef "@baseboard_fab2_lib.baseboard_fab2(sch_1):\MG_DQ-DQS_FAR_DIMM_NG_M_C_BYTE7\" )
					)
					( Units "uMatchProp" "ns" 1.000000)
					( Status sCSetFlattened )
					( Origin gBackEnd )
				)
			)
			( pinPair "@baseboard_fab2_lib.baseboard_fab2(sch_1):\PP579\"
				( pinRef "@baseboard_fab2_lib.baseboard_fab2(sch_1):page25_i172:DDR2_DQS_DN(7)" )
				( pinRef "@baseboard_fab2_lib.baseboard_fab2(sch_1):page48_i61:DQS7N" )
				( attribute "RELATIVE_PROPAGATION_DELAY_SCOPE" "G"
					( Parent
						( matchGroupRef "@baseboard_fab2_lib.baseboard_fab2(sch_1):\MG_DQ-DQS_NEAR_DIMM_NG_M_C_BYTE7\" )
					)
					( Status sCSetFlattened )
					( Origin gBackEnd )
				)
				( attribute "RELATIVE_PROPAGATION_DELAY" ",5.00 MIL"
					( Parent
						( matchGroupRef "@baseboard_fab2_lib.baseboard_fab2(sch_1):\MG_DQ-DQS_NEAR_DIMM_NG_M_C_BYTE7\" )
					)
					( Units "uMatchProp" "ns" 1.000000)
					( Status sCSetFlattened )
					( Origin gBackEnd )
				)
			)
			( pinPair "@baseboard_fab2_lib.baseboard_fab2(sch_1):\PP1213\"
				( pinRef "@baseboard_fab2_lib.baseboard_fab2(sch_1):page25_i172:DDR2_DQS_DN(8)" )
				( pinRef "@baseboard_fab2_lib.baseboard_fab2(sch_1):page47_i61:DQS8N" )
				( attribute "RELATIVE_PROPAGATION_DELAY_SCOPE" "G"
					( Parent
						( matchGroupRef "@baseboard_fab2_lib.baseboard_fab2(sch_1):\MG_DQ-DQS_FAR_DIMM_NG_M_C_BYTE-ECC\" )
					)
					( Status sCSetFlattened )
					( Origin gBackEnd )
				)
				( attribute "RELATIVE_PROPAGATION_DELAY" ",5.00 MIL"
					( Parent
						( matchGroupRef "@baseboard_fab2_lib.baseboard_fab2(sch_1):\MG_DQ-DQS_FAR_DIMM_NG_M_C_BYTE-ECC\" )
					)
					( Units "uMatchProp" "ns" 1.000000)
					( Status sCSetFlattened )
					( Origin gBackEnd )
				)
			)
			( pinPair "@baseboard_fab2_lib.baseboard_fab2(sch_1):\PP1214\"
				( pinRef "@baseboard_fab2_lib.baseboard_fab2(sch_1):page25_i172:DDR2_DQS_DN(8)" )
				( pinRef "@baseboard_fab2_lib.baseboard_fab2(sch_1):page48_i61:DQS8N" )
				( attribute "RELATIVE_PROPAGATION_DELAY_SCOPE" "G"
					( Parent
						( matchGroupRef "@baseboard_fab2_lib.baseboard_fab2(sch_1):\MG_DQ-DQS_NEAR_DIMM_NG_M_C_BYTE-ECC\" )
					)
					( Status sCSetFlattened )
					( Origin gBackEnd )
				)
				( attribute "RELATIVE_PROPAGATION_DELAY" ",5.00 MIL"
					( Parent
						( matchGroupRef "@baseboard_fab2_lib.baseboard_fab2(sch_1):\MG_DQ-DQS_NEAR_DIMM_NG_M_C_BYTE-ECC\" )
					)
					( Units "uMatchProp" "ns" 1.000000)
					( Status sCSetFlattened )
					( Origin gBackEnd )
				)
			)
			( pinPair "@baseboard_fab2_lib.baseboard_fab2(sch_1):\PP655\"
				( pinRef "@baseboard_fab2_lib.baseboard_fab2(sch_1):page25_i172:DDR2_DQS_DN(9)" )
				( pinRef "@baseboard_fab2_lib.baseboard_fab2(sch_1):page47_i61:DQS9N" )
				( attribute "RELATIVE_PROPAGATION_DELAY_SCOPE" "G"
					( Parent
						( matchGroupRef "@baseboard_fab2_lib.baseboard_fab2(sch_1):\MG_DQ-DQS_FAR_DIMM_NG_M_C_BYTE0\" )
					)
					( Status sCSetFlattened )
					( Origin gBackEnd )
				)
				( attribute "RELATIVE_PROPAGATION_DELAY" ",5.00 MIL"
					( Parent
						( matchGroupRef "@baseboard_fab2_lib.baseboard_fab2(sch_1):\MG_DQ-DQS_FAR_DIMM_NG_M_C_BYTE0\" )
					)
					( Units "uMatchProp" "ns" 1.000000)
					( Status sCSetFlattened )
					( Origin gBackEnd )
				)
			)
			( pinPair "@baseboard_fab2_lib.baseboard_fab2(sch_1):\PP656\"
				( pinRef "@baseboard_fab2_lib.baseboard_fab2(sch_1):page25_i172:DDR2_DQS_DN(9)" )
				( pinRef "@baseboard_fab2_lib.baseboard_fab2(sch_1):page48_i61:DQS9N" )
				( attribute "RELATIVE_PROPAGATION_DELAY_SCOPE" "G"
					( Parent
						( matchGroupRef "@baseboard_fab2_lib.baseboard_fab2(sch_1):\MG_DQ-DQS_NEAR_DIMM_NG_M_C_BYTE0\" )
					)
					( Status sCSetFlattened )
					( Origin gBackEnd )
				)
				( attribute "RELATIVE_PROPAGATION_DELAY" ",5.00 MIL"
					( Parent
						( matchGroupRef "@baseboard_fab2_lib.baseboard_fab2(sch_1):\MG_DQ-DQS_NEAR_DIMM_NG_M_C_BYTE0\" )
					)
					( Units "uMatchProp" "ns" 1.000000)
					( Status sCSetFlattened )
					( Origin gBackEnd )
				)
			)
			( pinPair "@baseboard_fab2_lib.baseboard_fab2(sch_1):\PP643\"
				( pinRef "@baseboard_fab2_lib.baseboard_fab2(sch_1):page25_i172:DDR2_DQS_DN(10)" )
				( pinRef "@baseboard_fab2_lib.baseboard_fab2(sch_1):page47_i61:DQS10N" )
				( attribute "RELATIVE_PROPAGATION_DELAY_SCOPE" "G"
					( Parent
						( matchGroupRef "@baseboard_fab2_lib.baseboard_fab2(sch_1):\MG_DQ-DQS_FAR_DIMM_NG_M_C_BYTE1\" )
					)
					( Status sCSetFlattened )
					( Origin gBackEnd )
				)
				( attribute "RELATIVE_PROPAGATION_DELAY" ",5.00 MIL"
					( Parent
						( matchGroupRef "@baseboard_fab2_lib.baseboard_fab2(sch_1):\MG_DQ-DQS_FAR_DIMM_NG_M_C_BYTE1\" )
					)
					( Units "uMatchProp" "ns" 1.000000)
					( Status sCSetFlattened )
					( Origin gBackEnd )
				)
			)
			( pinPair "@baseboard_fab2_lib.baseboard_fab2(sch_1):\PP644\"
				( pinRef "@baseboard_fab2_lib.baseboard_fab2(sch_1):page25_i172:DDR2_DQS_DN(10)" )
				( pinRef "@baseboard_fab2_lib.baseboard_fab2(sch_1):page48_i61:DQS10N" )
				( attribute "RELATIVE_PROPAGATION_DELAY_SCOPE" "G"
					( Parent
						( matchGroupRef "@baseboard_fab2_lib.baseboard_fab2(sch_1):\MG_DQ-DQS_NEAR_DIMM_NG_M_C_BYTE1\" )
					)
					( Status sCSetFlattened )
					( Origin gBackEnd )
				)
				( attribute "RELATIVE_PROPAGATION_DELAY" ",5.00 MIL"
					( Parent
						( matchGroupRef "@baseboard_fab2_lib.baseboard_fab2(sch_1):\MG_DQ-DQS_NEAR_DIMM_NG_M_C_BYTE1\" )
					)
					( Units "uMatchProp" "ns" 1.000000)
					( Status sCSetFlattened )
					( Origin gBackEnd )
				)
			)
			( pinPair "@baseboard_fab2_lib.baseboard_fab2(sch_1):\PP631\"
				( pinRef "@baseboard_fab2_lib.baseboard_fab2(sch_1):page25_i172:DDR2_DQS_DN(11)" )
				( pinRef "@baseboard_fab2_lib.baseboard_fab2(sch_1):page47_i61:DQS11N" )
				( attribute "RELATIVE_PROPAGATION_DELAY_SCOPE" "G"
					( Parent
						( matchGroupRef "@baseboard_fab2_lib.baseboard_fab2(sch_1):\MG_DQ-DQS_FAR_DIMM_NG_M_C_BYTE2\" )
					)
					( Status sCSetFlattened )
					( Origin gBackEnd )
				)
				( attribute "RELATIVE_PROPAGATION_DELAY" ",5.00 MIL"
					( Parent
						( matchGroupRef "@baseboard_fab2_lib.baseboard_fab2(sch_1):\MG_DQ-DQS_FAR_DIMM_NG_M_C_BYTE2\" )
					)
					( Units "uMatchProp" "ns" 1.000000)
					( Status sCSetFlattened )
					( Origin gBackEnd )
				)
			)
			( pinPair "@baseboard_fab2_lib.baseboard_fab2(sch_1):\PP632\"
				( pinRef "@baseboard_fab2_lib.baseboard_fab2(sch_1):page25_i172:DDR2_DQS_DN(11)" )
				( pinRef "@baseboard_fab2_lib.baseboard_fab2(sch_1):page48_i61:DQS11N" )
				( attribute "RELATIVE_PROPAGATION_DELAY_SCOPE" "G"
					( Parent
						( matchGroupRef "@baseboard_fab2_lib.baseboard_fab2(sch_1):\MG_DQ-DQS_NEAR_DIMM_NG_M_C_BYTE2\" )
					)
					( Status sCSetFlattened )
					( Origin gBackEnd )
				)
				( attribute "RELATIVE_PROPAGATION_DELAY" ",5.00 MIL"
					( Parent
						( matchGroupRef "@baseboard_fab2_lib.baseboard_fab2(sch_1):\MG_DQ-DQS_NEAR_DIMM_NG_M_C_BYTE2\" )
					)
					( Units "uMatchProp" "ns" 1.000000)
					( Status sCSetFlattened )
					( Origin gBackEnd )
				)
			)
			( pinPair "@baseboard_fab2_lib.baseboard_fab2(sch_1):\PP619\"
				( pinRef "@baseboard_fab2_lib.baseboard_fab2(sch_1):page25_i172:DDR2_DQS_DN(12)" )
				( pinRef "@baseboard_fab2_lib.baseboard_fab2(sch_1):page47_i61:DQS12N" )
				( attribute "RELATIVE_PROPAGATION_DELAY_SCOPE" "G"
					( Parent
						( matchGroupRef "@baseboard_fab2_lib.baseboard_fab2(sch_1):\MG_DQ-DQS_FAR_DIMM_NG_M_C_BYTE3\" )
					)
					( Status sCSetFlattened )
					( Origin gBackEnd )
				)
				( attribute "RELATIVE_PROPAGATION_DELAY" ",5.00 MIL"
					( Parent
						( matchGroupRef "@baseboard_fab2_lib.baseboard_fab2(sch_1):\MG_DQ-DQS_FAR_DIMM_NG_M_C_BYTE3\" )
					)
					( Units "uMatchProp" "ns" 1.000000)
					( Status sCSetFlattened )
					( Origin gBackEnd )
				)
			)
			( pinPair "@baseboard_fab2_lib.baseboard_fab2(sch_1):\PP620\"
				( pinRef "@baseboard_fab2_lib.baseboard_fab2(sch_1):page25_i172:DDR2_DQS_DN(12)" )
				( pinRef "@baseboard_fab2_lib.baseboard_fab2(sch_1):page48_i61:DQS12N" )
				( attribute "RELATIVE_PROPAGATION_DELAY_SCOPE" "G"
					( Parent
						( matchGroupRef "@baseboard_fab2_lib.baseboard_fab2(sch_1):\MG_DQ-DQS_NEAR_DIMM_NG_M_C_BYTE3\" )
					)
					( Status sCSetFlattened )
					( Origin gBackEnd )
				)
				( attribute "RELATIVE_PROPAGATION_DELAY" ",5.00 MIL"
					( Parent
						( matchGroupRef "@baseboard_fab2_lib.baseboard_fab2(sch_1):\MG_DQ-DQS_NEAR_DIMM_NG_M_C_BYTE3\" )
					)
					( Units "uMatchProp" "ns" 1.000000)
					( Status sCSetFlattened )
					( Origin gBackEnd )
				)
			)
			( pinPair "@baseboard_fab2_lib.baseboard_fab2(sch_1):\PP607\"
				( pinRef "@baseboard_fab2_lib.baseboard_fab2(sch_1):page25_i172:DDR2_DQS_DN(13)" )
				( pinRef "@baseboard_fab2_lib.baseboard_fab2(sch_1):page47_i61:DQS13N" )
				( attribute "RELATIVE_PROPAGATION_DELAY_SCOPE" "G"
					( Parent
						( matchGroupRef "@baseboard_fab2_lib.baseboard_fab2(sch_1):\MG_DQ-DQS_FAR_DIMM_NG_M_C_BYTE4\" )
					)
					( Status sCSetFlattened )
					( Origin gBackEnd )
				)
				( attribute "RELATIVE_PROPAGATION_DELAY" ",5.00 MIL"
					( Parent
						( matchGroupRef "@baseboard_fab2_lib.baseboard_fab2(sch_1):\MG_DQ-DQS_FAR_DIMM_NG_M_C_BYTE4\" )
					)
					( Units "uMatchProp" "ns" 1.000000)
					( Status sCSetFlattened )
					( Origin gBackEnd )
				)
			)
			( pinPair "@baseboard_fab2_lib.baseboard_fab2(sch_1):\PP609\"
				( pinRef "@baseboard_fab2_lib.baseboard_fab2(sch_1):page25_i172:DDR2_DQS_DN(13)" )
				( pinRef "@baseboard_fab2_lib.baseboard_fab2(sch_1):page48_i61:DQS13N" )
				( attribute "RELATIVE_PROPAGATION_DELAY_SCOPE" "G"
					( Parent
						( matchGroupRef "@baseboard_fab2_lib.baseboard_fab2(sch_1):\MG_DQ-DQS_NEAR_DIMM_NG_M_C_BYTE4\" )
					)
					( Status sCSetFlattened )
					( Origin gBackEnd )
				)
				( attribute "RELATIVE_PROPAGATION_DELAY" ",5.00 MIL"
					( Parent
						( matchGroupRef "@baseboard_fab2_lib.baseboard_fab2(sch_1):\MG_DQ-DQS_NEAR_DIMM_NG_M_C_BYTE4\" )
					)
					( Units "uMatchProp" "ns" 1.000000)
					( Status sCSetFlattened )
					( Origin gBackEnd )
				)
			)
			( pinPair "@baseboard_fab2_lib.baseboard_fab2(sch_1):\PP595\"
				( pinRef "@baseboard_fab2_lib.baseboard_fab2(sch_1):page25_i172:DDR2_DQS_DN(14)" )
				( pinRef "@baseboard_fab2_lib.baseboard_fab2(sch_1):page47_i61:DQS14N" )
				( attribute "RELATIVE_PROPAGATION_DELAY_SCOPE" "G"
					( Parent
						( matchGroupRef "@baseboard_fab2_lib.baseboard_fab2(sch_1):\MG_DQ-DQS_FAR_DIMM_NG_M_C_BYTE5\" )
					)
					( Status sCSetFlattened )
					( Origin gBackEnd )
				)
				( attribute "RELATIVE_PROPAGATION_DELAY" ",5.00 MIL"
					( Parent
						( matchGroupRef "@baseboard_fab2_lib.baseboard_fab2(sch_1):\MG_DQ-DQS_FAR_DIMM_NG_M_C_BYTE5\" )
					)
					( Units "uMatchProp" "ns" 1.000000)
					( Status sCSetFlattened )
					( Origin gBackEnd )
				)
			)
			( pinPair "@baseboard_fab2_lib.baseboard_fab2(sch_1):\PP597\"
				( pinRef "@baseboard_fab2_lib.baseboard_fab2(sch_1):page25_i172:DDR2_DQS_DN(14)" )
				( pinRef "@baseboard_fab2_lib.baseboard_fab2(sch_1):page48_i61:DQS14N" )
				( attribute "RELATIVE_PROPAGATION_DELAY_SCOPE" "G"
					( Parent
						( matchGroupRef "@baseboard_fab2_lib.baseboard_fab2(sch_1):\MG_DQ-DQS_NEAR_DIMM_NG_M_C_BYTE5\" )
					)
					( Status sCSetFlattened )
					( Origin gBackEnd )
				)
				( attribute "RELATIVE_PROPAGATION_DELAY" ",5.00 MIL"
					( Parent
						( matchGroupRef "@baseboard_fab2_lib.baseboard_fab2(sch_1):\MG_DQ-DQS_NEAR_DIMM_NG_M_C_BYTE5\" )
					)
					( Units "uMatchProp" "ns" 1.000000)
					( Status sCSetFlattened )
					( Origin gBackEnd )
				)
			)
			( pinPair "@baseboard_fab2_lib.baseboard_fab2(sch_1):\PP583\"
				( pinRef "@baseboard_fab2_lib.baseboard_fab2(sch_1):page25_i172:DDR2_DQS_DN(15)" )
				( pinRef "@baseboard_fab2_lib.baseboard_fab2(sch_1):page47_i61:DQS15N" )
				( attribute "RELATIVE_PROPAGATION_DELAY_SCOPE" "G"
					( Parent
						( matchGroupRef "@baseboard_fab2_lib.baseboard_fab2(sch_1):\MG_DQ-DQS_FAR_DIMM_NG_M_C_BYTE6\" )
					)
					( Status sCSetFlattened )
					( Origin gBackEnd )
				)
				( attribute "RELATIVE_PROPAGATION_DELAY" ",5.00 MIL"
					( Parent
						( matchGroupRef "@baseboard_fab2_lib.baseboard_fab2(sch_1):\MG_DQ-DQS_FAR_DIMM_NG_M_C_BYTE6\" )
					)
					( Units "uMatchProp" "ns" 1.000000)
					( Status sCSetFlattened )
					( Origin gBackEnd )
				)
			)
			( pinPair "@baseboard_fab2_lib.baseboard_fab2(sch_1):\PP585\"
				( pinRef "@baseboard_fab2_lib.baseboard_fab2(sch_1):page25_i172:DDR2_DQS_DN(15)" )
				( pinRef "@baseboard_fab2_lib.baseboard_fab2(sch_1):page48_i61:DQS15N" )
				( attribute "RELATIVE_PROPAGATION_DELAY_SCOPE" "G"
					( Parent
						( matchGroupRef "@baseboard_fab2_lib.baseboard_fab2(sch_1):\MG_DQ-DQS_NEAR_DIMM_NG_M_C_BYTE6\" )
					)
					( Status sCSetFlattened )
					( Origin gBackEnd )
				)
				( attribute "RELATIVE_PROPAGATION_DELAY" ",5.00 MIL"
					( Parent
						( matchGroupRef "@baseboard_fab2_lib.baseboard_fab2(sch_1):\MG_DQ-DQS_NEAR_DIMM_NG_M_C_BYTE6\" )
					)
					( Units "uMatchProp" "ns" 1.000000)
					( Status sCSetFlattened )
					( Origin gBackEnd )
				)
			)
			( pinPair "@baseboard_fab2_lib.baseboard_fab2(sch_1):\PP571\"
				( pinRef "@baseboard_fab2_lib.baseboard_fab2(sch_1):page25_i172:DDR2_DQS_DN(16)" )
				( pinRef "@baseboard_fab2_lib.baseboard_fab2(sch_1):page47_i61:DQS16N" )
				( attribute "RELATIVE_PROPAGATION_DELAY_SCOPE" "G"
					( Parent
						( matchGroupRef "@baseboard_fab2_lib.baseboard_fab2(sch_1):\MG_DQ-DQS_FAR_DIMM_NG_M_C_BYTE7\" )
					)
					( Status sCSetFlattened )
					( Origin gBackEnd )
				)
				( attribute "RELATIVE_PROPAGATION_DELAY" ",5.00 MIL"
					( Parent
						( matchGroupRef "@baseboard_fab2_lib.baseboard_fab2(sch_1):\MG_DQ-DQS_FAR_DIMM_NG_M_C_BYTE7\" )
					)
					( Units "uMatchProp" "ns" 1.000000)
					( Status sCSetFlattened )
					( Origin gBackEnd )
				)
			)
			( pinPair "@baseboard_fab2_lib.baseboard_fab2(sch_1):\PP573\"
				( pinRef "@baseboard_fab2_lib.baseboard_fab2(sch_1):page25_i172:DDR2_DQS_DN(16)" )
				( pinRef "@baseboard_fab2_lib.baseboard_fab2(sch_1):page48_i61:DQS16N" )
				( attribute "RELATIVE_PROPAGATION_DELAY_SCOPE" "G"
					( Parent
						( matchGroupRef "@baseboard_fab2_lib.baseboard_fab2(sch_1):\MG_DQ-DQS_NEAR_DIMM_NG_M_C_BYTE7\" )
					)
					( Status sCSetFlattened )
					( Origin gBackEnd )
				)
				( attribute "RELATIVE_PROPAGATION_DELAY" ",5.00 MIL"
					( Parent
						( matchGroupRef "@baseboard_fab2_lib.baseboard_fab2(sch_1):\MG_DQ-DQS_NEAR_DIMM_NG_M_C_BYTE7\" )
					)
					( Units "uMatchProp" "ns" 1.000000)
					( Status sCSetFlattened )
					( Origin gBackEnd )
				)
			)
			( pinPair "@baseboard_fab2_lib.baseboard_fab2(sch_1):\PP1207\"
				( pinRef "@baseboard_fab2_lib.baseboard_fab2(sch_1):page25_i172:DDR2_DQS_DN(17)" )
				( pinRef "@baseboard_fab2_lib.baseboard_fab2(sch_1):page47_i61:DQS17N" )
				( attribute "RELATIVE_PROPAGATION_DELAY_SCOPE" "G"
					( Parent
						( matchGroupRef "@baseboard_fab2_lib.baseboard_fab2(sch_1):\MG_DQ-DQS_FAR_DIMM_NG_M_C_BYTE-ECC\" )
					)
					( Status sCSetFlattened )
					( Origin gBackEnd )
				)
				( attribute "RELATIVE_PROPAGATION_DELAY" ",5.00 MIL"
					( Parent
						( matchGroupRef "@baseboard_fab2_lib.baseboard_fab2(sch_1):\MG_DQ-DQS_FAR_DIMM_NG_M_C_BYTE-ECC\" )
					)
					( Units "uMatchProp" "ns" 1.000000)
					( Status sCSetFlattened )
					( Origin gBackEnd )
				)
			)
			( pinPair "@baseboard_fab2_lib.baseboard_fab2(sch_1):\PP1208\"
				( pinRef "@baseboard_fab2_lib.baseboard_fab2(sch_1):page25_i172:DDR2_DQS_DN(17)" )
				( pinRef "@baseboard_fab2_lib.baseboard_fab2(sch_1):page48_i61:DQS17N" )
				( attribute "RELATIVE_PROPAGATION_DELAY_SCOPE" "G"
					( Parent
						( matchGroupRef "@baseboard_fab2_lib.baseboard_fab2(sch_1):\MG_DQ-DQS_NEAR_DIMM_NG_M_C_BYTE-ECC\" )
					)
					( Status sCSetFlattened )
					( Origin gBackEnd )
				)
				( attribute "RELATIVE_PROPAGATION_DELAY" ",5.00 MIL"
					( Parent
						( matchGroupRef "@baseboard_fab2_lib.baseboard_fab2(sch_1):\MG_DQ-DQS_NEAR_DIMM_NG_M_C_BYTE-ECC\" )
					)
					( Units "uMatchProp" "ns" 1.000000)
					( Status sCSetFlattened )
					( Origin gBackEnd )
				)
			)
			( pinPair "@baseboard_fab2_lib.baseboard_fab2(sch_1):\PP1189\"
				( pinRef "@baseboard_fab2_lib.baseboard_fab2(sch_1):page27_i172:DDR4_DQS_DN(0)" )
				( pinRef "@baseboard_fab2_lib.baseboard_fab2(sch_1):page51_i66:DQS0N" )
				( attribute "RELATIVE_PROPAGATION_DELAY_SCOPE" "G"
					( Parent
						( matchGroupRef "@baseboard_fab2_lib.baseboard_fab2(sch_1):\MG_DQ-DQS_FAR_DIMM_NG_M_E_BYTE0\" )
					)
					( Status sCSetFlattened )
					( Origin gBackEnd )
				)
				( attribute "RELATIVE_PROPAGATION_DELAY" ",5.00 MIL"
					( Parent
						( matchGroupRef "@baseboard_fab2_lib.baseboard_fab2(sch_1):\MG_DQ-DQS_FAR_DIMM_NG_M_E_BYTE0\" )
					)
					( Units "uMatchProp" "ns" 1.000000)
					( Status sCSetFlattened )
					( Origin gBackEnd )
				)
			)
			( pinPair "@baseboard_fab2_lib.baseboard_fab2(sch_1):\PP1190\"
				( pinRef "@baseboard_fab2_lib.baseboard_fab2(sch_1):page27_i172:DDR4_DQS_DN(0)" )
				( pinRef "@baseboard_fab2_lib.baseboard_fab2(sch_1):page52_i100:DQS0N" )
				( attribute "RELATIVE_PROPAGATION_DELAY_SCOPE" "G"
					( Parent
						( matchGroupRef "@baseboard_fab2_lib.baseboard_fab2(sch_1):\MG_DQ-DQS_NEAR_DIMM_NG_M_E_BYTE0\" )
					)
					( Status sCSetFlattened )
					( Origin gBackEnd )
				)
				( attribute "RELATIVE_PROPAGATION_DELAY" ",5.00 MIL"
					( Parent
						( matchGroupRef "@baseboard_fab2_lib.baseboard_fab2(sch_1):\MG_DQ-DQS_NEAR_DIMM_NG_M_E_BYTE0\" )
					)
					( Units "uMatchProp" "ns" 1.000000)
					( Status sCSetFlattened )
					( Origin gBackEnd )
				)
			)
			( pinPair "@baseboard_fab2_lib.baseboard_fab2(sch_1):\PP1177\"
				( pinRef "@baseboard_fab2_lib.baseboard_fab2(sch_1):page27_i172:DDR4_DQS_DN(1)" )
				( pinRef "@baseboard_fab2_lib.baseboard_fab2(sch_1):page51_i66:DQS1N" )
				( attribute "RELATIVE_PROPAGATION_DELAY_SCOPE" "G"
					( Parent
						( matchGroupRef "@baseboard_fab2_lib.baseboard_fab2(sch_1):\MG_DQ-DQS_FAR_DIMM_NG_M_E_BYTE1\" )
					)
					( Status sCSetFlattened )
					( Origin gBackEnd )
				)
				( attribute "RELATIVE_PROPAGATION_DELAY" ",5.00 MIL"
					( Parent
						( matchGroupRef "@baseboard_fab2_lib.baseboard_fab2(sch_1):\MG_DQ-DQS_FAR_DIMM_NG_M_E_BYTE1\" )
					)
					( Units "uMatchProp" "ns" 1.000000)
					( Status sCSetFlattened )
					( Origin gBackEnd )
				)
			)
			( pinPair "@baseboard_fab2_lib.baseboard_fab2(sch_1):\PP1178\"
				( pinRef "@baseboard_fab2_lib.baseboard_fab2(sch_1):page52_i100:DQS1N" )
				( pinRef "@baseboard_fab2_lib.baseboard_fab2(sch_1):page27_i172:DDR4_DQS_DN(1)" )
				( attribute "RELATIVE_PROPAGATION_DELAY_SCOPE" "G"
					( Parent
						( matchGroupRef "@baseboard_fab2_lib.baseboard_fab2(sch_1):\MG_DQ-DQS_NEAR_DIMM_NG_M_E_BYTE1\" )
					)
					( Status sCSetFlattened )
					( Origin gBackEnd )
				)
				( attribute "RELATIVE_PROPAGATION_DELAY" ",5.00 MIL"
					( Parent
						( matchGroupRef "@baseboard_fab2_lib.baseboard_fab2(sch_1):\MG_DQ-DQS_NEAR_DIMM_NG_M_E_BYTE1\" )
					)
					( Units "uMatchProp" "ns" 1.000000)
					( Status sCSetFlattened )
					( Origin gBackEnd )
				)
			)
			( pinPair "@baseboard_fab2_lib.baseboard_fab2(sch_1):\PP1165\"
				( pinRef "@baseboard_fab2_lib.baseboard_fab2(sch_1):page27_i172:DDR4_DQS_DN(2)" )
				( pinRef "@baseboard_fab2_lib.baseboard_fab2(sch_1):page51_i66:DQS2N" )
				( attribute "RELATIVE_PROPAGATION_DELAY_SCOPE" "G"
					( Parent
						( matchGroupRef "@baseboard_fab2_lib.baseboard_fab2(sch_1):\MG_DQ-DQS_FAR_DIMM_NG_M_E_BYTE2\" )
					)
					( Status sCSetFlattened )
					( Origin gBackEnd )
				)
				( attribute "RELATIVE_PROPAGATION_DELAY" ",5.00 MIL"
					( Parent
						( matchGroupRef "@baseboard_fab2_lib.baseboard_fab2(sch_1):\MG_DQ-DQS_FAR_DIMM_NG_M_E_BYTE2\" )
					)
					( Units "uMatchProp" "ns" 1.000000)
					( Status sCSetFlattened )
					( Origin gBackEnd )
				)
			)
			( pinPair "@baseboard_fab2_lib.baseboard_fab2(sch_1):\PP1166\"
				( pinRef "@baseboard_fab2_lib.baseboard_fab2(sch_1):page52_i100:DQS2N" )
				( pinRef "@baseboard_fab2_lib.baseboard_fab2(sch_1):page27_i172:DDR4_DQS_DN(2)" )
				( attribute "RELATIVE_PROPAGATION_DELAY_SCOPE" "G"
					( Parent
						( matchGroupRef "@baseboard_fab2_lib.baseboard_fab2(sch_1):\MG_DQ-DQS_NEAR_DIMM_NG_M_E_BYTE2\" )
					)
					( Status sCSetFlattened )
					( Origin gBackEnd )
				)
				( attribute "RELATIVE_PROPAGATION_DELAY" ",5.00 MIL"
					( Parent
						( matchGroupRef "@baseboard_fab2_lib.baseboard_fab2(sch_1):\MG_DQ-DQS_NEAR_DIMM_NG_M_E_BYTE2\" )
					)
					( Units "uMatchProp" "ns" 1.000000)
					( Status sCSetFlattened )
					( Origin gBackEnd )
				)
			)
			( pinPair "@baseboard_fab2_lib.baseboard_fab2(sch_1):\PP1153\"
				( pinRef "@baseboard_fab2_lib.baseboard_fab2(sch_1):page27_i172:DDR4_DQS_DN(3)" )
				( pinRef "@baseboard_fab2_lib.baseboard_fab2(sch_1):page51_i66:DQS3N" )
				( attribute "RELATIVE_PROPAGATION_DELAY_SCOPE" "G"
					( Parent
						( matchGroupRef "@baseboard_fab2_lib.baseboard_fab2(sch_1):\MG_DQ-DQS_FAR_DIMM_NG_M_E_BYTE3\" )
					)
					( Status sCSetFlattened )
					( Origin gBackEnd )
				)
				( attribute "RELATIVE_PROPAGATION_DELAY" ",5.00 MIL"
					( Parent
						( matchGroupRef "@baseboard_fab2_lib.baseboard_fab2(sch_1):\MG_DQ-DQS_FAR_DIMM_NG_M_E_BYTE3\" )
					)
					( Units "uMatchProp" "ns" 1.000000)
					( Status sCSetFlattened )
					( Origin gBackEnd )
				)
			)
			( pinPair "@baseboard_fab2_lib.baseboard_fab2(sch_1):\PP1154\"
				( pinRef "@baseboard_fab2_lib.baseboard_fab2(sch_1):page27_i172:DDR4_DQS_DN(3)" )
				( pinRef "@baseboard_fab2_lib.baseboard_fab2(sch_1):page52_i100:DQS3N" )
				( attribute "RELATIVE_PROPAGATION_DELAY_SCOPE" "G"
					( Parent
						( matchGroupRef "@baseboard_fab2_lib.baseboard_fab2(sch_1):\MG_DQ-DQS_NEAR_DIMM_NG_M_E_BYTE3\" )
					)
					( Status sCSetFlattened )
					( Origin gBackEnd )
				)
				( attribute "RELATIVE_PROPAGATION_DELAY" ",5.00 MIL"
					( Parent
						( matchGroupRef "@baseboard_fab2_lib.baseboard_fab2(sch_1):\MG_DQ-DQS_NEAR_DIMM_NG_M_E_BYTE3\" )
					)
					( Units "uMatchProp" "ns" 1.000000)
					( Status sCSetFlattened )
					( Origin gBackEnd )
				)
			)
			( pinPair "@baseboard_fab2_lib.baseboard_fab2(sch_1):\PP1141\"
				( pinRef "@baseboard_fab2_lib.baseboard_fab2(sch_1):page27_i172:DDR4_DQS_DN(4)" )
				( pinRef "@baseboard_fab2_lib.baseboard_fab2(sch_1):page51_i66:DQS4N" )
				( attribute "RELATIVE_PROPAGATION_DELAY_SCOPE" "G"
					( Parent
						( matchGroupRef "@baseboard_fab2_lib.baseboard_fab2(sch_1):\MG_DQ-DQS_FAR_DIMM_NG_M_E_BYTE4\" )
					)
					( Status sCSetFlattened )
					( Origin gBackEnd )
				)
				( attribute "RELATIVE_PROPAGATION_DELAY" ",5.00 MIL"
					( Parent
						( matchGroupRef "@baseboard_fab2_lib.baseboard_fab2(sch_1):\MG_DQ-DQS_FAR_DIMM_NG_M_E_BYTE4\" )
					)
					( Units "uMatchProp" "ns" 1.000000)
					( Status sCSetFlattened )
					( Origin gBackEnd )
				)
			)
			( pinPair "@baseboard_fab2_lib.baseboard_fab2(sch_1):\PP1143\"
				( pinRef "@baseboard_fab2_lib.baseboard_fab2(sch_1):page27_i172:DDR4_DQS_DN(4)" )
				( pinRef "@baseboard_fab2_lib.baseboard_fab2(sch_1):page52_i100:DQS4N" )
				( attribute "RELATIVE_PROPAGATION_DELAY_SCOPE" "G"
					( Parent
						( matchGroupRef "@baseboard_fab2_lib.baseboard_fab2(sch_1):\MG_DQ-DQS_NEAR_DIMM_NG_M_E_BYTE4\" )
					)
					( Status sCSetFlattened )
					( Origin gBackEnd )
				)
				( attribute "RELATIVE_PROPAGATION_DELAY" ",5.00 MIL"
					( Parent
						( matchGroupRef "@baseboard_fab2_lib.baseboard_fab2(sch_1):\MG_DQ-DQS_NEAR_DIMM_NG_M_E_BYTE4\" )
					)
					( Units "uMatchProp" "ns" 1.000000)
					( Status sCSetFlattened )
					( Origin gBackEnd )
				)
			)
			( pinPair "@baseboard_fab2_lib.baseboard_fab2(sch_1):\PP1129\"
				( pinRef "@baseboard_fab2_lib.baseboard_fab2(sch_1):page27_i172:DDR4_DQS_DN(5)" )
				( pinRef "@baseboard_fab2_lib.baseboard_fab2(sch_1):page51_i66:DQS5N" )
				( attribute "RELATIVE_PROPAGATION_DELAY_SCOPE" "G"
					( Parent
						( matchGroupRef "@baseboard_fab2_lib.baseboard_fab2(sch_1):\MG_DQ-DQS_FAR_DIMM_NG_M_E_BYTE5\" )
					)
					( Status sCSetFlattened )
					( Origin gBackEnd )
				)
				( attribute "RELATIVE_PROPAGATION_DELAY" ",5.00 MIL"
					( Parent
						( matchGroupRef "@baseboard_fab2_lib.baseboard_fab2(sch_1):\MG_DQ-DQS_FAR_DIMM_NG_M_E_BYTE5\" )
					)
					( Units "uMatchProp" "ns" 1.000000)
					( Status sCSetFlattened )
					( Origin gBackEnd )
				)
			)
			( pinPair "@baseboard_fab2_lib.baseboard_fab2(sch_1):\PP1131\"
				( pinRef "@baseboard_fab2_lib.baseboard_fab2(sch_1):page52_i100:DQS5N" )
				( pinRef "@baseboard_fab2_lib.baseboard_fab2(sch_1):page27_i172:DDR4_DQS_DN(5)" )
				( attribute "RELATIVE_PROPAGATION_DELAY_SCOPE" "G"
					( Parent
						( matchGroupRef "@baseboard_fab2_lib.baseboard_fab2(sch_1):\MG_DQ-DQS_NEAR_DIMM_NG_M_E_BYTE5\" )
					)
					( Status sCSetFlattened )
					( Origin gBackEnd )
				)
				( attribute "RELATIVE_PROPAGATION_DELAY" ",5.00 MIL"
					( Parent
						( matchGroupRef "@baseboard_fab2_lib.baseboard_fab2(sch_1):\MG_DQ-DQS_NEAR_DIMM_NG_M_E_BYTE5\" )
					)
					( Units "uMatchProp" "ns" 1.000000)
					( Status sCSetFlattened )
					( Origin gBackEnd )
				)
			)
			( pinPair "@baseboard_fab2_lib.baseboard_fab2(sch_1):\PP1117\"
				( pinRef "@baseboard_fab2_lib.baseboard_fab2(sch_1):page27_i172:DDR4_DQS_DN(6)" )
				( pinRef "@baseboard_fab2_lib.baseboard_fab2(sch_1):page51_i66:DQS6N" )
				( attribute "RELATIVE_PROPAGATION_DELAY_SCOPE" "G"
					( Parent
						( matchGroupRef "@baseboard_fab2_lib.baseboard_fab2(sch_1):\MG_DQ-DQS_FAR_DIMM_NG_M_E_BYTE6\" )
					)
					( Status sCSetFlattened )
					( Origin gBackEnd )
				)
				( attribute "RELATIVE_PROPAGATION_DELAY" ",5.00 MIL"
					( Parent
						( matchGroupRef "@baseboard_fab2_lib.baseboard_fab2(sch_1):\MG_DQ-DQS_FAR_DIMM_NG_M_E_BYTE6\" )
					)
					( Units "uMatchProp" "ns" 1.000000)
					( Status sCSetFlattened )
					( Origin gBackEnd )
				)
			)
			( pinPair "@baseboard_fab2_lib.baseboard_fab2(sch_1):\PP1119\"
				( pinRef "@baseboard_fab2_lib.baseboard_fab2(sch_1):page27_i172:DDR4_DQS_DN(6)" )
				( pinRef "@baseboard_fab2_lib.baseboard_fab2(sch_1):page52_i100:DQS6N" )
				( attribute "RELATIVE_PROPAGATION_DELAY_SCOPE" "G"
					( Parent
						( matchGroupRef "@baseboard_fab2_lib.baseboard_fab2(sch_1):\MG_DQ-DQS_NEAR_DIMM_NG_M_E_BYTE6\" )
					)
					( Status sCSetFlattened )
					( Origin gBackEnd )
				)
				( attribute "RELATIVE_PROPAGATION_DELAY" ",5.00 MIL"
					( Parent
						( matchGroupRef "@baseboard_fab2_lib.baseboard_fab2(sch_1):\MG_DQ-DQS_NEAR_DIMM_NG_M_E_BYTE6\" )
					)
					( Units "uMatchProp" "ns" 1.000000)
					( Status sCSetFlattened )
					( Origin gBackEnd )
				)
			)
			( pinPair "@baseboard_fab2_lib.baseboard_fab2(sch_1):\PP1105\"
				( pinRef "@baseboard_fab2_lib.baseboard_fab2(sch_1):page27_i172:DDR4_DQS_DN(7)" )
				( pinRef "@baseboard_fab2_lib.baseboard_fab2(sch_1):page51_i66:DQS7N" )
				( attribute "RELATIVE_PROPAGATION_DELAY_SCOPE" "G"
					( Parent
						( matchGroupRef "@baseboard_fab2_lib.baseboard_fab2(sch_1):\MG_DQ-DQS_FAR_DIMM_NG_M_E_BYTE7\" )
					)
					( Status sCSetFlattened )
					( Origin gBackEnd )
				)
				( attribute "RELATIVE_PROPAGATION_DELAY" ",5.00 MIL"
					( Parent
						( matchGroupRef "@baseboard_fab2_lib.baseboard_fab2(sch_1):\MG_DQ-DQS_FAR_DIMM_NG_M_E_BYTE7\" )
					)
					( Units "uMatchProp" "ns" 1.000000)
					( Status sCSetFlattened )
					( Origin gBackEnd )
				)
			)
			( pinPair "@baseboard_fab2_lib.baseboard_fab2(sch_1):\PP1107\"
				( pinRef "@baseboard_fab2_lib.baseboard_fab2(sch_1):page27_i172:DDR4_DQS_DN(7)" )
				( pinRef "@baseboard_fab2_lib.baseboard_fab2(sch_1):page52_i100:DQS7N" )
				( attribute "RELATIVE_PROPAGATION_DELAY_SCOPE" "G"
					( Parent
						( matchGroupRef "@baseboard_fab2_lib.baseboard_fab2(sch_1):\MG_DQ-DQS_NEAR_DIMM_NG_M_E_BYTE7\" )
					)
					( Status sCSetFlattened )
					( Origin gBackEnd )
				)
				( attribute "RELATIVE_PROPAGATION_DELAY" ",5.00 MIL"
					( Parent
						( matchGroupRef "@baseboard_fab2_lib.baseboard_fab2(sch_1):\MG_DQ-DQS_NEAR_DIMM_NG_M_E_BYTE7\" )
					)
					( Units "uMatchProp" "ns" 1.000000)
					( Status sCSetFlattened )
					( Origin gBackEnd )
				)
			)
			( pinPair "@baseboard_fab2_lib.baseboard_fab2(sch_1):\PP1093\"
				( pinRef "@baseboard_fab2_lib.baseboard_fab2(sch_1):page27_i172:DDR4_DQS_DN(8)" )
				( pinRef "@baseboard_fab2_lib.baseboard_fab2(sch_1):page51_i66:DQS8N" )
				( attribute "RELATIVE_PROPAGATION_DELAY_SCOPE" "G"
					( Parent
						( matchGroupRef "@baseboard_fab2_lib.baseboard_fab2(sch_1):\MG_DQ-DQS_FAR_DIMM_NG_M_E_BYTE-ECC\" )
					)
					( Status sCSetFlattened )
					( Origin gBackEnd )
				)
				( attribute "RELATIVE_PROPAGATION_DELAY" ",5.00 MIL"
					( Parent
						( matchGroupRef "@baseboard_fab2_lib.baseboard_fab2(sch_1):\MG_DQ-DQS_FAR_DIMM_NG_M_E_BYTE-ECC\" )
					)
					( Units "uMatchProp" "ns" 1.000000)
					( Status sCSetFlattened )
					( Origin gBackEnd )
				)
			)
			( pinPair "@baseboard_fab2_lib.baseboard_fab2(sch_1):\PP1094\"
				( pinRef "@baseboard_fab2_lib.baseboard_fab2(sch_1):page52_i100:DQS8N" )
				( pinRef "@baseboard_fab2_lib.baseboard_fab2(sch_1):page27_i172:DDR4_DQS_DN(8)" )
				( attribute "RELATIVE_PROPAGATION_DELAY_SCOPE" "G"
					( Parent
						( matchGroupRef "@baseboard_fab2_lib.baseboard_fab2(sch_1):\MG_DQ-DQS_NEAR_DIMM_NG_M_E_BYTE-ECC\" )
					)
					( Status sCSetFlattened )
					( Origin gBackEnd )
				)
				( attribute "RELATIVE_PROPAGATION_DELAY" ",5.00 MIL"
					( Parent
						( matchGroupRef "@baseboard_fab2_lib.baseboard_fab2(sch_1):\MG_DQ-DQS_NEAR_DIMM_NG_M_E_BYTE-ECC\" )
					)
					( Units "uMatchProp" "ns" 1.000000)
					( Status sCSetFlattened )
					( Origin gBackEnd )
				)
			)
			( pinPair "@baseboard_fab2_lib.baseboard_fab2(sch_1):\PP1183\"
				( pinRef "@baseboard_fab2_lib.baseboard_fab2(sch_1):page27_i172:DDR4_DQS_DN(9)" )
				( pinRef "@baseboard_fab2_lib.baseboard_fab2(sch_1):page51_i66:DQS9N" )
				( attribute "RELATIVE_PROPAGATION_DELAY_SCOPE" "G"
					( Parent
						( matchGroupRef "@baseboard_fab2_lib.baseboard_fab2(sch_1):\MG_DQ-DQS_FAR_DIMM_NG_M_E_BYTE0\" )
					)
					( Status sCSetFlattened )
					( Origin gBackEnd )
				)
				( attribute "RELATIVE_PROPAGATION_DELAY" ",5.00 MIL"
					( Parent
						( matchGroupRef "@baseboard_fab2_lib.baseboard_fab2(sch_1):\MG_DQ-DQS_FAR_DIMM_NG_M_E_BYTE0\" )
					)
					( Units "uMatchProp" "ns" 1.000000)
					( Status sCSetFlattened )
					( Origin gBackEnd )
				)
			)
			( pinPair "@baseboard_fab2_lib.baseboard_fab2(sch_1):\PP1184\"
				( pinRef "@baseboard_fab2_lib.baseboard_fab2(sch_1):page27_i172:DDR4_DQS_DN(9)" )
				( pinRef "@baseboard_fab2_lib.baseboard_fab2(sch_1):page52_i100:DQS9N" )
				( attribute "RELATIVE_PROPAGATION_DELAY_SCOPE" "G"
					( Parent
						( matchGroupRef "@baseboard_fab2_lib.baseboard_fab2(sch_1):\MG_DQ-DQS_NEAR_DIMM_NG_M_E_BYTE0\" )
					)
					( Status sCSetFlattened )
					( Origin gBackEnd )
				)
				( attribute "RELATIVE_PROPAGATION_DELAY" ",5.00 MIL"
					( Parent
						( matchGroupRef "@baseboard_fab2_lib.baseboard_fab2(sch_1):\MG_DQ-DQS_NEAR_DIMM_NG_M_E_BYTE0\" )
					)
					( Units "uMatchProp" "ns" 1.000000)
					( Status sCSetFlattened )
					( Origin gBackEnd )
				)
			)
			( pinPair "@baseboard_fab2_lib.baseboard_fab2(sch_1):\PP1171\"
				( pinRef "@baseboard_fab2_lib.baseboard_fab2(sch_1):page27_i172:DDR4_DQS_DN(10)" )
				( pinRef "@baseboard_fab2_lib.baseboard_fab2(sch_1):page51_i66:DQS10N" )
				( attribute "RELATIVE_PROPAGATION_DELAY_SCOPE" "G"
					( Parent
						( matchGroupRef "@baseboard_fab2_lib.baseboard_fab2(sch_1):\MG_DQ-DQS_FAR_DIMM_NG_M_E_BYTE1\" )
					)
					( Status sCSetFlattened )
					( Origin gBackEnd )
				)
				( attribute "RELATIVE_PROPAGATION_DELAY" ",5.00 MIL"
					( Parent
						( matchGroupRef "@baseboard_fab2_lib.baseboard_fab2(sch_1):\MG_DQ-DQS_FAR_DIMM_NG_M_E_BYTE1\" )
					)
					( Units "uMatchProp" "ns" 1.000000)
					( Status sCSetFlattened )
					( Origin gBackEnd )
				)
			)
			( pinPair "@baseboard_fab2_lib.baseboard_fab2(sch_1):\PP1172\"
				( pinRef "@baseboard_fab2_lib.baseboard_fab2(sch_1):page52_i100:DQS10N" )
				( pinRef "@baseboard_fab2_lib.baseboard_fab2(sch_1):page27_i172:DDR4_DQS_DN(10)" )
				( attribute "RELATIVE_PROPAGATION_DELAY_SCOPE" "G"
					( Parent
						( matchGroupRef "@baseboard_fab2_lib.baseboard_fab2(sch_1):\MG_DQ-DQS_NEAR_DIMM_NG_M_E_BYTE1\" )
					)
					( Status sCSetFlattened )
					( Origin gBackEnd )
				)
				( attribute "RELATIVE_PROPAGATION_DELAY" ",5.00 MIL"
					( Parent
						( matchGroupRef "@baseboard_fab2_lib.baseboard_fab2(sch_1):\MG_DQ-DQS_NEAR_DIMM_NG_M_E_BYTE1\" )
					)
					( Units "uMatchProp" "ns" 1.000000)
					( Status sCSetFlattened )
					( Origin gBackEnd )
				)
			)
			( pinPair "@baseboard_fab2_lib.baseboard_fab2(sch_1):\PP1159\"
				( pinRef "@baseboard_fab2_lib.baseboard_fab2(sch_1):page27_i172:DDR4_DQS_DN(11)" )
				( pinRef "@baseboard_fab2_lib.baseboard_fab2(sch_1):page51_i66:DQS11N" )
				( attribute "RELATIVE_PROPAGATION_DELAY_SCOPE" "G"
					( Parent
						( matchGroupRef "@baseboard_fab2_lib.baseboard_fab2(sch_1):\MG_DQ-DQS_FAR_DIMM_NG_M_E_BYTE2\" )
					)
					( Status sCSetFlattened )
					( Origin gBackEnd )
				)
				( attribute "RELATIVE_PROPAGATION_DELAY" ",5.00 MIL"
					( Parent
						( matchGroupRef "@baseboard_fab2_lib.baseboard_fab2(sch_1):\MG_DQ-DQS_FAR_DIMM_NG_M_E_BYTE2\" )
					)
					( Units "uMatchProp" "ns" 1.000000)
					( Status sCSetFlattened )
					( Origin gBackEnd )
				)
			)
			( pinPair "@baseboard_fab2_lib.baseboard_fab2(sch_1):\PP1160\"
				( pinRef "@baseboard_fab2_lib.baseboard_fab2(sch_1):page52_i100:DQS11N" )
				( pinRef "@baseboard_fab2_lib.baseboard_fab2(sch_1):page27_i172:DDR4_DQS_DN(11)" )
				( attribute "RELATIVE_PROPAGATION_DELAY_SCOPE" "G"
					( Parent
						( matchGroupRef "@baseboard_fab2_lib.baseboard_fab2(sch_1):\MG_DQ-DQS_NEAR_DIMM_NG_M_E_BYTE2\" )
					)
					( Status sCSetFlattened )
					( Origin gBackEnd )
				)
				( attribute "RELATIVE_PROPAGATION_DELAY" ",5.00 MIL"
					( Parent
						( matchGroupRef "@baseboard_fab2_lib.baseboard_fab2(sch_1):\MG_DQ-DQS_NEAR_DIMM_NG_M_E_BYTE2\" )
					)
					( Units "uMatchProp" "ns" 1.000000)
					( Status sCSetFlattened )
					( Origin gBackEnd )
				)
			)
			( pinPair "@baseboard_fab2_lib.baseboard_fab2(sch_1):\PP1147\"
				( pinRef "@baseboard_fab2_lib.baseboard_fab2(sch_1):page27_i172:DDR4_DQS_DN(12)" )
				( pinRef "@baseboard_fab2_lib.baseboard_fab2(sch_1):page51_i66:DQS12N" )
				( attribute "RELATIVE_PROPAGATION_DELAY_SCOPE" "G"
					( Parent
						( matchGroupRef "@baseboard_fab2_lib.baseboard_fab2(sch_1):\MG_DQ-DQS_FAR_DIMM_NG_M_E_BYTE3\" )
					)
					( Status sCSetFlattened )
					( Origin gBackEnd )
				)
				( attribute "RELATIVE_PROPAGATION_DELAY" ",5.00 MIL"
					( Parent
						( matchGroupRef "@baseboard_fab2_lib.baseboard_fab2(sch_1):\MG_DQ-DQS_FAR_DIMM_NG_M_E_BYTE3\" )
					)
					( Units "uMatchProp" "ns" 1.000000)
					( Status sCSetFlattened )
					( Origin gBackEnd )
				)
			)
			( pinPair "@baseboard_fab2_lib.baseboard_fab2(sch_1):\PP1148\"
				( pinRef "@baseboard_fab2_lib.baseboard_fab2(sch_1):page27_i172:DDR4_DQS_DN(12)" )
				( pinRef "@baseboard_fab2_lib.baseboard_fab2(sch_1):page52_i100:DQS12N" )
				( attribute "RELATIVE_PROPAGATION_DELAY_SCOPE" "G"
					( Parent
						( matchGroupRef "@baseboard_fab2_lib.baseboard_fab2(sch_1):\MG_DQ-DQS_NEAR_DIMM_NG_M_E_BYTE3\" )
					)
					( Status sCSetFlattened )
					( Origin gBackEnd )
				)
				( attribute "RELATIVE_PROPAGATION_DELAY" ",5.00 MIL"
					( Parent
						( matchGroupRef "@baseboard_fab2_lib.baseboard_fab2(sch_1):\MG_DQ-DQS_NEAR_DIMM_NG_M_E_BYTE3\" )
					)
					( Units "uMatchProp" "ns" 1.000000)
					( Status sCSetFlattened )
					( Origin gBackEnd )
				)
			)
			( pinPair "@baseboard_fab2_lib.baseboard_fab2(sch_1):\PP1135\"
				( pinRef "@baseboard_fab2_lib.baseboard_fab2(sch_1):page27_i172:DDR4_DQS_DN(13)" )
				( pinRef "@baseboard_fab2_lib.baseboard_fab2(sch_1):page51_i66:DQS13N" )
				( attribute "RELATIVE_PROPAGATION_DELAY_SCOPE" "G"
					( Parent
						( matchGroupRef "@baseboard_fab2_lib.baseboard_fab2(sch_1):\MG_DQ-DQS_FAR_DIMM_NG_M_E_BYTE4\" )
					)
					( Status sCSetFlattened )
					( Origin gBackEnd )
				)
				( attribute "RELATIVE_PROPAGATION_DELAY" ",5.00 MIL"
					( Parent
						( matchGroupRef "@baseboard_fab2_lib.baseboard_fab2(sch_1):\MG_DQ-DQS_FAR_DIMM_NG_M_E_BYTE4\" )
					)
					( Units "uMatchProp" "ns" 1.000000)
					( Status sCSetFlattened )
					( Origin gBackEnd )
				)
			)
			( pinPair "@baseboard_fab2_lib.baseboard_fab2(sch_1):\PP1137\"
				( pinRef "@baseboard_fab2_lib.baseboard_fab2(sch_1):page27_i172:DDR4_DQS_DN(13)" )
				( pinRef "@baseboard_fab2_lib.baseboard_fab2(sch_1):page52_i100:DQS13N" )
				( attribute "RELATIVE_PROPAGATION_DELAY_SCOPE" "G"
					( Parent
						( matchGroupRef "@baseboard_fab2_lib.baseboard_fab2(sch_1):\MG_DQ-DQS_NEAR_DIMM_NG_M_E_BYTE4\" )
					)
					( Status sCSetFlattened )
					( Origin gBackEnd )
				)
				( attribute "RELATIVE_PROPAGATION_DELAY" ",5.00 MIL"
					( Parent
						( matchGroupRef "@baseboard_fab2_lib.baseboard_fab2(sch_1):\MG_DQ-DQS_NEAR_DIMM_NG_M_E_BYTE4\" )
					)
					( Units "uMatchProp" "ns" 1.000000)
					( Status sCSetFlattened )
					( Origin gBackEnd )
				)
			)
			( pinPair "@baseboard_fab2_lib.baseboard_fab2(sch_1):\PP1123\"
				( pinRef "@baseboard_fab2_lib.baseboard_fab2(sch_1):page27_i172:DDR4_DQS_DN(14)" )
				( pinRef "@baseboard_fab2_lib.baseboard_fab2(sch_1):page51_i66:DQS14N" )
				( attribute "RELATIVE_PROPAGATION_DELAY_SCOPE" "G"
					( Parent
						( matchGroupRef "@baseboard_fab2_lib.baseboard_fab2(sch_1):\MG_DQ-DQS_FAR_DIMM_NG_M_E_BYTE5\" )
					)
					( Status sCSetFlattened )
					( Origin gBackEnd )
				)
				( attribute "RELATIVE_PROPAGATION_DELAY" ",5.00 MIL"
					( Parent
						( matchGroupRef "@baseboard_fab2_lib.baseboard_fab2(sch_1):\MG_DQ-DQS_FAR_DIMM_NG_M_E_BYTE5\" )
					)
					( Units "uMatchProp" "ns" 1.000000)
					( Status sCSetFlattened )
					( Origin gBackEnd )
				)
			)
			( pinPair "@baseboard_fab2_lib.baseboard_fab2(sch_1):\PP1125\"
				( pinRef "@baseboard_fab2_lib.baseboard_fab2(sch_1):page52_i100:DQS14N" )
				( pinRef "@baseboard_fab2_lib.baseboard_fab2(sch_1):page27_i172:DDR4_DQS_DN(14)" )
				( attribute "RELATIVE_PROPAGATION_DELAY_SCOPE" "G"
					( Parent
						( matchGroupRef "@baseboard_fab2_lib.baseboard_fab2(sch_1):\MG_DQ-DQS_NEAR_DIMM_NG_M_E_BYTE5\" )
					)
					( Status sCSetFlattened )
					( Origin gBackEnd )
				)
				( attribute "RELATIVE_PROPAGATION_DELAY" ",5.00 MIL"
					( Parent
						( matchGroupRef "@baseboard_fab2_lib.baseboard_fab2(sch_1):\MG_DQ-DQS_NEAR_DIMM_NG_M_E_BYTE5\" )
					)
					( Units "uMatchProp" "ns" 1.000000)
					( Status sCSetFlattened )
					( Origin gBackEnd )
				)
			)
			( pinPair "@baseboard_fab2_lib.baseboard_fab2(sch_1):\PP1111\"
				( pinRef "@baseboard_fab2_lib.baseboard_fab2(sch_1):page27_i172:DDR4_DQS_DN(15)" )
				( pinRef "@baseboard_fab2_lib.baseboard_fab2(sch_1):page51_i66:DQS15N" )
				( attribute "RELATIVE_PROPAGATION_DELAY_SCOPE" "G"
					( Parent
						( matchGroupRef "@baseboard_fab2_lib.baseboard_fab2(sch_1):\MG_DQ-DQS_FAR_DIMM_NG_M_E_BYTE6\" )
					)
					( Status sCSetFlattened )
					( Origin gBackEnd )
				)
				( attribute "RELATIVE_PROPAGATION_DELAY" ",5.00 MIL"
					( Parent
						( matchGroupRef "@baseboard_fab2_lib.baseboard_fab2(sch_1):\MG_DQ-DQS_FAR_DIMM_NG_M_E_BYTE6\" )
					)
					( Units "uMatchProp" "ns" 1.000000)
					( Status sCSetFlattened )
					( Origin gBackEnd )
				)
			)
			( pinPair "@baseboard_fab2_lib.baseboard_fab2(sch_1):\PP1113\"
				( pinRef "@baseboard_fab2_lib.baseboard_fab2(sch_1):page27_i172:DDR4_DQS_DN(15)" )
				( pinRef "@baseboard_fab2_lib.baseboard_fab2(sch_1):page52_i100:DQS15N" )
				( attribute "RELATIVE_PROPAGATION_DELAY_SCOPE" "G"
					( Parent
						( matchGroupRef "@baseboard_fab2_lib.baseboard_fab2(sch_1):\MG_DQ-DQS_NEAR_DIMM_NG_M_E_BYTE6\" )
					)
					( Status sCSetFlattened )
					( Origin gBackEnd )
				)
				( attribute "RELATIVE_PROPAGATION_DELAY" ",5.00 MIL"
					( Parent
						( matchGroupRef "@baseboard_fab2_lib.baseboard_fab2(sch_1):\MG_DQ-DQS_NEAR_DIMM_NG_M_E_BYTE6\" )
					)
					( Units "uMatchProp" "ns" 1.000000)
					( Status sCSetFlattened )
					( Origin gBackEnd )
				)
			)
			( pinPair "@baseboard_fab2_lib.baseboard_fab2(sch_1):\PP1099\"
				( pinRef "@baseboard_fab2_lib.baseboard_fab2(sch_1):page27_i172:DDR4_DQS_DN(16)" )
				( pinRef "@baseboard_fab2_lib.baseboard_fab2(sch_1):page51_i66:DQS16N" )
				( attribute "RELATIVE_PROPAGATION_DELAY_SCOPE" "G"
					( Parent
						( matchGroupRef "@baseboard_fab2_lib.baseboard_fab2(sch_1):\MG_DQ-DQS_FAR_DIMM_NG_M_E_BYTE7\" )
					)
					( Status sCSetFlattened )
					( Origin gBackEnd )
				)
				( attribute "RELATIVE_PROPAGATION_DELAY" ",5.00 MIL"
					( Parent
						( matchGroupRef "@baseboard_fab2_lib.baseboard_fab2(sch_1):\MG_DQ-DQS_FAR_DIMM_NG_M_E_BYTE7\" )
					)
					( Units "uMatchProp" "ns" 1.000000)
					( Status sCSetFlattened )
					( Origin gBackEnd )
				)
			)
			( pinPair "@baseboard_fab2_lib.baseboard_fab2(sch_1):\PP1101\"
				( pinRef "@baseboard_fab2_lib.baseboard_fab2(sch_1):page52_i100:DQS16N" )
				( pinRef "@baseboard_fab2_lib.baseboard_fab2(sch_1):page27_i172:DDR4_DQS_DN(16)" )
				( attribute "RELATIVE_PROPAGATION_DELAY_SCOPE" "G"
					( Parent
						( matchGroupRef "@baseboard_fab2_lib.baseboard_fab2(sch_1):\MG_DQ-DQS_NEAR_DIMM_NG_M_E_BYTE7\" )
					)
					( Status sCSetFlattened )
					( Origin gBackEnd )
				)
				( attribute "RELATIVE_PROPAGATION_DELAY" ",5.00 MIL"
					( Parent
						( matchGroupRef "@baseboard_fab2_lib.baseboard_fab2(sch_1):\MG_DQ-DQS_NEAR_DIMM_NG_M_E_BYTE7\" )
					)
					( Units "uMatchProp" "ns" 1.000000)
					( Status sCSetFlattened )
					( Origin gBackEnd )
				)
			)
			( pinPair "@baseboard_fab2_lib.baseboard_fab2(sch_1):\PP1087\"
				( pinRef "@baseboard_fab2_lib.baseboard_fab2(sch_1):page27_i172:DDR4_DQS_DN(17)" )
				( pinRef "@baseboard_fab2_lib.baseboard_fab2(sch_1):page51_i66:DQS17N" )
				( attribute "RELATIVE_PROPAGATION_DELAY_SCOPE" "G"
					( Parent
						( matchGroupRef "@baseboard_fab2_lib.baseboard_fab2(sch_1):\MG_DQ-DQS_FAR_DIMM_NG_M_E_BYTE-ECC\" )
					)
					( Status sCSetFlattened )
					( Origin gBackEnd )
				)
				( attribute "RELATIVE_PROPAGATION_DELAY" ",5.00 MIL"
					( Parent
						( matchGroupRef "@baseboard_fab2_lib.baseboard_fab2(sch_1):\MG_DQ-DQS_FAR_DIMM_NG_M_E_BYTE-ECC\" )
					)
					( Units "uMatchProp" "ns" 1.000000)
					( Status sCSetFlattened )
					( Origin gBackEnd )
				)
			)
			( pinPair "@baseboard_fab2_lib.baseboard_fab2(sch_1):\PP1088\"
				( pinRef "@baseboard_fab2_lib.baseboard_fab2(sch_1):page27_i172:DDR4_DQS_DN(17)" )
				( pinRef "@baseboard_fab2_lib.baseboard_fab2(sch_1):page52_i100:DQS17N" )
				( attribute "RELATIVE_PROPAGATION_DELAY_SCOPE" "G"
					( Parent
						( matchGroupRef "@baseboard_fab2_lib.baseboard_fab2(sch_1):\MG_DQ-DQS_NEAR_DIMM_NG_M_E_BYTE-ECC\" )
					)
					( Status sCSetFlattened )
					( Origin gBackEnd )
				)
				( attribute "RELATIVE_PROPAGATION_DELAY" ",5.00 MIL"
					( Parent
						( matchGroupRef "@baseboard_fab2_lib.baseboard_fab2(sch_1):\MG_DQ-DQS_NEAR_DIMM_NG_M_E_BYTE-ECC\" )
					)
					( Units "uMatchProp" "ns" 1.000000)
					( Status sCSetFlattened )
					( Origin gBackEnd )
				)
			)
			( pinPair "@baseboard_fab2_lib.baseboard_fab2(sch_1):\PP664\"
				( pinRef "@baseboard_fab2_lib.baseboard_fab2(sch_1):page25_i172:DDR2_DQS_DP(0)" )
				( pinRef "@baseboard_fab2_lib.baseboard_fab2(sch_1):page47_i61:DQS0P" )
				( attribute "RELATIVE_PROPAGATION_DELAY_SCOPE" "G"
					( Parent
						( matchGroupRef "@baseboard_fab2_lib.baseboard_fab2(sch_1):\MG_DQ-DQS_FAR_DIMM_NG_M_C_BYTE0\" )
					)
					( Status sCSetFlattened )
					( Origin gBackEnd )
				)
				( attribute "RELATIVE_PROPAGATION_DELAY" ",5.00 MIL"
					( Parent
						( matchGroupRef "@baseboard_fab2_lib.baseboard_fab2(sch_1):\MG_DQ-DQS_FAR_DIMM_NG_M_C_BYTE0\" )
					)
					( Units "uMatchProp" "ns" 1.000000)
					( Status sCSetFlattened )
					( Origin gBackEnd )
				)
			)
			( pinPair "@baseboard_fab2_lib.baseboard_fab2(sch_1):\PP665\"
				( pinRef "@baseboard_fab2_lib.baseboard_fab2(sch_1):page25_i172:DDR2_DQS_DP(0)" )
				( pinRef "@baseboard_fab2_lib.baseboard_fab2(sch_1):page48_i61:DQS0P" )
				( attribute "RELATIVE_PROPAGATION_DELAY_SCOPE" "G"
					( Parent
						( matchGroupRef "@baseboard_fab2_lib.baseboard_fab2(sch_1):\MG_DQ-DQS_NEAR_DIMM_NG_M_C_BYTE0\" )
					)
					( Status sCSetFlattened )
					( Origin gBackEnd )
				)
				( attribute "RELATIVE_PROPAGATION_DELAY" ",5.00 MIL"
					( Parent
						( matchGroupRef "@baseboard_fab2_lib.baseboard_fab2(sch_1):\MG_DQ-DQS_NEAR_DIMM_NG_M_C_BYTE0\" )
					)
					( Units "uMatchProp" "ns" 1.000000)
					( Status sCSetFlattened )
					( Origin gBackEnd )
				)
			)
			( pinPair "@baseboard_fab2_lib.baseboard_fab2(sch_1):\PP652\"
				( pinRef "@baseboard_fab2_lib.baseboard_fab2(sch_1):page25_i172:DDR2_DQS_DP(1)" )
				( pinRef "@baseboard_fab2_lib.baseboard_fab2(sch_1):page47_i61:DQS1P" )
				( attribute "RELATIVE_PROPAGATION_DELAY_SCOPE" "G"
					( Parent
						( matchGroupRef "@baseboard_fab2_lib.baseboard_fab2(sch_1):\MG_DQ-DQS_FAR_DIMM_NG_M_C_BYTE1\" )
					)
					( Status sCSetFlattened )
					( Origin gBackEnd )
				)
				( attribute "RELATIVE_PROPAGATION_DELAY" ",5.00 MIL"
					( Parent
						( matchGroupRef "@baseboard_fab2_lib.baseboard_fab2(sch_1):\MG_DQ-DQS_FAR_DIMM_NG_M_C_BYTE1\" )
					)
					( Units "uMatchProp" "ns" 1.000000)
					( Status sCSetFlattened )
					( Origin gBackEnd )
				)
			)
			( pinPair "@baseboard_fab2_lib.baseboard_fab2(sch_1):\PP653\"
				( pinRef "@baseboard_fab2_lib.baseboard_fab2(sch_1):page25_i172:DDR2_DQS_DP(1)" )
				( pinRef "@baseboard_fab2_lib.baseboard_fab2(sch_1):page48_i61:DQS1P" )
				( attribute "RELATIVE_PROPAGATION_DELAY_SCOPE" "G"
					( Parent
						( matchGroupRef "@baseboard_fab2_lib.baseboard_fab2(sch_1):\MG_DQ-DQS_NEAR_DIMM_NG_M_C_BYTE1\" )
					)
					( Status sCSetFlattened )
					( Origin gBackEnd )
				)
				( attribute "RELATIVE_PROPAGATION_DELAY" ",5.00 MIL"
					( Parent
						( matchGroupRef "@baseboard_fab2_lib.baseboard_fab2(sch_1):\MG_DQ-DQS_NEAR_DIMM_NG_M_C_BYTE1\" )
					)
					( Units "uMatchProp" "ns" 1.000000)
					( Status sCSetFlattened )
					( Origin gBackEnd )
				)
			)
			( pinPair "@baseboard_fab2_lib.baseboard_fab2(sch_1):\PP640\"
				( pinRef "@baseboard_fab2_lib.baseboard_fab2(sch_1):page25_i172:DDR2_DQS_DP(2)" )
				( pinRef "@baseboard_fab2_lib.baseboard_fab2(sch_1):page47_i61:DQS2P" )
				( attribute "RELATIVE_PROPAGATION_DELAY_SCOPE" "G"
					( Parent
						( matchGroupRef "@baseboard_fab2_lib.baseboard_fab2(sch_1):\MG_DQ-DQS_FAR_DIMM_NG_M_C_BYTE2\" )
					)
					( Status sCSetFlattened )
					( Origin gBackEnd )
				)
				( attribute "RELATIVE_PROPAGATION_DELAY" ",5.00 MIL"
					( Parent
						( matchGroupRef "@baseboard_fab2_lib.baseboard_fab2(sch_1):\MG_DQ-DQS_FAR_DIMM_NG_M_C_BYTE2\" )
					)
					( Units "uMatchProp" "ns" 1.000000)
					( Status sCSetFlattened )
					( Origin gBackEnd )
				)
			)
			( pinPair "@baseboard_fab2_lib.baseboard_fab2(sch_1):\PP641\"
				( pinRef "@baseboard_fab2_lib.baseboard_fab2(sch_1):page25_i172:DDR2_DQS_DP(2)" )
				( pinRef "@baseboard_fab2_lib.baseboard_fab2(sch_1):page48_i61:DQS2P" )
				( attribute "RELATIVE_PROPAGATION_DELAY_SCOPE" "G"
					( Parent
						( matchGroupRef "@baseboard_fab2_lib.baseboard_fab2(sch_1):\MG_DQ-DQS_NEAR_DIMM_NG_M_C_BYTE2\" )
					)
					( Status sCSetFlattened )
					( Origin gBackEnd )
				)
				( attribute "RELATIVE_PROPAGATION_DELAY" ",5.00 MIL"
					( Parent
						( matchGroupRef "@baseboard_fab2_lib.baseboard_fab2(sch_1):\MG_DQ-DQS_NEAR_DIMM_NG_M_C_BYTE2\" )
					)
					( Units "uMatchProp" "ns" 1.000000)
					( Status sCSetFlattened )
					( Origin gBackEnd )
				)
			)
			( pinPair "@baseboard_fab2_lib.baseboard_fab2(sch_1):\PP628\"
				( pinRef "@baseboard_fab2_lib.baseboard_fab2(sch_1):page25_i172:DDR2_DQS_DP(3)" )
				( pinRef "@baseboard_fab2_lib.baseboard_fab2(sch_1):page47_i61:DQS3P" )
				( attribute "RELATIVE_PROPAGATION_DELAY_SCOPE" "G"
					( Parent
						( matchGroupRef "@baseboard_fab2_lib.baseboard_fab2(sch_1):\MG_DQ-DQS_FAR_DIMM_NG_M_C_BYTE3\" )
					)
					( Status sCSetFlattened )
					( Origin gBackEnd )
				)
				( attribute "RELATIVE_PROPAGATION_DELAY" ",5.00 MIL"
					( Parent
						( matchGroupRef "@baseboard_fab2_lib.baseboard_fab2(sch_1):\MG_DQ-DQS_FAR_DIMM_NG_M_C_BYTE3\" )
					)
					( Units "uMatchProp" "ns" 1.000000)
					( Status sCSetFlattened )
					( Origin gBackEnd )
				)
			)
			( pinPair "@baseboard_fab2_lib.baseboard_fab2(sch_1):\PP629\"
				( pinRef "@baseboard_fab2_lib.baseboard_fab2(sch_1):page25_i172:DDR2_DQS_DP(3)" )
				( pinRef "@baseboard_fab2_lib.baseboard_fab2(sch_1):page48_i61:DQS3P" )
				( attribute "RELATIVE_PROPAGATION_DELAY_SCOPE" "G"
					( Parent
						( matchGroupRef "@baseboard_fab2_lib.baseboard_fab2(sch_1):\MG_DQ-DQS_NEAR_DIMM_NG_M_C_BYTE3\" )
					)
					( Status sCSetFlattened )
					( Origin gBackEnd )
				)
				( attribute "RELATIVE_PROPAGATION_DELAY" ",5.00 MIL"
					( Parent
						( matchGroupRef "@baseboard_fab2_lib.baseboard_fab2(sch_1):\MG_DQ-DQS_NEAR_DIMM_NG_M_C_BYTE3\" )
					)
					( Units "uMatchProp" "ns" 1.000000)
					( Status sCSetFlattened )
					( Origin gBackEnd )
				)
			)
			( pinPair "@baseboard_fab2_lib.baseboard_fab2(sch_1):\PP616\"
				( pinRef "@baseboard_fab2_lib.baseboard_fab2(sch_1):page25_i172:DDR2_DQS_DP(4)" )
				( pinRef "@baseboard_fab2_lib.baseboard_fab2(sch_1):page47_i61:DQS4P" )
				( attribute "RELATIVE_PROPAGATION_DELAY_SCOPE" "G"
					( Parent
						( matchGroupRef "@baseboard_fab2_lib.baseboard_fab2(sch_1):\MG_DQ-DQS_FAR_DIMM_NG_M_C_BYTE4\" )
					)
					( Status sCSetFlattened )
					( Origin gBackEnd )
				)
				( attribute "RELATIVE_PROPAGATION_DELAY" ",5.00 MIL"
					( Parent
						( matchGroupRef "@baseboard_fab2_lib.baseboard_fab2(sch_1):\MG_DQ-DQS_FAR_DIMM_NG_M_C_BYTE4\" )
					)
					( Units "uMatchProp" "ns" 1.000000)
					( Status sCSetFlattened )
					( Origin gBackEnd )
				)
			)
			( pinPair "@baseboard_fab2_lib.baseboard_fab2(sch_1):\PP618\"
				( pinRef "@baseboard_fab2_lib.baseboard_fab2(sch_1):page25_i172:DDR2_DQS_DP(4)" )
				( pinRef "@baseboard_fab2_lib.baseboard_fab2(sch_1):page48_i61:DQS4P" )
				( attribute "RELATIVE_PROPAGATION_DELAY_SCOPE" "G"
					( Parent
						( matchGroupRef "@baseboard_fab2_lib.baseboard_fab2(sch_1):\MG_DQ-DQS_NEAR_DIMM_NG_M_C_BYTE4\" )
					)
					( Status sCSetFlattened )
					( Origin gBackEnd )
				)
				( attribute "RELATIVE_PROPAGATION_DELAY" ",5.00 MIL"
					( Parent
						( matchGroupRef "@baseboard_fab2_lib.baseboard_fab2(sch_1):\MG_DQ-DQS_NEAR_DIMM_NG_M_C_BYTE4\" )
					)
					( Units "uMatchProp" "ns" 1.000000)
					( Status sCSetFlattened )
					( Origin gBackEnd )
				)
			)
			( pinPair "@baseboard_fab2_lib.baseboard_fab2(sch_1):\PP604\"
				( pinRef "@baseboard_fab2_lib.baseboard_fab2(sch_1):page25_i172:DDR2_DQS_DP(5)" )
				( pinRef "@baseboard_fab2_lib.baseboard_fab2(sch_1):page47_i61:DQS5P" )
				( attribute "RELATIVE_PROPAGATION_DELAY_SCOPE" "G"
					( Parent
						( matchGroupRef "@baseboard_fab2_lib.baseboard_fab2(sch_1):\MG_DQ-DQS_FAR_DIMM_NG_M_C_BYTE5\" )
					)
					( Status sCSetFlattened )
					( Origin gBackEnd )
				)
				( attribute "RELATIVE_PROPAGATION_DELAY" ",5.00 MIL"
					( Parent
						( matchGroupRef "@baseboard_fab2_lib.baseboard_fab2(sch_1):\MG_DQ-DQS_FAR_DIMM_NG_M_C_BYTE5\" )
					)
					( Units "uMatchProp" "ns" 1.000000)
					( Status sCSetFlattened )
					( Origin gBackEnd )
				)
			)
			( pinPair "@baseboard_fab2_lib.baseboard_fab2(sch_1):\PP606\"
				( pinRef "@baseboard_fab2_lib.baseboard_fab2(sch_1):page25_i172:DDR2_DQS_DP(5)" )
				( pinRef "@baseboard_fab2_lib.baseboard_fab2(sch_1):page48_i61:DQS5P" )
				( attribute "RELATIVE_PROPAGATION_DELAY_SCOPE" "G"
					( Parent
						( matchGroupRef "@baseboard_fab2_lib.baseboard_fab2(sch_1):\MG_DQ-DQS_NEAR_DIMM_NG_M_C_BYTE5\" )
					)
					( Status sCSetFlattened )
					( Origin gBackEnd )
				)
				( attribute "RELATIVE_PROPAGATION_DELAY" ",5.00 MIL"
					( Parent
						( matchGroupRef "@baseboard_fab2_lib.baseboard_fab2(sch_1):\MG_DQ-DQS_NEAR_DIMM_NG_M_C_BYTE5\" )
					)
					( Units "uMatchProp" "ns" 1.000000)
					( Status sCSetFlattened )
					( Origin gBackEnd )
				)
			)
			( pinPair "@baseboard_fab2_lib.baseboard_fab2(sch_1):\PP592\"
				( pinRef "@baseboard_fab2_lib.baseboard_fab2(sch_1):page25_i172:DDR2_DQS_DP(6)" )
				( pinRef "@baseboard_fab2_lib.baseboard_fab2(sch_1):page47_i61:DQS6P" )
				( attribute "RELATIVE_PROPAGATION_DELAY_SCOPE" "G"
					( Parent
						( matchGroupRef "@baseboard_fab2_lib.baseboard_fab2(sch_1):\MG_DQ-DQS_FAR_DIMM_NG_M_C_BYTE6\" )
					)
					( Status sCSetFlattened )
					( Origin gBackEnd )
				)
				( attribute "RELATIVE_PROPAGATION_DELAY" ",5.00 MIL"
					( Parent
						( matchGroupRef "@baseboard_fab2_lib.baseboard_fab2(sch_1):\MG_DQ-DQS_FAR_DIMM_NG_M_C_BYTE6\" )
					)
					( Units "uMatchProp" "ns" 1.000000)
					( Status sCSetFlattened )
					( Origin gBackEnd )
				)
			)
			( pinPair "@baseboard_fab2_lib.baseboard_fab2(sch_1):\PP594\"
				( pinRef "@baseboard_fab2_lib.baseboard_fab2(sch_1):page25_i172:DDR2_DQS_DP(6)" )
				( pinRef "@baseboard_fab2_lib.baseboard_fab2(sch_1):page48_i61:DQS6P" )
				( attribute "RELATIVE_PROPAGATION_DELAY_SCOPE" "G"
					( Parent
						( matchGroupRef "@baseboard_fab2_lib.baseboard_fab2(sch_1):\MG_DQ-DQS_NEAR_DIMM_NG_M_C_BYTE6\" )
					)
					( Status sCSetFlattened )
					( Origin gBackEnd )
				)
				( attribute "RELATIVE_PROPAGATION_DELAY" ",5.00 MIL"
					( Parent
						( matchGroupRef "@baseboard_fab2_lib.baseboard_fab2(sch_1):\MG_DQ-DQS_NEAR_DIMM_NG_M_C_BYTE6\" )
					)
					( Units "uMatchProp" "ns" 1.000000)
					( Status sCSetFlattened )
					( Origin gBackEnd )
				)
			)
			( pinPair "@baseboard_fab2_lib.baseboard_fab2(sch_1):\PP580\"
				( pinRef "@baseboard_fab2_lib.baseboard_fab2(sch_1):page25_i172:DDR2_DQS_DP(7)" )
				( pinRef "@baseboard_fab2_lib.baseboard_fab2(sch_1):page47_i61:DQS7P" )
				( attribute "RELATIVE_PROPAGATION_DELAY_SCOPE" "G"
					( Parent
						( matchGroupRef "@baseboard_fab2_lib.baseboard_fab2(sch_1):\MG_DQ-DQS_FAR_DIMM_NG_M_C_BYTE7\" )
					)
					( Status sCSetFlattened )
					( Origin gBackEnd )
				)
				( attribute "RELATIVE_PROPAGATION_DELAY" ",5.00 MIL"
					( Parent
						( matchGroupRef "@baseboard_fab2_lib.baseboard_fab2(sch_1):\MG_DQ-DQS_FAR_DIMM_NG_M_C_BYTE7\" )
					)
					( Units "uMatchProp" "ns" 1.000000)
					( Status sCSetFlattened )
					( Origin gBackEnd )
				)
			)
			( pinPair "@baseboard_fab2_lib.baseboard_fab2(sch_1):\PP582\"
				( pinRef "@baseboard_fab2_lib.baseboard_fab2(sch_1):page25_i172:DDR2_DQS_DP(7)" )
				( pinRef "@baseboard_fab2_lib.baseboard_fab2(sch_1):page48_i61:DQS7P" )
				( attribute "RELATIVE_PROPAGATION_DELAY_SCOPE" "G"
					( Parent
						( matchGroupRef "@baseboard_fab2_lib.baseboard_fab2(sch_1):\MG_DQ-DQS_NEAR_DIMM_NG_M_C_BYTE7\" )
					)
					( Status sCSetFlattened )
					( Origin gBackEnd )
				)
				( attribute "RELATIVE_PROPAGATION_DELAY" ",5.00 MIL"
					( Parent
						( matchGroupRef "@baseboard_fab2_lib.baseboard_fab2(sch_1):\MG_DQ-DQS_NEAR_DIMM_NG_M_C_BYTE7\" )
					)
					( Units "uMatchProp" "ns" 1.000000)
					( Status sCSetFlattened )
					( Origin gBackEnd )
				)
			)
			( pinPair "@baseboard_fab2_lib.baseboard_fab2(sch_1):\PP1216\"
				( pinRef "@baseboard_fab2_lib.baseboard_fab2(sch_1):page25_i172:DDR2_DQS_DP(8)" )
				( pinRef "@baseboard_fab2_lib.baseboard_fab2(sch_1):page47_i61:DQS8P" )
				( attribute "RELATIVE_PROPAGATION_DELAY_SCOPE" "G"
					( Parent
						( matchGroupRef "@baseboard_fab2_lib.baseboard_fab2(sch_1):\MG_DQ-DQS_FAR_DIMM_NG_M_C_BYTE-ECC\" )
					)
					( Status sCSetFlattened )
					( Origin gBackEnd )
				)
				( attribute "RELATIVE_PROPAGATION_DELAY" ",5.00 MIL"
					( Parent
						( matchGroupRef "@baseboard_fab2_lib.baseboard_fab2(sch_1):\MG_DQ-DQS_FAR_DIMM_NG_M_C_BYTE-ECC\" )
					)
					( Units "uMatchProp" "ns" 1.000000)
					( Status sCSetFlattened )
					( Origin gBackEnd )
				)
			)
			( pinPair "@baseboard_fab2_lib.baseboard_fab2(sch_1):\PP1217\"
				( pinRef "@baseboard_fab2_lib.baseboard_fab2(sch_1):page25_i172:DDR2_DQS_DP(8)" )
				( pinRef "@baseboard_fab2_lib.baseboard_fab2(sch_1):page48_i61:DQS8P" )
				( attribute "RELATIVE_PROPAGATION_DELAY_SCOPE" "G"
					( Parent
						( matchGroupRef "@baseboard_fab2_lib.baseboard_fab2(sch_1):\MG_DQ-DQS_NEAR_DIMM_NG_M_C_BYTE-ECC\" )
					)
					( Status sCSetFlattened )
					( Origin gBackEnd )
				)
				( attribute "RELATIVE_PROPAGATION_DELAY" ",5.00 MIL"
					( Parent
						( matchGroupRef "@baseboard_fab2_lib.baseboard_fab2(sch_1):\MG_DQ-DQS_NEAR_DIMM_NG_M_C_BYTE-ECC\" )
					)
					( Units "uMatchProp" "ns" 1.000000)
					( Status sCSetFlattened )
					( Origin gBackEnd )
				)
			)
			( pinPair "@baseboard_fab2_lib.baseboard_fab2(sch_1):\PP658\"
				( pinRef "@baseboard_fab2_lib.baseboard_fab2(sch_1):page25_i172:DDR2_DQS_DP(9)" )
				( pinRef "@baseboard_fab2_lib.baseboard_fab2(sch_1):page47_i61:DQS9P" )
				( attribute "RELATIVE_PROPAGATION_DELAY_SCOPE" "G"
					( Parent
						( matchGroupRef "@baseboard_fab2_lib.baseboard_fab2(sch_1):\MG_DQ-DQS_FAR_DIMM_NG_M_C_BYTE0\" )
					)
					( Status sCSetFlattened )
					( Origin gBackEnd )
				)
				( attribute "RELATIVE_PROPAGATION_DELAY" ",5.00 MIL"
					( Parent
						( matchGroupRef "@baseboard_fab2_lib.baseboard_fab2(sch_1):\MG_DQ-DQS_FAR_DIMM_NG_M_C_BYTE0\" )
					)
					( Units "uMatchProp" "ns" 1.000000)
					( Status sCSetFlattened )
					( Origin gBackEnd )
				)
			)
			( pinPair "@baseboard_fab2_lib.baseboard_fab2(sch_1):\PP659\"
				( pinRef "@baseboard_fab2_lib.baseboard_fab2(sch_1):page25_i172:DDR2_DQS_DP(9)" )
				( pinRef "@baseboard_fab2_lib.baseboard_fab2(sch_1):page48_i61:DQS9P" )
				( attribute "RELATIVE_PROPAGATION_DELAY_SCOPE" "G"
					( Parent
						( matchGroupRef "@baseboard_fab2_lib.baseboard_fab2(sch_1):\MG_DQ-DQS_NEAR_DIMM_NG_M_C_BYTE0\" )
					)
					( Status sCSetFlattened )
					( Origin gBackEnd )
				)
				( attribute "RELATIVE_PROPAGATION_DELAY" ",5.00 MIL"
					( Parent
						( matchGroupRef "@baseboard_fab2_lib.baseboard_fab2(sch_1):\MG_DQ-DQS_NEAR_DIMM_NG_M_C_BYTE0\" )
					)
					( Units "uMatchProp" "ns" 1.000000)
					( Status sCSetFlattened )
					( Origin gBackEnd )
				)
			)
			( pinPair "@baseboard_fab2_lib.baseboard_fab2(sch_1):\PP646\"
				( pinRef "@baseboard_fab2_lib.baseboard_fab2(sch_1):page25_i172:DDR2_DQS_DP(10)" )
				( pinRef "@baseboard_fab2_lib.baseboard_fab2(sch_1):page47_i61:DQS10P" )
				( attribute "RELATIVE_PROPAGATION_DELAY_SCOPE" "G"
					( Parent
						( matchGroupRef "@baseboard_fab2_lib.baseboard_fab2(sch_1):\MG_DQ-DQS_FAR_DIMM_NG_M_C_BYTE1\" )
					)
					( Status sCSetFlattened )
					( Origin gBackEnd )
				)
				( attribute "RELATIVE_PROPAGATION_DELAY" ",5.00 MIL"
					( Parent
						( matchGroupRef "@baseboard_fab2_lib.baseboard_fab2(sch_1):\MG_DQ-DQS_FAR_DIMM_NG_M_C_BYTE1\" )
					)
					( Units "uMatchProp" "ns" 1.000000)
					( Status sCSetFlattened )
					( Origin gBackEnd )
				)
			)
			( pinPair "@baseboard_fab2_lib.baseboard_fab2(sch_1):\PP647\"
				( pinRef "@baseboard_fab2_lib.baseboard_fab2(sch_1):page25_i172:DDR2_DQS_DP(10)" )
				( pinRef "@baseboard_fab2_lib.baseboard_fab2(sch_1):page48_i61:DQS10P" )
				( attribute "RELATIVE_PROPAGATION_DELAY_SCOPE" "G"
					( Parent
						( matchGroupRef "@baseboard_fab2_lib.baseboard_fab2(sch_1):\MG_DQ-DQS_NEAR_DIMM_NG_M_C_BYTE1\" )
					)
					( Status sCSetFlattened )
					( Origin gBackEnd )
				)
				( attribute "RELATIVE_PROPAGATION_DELAY" ",5.00 MIL"
					( Parent
						( matchGroupRef "@baseboard_fab2_lib.baseboard_fab2(sch_1):\MG_DQ-DQS_NEAR_DIMM_NG_M_C_BYTE1\" )
					)
					( Units "uMatchProp" "ns" 1.000000)
					( Status sCSetFlattened )
					( Origin gBackEnd )
				)
			)
			( pinPair "@baseboard_fab2_lib.baseboard_fab2(sch_1):\PP634\"
				( pinRef "@baseboard_fab2_lib.baseboard_fab2(sch_1):page25_i172:DDR2_DQS_DP(11)" )
				( pinRef "@baseboard_fab2_lib.baseboard_fab2(sch_1):page47_i61:DQS11P" )
				( attribute "RELATIVE_PROPAGATION_DELAY_SCOPE" "G"
					( Parent
						( matchGroupRef "@baseboard_fab2_lib.baseboard_fab2(sch_1):\MG_DQ-DQS_FAR_DIMM_NG_M_C_BYTE2\" )
					)
					( Status sCSetFlattened )
					( Origin gBackEnd )
				)
				( attribute "RELATIVE_PROPAGATION_DELAY" ",5.00 MIL"
					( Parent
						( matchGroupRef "@baseboard_fab2_lib.baseboard_fab2(sch_1):\MG_DQ-DQS_FAR_DIMM_NG_M_C_BYTE2\" )
					)
					( Units "uMatchProp" "ns" 1.000000)
					( Status sCSetFlattened )
					( Origin gBackEnd )
				)
			)
			( pinPair "@baseboard_fab2_lib.baseboard_fab2(sch_1):\PP635\"
				( pinRef "@baseboard_fab2_lib.baseboard_fab2(sch_1):page25_i172:DDR2_DQS_DP(11)" )
				( pinRef "@baseboard_fab2_lib.baseboard_fab2(sch_1):page48_i61:DQS11P" )
				( attribute "RELATIVE_PROPAGATION_DELAY_SCOPE" "G"
					( Parent
						( matchGroupRef "@baseboard_fab2_lib.baseboard_fab2(sch_1):\MG_DQ-DQS_NEAR_DIMM_NG_M_C_BYTE2\" )
					)
					( Status sCSetFlattened )
					( Origin gBackEnd )
				)
				( attribute "RELATIVE_PROPAGATION_DELAY" ",5.00 MIL"
					( Parent
						( matchGroupRef "@baseboard_fab2_lib.baseboard_fab2(sch_1):\MG_DQ-DQS_NEAR_DIMM_NG_M_C_BYTE2\" )
					)
					( Units "uMatchProp" "ns" 1.000000)
					( Status sCSetFlattened )
					( Origin gBackEnd )
				)
			)
			( pinPair "@baseboard_fab2_lib.baseboard_fab2(sch_1):\PP622\"
				( pinRef "@baseboard_fab2_lib.baseboard_fab2(sch_1):page25_i172:DDR2_DQS_DP(12)" )
				( pinRef "@baseboard_fab2_lib.baseboard_fab2(sch_1):page47_i61:DQS12P" )
				( attribute "RELATIVE_PROPAGATION_DELAY_SCOPE" "G"
					( Parent
						( matchGroupRef "@baseboard_fab2_lib.baseboard_fab2(sch_1):\MG_DQ-DQS_FAR_DIMM_NG_M_C_BYTE3\" )
					)
					( Status sCSetFlattened )
					( Origin gBackEnd )
				)
				( attribute "RELATIVE_PROPAGATION_DELAY" ",5.00 MIL"
					( Parent
						( matchGroupRef "@baseboard_fab2_lib.baseboard_fab2(sch_1):\MG_DQ-DQS_FAR_DIMM_NG_M_C_BYTE3\" )
					)
					( Units "uMatchProp" "ns" 1.000000)
					( Status sCSetFlattened )
					( Origin gBackEnd )
				)
			)
			( pinPair "@baseboard_fab2_lib.baseboard_fab2(sch_1):\PP623\"
				( pinRef "@baseboard_fab2_lib.baseboard_fab2(sch_1):page25_i172:DDR2_DQS_DP(12)" )
				( pinRef "@baseboard_fab2_lib.baseboard_fab2(sch_1):page48_i61:DQS12P" )
				( attribute "RELATIVE_PROPAGATION_DELAY_SCOPE" "G"
					( Parent
						( matchGroupRef "@baseboard_fab2_lib.baseboard_fab2(sch_1):\MG_DQ-DQS_NEAR_DIMM_NG_M_C_BYTE3\" )
					)
					( Status sCSetFlattened )
					( Origin gBackEnd )
				)
				( attribute "RELATIVE_PROPAGATION_DELAY" ",5.00 MIL"
					( Parent
						( matchGroupRef "@baseboard_fab2_lib.baseboard_fab2(sch_1):\MG_DQ-DQS_NEAR_DIMM_NG_M_C_BYTE3\" )
					)
					( Units "uMatchProp" "ns" 1.000000)
					( Status sCSetFlattened )
					( Origin gBackEnd )
				)
			)
			( pinPair "@baseboard_fab2_lib.baseboard_fab2(sch_1):\PP610\"
				( pinRef "@baseboard_fab2_lib.baseboard_fab2(sch_1):page25_i172:DDR2_DQS_DP(13)" )
				( pinRef "@baseboard_fab2_lib.baseboard_fab2(sch_1):page47_i61:DQS13P" )
				( attribute "RELATIVE_PROPAGATION_DELAY_SCOPE" "G"
					( Parent
						( matchGroupRef "@baseboard_fab2_lib.baseboard_fab2(sch_1):\MG_DQ-DQS_FAR_DIMM_NG_M_C_BYTE4\" )
					)
					( Status sCSetFlattened )
					( Origin gBackEnd )
				)
				( attribute "RELATIVE_PROPAGATION_DELAY" ",5.00 MIL"
					( Parent
						( matchGroupRef "@baseboard_fab2_lib.baseboard_fab2(sch_1):\MG_DQ-DQS_FAR_DIMM_NG_M_C_BYTE4\" )
					)
					( Units "uMatchProp" "ns" 1.000000)
					( Status sCSetFlattened )
					( Origin gBackEnd )
				)
			)
			( pinPair "@baseboard_fab2_lib.baseboard_fab2(sch_1):\PP612\"
				( pinRef "@baseboard_fab2_lib.baseboard_fab2(sch_1):page25_i172:DDR2_DQS_DP(13)" )
				( pinRef "@baseboard_fab2_lib.baseboard_fab2(sch_1):page48_i61:DQS13P" )
				( attribute "RELATIVE_PROPAGATION_DELAY_SCOPE" "G"
					( Parent
						( matchGroupRef "@baseboard_fab2_lib.baseboard_fab2(sch_1):\MG_DQ-DQS_NEAR_DIMM_NG_M_C_BYTE4\" )
					)
					( Status sCSetFlattened )
					( Origin gBackEnd )
				)
				( attribute "RELATIVE_PROPAGATION_DELAY" ",5.00 MIL"
					( Parent
						( matchGroupRef "@baseboard_fab2_lib.baseboard_fab2(sch_1):\MG_DQ-DQS_NEAR_DIMM_NG_M_C_BYTE4\" )
					)
					( Units "uMatchProp" "ns" 1.000000)
					( Status sCSetFlattened )
					( Origin gBackEnd )
				)
			)
			( pinPair "@baseboard_fab2_lib.baseboard_fab2(sch_1):\PP598\"
				( pinRef "@baseboard_fab2_lib.baseboard_fab2(sch_1):page25_i172:DDR2_DQS_DP(14)" )
				( pinRef "@baseboard_fab2_lib.baseboard_fab2(sch_1):page47_i61:DQS14P" )
				( attribute "RELATIVE_PROPAGATION_DELAY_SCOPE" "G"
					( Parent
						( matchGroupRef "@baseboard_fab2_lib.baseboard_fab2(sch_1):\MG_DQ-DQS_FAR_DIMM_NG_M_C_BYTE5\" )
					)
					( Status sCSetFlattened )
					( Origin gBackEnd )
				)
				( attribute "RELATIVE_PROPAGATION_DELAY" ",5.00 MIL"
					( Parent
						( matchGroupRef "@baseboard_fab2_lib.baseboard_fab2(sch_1):\MG_DQ-DQS_FAR_DIMM_NG_M_C_BYTE5\" )
					)
					( Units "uMatchProp" "ns" 1.000000)
					( Status sCSetFlattened )
					( Origin gBackEnd )
				)
			)
			( pinPair "@baseboard_fab2_lib.baseboard_fab2(sch_1):\PP600\"
				( pinRef "@baseboard_fab2_lib.baseboard_fab2(sch_1):page25_i172:DDR2_DQS_DP(14)" )
				( pinRef "@baseboard_fab2_lib.baseboard_fab2(sch_1):page48_i61:DQS14P" )
				( attribute "RELATIVE_PROPAGATION_DELAY_SCOPE" "G"
					( Parent
						( matchGroupRef "@baseboard_fab2_lib.baseboard_fab2(sch_1):\MG_DQ-DQS_NEAR_DIMM_NG_M_C_BYTE5\" )
					)
					( Status sCSetFlattened )
					( Origin gBackEnd )
				)
				( attribute "RELATIVE_PROPAGATION_DELAY" ",5.00 MIL"
					( Parent
						( matchGroupRef "@baseboard_fab2_lib.baseboard_fab2(sch_1):\MG_DQ-DQS_NEAR_DIMM_NG_M_C_BYTE5\" )
					)
					( Units "uMatchProp" "ns" 1.000000)
					( Status sCSetFlattened )
					( Origin gBackEnd )
				)
			)
			( pinPair "@baseboard_fab2_lib.baseboard_fab2(sch_1):\PP586\"
				( pinRef "@baseboard_fab2_lib.baseboard_fab2(sch_1):page25_i172:DDR2_DQS_DP(15)" )
				( pinRef "@baseboard_fab2_lib.baseboard_fab2(sch_1):page47_i61:DQS15P" )
				( attribute "RELATIVE_PROPAGATION_DELAY_SCOPE" "G"
					( Parent
						( matchGroupRef "@baseboard_fab2_lib.baseboard_fab2(sch_1):\MG_DQ-DQS_FAR_DIMM_NG_M_C_BYTE6\" )
					)
					( Status sCSetFlattened )
					( Origin gBackEnd )
				)
				( attribute "RELATIVE_PROPAGATION_DELAY" ",5.00 MIL"
					( Parent
						( matchGroupRef "@baseboard_fab2_lib.baseboard_fab2(sch_1):\MG_DQ-DQS_FAR_DIMM_NG_M_C_BYTE6\" )
					)
					( Units "uMatchProp" "ns" 1.000000)
					( Status sCSetFlattened )
					( Origin gBackEnd )
				)
			)
			( pinPair "@baseboard_fab2_lib.baseboard_fab2(sch_1):\PP588\"
				( pinRef "@baseboard_fab2_lib.baseboard_fab2(sch_1):page25_i172:DDR2_DQS_DP(15)" )
				( pinRef "@baseboard_fab2_lib.baseboard_fab2(sch_1):page48_i61:DQS15P" )
				( attribute "RELATIVE_PROPAGATION_DELAY_SCOPE" "G"
					( Parent
						( matchGroupRef "@baseboard_fab2_lib.baseboard_fab2(sch_1):\MG_DQ-DQS_NEAR_DIMM_NG_M_C_BYTE6\" )
					)
					( Status sCSetFlattened )
					( Origin gBackEnd )
				)
				( attribute "RELATIVE_PROPAGATION_DELAY" ",5.00 MIL"
					( Parent
						( matchGroupRef "@baseboard_fab2_lib.baseboard_fab2(sch_1):\MG_DQ-DQS_NEAR_DIMM_NG_M_C_BYTE6\" )
					)
					( Units "uMatchProp" "ns" 1.000000)
					( Status sCSetFlattened )
					( Origin gBackEnd )
				)
			)
			( pinPair "@baseboard_fab2_lib.baseboard_fab2(sch_1):\PP574\"
				( pinRef "@baseboard_fab2_lib.baseboard_fab2(sch_1):page25_i172:DDR2_DQS_DP(16)" )
				( pinRef "@baseboard_fab2_lib.baseboard_fab2(sch_1):page47_i61:DQS16P" )
				( attribute "RELATIVE_PROPAGATION_DELAY_SCOPE" "G"
					( Parent
						( matchGroupRef "@baseboard_fab2_lib.baseboard_fab2(sch_1):\MG_DQ-DQS_FAR_DIMM_NG_M_C_BYTE7\" )
					)
					( Status sCSetFlattened )
					( Origin gBackEnd )
				)
				( attribute "RELATIVE_PROPAGATION_DELAY" ",5.00 MIL"
					( Parent
						( matchGroupRef "@baseboard_fab2_lib.baseboard_fab2(sch_1):\MG_DQ-DQS_FAR_DIMM_NG_M_C_BYTE7\" )
					)
					( Units "uMatchProp" "ns" 1.000000)
					( Status sCSetFlattened )
					( Origin gBackEnd )
				)
			)
			( pinPair "@baseboard_fab2_lib.baseboard_fab2(sch_1):\PP576\"
				( pinRef "@baseboard_fab2_lib.baseboard_fab2(sch_1):page25_i172:DDR2_DQS_DP(16)" )
				( pinRef "@baseboard_fab2_lib.baseboard_fab2(sch_1):page48_i61:DQS16P" )
				( attribute "RELATIVE_PROPAGATION_DELAY_SCOPE" "G"
					( Parent
						( matchGroupRef "@baseboard_fab2_lib.baseboard_fab2(sch_1):\MG_DQ-DQS_NEAR_DIMM_NG_M_C_BYTE7\" )
					)
					( Status sCSetFlattened )
					( Origin gBackEnd )
				)
				( attribute "RELATIVE_PROPAGATION_DELAY" ",5.00 MIL"
					( Parent
						( matchGroupRef "@baseboard_fab2_lib.baseboard_fab2(sch_1):\MG_DQ-DQS_NEAR_DIMM_NG_M_C_BYTE7\" )
					)
					( Units "uMatchProp" "ns" 1.000000)
					( Status sCSetFlattened )
					( Origin gBackEnd )
				)
			)
			( pinPair "@baseboard_fab2_lib.baseboard_fab2(sch_1):\PP1210\"
				( pinRef "@baseboard_fab2_lib.baseboard_fab2(sch_1):page25_i172:DDR2_DQS_DP(17)" )
				( pinRef "@baseboard_fab2_lib.baseboard_fab2(sch_1):page47_i61:DQS17P" )
				( attribute "RELATIVE_PROPAGATION_DELAY_SCOPE" "G"
					( Parent
						( matchGroupRef "@baseboard_fab2_lib.baseboard_fab2(sch_1):\MG_DQ-DQS_FAR_DIMM_NG_M_C_BYTE-ECC\" )
					)
					( Status sCSetFlattened )
					( Origin gBackEnd )
				)
				( attribute "RELATIVE_PROPAGATION_DELAY" ",5.00 MIL"
					( Parent
						( matchGroupRef "@baseboard_fab2_lib.baseboard_fab2(sch_1):\MG_DQ-DQS_FAR_DIMM_NG_M_C_BYTE-ECC\" )
					)
					( Units "uMatchProp" "ns" 1.000000)
					( Status sCSetFlattened )
					( Origin gBackEnd )
				)
			)
			( pinPair "@baseboard_fab2_lib.baseboard_fab2(sch_1):\PP1211\"
				( pinRef "@baseboard_fab2_lib.baseboard_fab2(sch_1):page25_i172:DDR2_DQS_DP(17)" )
				( pinRef "@baseboard_fab2_lib.baseboard_fab2(sch_1):page48_i61:DQS17P" )
				( attribute "RELATIVE_PROPAGATION_DELAY_SCOPE" "G"
					( Parent
						( matchGroupRef "@baseboard_fab2_lib.baseboard_fab2(sch_1):\MG_DQ-DQS_NEAR_DIMM_NG_M_C_BYTE-ECC\" )
					)
					( Status sCSetFlattened )
					( Origin gBackEnd )
				)
				( attribute "RELATIVE_PROPAGATION_DELAY" ",5.00 MIL"
					( Parent
						( matchGroupRef "@baseboard_fab2_lib.baseboard_fab2(sch_1):\MG_DQ-DQS_NEAR_DIMM_NG_M_C_BYTE-ECC\" )
					)
					( Units "uMatchProp" "ns" 1.000000)
					( Status sCSetFlattened )
					( Origin gBackEnd )
				)
			)
			( pinPair "@baseboard_fab2_lib.baseboard_fab2(sch_1):\PP673\"
				( pinRef "@baseboard_fab2_lib.baseboard_fab2(sch_1):page26_i172:DDR3_DQS_DN(0)" )
				( pinRef "@baseboard_fab2_lib.baseboard_fab2(sch_1):page49_i66:DQS0N" )
				( attribute "RELATIVE_PROPAGATION_DELAY_SCOPE" "G"
					( Parent
						( matchGroupRef "@baseboard_fab2_lib.baseboard_fab2(sch_1):\MG_DQ-DQS_FAR_DIMM_NG_M_D_BYTE0\" )
					)
					( Status sCSetFlattened )
					( Origin gBackEnd )
				)
				( attribute "RELATIVE_PROPAGATION_DELAY" ",5.00 MIL"
					( Parent
						( matchGroupRef "@baseboard_fab2_lib.baseboard_fab2(sch_1):\MG_DQ-DQS_FAR_DIMM_NG_M_D_BYTE0\" )
					)
					( Units "uMatchProp" "ns" 1.000000)
					( Status sCSetFlattened )
					( Origin gBackEnd )
				)
			)
			( pinPair "@baseboard_fab2_lib.baseboard_fab2(sch_1):\PP674\"
				( pinRef "@baseboard_fab2_lib.baseboard_fab2(sch_1):page50_i46:DQS0N" )
				( pinRef "@baseboard_fab2_lib.baseboard_fab2(sch_1):page26_i172:DDR3_DQS_DN(0)" )
				( attribute "RELATIVE_PROPAGATION_DELAY_SCOPE" "G"
					( Parent
						( matchGroupRef "@baseboard_fab2_lib.baseboard_fab2(sch_1):\MG_DQ-DQS_NEAR_DIMM_NG_M_D_BYTE0\" )
					)
					( Status sCSetFlattened )
					( Origin gBackEnd )
				)
				( attribute "RELATIVE_PROPAGATION_DELAY" ",5.00 MIL"
					( Parent
						( matchGroupRef "@baseboard_fab2_lib.baseboard_fab2(sch_1):\MG_DQ-DQS_NEAR_DIMM_NG_M_D_BYTE0\" )
					)
					( Units "uMatchProp" "ns" 1.000000)
					( Status sCSetFlattened )
					( Origin gBackEnd )
				)
			)
			( pinPair "@baseboard_fab2_lib.baseboard_fab2(sch_1):\PP685\"
				( pinRef "@baseboard_fab2_lib.baseboard_fab2(sch_1):page26_i172:DDR3_DQS_DN(1)" )
				( pinRef "@baseboard_fab2_lib.baseboard_fab2(sch_1):page49_i66:DQS1N" )
				( attribute "RELATIVE_PROPAGATION_DELAY_SCOPE" "G"
					( Parent
						( matchGroupRef "@baseboard_fab2_lib.baseboard_fab2(sch_1):\MG_DQ-DQS_FAR_DIMM_NG_M_D_BYTE1\" )
					)
					( Status sCSetFlattened )
					( Origin gBackEnd )
				)
				( attribute "RELATIVE_PROPAGATION_DELAY" ",5.00 MIL"
					( Parent
						( matchGroupRef "@baseboard_fab2_lib.baseboard_fab2(sch_1):\MG_DQ-DQS_FAR_DIMM_NG_M_D_BYTE1\" )
					)
					( Units "uMatchProp" "ns" 1.000000)
					( Status sCSetFlattened )
					( Origin gBackEnd )
				)
			)
			( pinPair "@baseboard_fab2_lib.baseboard_fab2(sch_1):\PP686\"
				( pinRef "@baseboard_fab2_lib.baseboard_fab2(sch_1):page50_i46:DQS1N" )
				( pinRef "@baseboard_fab2_lib.baseboard_fab2(sch_1):page26_i172:DDR3_DQS_DN(1)" )
				( attribute "RELATIVE_PROPAGATION_DELAY_SCOPE" "G"
					( Parent
						( matchGroupRef "@baseboard_fab2_lib.baseboard_fab2(sch_1):\MG_DQ-DQS_NEAR_DIMM_NG_M_D_BYTE1\" )
					)
					( Status sCSetFlattened )
					( Origin gBackEnd )
				)
				( attribute "RELATIVE_PROPAGATION_DELAY" ",5.00 MIL"
					( Parent
						( matchGroupRef "@baseboard_fab2_lib.baseboard_fab2(sch_1):\MG_DQ-DQS_NEAR_DIMM_NG_M_D_BYTE1\" )
					)
					( Units "uMatchProp" "ns" 1.000000)
					( Status sCSetFlattened )
					( Origin gBackEnd )
				)
			)
			( pinPair "@baseboard_fab2_lib.baseboard_fab2(sch_1):\PP697\"
				( pinRef "@baseboard_fab2_lib.baseboard_fab2(sch_1):page26_i172:DDR3_DQS_DN(2)" )
				( pinRef "@baseboard_fab2_lib.baseboard_fab2(sch_1):page49_i66:DQS2N" )
				( attribute "RELATIVE_PROPAGATION_DELAY_SCOPE" "G"
					( Parent
						( matchGroupRef "@baseboard_fab2_lib.baseboard_fab2(sch_1):\MG_DQ-DQS_FAR_DIMM_NG_M_D_BYTE2\" )
					)
					( Status sCSetFlattened )
					( Origin gBackEnd )
				)
				( attribute "RELATIVE_PROPAGATION_DELAY" ",5.00 MIL"
					( Parent
						( matchGroupRef "@baseboard_fab2_lib.baseboard_fab2(sch_1):\MG_DQ-DQS_FAR_DIMM_NG_M_D_BYTE2\" )
					)
					( Units "uMatchProp" "ns" 1.000000)
					( Status sCSetFlattened )
					( Origin gBackEnd )
				)
			)
			( pinPair "@baseboard_fab2_lib.baseboard_fab2(sch_1):\PP698\"
				( pinRef "@baseboard_fab2_lib.baseboard_fab2(sch_1):page26_i172:DDR3_DQS_DN(2)" )
				( pinRef "@baseboard_fab2_lib.baseboard_fab2(sch_1):page50_i46:DQS2N" )
				( attribute "RELATIVE_PROPAGATION_DELAY_SCOPE" "G"
					( Parent
						( matchGroupRef "@baseboard_fab2_lib.baseboard_fab2(sch_1):\MG_DQ-DQS_NEAR_DIMM_NG_M_D_BYTE2\" )
					)
					( Status sCSetFlattened )
					( Origin gBackEnd )
				)
				( attribute "RELATIVE_PROPAGATION_DELAY" ",5.00 MIL"
					( Parent
						( matchGroupRef "@baseboard_fab2_lib.baseboard_fab2(sch_1):\MG_DQ-DQS_NEAR_DIMM_NG_M_D_BYTE2\" )
					)
					( Units "uMatchProp" "ns" 1.000000)
					( Status sCSetFlattened )
					( Origin gBackEnd )
				)
			)
			( pinPair "@baseboard_fab2_lib.baseboard_fab2(sch_1):\PP709\"
				( pinRef "@baseboard_fab2_lib.baseboard_fab2(sch_1):page26_i172:DDR3_DQS_DN(3)" )
				( pinRef "@baseboard_fab2_lib.baseboard_fab2(sch_1):page49_i66:DQS3N" )
				( attribute "RELATIVE_PROPAGATION_DELAY_SCOPE" "G"
					( Parent
						( matchGroupRef "@baseboard_fab2_lib.baseboard_fab2(sch_1):\MG_DQ-DQS_FAR_DIMM_NG_M_D_BYTE3\" )
					)
					( Status sCSetFlattened )
					( Origin gBackEnd )
				)
				( attribute "RELATIVE_PROPAGATION_DELAY" ",5.00 MIL"
					( Parent
						( matchGroupRef "@baseboard_fab2_lib.baseboard_fab2(sch_1):\MG_DQ-DQS_FAR_DIMM_NG_M_D_BYTE3\" )
					)
					( Units "uMatchProp" "ns" 1.000000)
					( Status sCSetFlattened )
					( Origin gBackEnd )
				)
			)
			( pinPair "@baseboard_fab2_lib.baseboard_fab2(sch_1):\PP710\"
				( pinRef "@baseboard_fab2_lib.baseboard_fab2(sch_1):page50_i46:DQS3N" )
				( pinRef "@baseboard_fab2_lib.baseboard_fab2(sch_1):page26_i172:DDR3_DQS_DN(3)" )
				( attribute "RELATIVE_PROPAGATION_DELAY_SCOPE" "G"
					( Parent
						( matchGroupRef "@baseboard_fab2_lib.baseboard_fab2(sch_1):\MG_DQ-DQS_NEAR_DIMM_NG_M_D_BYTE3\" )
					)
					( Status sCSetFlattened )
					( Origin gBackEnd )
				)
				( attribute "RELATIVE_PROPAGATION_DELAY" ",5.00 MIL"
					( Parent
						( matchGroupRef "@baseboard_fab2_lib.baseboard_fab2(sch_1):\MG_DQ-DQS_NEAR_DIMM_NG_M_D_BYTE3\" )
					)
					( Units "uMatchProp" "ns" 1.000000)
					( Status sCSetFlattened )
					( Origin gBackEnd )
				)
			)
			( pinPair "@baseboard_fab2_lib.baseboard_fab2(sch_1):\PP721\"
				( pinRef "@baseboard_fab2_lib.baseboard_fab2(sch_1):page26_i172:DDR3_DQS_DN(4)" )
				( pinRef "@baseboard_fab2_lib.baseboard_fab2(sch_1):page49_i66:DQS4N" )
				( attribute "RELATIVE_PROPAGATION_DELAY_SCOPE" "G"
					( Parent
						( matchGroupRef "@baseboard_fab2_lib.baseboard_fab2(sch_1):\MG_DQ-DQS_FAR_DIMM_NG_M_D_BYTE4\" )
					)
					( Status sCSetFlattened )
					( Origin gBackEnd )
				)
				( attribute "RELATIVE_PROPAGATION_DELAY" ",5.00 MIL"
					( Parent
						( matchGroupRef "@baseboard_fab2_lib.baseboard_fab2(sch_1):\MG_DQ-DQS_FAR_DIMM_NG_M_D_BYTE4\" )
					)
					( Units "uMatchProp" "ns" 1.000000)
					( Status sCSetFlattened )
					( Origin gBackEnd )
				)
			)
			( pinPair "@baseboard_fab2_lib.baseboard_fab2(sch_1):\PP723\"
				( pinRef "@baseboard_fab2_lib.baseboard_fab2(sch_1):page50_i46:DQS4N" )
				( pinRef "@baseboard_fab2_lib.baseboard_fab2(sch_1):page26_i172:DDR3_DQS_DN(4)" )
				( attribute "RELATIVE_PROPAGATION_DELAY_SCOPE" "G"
					( Parent
						( matchGroupRef "@baseboard_fab2_lib.baseboard_fab2(sch_1):\MG_DQ-DQS_NEAR_DIMM_NG_M_D_BYTE4\" )
					)
					( Status sCSetFlattened )
					( Origin gBackEnd )
				)
				( attribute "RELATIVE_PROPAGATION_DELAY" ",5.00 MIL"
					( Parent
						( matchGroupRef "@baseboard_fab2_lib.baseboard_fab2(sch_1):\MG_DQ-DQS_NEAR_DIMM_NG_M_D_BYTE4\" )
					)
					( Units "uMatchProp" "ns" 1.000000)
					( Status sCSetFlattened )
					( Origin gBackEnd )
				)
			)
			( pinPair "@baseboard_fab2_lib.baseboard_fab2(sch_1):\PP733\"
				( pinRef "@baseboard_fab2_lib.baseboard_fab2(sch_1):page26_i172:DDR3_DQS_DN(5)" )
				( pinRef "@baseboard_fab2_lib.baseboard_fab2(sch_1):page49_i66:DQS5N" )
				( attribute "RELATIVE_PROPAGATION_DELAY_SCOPE" "G"
					( Parent
						( matchGroupRef "@baseboard_fab2_lib.baseboard_fab2(sch_1):\MG_DQ-DQS_FAR_DIMM_NG_M_D_BYTE5\" )
					)
					( Status sCSetFlattened )
					( Origin gBackEnd )
				)
				( attribute "RELATIVE_PROPAGATION_DELAY" ",5.00 MIL"
					( Parent
						( matchGroupRef "@baseboard_fab2_lib.baseboard_fab2(sch_1):\MG_DQ-DQS_FAR_DIMM_NG_M_D_BYTE5\" )
					)
					( Units "uMatchProp" "ns" 1.000000)
					( Status sCSetFlattened )
					( Origin gBackEnd )
				)
			)
			( pinPair "@baseboard_fab2_lib.baseboard_fab2(sch_1):\PP735\"
				( pinRef "@baseboard_fab2_lib.baseboard_fab2(sch_1):page26_i172:DDR3_DQS_DN(5)" )
				( pinRef "@baseboard_fab2_lib.baseboard_fab2(sch_1):page50_i46:DQS5N" )
				( attribute "RELATIVE_PROPAGATION_DELAY_SCOPE" "G"
					( Parent
						( matchGroupRef "@baseboard_fab2_lib.baseboard_fab2(sch_1):\MG_DQ-DQS_NEAR_DIMM_NG_M_D_BYTE5\" )
					)
					( Status sCSetFlattened )
					( Origin gBackEnd )
				)
				( attribute "RELATIVE_PROPAGATION_DELAY" ",5.00 MIL"
					( Parent
						( matchGroupRef "@baseboard_fab2_lib.baseboard_fab2(sch_1):\MG_DQ-DQS_NEAR_DIMM_NG_M_D_BYTE5\" )
					)
					( Units "uMatchProp" "ns" 1.000000)
					( Status sCSetFlattened )
					( Origin gBackEnd )
				)
			)
			( pinPair "@baseboard_fab2_lib.baseboard_fab2(sch_1):\PP745\"
				( pinRef "@baseboard_fab2_lib.baseboard_fab2(sch_1):page26_i172:DDR3_DQS_DN(6)" )
				( pinRef "@baseboard_fab2_lib.baseboard_fab2(sch_1):page49_i66:DQS6N" )
				( attribute "RELATIVE_PROPAGATION_DELAY_SCOPE" "G"
					( Parent
						( matchGroupRef "@baseboard_fab2_lib.baseboard_fab2(sch_1):\MG_DQ-DQS_FAR_DIMM_NG_M_D_BYTE6\" )
					)
					( Status sCSetFlattened )
					( Origin gBackEnd )
				)
				( attribute "RELATIVE_PROPAGATION_DELAY" ",5.00 MIL"
					( Parent
						( matchGroupRef "@baseboard_fab2_lib.baseboard_fab2(sch_1):\MG_DQ-DQS_FAR_DIMM_NG_M_D_BYTE6\" )
					)
					( Units "uMatchProp" "ns" 1.000000)
					( Status sCSetFlattened )
					( Origin gBackEnd )
				)
			)
			( pinPair "@baseboard_fab2_lib.baseboard_fab2(sch_1):\PP747\"
				( pinRef "@baseboard_fab2_lib.baseboard_fab2(sch_1):page26_i172:DDR3_DQS_DN(6)" )
				( pinRef "@baseboard_fab2_lib.baseboard_fab2(sch_1):page50_i46:DQS6N" )
				( attribute "RELATIVE_PROPAGATION_DELAY_SCOPE" "G"
					( Parent
						( matchGroupRef "@baseboard_fab2_lib.baseboard_fab2(sch_1):\MG_DQ-DQS_NEAR_DIMM_NG_M_D_BYTE6\" )
					)
					( Status sCSetFlattened )
					( Origin gBackEnd )
				)
				( attribute "RELATIVE_PROPAGATION_DELAY" ",5.00 MIL"
					( Parent
						( matchGroupRef "@baseboard_fab2_lib.baseboard_fab2(sch_1):\MG_DQ-DQS_NEAR_DIMM_NG_M_D_BYTE6\" )
					)
					( Units "uMatchProp" "ns" 1.000000)
					( Status sCSetFlattened )
					( Origin gBackEnd )
				)
			)
			( pinPair "@baseboard_fab2_lib.baseboard_fab2(sch_1):\PP757\"
				( pinRef "@baseboard_fab2_lib.baseboard_fab2(sch_1):page26_i172:DDR3_DQS_DN(7)" )
				( pinRef "@baseboard_fab2_lib.baseboard_fab2(sch_1):page49_i66:DQS7N" )
				( attribute "RELATIVE_PROPAGATION_DELAY_SCOPE" "G"
					( Parent
						( matchGroupRef "@baseboard_fab2_lib.baseboard_fab2(sch_1):\MG_DQ-DQS_FAR_DIMM_NG_M_D_BYTE7\" )
					)
					( Status sCSetFlattened )
					( Origin gBackEnd )
				)
				( attribute "RELATIVE_PROPAGATION_DELAY" ",5.00 MIL"
					( Parent
						( matchGroupRef "@baseboard_fab2_lib.baseboard_fab2(sch_1):\MG_DQ-DQS_FAR_DIMM_NG_M_D_BYTE7\" )
					)
					( Units "uMatchProp" "ns" 1.000000)
					( Status sCSetFlattened )
					( Origin gBackEnd )
				)
			)
			( pinPair "@baseboard_fab2_lib.baseboard_fab2(sch_1):\PP759\"
				( pinRef "@baseboard_fab2_lib.baseboard_fab2(sch_1):page26_i172:DDR3_DQS_DN(7)" )
				( pinRef "@baseboard_fab2_lib.baseboard_fab2(sch_1):page50_i46:DQS7N" )
				( attribute "RELATIVE_PROPAGATION_DELAY_SCOPE" "G"
					( Parent
						( matchGroupRef "@baseboard_fab2_lib.baseboard_fab2(sch_1):\MG_DQ-DQS_NEAR_DIMM_NG_M_D_BYTE7\" )
					)
					( Status sCSetFlattened )
					( Origin gBackEnd )
				)
				( attribute "RELATIVE_PROPAGATION_DELAY" ",5.00 MIL"
					( Parent
						( matchGroupRef "@baseboard_fab2_lib.baseboard_fab2(sch_1):\MG_DQ-DQS_NEAR_DIMM_NG_M_D_BYTE7\" )
					)
					( Units "uMatchProp" "ns" 1.000000)
					( Status sCSetFlattened )
					( Origin gBackEnd )
				)
			)
			( pinPair "@baseboard_fab2_lib.baseboard_fab2(sch_1):\PP1201\"
				( pinRef "@baseboard_fab2_lib.baseboard_fab2(sch_1):page26_i172:DDR3_DQS_DN(8)" )
				( pinRef "@baseboard_fab2_lib.baseboard_fab2(sch_1):page49_i66:DQS8N" )
				( attribute "RELATIVE_PROPAGATION_DELAY_SCOPE" "G"
					( Parent
						( matchGroupRef "@baseboard_fab2_lib.baseboard_fab2(sch_1):\MG_DQ-DQS_FAR_DIMM_NG_M_D_BYTE-ECC\" )
					)
					( Status sCSetFlattened )
					( Origin gBackEnd )
				)
				( attribute "RELATIVE_PROPAGATION_DELAY" ",5.00 MIL"
					( Parent
						( matchGroupRef "@baseboard_fab2_lib.baseboard_fab2(sch_1):\MG_DQ-DQS_FAR_DIMM_NG_M_D_BYTE-ECC\" )
					)
					( Units "uMatchProp" "ns" 1.000000)
					( Status sCSetFlattened )
					( Origin gBackEnd )
				)
			)
			( pinPair "@baseboard_fab2_lib.baseboard_fab2(sch_1):\PP1202\"
				( pinRef "@baseboard_fab2_lib.baseboard_fab2(sch_1):page50_i46:DQS8N" )
				( pinRef "@baseboard_fab2_lib.baseboard_fab2(sch_1):page26_i172:DDR3_DQS_DN(8)" )
				( attribute "RELATIVE_PROPAGATION_DELAY_SCOPE" "G"
					( Parent
						( matchGroupRef "@baseboard_fab2_lib.baseboard_fab2(sch_1):\MG_DQ-DQS_NEAR_DIMM_NG_M_D_BYTE-ECC\" )
					)
					( Status sCSetFlattened )
					( Origin gBackEnd )
				)
				( attribute "RELATIVE_PROPAGATION_DELAY" ",5.00 MIL"
					( Parent
						( matchGroupRef "@baseboard_fab2_lib.baseboard_fab2(sch_1):\MG_DQ-DQS_NEAR_DIMM_NG_M_D_BYTE-ECC\" )
					)
					( Units "uMatchProp" "ns" 1.000000)
					( Status sCSetFlattened )
					( Origin gBackEnd )
				)
			)
			( pinPair "@baseboard_fab2_lib.baseboard_fab2(sch_1):\PP667\"
				( pinRef "@baseboard_fab2_lib.baseboard_fab2(sch_1):page26_i172:DDR3_DQS_DN(9)" )
				( pinRef "@baseboard_fab2_lib.baseboard_fab2(sch_1):page49_i66:DQS9N" )
				( attribute "RELATIVE_PROPAGATION_DELAY_SCOPE" "G"
					( Parent
						( matchGroupRef "@baseboard_fab2_lib.baseboard_fab2(sch_1):\MG_DQ-DQS_FAR_DIMM_NG_M_D_BYTE0\" )
					)
					( Status sCSetFlattened )
					( Origin gBackEnd )
				)
				( attribute "RELATIVE_PROPAGATION_DELAY" ",5.00 MIL"
					( Parent
						( matchGroupRef "@baseboard_fab2_lib.baseboard_fab2(sch_1):\MG_DQ-DQS_FAR_DIMM_NG_M_D_BYTE0\" )
					)
					( Units "uMatchProp" "ns" 1.000000)
					( Status sCSetFlattened )
					( Origin gBackEnd )
				)
			)
			( pinPair "@baseboard_fab2_lib.baseboard_fab2(sch_1):\PP668\"
				( pinRef "@baseboard_fab2_lib.baseboard_fab2(sch_1):page50_i46:DQS9N" )
				( pinRef "@baseboard_fab2_lib.baseboard_fab2(sch_1):page26_i172:DDR3_DQS_DN(9)" )
				( attribute "RELATIVE_PROPAGATION_DELAY_SCOPE" "G"
					( Parent
						( matchGroupRef "@baseboard_fab2_lib.baseboard_fab2(sch_1):\MG_DQ-DQS_NEAR_DIMM_NG_M_D_BYTE0\" )
					)
					( Status sCSetFlattened )
					( Origin gBackEnd )
				)
				( attribute "RELATIVE_PROPAGATION_DELAY" ",5.00 MIL"
					( Parent
						( matchGroupRef "@baseboard_fab2_lib.baseboard_fab2(sch_1):\MG_DQ-DQS_NEAR_DIMM_NG_M_D_BYTE0\" )
					)
					( Units "uMatchProp" "ns" 1.000000)
					( Status sCSetFlattened )
					( Origin gBackEnd )
				)
			)
			( pinPair "@baseboard_fab2_lib.baseboard_fab2(sch_1):\PP679\"
				( pinRef "@baseboard_fab2_lib.baseboard_fab2(sch_1):page26_i172:DDR3_DQS_DN(10)" )
				( pinRef "@baseboard_fab2_lib.baseboard_fab2(sch_1):page49_i66:DQS10N" )
				( attribute "RELATIVE_PROPAGATION_DELAY_SCOPE" "G"
					( Parent
						( matchGroupRef "@baseboard_fab2_lib.baseboard_fab2(sch_1):\MG_DQ-DQS_FAR_DIMM_NG_M_D_BYTE1\" )
					)
					( Status sCSetFlattened )
					( Origin gBackEnd )
				)
				( attribute "RELATIVE_PROPAGATION_DELAY" ",5.00 MIL"
					( Parent
						( matchGroupRef "@baseboard_fab2_lib.baseboard_fab2(sch_1):\MG_DQ-DQS_FAR_DIMM_NG_M_D_BYTE1\" )
					)
					( Units "uMatchProp" "ns" 1.000000)
					( Status sCSetFlattened )
					( Origin gBackEnd )
				)
			)
			( pinPair "@baseboard_fab2_lib.baseboard_fab2(sch_1):\PP680\"
				( pinRef "@baseboard_fab2_lib.baseboard_fab2(sch_1):page50_i46:DQS10N" )
				( pinRef "@baseboard_fab2_lib.baseboard_fab2(sch_1):page26_i172:DDR3_DQS_DN(10)" )
				( attribute "RELATIVE_PROPAGATION_DELAY_SCOPE" "G"
					( Parent
						( matchGroupRef "@baseboard_fab2_lib.baseboard_fab2(sch_1):\MG_DQ-DQS_NEAR_DIMM_NG_M_D_BYTE1\" )
					)
					( Status sCSetFlattened )
					( Origin gBackEnd )
				)
				( attribute "RELATIVE_PROPAGATION_DELAY" ",5.00 MIL"
					( Parent
						( matchGroupRef "@baseboard_fab2_lib.baseboard_fab2(sch_1):\MG_DQ-DQS_NEAR_DIMM_NG_M_D_BYTE1\" )
					)
					( Units "uMatchProp" "ns" 1.000000)
					( Status sCSetFlattened )
					( Origin gBackEnd )
				)
			)
			( pinPair "@baseboard_fab2_lib.baseboard_fab2(sch_1):\PP691\"
				( pinRef "@baseboard_fab2_lib.baseboard_fab2(sch_1):page26_i172:DDR3_DQS_DN(11)" )
				( pinRef "@baseboard_fab2_lib.baseboard_fab2(sch_1):page49_i66:DQS11N" )
				( attribute "RELATIVE_PROPAGATION_DELAY_SCOPE" "G"
					( Parent
						( matchGroupRef "@baseboard_fab2_lib.baseboard_fab2(sch_1):\MG_DQ-DQS_FAR_DIMM_NG_M_D_BYTE2\" )
					)
					( Status sCSetFlattened )
					( Origin gBackEnd )
				)
				( attribute "RELATIVE_PROPAGATION_DELAY" ",5.00 MIL"
					( Parent
						( matchGroupRef "@baseboard_fab2_lib.baseboard_fab2(sch_1):\MG_DQ-DQS_FAR_DIMM_NG_M_D_BYTE2\" )
					)
					( Units "uMatchProp" "ns" 1.000000)
					( Status sCSetFlattened )
					( Origin gBackEnd )
				)
			)
			( pinPair "@baseboard_fab2_lib.baseboard_fab2(sch_1):\PP692\"
				( pinRef "@baseboard_fab2_lib.baseboard_fab2(sch_1):page26_i172:DDR3_DQS_DN(11)" )
				( pinRef "@baseboard_fab2_lib.baseboard_fab2(sch_1):page50_i46:DQS11N" )
				( attribute "RELATIVE_PROPAGATION_DELAY_SCOPE" "G"
					( Parent
						( matchGroupRef "@baseboard_fab2_lib.baseboard_fab2(sch_1):\MG_DQ-DQS_NEAR_DIMM_NG_M_D_BYTE2\" )
					)
					( Status sCSetFlattened )
					( Origin gBackEnd )
				)
				( attribute "RELATIVE_PROPAGATION_DELAY" ",5.00 MIL"
					( Parent
						( matchGroupRef "@baseboard_fab2_lib.baseboard_fab2(sch_1):\MG_DQ-DQS_NEAR_DIMM_NG_M_D_BYTE2\" )
					)
					( Units "uMatchProp" "ns" 1.000000)
					( Status sCSetFlattened )
					( Origin gBackEnd )
				)
			)
			( pinPair "@baseboard_fab2_lib.baseboard_fab2(sch_1):\PP703\"
				( pinRef "@baseboard_fab2_lib.baseboard_fab2(sch_1):page26_i172:DDR3_DQS_DN(12)" )
				( pinRef "@baseboard_fab2_lib.baseboard_fab2(sch_1):page49_i66:DQS12N" )
				( attribute "RELATIVE_PROPAGATION_DELAY_SCOPE" "G"
					( Parent
						( matchGroupRef "@baseboard_fab2_lib.baseboard_fab2(sch_1):\MG_DQ-DQS_FAR_DIMM_NG_M_D_BYTE3\" )
					)
					( Status sCSetFlattened )
					( Origin gBackEnd )
				)
				( attribute "RELATIVE_PROPAGATION_DELAY" ",5.00 MIL"
					( Parent
						( matchGroupRef "@baseboard_fab2_lib.baseboard_fab2(sch_1):\MG_DQ-DQS_FAR_DIMM_NG_M_D_BYTE3\" )
					)
					( Units "uMatchProp" "ns" 1.000000)
					( Status sCSetFlattened )
					( Origin gBackEnd )
				)
			)
			( pinPair "@baseboard_fab2_lib.baseboard_fab2(sch_1):\PP704\"
				( pinRef "@baseboard_fab2_lib.baseboard_fab2(sch_1):page50_i46:DQS12N" )
				( pinRef "@baseboard_fab2_lib.baseboard_fab2(sch_1):page26_i172:DDR3_DQS_DN(12)" )
				( attribute "RELATIVE_PROPAGATION_DELAY_SCOPE" "G"
					( Parent
						( matchGroupRef "@baseboard_fab2_lib.baseboard_fab2(sch_1):\MG_DQ-DQS_NEAR_DIMM_NG_M_D_BYTE3\" )
					)
					( Status sCSetFlattened )
					( Origin gBackEnd )
				)
				( attribute "RELATIVE_PROPAGATION_DELAY" ",5.00 MIL"
					( Parent
						( matchGroupRef "@baseboard_fab2_lib.baseboard_fab2(sch_1):\MG_DQ-DQS_NEAR_DIMM_NG_M_D_BYTE3\" )
					)
					( Units "uMatchProp" "ns" 1.000000)
					( Status sCSetFlattened )
					( Origin gBackEnd )
				)
			)
			( pinPair "@baseboard_fab2_lib.baseboard_fab2(sch_1):\PP715\"
				( pinRef "@baseboard_fab2_lib.baseboard_fab2(sch_1):page26_i172:DDR3_DQS_DN(13)" )
				( pinRef "@baseboard_fab2_lib.baseboard_fab2(sch_1):page49_i66:DQS13N" )
				( attribute "RELATIVE_PROPAGATION_DELAY_SCOPE" "G"
					( Parent
						( matchGroupRef "@baseboard_fab2_lib.baseboard_fab2(sch_1):\MG_DQ-DQS_FAR_DIMM_NG_M_D_BYTE4\" )
					)
					( Status sCSetFlattened )
					( Origin gBackEnd )
				)
				( attribute "RELATIVE_PROPAGATION_DELAY" ",5.00 MIL"
					( Parent
						( matchGroupRef "@baseboard_fab2_lib.baseboard_fab2(sch_1):\MG_DQ-DQS_FAR_DIMM_NG_M_D_BYTE4\" )
					)
					( Units "uMatchProp" "ns" 1.000000)
					( Status sCSetFlattened )
					( Origin gBackEnd )
				)
			)
			( pinPair "@baseboard_fab2_lib.baseboard_fab2(sch_1):\PP717\"
				( pinRef "@baseboard_fab2_lib.baseboard_fab2(sch_1):page50_i46:DQS13N" )
				( pinRef "@baseboard_fab2_lib.baseboard_fab2(sch_1):page26_i172:DDR3_DQS_DN(13)" )
				( attribute "RELATIVE_PROPAGATION_DELAY_SCOPE" "G"
					( Parent
						( matchGroupRef "@baseboard_fab2_lib.baseboard_fab2(sch_1):\MG_DQ-DQS_NEAR_DIMM_NG_M_D_BYTE4\" )
					)
					( Status sCSetFlattened )
					( Origin gBackEnd )
				)
				( attribute "RELATIVE_PROPAGATION_DELAY" ",5.00 MIL"
					( Parent
						( matchGroupRef "@baseboard_fab2_lib.baseboard_fab2(sch_1):\MG_DQ-DQS_NEAR_DIMM_NG_M_D_BYTE4\" )
					)
					( Units "uMatchProp" "ns" 1.000000)
					( Status sCSetFlattened )
					( Origin gBackEnd )
				)
			)
			( pinPair "@baseboard_fab2_lib.baseboard_fab2(sch_1):\PP727\"
				( pinRef "@baseboard_fab2_lib.baseboard_fab2(sch_1):page26_i172:DDR3_DQS_DN(14)" )
				( pinRef "@baseboard_fab2_lib.baseboard_fab2(sch_1):page49_i66:DQS14N" )
				( attribute "RELATIVE_PROPAGATION_DELAY_SCOPE" "G"
					( Parent
						( matchGroupRef "@baseboard_fab2_lib.baseboard_fab2(sch_1):\MG_DQ-DQS_FAR_DIMM_NG_M_D_BYTE5\" )
					)
					( Status sCSetFlattened )
					( Origin gBackEnd )
				)
				( attribute "RELATIVE_PROPAGATION_DELAY" ",5.00 MIL"
					( Parent
						( matchGroupRef "@baseboard_fab2_lib.baseboard_fab2(sch_1):\MG_DQ-DQS_FAR_DIMM_NG_M_D_BYTE5\" )
					)
					( Units "uMatchProp" "ns" 1.000000)
					( Status sCSetFlattened )
					( Origin gBackEnd )
				)
			)
			( pinPair "@baseboard_fab2_lib.baseboard_fab2(sch_1):\PP729\"
				( pinRef "@baseboard_fab2_lib.baseboard_fab2(sch_1):page26_i172:DDR3_DQS_DN(14)" )
				( pinRef "@baseboard_fab2_lib.baseboard_fab2(sch_1):page50_i46:DQS14N" )
				( attribute "RELATIVE_PROPAGATION_DELAY_SCOPE" "G"
					( Parent
						( matchGroupRef "@baseboard_fab2_lib.baseboard_fab2(sch_1):\MG_DQ-DQS_NEAR_DIMM_NG_M_D_BYTE5\" )
					)
					( Status sCSetFlattened )
					( Origin gBackEnd )
				)
				( attribute "RELATIVE_PROPAGATION_DELAY" ",5.00 MIL"
					( Parent
						( matchGroupRef "@baseboard_fab2_lib.baseboard_fab2(sch_1):\MG_DQ-DQS_NEAR_DIMM_NG_M_D_BYTE5\" )
					)
					( Units "uMatchProp" "ns" 1.000000)
					( Status sCSetFlattened )
					( Origin gBackEnd )
				)
			)
			( pinPair "@baseboard_fab2_lib.baseboard_fab2(sch_1):\PP739\"
				( pinRef "@baseboard_fab2_lib.baseboard_fab2(sch_1):page26_i172:DDR3_DQS_DN(15)" )
				( pinRef "@baseboard_fab2_lib.baseboard_fab2(sch_1):page49_i66:DQS15N" )
				( attribute "RELATIVE_PROPAGATION_DELAY_SCOPE" "G"
					( Parent
						( matchGroupRef "@baseboard_fab2_lib.baseboard_fab2(sch_1):\MG_DQ-DQS_FAR_DIMM_NG_M_D_BYTE6\" )
					)
					( Status sCSetFlattened )
					( Origin gBackEnd )
				)
				( attribute "RELATIVE_PROPAGATION_DELAY" ",5.00 MIL"
					( Parent
						( matchGroupRef "@baseboard_fab2_lib.baseboard_fab2(sch_1):\MG_DQ-DQS_FAR_DIMM_NG_M_D_BYTE6\" )
					)
					( Units "uMatchProp" "ns" 1.000000)
					( Status sCSetFlattened )
					( Origin gBackEnd )
				)
			)
			( pinPair "@baseboard_fab2_lib.baseboard_fab2(sch_1):\PP741\"
				( pinRef "@baseboard_fab2_lib.baseboard_fab2(sch_1):page26_i172:DDR3_DQS_DN(15)" )
				( pinRef "@baseboard_fab2_lib.baseboard_fab2(sch_1):page50_i46:DQS15N" )
				( attribute "RELATIVE_PROPAGATION_DELAY_SCOPE" "G"
					( Parent
						( matchGroupRef "@baseboard_fab2_lib.baseboard_fab2(sch_1):\MG_DQ-DQS_NEAR_DIMM_NG_M_D_BYTE6\" )
					)
					( Status sCSetFlattened )
					( Origin gBackEnd )
				)
				( attribute "RELATIVE_PROPAGATION_DELAY" ",5.00 MIL"
					( Parent
						( matchGroupRef "@baseboard_fab2_lib.baseboard_fab2(sch_1):\MG_DQ-DQS_NEAR_DIMM_NG_M_D_BYTE6\" )
					)
					( Units "uMatchProp" "ns" 1.000000)
					( Status sCSetFlattened )
					( Origin gBackEnd )
				)
			)
			( pinPair "@baseboard_fab2_lib.baseboard_fab2(sch_1):\PP751\"
				( pinRef "@baseboard_fab2_lib.baseboard_fab2(sch_1):page26_i172:DDR3_DQS_DN(16)" )
				( pinRef "@baseboard_fab2_lib.baseboard_fab2(sch_1):page49_i66:DQS16N" )
				( attribute "RELATIVE_PROPAGATION_DELAY_SCOPE" "G"
					( Parent
						( matchGroupRef "@baseboard_fab2_lib.baseboard_fab2(sch_1):\MG_DQ-DQS_FAR_DIMM_NG_M_D_BYTE7\" )
					)
					( Status sCSetFlattened )
					( Origin gBackEnd )
				)
				( attribute "RELATIVE_PROPAGATION_DELAY" ",5.00 MIL"
					( Parent
						( matchGroupRef "@baseboard_fab2_lib.baseboard_fab2(sch_1):\MG_DQ-DQS_FAR_DIMM_NG_M_D_BYTE7\" )
					)
					( Units "uMatchProp" "ns" 1.000000)
					( Status sCSetFlattened )
					( Origin gBackEnd )
				)
			)
			( pinPair "@baseboard_fab2_lib.baseboard_fab2(sch_1):\PP753\"
				( pinRef "@baseboard_fab2_lib.baseboard_fab2(sch_1):page26_i172:DDR3_DQS_DN(16)" )
				( pinRef "@baseboard_fab2_lib.baseboard_fab2(sch_1):page50_i46:DQS16N" )
				( attribute "RELATIVE_PROPAGATION_DELAY_SCOPE" "G"
					( Parent
						( matchGroupRef "@baseboard_fab2_lib.baseboard_fab2(sch_1):\MG_DQ-DQS_NEAR_DIMM_NG_M_D_BYTE7\" )
					)
					( Status sCSetFlattened )
					( Origin gBackEnd )
				)
				( attribute "RELATIVE_PROPAGATION_DELAY" ",5.00 MIL"
					( Parent
						( matchGroupRef "@baseboard_fab2_lib.baseboard_fab2(sch_1):\MG_DQ-DQS_NEAR_DIMM_NG_M_D_BYTE7\" )
					)
					( Units "uMatchProp" "ns" 1.000000)
					( Status sCSetFlattened )
					( Origin gBackEnd )
				)
			)
			( pinPair "@baseboard_fab2_lib.baseboard_fab2(sch_1):\PP1195\"
				( pinRef "@baseboard_fab2_lib.baseboard_fab2(sch_1):page26_i172:DDR3_DQS_DN(17)" )
				( pinRef "@baseboard_fab2_lib.baseboard_fab2(sch_1):page49_i66:DQS17N" )
				( attribute "RELATIVE_PROPAGATION_DELAY_SCOPE" "G"
					( Parent
						( matchGroupRef "@baseboard_fab2_lib.baseboard_fab2(sch_1):\MG_DQ-DQS_FAR_DIMM_NG_M_D_BYTE-ECC\" )
					)
					( Status sCSetFlattened )
					( Origin gBackEnd )
				)
				( attribute "RELATIVE_PROPAGATION_DELAY" ",5.00 MIL"
					( Parent
						( matchGroupRef "@baseboard_fab2_lib.baseboard_fab2(sch_1):\MG_DQ-DQS_FAR_DIMM_NG_M_D_BYTE-ECC\" )
					)
					( Units "uMatchProp" "ns" 1.000000)
					( Status sCSetFlattened )
					( Origin gBackEnd )
				)
			)
			( pinPair "@baseboard_fab2_lib.baseboard_fab2(sch_1):\PP1196\"
				( pinRef "@baseboard_fab2_lib.baseboard_fab2(sch_1):page50_i46:DQS17N" )
				( pinRef "@baseboard_fab2_lib.baseboard_fab2(sch_1):page26_i172:DDR3_DQS_DN(17)" )
				( attribute "RELATIVE_PROPAGATION_DELAY_SCOPE" "G"
					( Parent
						( matchGroupRef "@baseboard_fab2_lib.baseboard_fab2(sch_1):\MG_DQ-DQS_NEAR_DIMM_NG_M_D_BYTE-ECC\" )
					)
					( Status sCSetFlattened )
					( Origin gBackEnd )
				)
				( attribute "RELATIVE_PROPAGATION_DELAY" ",5.00 MIL"
					( Parent
						( matchGroupRef "@baseboard_fab2_lib.baseboard_fab2(sch_1):\MG_DQ-DQS_NEAR_DIMM_NG_M_D_BYTE-ECC\" )
					)
					( Units "uMatchProp" "ns" 1.000000)
					( Status sCSetFlattened )
					( Origin gBackEnd )
				)
			)
			( pinPair "@baseboard_fab2_lib.baseboard_fab2(sch_1):\PP676\"
				( pinRef "@baseboard_fab2_lib.baseboard_fab2(sch_1):page26_i172:DDR3_DQS_DP(0)" )
				( pinRef "@baseboard_fab2_lib.baseboard_fab2(sch_1):page49_i66:DQS0P" )
				( attribute "RELATIVE_PROPAGATION_DELAY_SCOPE" "G"
					( Parent
						( matchGroupRef "@baseboard_fab2_lib.baseboard_fab2(sch_1):\MG_DQ-DQS_FAR_DIMM_NG_M_D_BYTE0\" )
					)
					( Status sCSetFlattened )
					( Origin gBackEnd )
				)
				( attribute "RELATIVE_PROPAGATION_DELAY" ",5.00 MIL"
					( Parent
						( matchGroupRef "@baseboard_fab2_lib.baseboard_fab2(sch_1):\MG_DQ-DQS_FAR_DIMM_NG_M_D_BYTE0\" )
					)
					( Units "uMatchProp" "ns" 1.000000)
					( Status sCSetFlattened )
					( Origin gBackEnd )
				)
			)
			( pinPair "@baseboard_fab2_lib.baseboard_fab2(sch_1):\PP677\"
				( pinRef "@baseboard_fab2_lib.baseboard_fab2(sch_1):page50_i46:DQS0P" )
				( pinRef "@baseboard_fab2_lib.baseboard_fab2(sch_1):page26_i172:DDR3_DQS_DP(0)" )
				( attribute "RELATIVE_PROPAGATION_DELAY_SCOPE" "G"
					( Parent
						( matchGroupRef "@baseboard_fab2_lib.baseboard_fab2(sch_1):\MG_DQ-DQS_NEAR_DIMM_NG_M_D_BYTE0\" )
					)
					( Status sCSetFlattened )
					( Origin gBackEnd )
				)
				( attribute "RELATIVE_PROPAGATION_DELAY" ",5.00 MIL"
					( Parent
						( matchGroupRef "@baseboard_fab2_lib.baseboard_fab2(sch_1):\MG_DQ-DQS_NEAR_DIMM_NG_M_D_BYTE0\" )
					)
					( Units "uMatchProp" "ns" 1.000000)
					( Status sCSetFlattened )
					( Origin gBackEnd )
				)
			)
			( pinPair "@baseboard_fab2_lib.baseboard_fab2(sch_1):\PP688\"
				( pinRef "@baseboard_fab2_lib.baseboard_fab2(sch_1):page26_i172:DDR3_DQS_DP(1)" )
				( pinRef "@baseboard_fab2_lib.baseboard_fab2(sch_1):page49_i66:DQS1P" )
				( attribute "RELATIVE_PROPAGATION_DELAY_SCOPE" "G"
					( Parent
						( matchGroupRef "@baseboard_fab2_lib.baseboard_fab2(sch_1):\MG_DQ-DQS_FAR_DIMM_NG_M_D_BYTE1\" )
					)
					( Status sCSetFlattened )
					( Origin gBackEnd )
				)
				( attribute "RELATIVE_PROPAGATION_DELAY" ",5.00 MIL"
					( Parent
						( matchGroupRef "@baseboard_fab2_lib.baseboard_fab2(sch_1):\MG_DQ-DQS_FAR_DIMM_NG_M_D_BYTE1\" )
					)
					( Units "uMatchProp" "ns" 1.000000)
					( Status sCSetFlattened )
					( Origin gBackEnd )
				)
			)
			( pinPair "@baseboard_fab2_lib.baseboard_fab2(sch_1):\PP689\"
				( pinRef "@baseboard_fab2_lib.baseboard_fab2(sch_1):page50_i46:DQS1P" )
				( pinRef "@baseboard_fab2_lib.baseboard_fab2(sch_1):page26_i172:DDR3_DQS_DP(1)" )
				( attribute "RELATIVE_PROPAGATION_DELAY_SCOPE" "G"
					( Parent
						( matchGroupRef "@baseboard_fab2_lib.baseboard_fab2(sch_1):\MG_DQ-DQS_NEAR_DIMM_NG_M_D_BYTE1\" )
					)
					( Status sCSetFlattened )
					( Origin gBackEnd )
				)
				( attribute "RELATIVE_PROPAGATION_DELAY" ",5.00 MIL"
					( Parent
						( matchGroupRef "@baseboard_fab2_lib.baseboard_fab2(sch_1):\MG_DQ-DQS_NEAR_DIMM_NG_M_D_BYTE1\" )
					)
					( Units "uMatchProp" "ns" 1.000000)
					( Status sCSetFlattened )
					( Origin gBackEnd )
				)
			)
			( pinPair "@baseboard_fab2_lib.baseboard_fab2(sch_1):\PP700\"
				( pinRef "@baseboard_fab2_lib.baseboard_fab2(sch_1):page26_i172:DDR3_DQS_DP(2)" )
				( pinRef "@baseboard_fab2_lib.baseboard_fab2(sch_1):page49_i66:DQS2P" )
				( attribute "RELATIVE_PROPAGATION_DELAY_SCOPE" "G"
					( Parent
						( matchGroupRef "@baseboard_fab2_lib.baseboard_fab2(sch_1):\MG_DQ-DQS_FAR_DIMM_NG_M_D_BYTE2\" )
					)
					( Status sCSetFlattened )
					( Origin gBackEnd )
				)
				( attribute "RELATIVE_PROPAGATION_DELAY" ",5.00 MIL"
					( Parent
						( matchGroupRef "@baseboard_fab2_lib.baseboard_fab2(sch_1):\MG_DQ-DQS_FAR_DIMM_NG_M_D_BYTE2\" )
					)
					( Units "uMatchProp" "ns" 1.000000)
					( Status sCSetFlattened )
					( Origin gBackEnd )
				)
			)
			( pinPair "@baseboard_fab2_lib.baseboard_fab2(sch_1):\PP701\"
				( pinRef "@baseboard_fab2_lib.baseboard_fab2(sch_1):page26_i172:DDR3_DQS_DP(2)" )
				( pinRef "@baseboard_fab2_lib.baseboard_fab2(sch_1):page50_i46:DQS2P" )
				( attribute "RELATIVE_PROPAGATION_DELAY_SCOPE" "G"
					( Parent
						( matchGroupRef "@baseboard_fab2_lib.baseboard_fab2(sch_1):\MG_DQ-DQS_NEAR_DIMM_NG_M_D_BYTE2\" )
					)
					( Status sCSetFlattened )
					( Origin gBackEnd )
				)
				( attribute "RELATIVE_PROPAGATION_DELAY" ",5.00 MIL"
					( Parent
						( matchGroupRef "@baseboard_fab2_lib.baseboard_fab2(sch_1):\MG_DQ-DQS_NEAR_DIMM_NG_M_D_BYTE2\" )
					)
					( Units "uMatchProp" "ns" 1.000000)
					( Status sCSetFlattened )
					( Origin gBackEnd )
				)
			)
			( pinPair "@baseboard_fab2_lib.baseboard_fab2(sch_1):\PP712\"
				( pinRef "@baseboard_fab2_lib.baseboard_fab2(sch_1):page26_i172:DDR3_DQS_DP(3)" )
				( pinRef "@baseboard_fab2_lib.baseboard_fab2(sch_1):page49_i66:DQS3P" )
				( attribute "RELATIVE_PROPAGATION_DELAY_SCOPE" "G"
					( Parent
						( matchGroupRef "@baseboard_fab2_lib.baseboard_fab2(sch_1):\MG_DQ-DQS_FAR_DIMM_NG_M_D_BYTE3\" )
					)
					( Status sCSetFlattened )
					( Origin gBackEnd )
				)
				( attribute "RELATIVE_PROPAGATION_DELAY" ",5.00 MIL"
					( Parent
						( matchGroupRef "@baseboard_fab2_lib.baseboard_fab2(sch_1):\MG_DQ-DQS_FAR_DIMM_NG_M_D_BYTE3\" )
					)
					( Units "uMatchProp" "ns" 1.000000)
					( Status sCSetFlattened )
					( Origin gBackEnd )
				)
			)
			( pinPair "@baseboard_fab2_lib.baseboard_fab2(sch_1):\PP713\"
				( pinRef "@baseboard_fab2_lib.baseboard_fab2(sch_1):page50_i46:DQS3P" )
				( pinRef "@baseboard_fab2_lib.baseboard_fab2(sch_1):page26_i172:DDR3_DQS_DP(3)" )
				( attribute "RELATIVE_PROPAGATION_DELAY_SCOPE" "G"
					( Parent
						( matchGroupRef "@baseboard_fab2_lib.baseboard_fab2(sch_1):\MG_DQ-DQS_NEAR_DIMM_NG_M_D_BYTE3\" )
					)
					( Status sCSetFlattened )
					( Origin gBackEnd )
				)
				( attribute "RELATIVE_PROPAGATION_DELAY" ",5.00 MIL"
					( Parent
						( matchGroupRef "@baseboard_fab2_lib.baseboard_fab2(sch_1):\MG_DQ-DQS_NEAR_DIMM_NG_M_D_BYTE3\" )
					)
					( Units "uMatchProp" "ns" 1.000000)
					( Status sCSetFlattened )
					( Origin gBackEnd )
				)
			)
			( pinPair "@baseboard_fab2_lib.baseboard_fab2(sch_1):\PP724\"
				( pinRef "@baseboard_fab2_lib.baseboard_fab2(sch_1):page26_i172:DDR3_DQS_DP(4)" )
				( pinRef "@baseboard_fab2_lib.baseboard_fab2(sch_1):page49_i66:DQS4P" )
				( attribute "RELATIVE_PROPAGATION_DELAY_SCOPE" "G"
					( Parent
						( matchGroupRef "@baseboard_fab2_lib.baseboard_fab2(sch_1):\MG_DQ-DQS_FAR_DIMM_NG_M_D_BYTE4\" )
					)
					( Status sCSetFlattened )
					( Origin gBackEnd )
				)
				( attribute "RELATIVE_PROPAGATION_DELAY" ",5.00 MIL"
					( Parent
						( matchGroupRef "@baseboard_fab2_lib.baseboard_fab2(sch_1):\MG_DQ-DQS_FAR_DIMM_NG_M_D_BYTE4\" )
					)
					( Units "uMatchProp" "ns" 1.000000)
					( Status sCSetFlattened )
					( Origin gBackEnd )
				)
			)
			( pinPair "@baseboard_fab2_lib.baseboard_fab2(sch_1):\PP726\"
				( pinRef "@baseboard_fab2_lib.baseboard_fab2(sch_1):page50_i46:DQS4P" )
				( pinRef "@baseboard_fab2_lib.baseboard_fab2(sch_1):page26_i172:DDR3_DQS_DP(4)" )
				( attribute "RELATIVE_PROPAGATION_DELAY_SCOPE" "G"
					( Parent
						( matchGroupRef "@baseboard_fab2_lib.baseboard_fab2(sch_1):\MG_DQ-DQS_NEAR_DIMM_NG_M_D_BYTE4\" )
					)
					( Status sCSetFlattened )
					( Origin gBackEnd )
				)
				( attribute "RELATIVE_PROPAGATION_DELAY" ",5.00 MIL"
					( Parent
						( matchGroupRef "@baseboard_fab2_lib.baseboard_fab2(sch_1):\MG_DQ-DQS_NEAR_DIMM_NG_M_D_BYTE4\" )
					)
					( Units "uMatchProp" "ns" 1.000000)
					( Status sCSetFlattened )
					( Origin gBackEnd )
				)
			)
			( pinPair "@baseboard_fab2_lib.baseboard_fab2(sch_1):\PP736\"
				( pinRef "@baseboard_fab2_lib.baseboard_fab2(sch_1):page26_i172:DDR3_DQS_DP(5)" )
				( pinRef "@baseboard_fab2_lib.baseboard_fab2(sch_1):page49_i66:DQS5P" )
				( attribute "RELATIVE_PROPAGATION_DELAY_SCOPE" "G"
					( Parent
						( matchGroupRef "@baseboard_fab2_lib.baseboard_fab2(sch_1):\MG_DQ-DQS_FAR_DIMM_NG_M_D_BYTE5\" )
					)
					( Status sCSetFlattened )
					( Origin gBackEnd )
				)
				( attribute "RELATIVE_PROPAGATION_DELAY" ",5.00 MIL"
					( Parent
						( matchGroupRef "@baseboard_fab2_lib.baseboard_fab2(sch_1):\MG_DQ-DQS_FAR_DIMM_NG_M_D_BYTE5\" )
					)
					( Units "uMatchProp" "ns" 1.000000)
					( Status sCSetFlattened )
					( Origin gBackEnd )
				)
			)
			( pinPair "@baseboard_fab2_lib.baseboard_fab2(sch_1):\PP738\"
				( pinRef "@baseboard_fab2_lib.baseboard_fab2(sch_1):page26_i172:DDR3_DQS_DP(5)" )
				( pinRef "@baseboard_fab2_lib.baseboard_fab2(sch_1):page50_i46:DQS5P" )
				( attribute "RELATIVE_PROPAGATION_DELAY_SCOPE" "G"
					( Parent
						( matchGroupRef "@baseboard_fab2_lib.baseboard_fab2(sch_1):\MG_DQ-DQS_NEAR_DIMM_NG_M_D_BYTE5\" )
					)
					( Status sCSetFlattened )
					( Origin gBackEnd )
				)
				( attribute "RELATIVE_PROPAGATION_DELAY" ",5.00 MIL"
					( Parent
						( matchGroupRef "@baseboard_fab2_lib.baseboard_fab2(sch_1):\MG_DQ-DQS_NEAR_DIMM_NG_M_D_BYTE5\" )
					)
					( Units "uMatchProp" "ns" 1.000000)
					( Status sCSetFlattened )
					( Origin gBackEnd )
				)
			)
			( pinPair "@baseboard_fab2_lib.baseboard_fab2(sch_1):\PP748\"
				( pinRef "@baseboard_fab2_lib.baseboard_fab2(sch_1):page26_i172:DDR3_DQS_DP(6)" )
				( pinRef "@baseboard_fab2_lib.baseboard_fab2(sch_1):page49_i66:DQS6P" )
				( attribute "RELATIVE_PROPAGATION_DELAY_SCOPE" "G"
					( Parent
						( matchGroupRef "@baseboard_fab2_lib.baseboard_fab2(sch_1):\MG_DQ-DQS_FAR_DIMM_NG_M_D_BYTE6\" )
					)
					( Status sCSetFlattened )
					( Origin gBackEnd )
				)
				( attribute "RELATIVE_PROPAGATION_DELAY" ",5.00 MIL"
					( Parent
						( matchGroupRef "@baseboard_fab2_lib.baseboard_fab2(sch_1):\MG_DQ-DQS_FAR_DIMM_NG_M_D_BYTE6\" )
					)
					( Units "uMatchProp" "ns" 1.000000)
					( Status sCSetFlattened )
					( Origin gBackEnd )
				)
			)
			( pinPair "@baseboard_fab2_lib.baseboard_fab2(sch_1):\PP750\"
				( pinRef "@baseboard_fab2_lib.baseboard_fab2(sch_1):page50_i46:DQS6P" )
				( pinRef "@baseboard_fab2_lib.baseboard_fab2(sch_1):page26_i172:DDR3_DQS_DP(6)" )
				( attribute "RELATIVE_PROPAGATION_DELAY_SCOPE" "G"
					( Parent
						( matchGroupRef "@baseboard_fab2_lib.baseboard_fab2(sch_1):\MG_DQ-DQS_NEAR_DIMM_NG_M_D_BYTE6\" )
					)
					( Status sCSetFlattened )
					( Origin gBackEnd )
				)
				( attribute "RELATIVE_PROPAGATION_DELAY" ",5.00 MIL"
					( Parent
						( matchGroupRef "@baseboard_fab2_lib.baseboard_fab2(sch_1):\MG_DQ-DQS_NEAR_DIMM_NG_M_D_BYTE6\" )
					)
					( Units "uMatchProp" "ns" 1.000000)
					( Status sCSetFlattened )
					( Origin gBackEnd )
				)
			)
			( pinPair "@baseboard_fab2_lib.baseboard_fab2(sch_1):\PP760\"
				( pinRef "@baseboard_fab2_lib.baseboard_fab2(sch_1):page26_i172:DDR3_DQS_DP(7)" )
				( pinRef "@baseboard_fab2_lib.baseboard_fab2(sch_1):page49_i66:DQS7P" )
				( attribute "RELATIVE_PROPAGATION_DELAY_SCOPE" "G"
					( Parent
						( matchGroupRef "@baseboard_fab2_lib.baseboard_fab2(sch_1):\MG_DQ-DQS_FAR_DIMM_NG_M_D_BYTE7\" )
					)
					( Status sCSetFlattened )
					( Origin gBackEnd )
				)
				( attribute "RELATIVE_PROPAGATION_DELAY" ",5.00 MIL"
					( Parent
						( matchGroupRef "@baseboard_fab2_lib.baseboard_fab2(sch_1):\MG_DQ-DQS_FAR_DIMM_NG_M_D_BYTE7\" )
					)
					( Units "uMatchProp" "ns" 1.000000)
					( Status sCSetFlattened )
					( Origin gBackEnd )
				)
			)
			( pinPair "@baseboard_fab2_lib.baseboard_fab2(sch_1):\PP762\"
				( pinRef "@baseboard_fab2_lib.baseboard_fab2(sch_1):page26_i172:DDR3_DQS_DP(7)" )
				( pinRef "@baseboard_fab2_lib.baseboard_fab2(sch_1):page50_i46:DQS7P" )
				( attribute "RELATIVE_PROPAGATION_DELAY_SCOPE" "G"
					( Parent
						( matchGroupRef "@baseboard_fab2_lib.baseboard_fab2(sch_1):\MG_DQ-DQS_NEAR_DIMM_NG_M_D_BYTE7\" )
					)
					( Status sCSetFlattened )
					( Origin gBackEnd )
				)
				( attribute "RELATIVE_PROPAGATION_DELAY" ",5.00 MIL"
					( Parent
						( matchGroupRef "@baseboard_fab2_lib.baseboard_fab2(sch_1):\MG_DQ-DQS_NEAR_DIMM_NG_M_D_BYTE7\" )
					)
					( Units "uMatchProp" "ns" 1.000000)
					( Status sCSetFlattened )
					( Origin gBackEnd )
				)
			)
			( pinPair "@baseboard_fab2_lib.baseboard_fab2(sch_1):\PP469\"
				( pinRef "@baseboard_fab2_lib.baseboard_fab2(sch_1):page23_i172:DDR0_DQS_DN(0)" )
				( pinRef "@baseboard_fab2_lib.baseboard_fab2(sch_1):page43_i2:DQS0N" )
				( attribute "RELATIVE_PROPAGATION_DELAY_SCOPE" "G"
					( Parent
						( matchGroupRef "@baseboard_fab2_lib.baseboard_fab2(sch_1):\MG_DQ-DQS_FAR_DIMM_NG_M_A_BYTE0\" )
					)
					( Status sCSetFlattened )
					( Origin gBackEnd )
				)
				( attribute "RELATIVE_PROPAGATION_DELAY" ",5.00 MIL"
					( Parent
						( matchGroupRef "@baseboard_fab2_lib.baseboard_fab2(sch_1):\MG_DQ-DQS_FAR_DIMM_NG_M_A_BYTE0\" )
					)
					( Units "uMatchProp" "ns" 1.000000)
					( Status sCSetFlattened )
					( Origin gBackEnd )
				)
			)
			( pinPair "@baseboard_fab2_lib.baseboard_fab2(sch_1):\PP471\"
				( pinRef "@baseboard_fab2_lib.baseboard_fab2(sch_1):page23_i172:DDR0_DQS_DN(0)" )
				( pinRef "@baseboard_fab2_lib.baseboard_fab2(sch_1):page44_i120:DQS0N" )
				( attribute "RELATIVE_PROPAGATION_DELAY_SCOPE" "G"
					( Parent
						( matchGroupRef "@baseboard_fab2_lib.baseboard_fab2(sch_1):\MG_DQ-DQS_NEAR_DIMM_NG_M_A_BYTE0\" )
					)
					( Status sCSetFlattened )
					( Origin gBackEnd )
				)
				( attribute "RELATIVE_PROPAGATION_DELAY" ",5.00 MIL"
					( Parent
						( matchGroupRef "@baseboard_fab2_lib.baseboard_fab2(sch_1):\MG_DQ-DQS_NEAR_DIMM_NG_M_A_BYTE0\" )
					)
					( Units "uMatchProp" "ns" 1.000000)
					( Status sCSetFlattened )
					( Origin gBackEnd )
				)
			)
			( pinPair "@baseboard_fab2_lib.baseboard_fab2(sch_1):\PP457\"
				( pinRef "@baseboard_fab2_lib.baseboard_fab2(sch_1):page23_i172:DDR0_DQS_DN(1)" )
				( pinRef "@baseboard_fab2_lib.baseboard_fab2(sch_1):page43_i2:DQS1N" )
				( attribute "RELATIVE_PROPAGATION_DELAY_SCOPE" "G"
					( Parent
						( matchGroupRef "@baseboard_fab2_lib.baseboard_fab2(sch_1):\MG_DQ-DQS_FAR_DIMM_NG_M_A_BYTE1\" )
					)
					( Status sCSetFlattened )
					( Origin gBackEnd )
				)
				( attribute "RELATIVE_PROPAGATION_DELAY" ",5.00 MIL"
					( Parent
						( matchGroupRef "@baseboard_fab2_lib.baseboard_fab2(sch_1):\MG_DQ-DQS_FAR_DIMM_NG_M_A_BYTE1\" )
					)
					( Units "uMatchProp" "ns" 1.000000)
					( Status sCSetFlattened )
					( Origin gBackEnd )
				)
			)
			( pinPair "@baseboard_fab2_lib.baseboard_fab2(sch_1):\PP459\"
				( pinRef "@baseboard_fab2_lib.baseboard_fab2(sch_1):page23_i172:DDR0_DQS_DN(1)" )
				( pinRef "@baseboard_fab2_lib.baseboard_fab2(sch_1):page44_i120:DQS1N" )
				( attribute "RELATIVE_PROPAGATION_DELAY_SCOPE" "G"
					( Parent
						( matchGroupRef "@baseboard_fab2_lib.baseboard_fab2(sch_1):\MG_DQ-DQS_NEAR_DIMM_NG_M_A_BYTE1\" )
					)
					( Status sCSetFlattened )
					( Origin gBackEnd )
				)
				( attribute "RELATIVE_PROPAGATION_DELAY" ",5.00 MIL"
					( Parent
						( matchGroupRef "@baseboard_fab2_lib.baseboard_fab2(sch_1):\MG_DQ-DQS_NEAR_DIMM_NG_M_A_BYTE1\" )
					)
					( Units "uMatchProp" "ns" 1.000000)
					( Status sCSetFlattened )
					( Origin gBackEnd )
				)
			)
			( pinPair "@baseboard_fab2_lib.baseboard_fab2(sch_1):\PP445\"
				( pinRef "@baseboard_fab2_lib.baseboard_fab2(sch_1):page23_i172:DDR0_DQS_DN(2)" )
				( pinRef "@baseboard_fab2_lib.baseboard_fab2(sch_1):page43_i2:DQS2N" )
				( attribute "RELATIVE_PROPAGATION_DELAY_SCOPE" "G"
					( Parent
						( matchGroupRef "@baseboard_fab2_lib.baseboard_fab2(sch_1):\MG_DQ-DQS_FAR_DIMM_NG_M_A_BYTE2\" )
					)
					( Status sCSetFlattened )
					( Origin gBackEnd )
				)
				( attribute "RELATIVE_PROPAGATION_DELAY" ",5.00 MIL"
					( Parent
						( matchGroupRef "@baseboard_fab2_lib.baseboard_fab2(sch_1):\MG_DQ-DQS_FAR_DIMM_NG_M_A_BYTE2\" )
					)
					( Units "uMatchProp" "ns" 1.000000)
					( Status sCSetFlattened )
					( Origin gBackEnd )
				)
			)
			( pinPair "@baseboard_fab2_lib.baseboard_fab2(sch_1):\PP447\"
				( pinRef "@baseboard_fab2_lib.baseboard_fab2(sch_1):page23_i172:DDR0_DQS_DN(2)" )
				( pinRef "@baseboard_fab2_lib.baseboard_fab2(sch_1):page44_i120:DQS2N" )
				( attribute "RELATIVE_PROPAGATION_DELAY_SCOPE" "G"
					( Parent
						( matchGroupRef "@baseboard_fab2_lib.baseboard_fab2(sch_1):\MG_DQ-DQS_NEAR_DIMM_NG_M_A_BYTE2\" )
					)
					( Status sCSetFlattened )
					( Origin gBackEnd )
				)
				( attribute "RELATIVE_PROPAGATION_DELAY" ",5.00 MIL"
					( Parent
						( matchGroupRef "@baseboard_fab2_lib.baseboard_fab2(sch_1):\MG_DQ-DQS_NEAR_DIMM_NG_M_A_BYTE2\" )
					)
					( Units "uMatchProp" "ns" 1.000000)
					( Status sCSetFlattened )
					( Origin gBackEnd )
				)
			)
			( pinPair "@baseboard_fab2_lib.baseboard_fab2(sch_1):\PP433\"
				( pinRef "@baseboard_fab2_lib.baseboard_fab2(sch_1):page23_i172:DDR0_DQS_DN(3)" )
				( pinRef "@baseboard_fab2_lib.baseboard_fab2(sch_1):page43_i2:DQS3N" )
				( attribute "RELATIVE_PROPAGATION_DELAY_SCOPE" "G"
					( Parent
						( matchGroupRef "@baseboard_fab2_lib.baseboard_fab2(sch_1):\MG_DQ-DQS_FAR_DIMM_NG_M_A_BYTE3\" )
					)
					( Status sCSetFlattened )
					( Origin gBackEnd )
				)
				( attribute "RELATIVE_PROPAGATION_DELAY" ",5.00 MIL"
					( Parent
						( matchGroupRef "@baseboard_fab2_lib.baseboard_fab2(sch_1):\MG_DQ-DQS_FAR_DIMM_NG_M_A_BYTE3\" )
					)
					( Units "uMatchProp" "ns" 1.000000)
					( Status sCSetFlattened )
					( Origin gBackEnd )
				)
			)
			( pinPair "@baseboard_fab2_lib.baseboard_fab2(sch_1):\PP435\"
				( pinRef "@baseboard_fab2_lib.baseboard_fab2(sch_1):page23_i172:DDR0_DQS_DN(3)" )
				( pinRef "@baseboard_fab2_lib.baseboard_fab2(sch_1):page44_i120:DQS3N" )
				( attribute "RELATIVE_PROPAGATION_DELAY_SCOPE" "G"
					( Parent
						( matchGroupRef "@baseboard_fab2_lib.baseboard_fab2(sch_1):\MG_DQ-DQS_NEAR_DIMM_NG_M_A_BYTE3\" )
					)
					( Status sCSetFlattened )
					( Origin gBackEnd )
				)
				( attribute "RELATIVE_PROPAGATION_DELAY" ",5.00 MIL"
					( Parent
						( matchGroupRef "@baseboard_fab2_lib.baseboard_fab2(sch_1):\MG_DQ-DQS_NEAR_DIMM_NG_M_A_BYTE3\" )
					)
					( Units "uMatchProp" "ns" 1.000000)
					( Status sCSetFlattened )
					( Origin gBackEnd )
				)
			)
			( pinPair "@baseboard_fab2_lib.baseboard_fab2(sch_1):\PP421\"
				( pinRef "@baseboard_fab2_lib.baseboard_fab2(sch_1):page23_i172:DDR0_DQS_DN(4)" )
				( pinRef "@baseboard_fab2_lib.baseboard_fab2(sch_1):page43_i2:DQS4N" )
				( attribute "RELATIVE_PROPAGATION_DELAY_SCOPE" "G"
					( Parent
						( matchGroupRef "@baseboard_fab2_lib.baseboard_fab2(sch_1):\MG_DQ-DQS_FAR_DIMM_NG_M_A_BYTE4\" )
					)
					( Status sCSetFlattened )
					( Origin gBackEnd )
				)
				( attribute "RELATIVE_PROPAGATION_DELAY" ",5.00 MIL"
					( Parent
						( matchGroupRef "@baseboard_fab2_lib.baseboard_fab2(sch_1):\MG_DQ-DQS_FAR_DIMM_NG_M_A_BYTE4\" )
					)
					( Units "uMatchProp" "ns" 1.000000)
					( Status sCSetFlattened )
					( Origin gBackEnd )
				)
			)
			( pinPair "@baseboard_fab2_lib.baseboard_fab2(sch_1):\PP423\"
				( pinRef "@baseboard_fab2_lib.baseboard_fab2(sch_1):page23_i172:DDR0_DQS_DN(4)" )
				( pinRef "@baseboard_fab2_lib.baseboard_fab2(sch_1):page44_i120:DQS4N" )
				( attribute "RELATIVE_PROPAGATION_DELAY_SCOPE" "G"
					( Parent
						( matchGroupRef "@baseboard_fab2_lib.baseboard_fab2(sch_1):\MG_DQ-DQS_NEAR_DIMM_NG_M_A_BYTE4\" )
					)
					( Status sCSetFlattened )
					( Origin gBackEnd )
				)
				( attribute "RELATIVE_PROPAGATION_DELAY" ",5.00 MIL"
					( Parent
						( matchGroupRef "@baseboard_fab2_lib.baseboard_fab2(sch_1):\MG_DQ-DQS_NEAR_DIMM_NG_M_A_BYTE4\" )
					)
					( Units "uMatchProp" "ns" 1.000000)
					( Status sCSetFlattened )
					( Origin gBackEnd )
				)
			)
			( pinPair "@baseboard_fab2_lib.baseboard_fab2(sch_1):\PP409\"
				( pinRef "@baseboard_fab2_lib.baseboard_fab2(sch_1):page23_i172:DDR0_DQS_DN(5)" )
				( pinRef "@baseboard_fab2_lib.baseboard_fab2(sch_1):page43_i2:DQS5N" )
				( attribute "RELATIVE_PROPAGATION_DELAY_SCOPE" "G"
					( Parent
						( matchGroupRef "@baseboard_fab2_lib.baseboard_fab2(sch_1):\MG_DQ-DQS_FAR_DIMM_NG_M_A_BYTE5\" )
					)
					( Status sCSetFlattened )
					( Origin gBackEnd )
				)
				( attribute "RELATIVE_PROPAGATION_DELAY" ",5.00 MIL"
					( Parent
						( matchGroupRef "@baseboard_fab2_lib.baseboard_fab2(sch_1):\MG_DQ-DQS_FAR_DIMM_NG_M_A_BYTE5\" )
					)
					( Units "uMatchProp" "ns" 1.000000)
					( Status sCSetFlattened )
					( Origin gBackEnd )
				)
			)
			( pinPair "@baseboard_fab2_lib.baseboard_fab2(sch_1):\PP411\"
				( pinRef "@baseboard_fab2_lib.baseboard_fab2(sch_1):page23_i172:DDR0_DQS_DN(5)" )
				( pinRef "@baseboard_fab2_lib.baseboard_fab2(sch_1):page44_i120:DQS5N" )
				( attribute "RELATIVE_PROPAGATION_DELAY_SCOPE" "G"
					( Parent
						( matchGroupRef "@baseboard_fab2_lib.baseboard_fab2(sch_1):\MG_DQ-DQS_NEAR_DIMM_NG_M_A_BYTE5\" )
					)
					( Status sCSetFlattened )
					( Origin gBackEnd )
				)
				( attribute "RELATIVE_PROPAGATION_DELAY" ",5.00 MIL"
					( Parent
						( matchGroupRef "@baseboard_fab2_lib.baseboard_fab2(sch_1):\MG_DQ-DQS_NEAR_DIMM_NG_M_A_BYTE5\" )
					)
					( Units "uMatchProp" "ns" 1.000000)
					( Status sCSetFlattened )
					( Origin gBackEnd )
				)
			)
			( pinPair "@baseboard_fab2_lib.baseboard_fab2(sch_1):\PP397\"
				( pinRef "@baseboard_fab2_lib.baseboard_fab2(sch_1):page23_i172:DDR0_DQS_DN(6)" )
				( pinRef "@baseboard_fab2_lib.baseboard_fab2(sch_1):page43_i2:DQS6N" )
				( attribute "RELATIVE_PROPAGATION_DELAY_SCOPE" "G"
					( Parent
						( matchGroupRef "@baseboard_fab2_lib.baseboard_fab2(sch_1):\MG_DQ-DQS_FAR_DIMM_NG_M_A_BYTE6\" )
					)
					( Status sCSetFlattened )
					( Origin gBackEnd )
				)
				( attribute "RELATIVE_PROPAGATION_DELAY" ",5.00 MIL"
					( Parent
						( matchGroupRef "@baseboard_fab2_lib.baseboard_fab2(sch_1):\MG_DQ-DQS_FAR_DIMM_NG_M_A_BYTE6\" )
					)
					( Units "uMatchProp" "ns" 1.000000)
					( Status sCSetFlattened )
					( Origin gBackEnd )
				)
			)
			( pinPair "@baseboard_fab2_lib.baseboard_fab2(sch_1):\PP399\"
				( pinRef "@baseboard_fab2_lib.baseboard_fab2(sch_1):page23_i172:DDR0_DQS_DN(6)" )
				( pinRef "@baseboard_fab2_lib.baseboard_fab2(sch_1):page44_i120:DQS6N" )
				( attribute "RELATIVE_PROPAGATION_DELAY_SCOPE" "G"
					( Parent
						( matchGroupRef "@baseboard_fab2_lib.baseboard_fab2(sch_1):\MG_DQ-DQS_NEAR_DIMM_NG_M_A_BYTE6\" )
					)
					( Status sCSetFlattened )
					( Origin gBackEnd )
				)
				( attribute "RELATIVE_PROPAGATION_DELAY" ",5.00 MIL"
					( Parent
						( matchGroupRef "@baseboard_fab2_lib.baseboard_fab2(sch_1):\MG_DQ-DQS_NEAR_DIMM_NG_M_A_BYTE6\" )
					)
					( Units "uMatchProp" "ns" 1.000000)
					( Status sCSetFlattened )
					( Origin gBackEnd )
				)
			)
			( pinPair "@baseboard_fab2_lib.baseboard_fab2(sch_1):\PP5187\"
				( pinRef "@baseboard_fab2_lib.baseboard_fab2(sch_1):page23_i172:DDR0_DQS_DN(7)" )
				( pinRef "@baseboard_fab2_lib.baseboard_fab2(sch_1):page43_i2:DQS7N" )
				( attribute "RELATIVE_PROPAGATION_DELAY_SCOPE" "G"
					( Parent
						( matchGroupRef "@baseboard_fab2_lib.baseboard_fab2(sch_1):\MG_DQ-DQS_FAR_DIMM_NG_M_A_BYTE7\" )
					)
					( Status sCSetFlattened )
					( Origin gBackEnd )
				)
				( attribute "RELATIVE_PROPAGATION_DELAY" ",5.00 MIL"
					( Parent
						( matchGroupRef "@baseboard_fab2_lib.baseboard_fab2(sch_1):\MG_DQ-DQS_FAR_DIMM_NG_M_A_BYTE7\" )
					)
					( Units "uMatchProp" "ns" 1.000000)
					( Status sCSetFlattened )
					( Origin gBackEnd )
				)
			)
			( pinPair "@baseboard_fab2_lib.baseboard_fab2(sch_1):\PP5189\"
				( pinRef "@baseboard_fab2_lib.baseboard_fab2(sch_1):page23_i172:DDR0_DQS_DN(7)" )
				( pinRef "@baseboard_fab2_lib.baseboard_fab2(sch_1):page44_i120:DQS7N" )
				( attribute "RELATIVE_PROPAGATION_DELAY_SCOPE" "G"
					( Parent
						( matchGroupRef "@baseboard_fab2_lib.baseboard_fab2(sch_1):\MG_DQ-DQS_NEAR_DIMM_NG_M_A_BYTE7\" )
					)
					( Status sCSetFlattened )
					( Origin gBackEnd )
				)
				( attribute "RELATIVE_PROPAGATION_DELAY" ",5.00 MIL"
					( Parent
						( matchGroupRef "@baseboard_fab2_lib.baseboard_fab2(sch_1):\MG_DQ-DQS_NEAR_DIMM_NG_M_A_BYTE7\" )
					)
					( Units "uMatchProp" "ns" 1.000000)
					( Status sCSetFlattened )
					( Origin gBackEnd )
				)
			)
			( pinPair "@baseboard_fab2_lib.baseboard_fab2(sch_1):\PP1237\"
				( pinRef "@baseboard_fab2_lib.baseboard_fab2(sch_1):page23_i172:DDR0_DQS_DN(8)" )
				( pinRef "@baseboard_fab2_lib.baseboard_fab2(sch_1):page43_i2:DQS8N" )
				( attribute "RELATIVE_PROPAGATION_DELAY_SCOPE" "G"
					( Parent
						( matchGroupRef "@baseboard_fab2_lib.baseboard_fab2(sch_1):\MG_DQ-DQS_FAR_DIMM_NG_M_A_BYTE-ECC\" )
					)
					( Status sCSetFlattened )
					( Origin gBackEnd )
				)
				( attribute "RELATIVE_PROPAGATION_DELAY" ",5.00 MIL"
					( Parent
						( matchGroupRef "@baseboard_fab2_lib.baseboard_fab2(sch_1):\MG_DQ-DQS_FAR_DIMM_NG_M_A_BYTE-ECC\" )
					)
					( Units "uMatchProp" "ns" 1.000000)
					( Status sCSetFlattened )
					( Origin gBackEnd )
				)
			)
			( pinPair "@baseboard_fab2_lib.baseboard_fab2(sch_1):\PP1239\"
				( pinRef "@baseboard_fab2_lib.baseboard_fab2(sch_1):page23_i172:DDR0_DQS_DN(8)" )
				( pinRef "@baseboard_fab2_lib.baseboard_fab2(sch_1):page44_i120:DQS8N" )
				( attribute "RELATIVE_PROPAGATION_DELAY_SCOPE" "G"
					( Parent
						( matchGroupRef "@baseboard_fab2_lib.baseboard_fab2(sch_1):\MG_DQ-DQS_NEAR_DIMM_NG_M_A_BYTE-ECC\" )
					)
					( Status sCSetFlattened )
					( Origin gBackEnd )
				)
				( attribute "RELATIVE_PROPAGATION_DELAY" ",5.00 MIL"
					( Parent
						( matchGroupRef "@baseboard_fab2_lib.baseboard_fab2(sch_1):\MG_DQ-DQS_NEAR_DIMM_NG_M_A_BYTE-ECC\" )
					)
					( Units "uMatchProp" "ns" 1.000000)
					( Status sCSetFlattened )
					( Origin gBackEnd )
				)
			)
			( pinPair "@baseboard_fab2_lib.baseboard_fab2(sch_1):\PP463\"
				( pinRef "@baseboard_fab2_lib.baseboard_fab2(sch_1):page23_i172:DDR0_DQS_DN(9)" )
				( pinRef "@baseboard_fab2_lib.baseboard_fab2(sch_1):page43_i2:DQS9N" )
				( attribute "RELATIVE_PROPAGATION_DELAY_SCOPE" "G"
					( Parent
						( matchGroupRef "@baseboard_fab2_lib.baseboard_fab2(sch_1):\MG_DQ-DQS_FAR_DIMM_NG_M_A_BYTE0\" )
					)
					( Status sCSetFlattened )
					( Origin gBackEnd )
				)
				( attribute "RELATIVE_PROPAGATION_DELAY" ",5.00 MIL"
					( Parent
						( matchGroupRef "@baseboard_fab2_lib.baseboard_fab2(sch_1):\MG_DQ-DQS_FAR_DIMM_NG_M_A_BYTE0\" )
					)
					( Units "uMatchProp" "ns" 1.000000)
					( Status sCSetFlattened )
					( Origin gBackEnd )
				)
			)
			( pinPair "@baseboard_fab2_lib.baseboard_fab2(sch_1):\PP465\"
				( pinRef "@baseboard_fab2_lib.baseboard_fab2(sch_1):page23_i172:DDR0_DQS_DN(9)" )
				( pinRef "@baseboard_fab2_lib.baseboard_fab2(sch_1):page44_i120:DQS9N" )
				( attribute "RELATIVE_PROPAGATION_DELAY_SCOPE" "G"
					( Parent
						( matchGroupRef "@baseboard_fab2_lib.baseboard_fab2(sch_1):\MG_DQ-DQS_NEAR_DIMM_NG_M_A_BYTE0\" )
					)
					( Status sCSetFlattened )
					( Origin gBackEnd )
				)
				( attribute "RELATIVE_PROPAGATION_DELAY" ",5.00 MIL"
					( Parent
						( matchGroupRef "@baseboard_fab2_lib.baseboard_fab2(sch_1):\MG_DQ-DQS_NEAR_DIMM_NG_M_A_BYTE0\" )
					)
					( Units "uMatchProp" "ns" 1.000000)
					( Status sCSetFlattened )
					( Origin gBackEnd )
				)
			)
			( pinPair "@baseboard_fab2_lib.baseboard_fab2(sch_1):\PP451\"
				( pinRef "@baseboard_fab2_lib.baseboard_fab2(sch_1):page23_i172:DDR0_DQS_DN(10)" )
				( pinRef "@baseboard_fab2_lib.baseboard_fab2(sch_1):page43_i2:DQS10N" )
				( attribute "RELATIVE_PROPAGATION_DELAY_SCOPE" "G"
					( Parent
						( matchGroupRef "@baseboard_fab2_lib.baseboard_fab2(sch_1):\MG_DQ-DQS_FAR_DIMM_NG_M_A_BYTE1\" )
					)
					( Status sCSetFlattened )
					( Origin gBackEnd )
				)
				( attribute "RELATIVE_PROPAGATION_DELAY" ",5.00 MIL"
					( Parent
						( matchGroupRef "@baseboard_fab2_lib.baseboard_fab2(sch_1):\MG_DQ-DQS_FAR_DIMM_NG_M_A_BYTE1\" )
					)
					( Units "uMatchProp" "ns" 1.000000)
					( Status sCSetFlattened )
					( Origin gBackEnd )
				)
			)
			( pinPair "@baseboard_fab2_lib.baseboard_fab2(sch_1):\PP453\"
				( pinRef "@baseboard_fab2_lib.baseboard_fab2(sch_1):page23_i172:DDR0_DQS_DN(10)" )
				( pinRef "@baseboard_fab2_lib.baseboard_fab2(sch_1):page44_i120:DQS10N" )
				( attribute "RELATIVE_PROPAGATION_DELAY_SCOPE" "G"
					( Parent
						( matchGroupRef "@baseboard_fab2_lib.baseboard_fab2(sch_1):\MG_DQ-DQS_NEAR_DIMM_NG_M_A_BYTE1\" )
					)
					( Status sCSetFlattened )
					( Origin gBackEnd )
				)
				( attribute "RELATIVE_PROPAGATION_DELAY" ",5.00 MIL"
					( Parent
						( matchGroupRef "@baseboard_fab2_lib.baseboard_fab2(sch_1):\MG_DQ-DQS_NEAR_DIMM_NG_M_A_BYTE1\" )
					)
					( Units "uMatchProp" "ns" 1.000000)
					( Status sCSetFlattened )
					( Origin gBackEnd )
				)
			)
			( pinPair "@baseboard_fab2_lib.baseboard_fab2(sch_1):\PP439\"
				( pinRef "@baseboard_fab2_lib.baseboard_fab2(sch_1):page23_i172:DDR0_DQS_DN(11)" )
				( pinRef "@baseboard_fab2_lib.baseboard_fab2(sch_1):page43_i2:DQS11N" )
				( attribute "RELATIVE_PROPAGATION_DELAY_SCOPE" "G"
					( Parent
						( matchGroupRef "@baseboard_fab2_lib.baseboard_fab2(sch_1):\MG_DQ-DQS_FAR_DIMM_NG_M_A_BYTE2\" )
					)
					( Status sCSetFlattened )
					( Origin gBackEnd )
				)
				( attribute "RELATIVE_PROPAGATION_DELAY" ",5.00 MIL"
					( Parent
						( matchGroupRef "@baseboard_fab2_lib.baseboard_fab2(sch_1):\MG_DQ-DQS_FAR_DIMM_NG_M_A_BYTE2\" )
					)
					( Units "uMatchProp" "ns" 1.000000)
					( Status sCSetFlattened )
					( Origin gBackEnd )
				)
			)
			( pinPair "@baseboard_fab2_lib.baseboard_fab2(sch_1):\PP441\"
				( pinRef "@baseboard_fab2_lib.baseboard_fab2(sch_1):page23_i172:DDR0_DQS_DN(11)" )
				( pinRef "@baseboard_fab2_lib.baseboard_fab2(sch_1):page44_i120:DQS11N" )
				( attribute "RELATIVE_PROPAGATION_DELAY_SCOPE" "G"
					( Parent
						( matchGroupRef "@baseboard_fab2_lib.baseboard_fab2(sch_1):\MG_DQ-DQS_NEAR_DIMM_NG_M_A_BYTE2\" )
					)
					( Status sCSetFlattened )
					( Origin gBackEnd )
				)
				( attribute "RELATIVE_PROPAGATION_DELAY" ",5.00 MIL"
					( Parent
						( matchGroupRef "@baseboard_fab2_lib.baseboard_fab2(sch_1):\MG_DQ-DQS_NEAR_DIMM_NG_M_A_BYTE2\" )
					)
					( Units "uMatchProp" "ns" 1.000000)
					( Status sCSetFlattened )
					( Origin gBackEnd )
				)
			)
			( pinPair "@baseboard_fab2_lib.baseboard_fab2(sch_1):\PP427\"
				( pinRef "@baseboard_fab2_lib.baseboard_fab2(sch_1):page23_i172:DDR0_DQS_DN(12)" )
				( pinRef "@baseboard_fab2_lib.baseboard_fab2(sch_1):page43_i2:DQS12N" )
				( attribute "RELATIVE_PROPAGATION_DELAY_SCOPE" "G"
					( Parent
						( matchGroupRef "@baseboard_fab2_lib.baseboard_fab2(sch_1):\MG_DQ-DQS_FAR_DIMM_NG_M_A_BYTE3\" )
					)
					( Status sCSetFlattened )
					( Origin gBackEnd )
				)
				( attribute "RELATIVE_PROPAGATION_DELAY" ",5.00 MIL"
					( Parent
						( matchGroupRef "@baseboard_fab2_lib.baseboard_fab2(sch_1):\MG_DQ-DQS_FAR_DIMM_NG_M_A_BYTE3\" )
					)
					( Units "uMatchProp" "ns" 1.000000)
					( Status sCSetFlattened )
					( Origin gBackEnd )
				)
			)
			( pinPair "@baseboard_fab2_lib.baseboard_fab2(sch_1):\PP429\"
				( pinRef "@baseboard_fab2_lib.baseboard_fab2(sch_1):page23_i172:DDR0_DQS_DN(12)" )
				( pinRef "@baseboard_fab2_lib.baseboard_fab2(sch_1):page44_i120:DQS12N" )
				( attribute "RELATIVE_PROPAGATION_DELAY_SCOPE" "G"
					( Parent
						( matchGroupRef "@baseboard_fab2_lib.baseboard_fab2(sch_1):\MG_DQ-DQS_NEAR_DIMM_NG_M_A_BYTE3\" )
					)
					( Status sCSetFlattened )
					( Origin gBackEnd )
				)
				( attribute "RELATIVE_PROPAGATION_DELAY" ",5.00 MIL"
					( Parent
						( matchGroupRef "@baseboard_fab2_lib.baseboard_fab2(sch_1):\MG_DQ-DQS_NEAR_DIMM_NG_M_A_BYTE3\" )
					)
					( Units "uMatchProp" "ns" 1.000000)
					( Status sCSetFlattened )
					( Origin gBackEnd )
				)
			)
			( pinPair "@baseboard_fab2_lib.baseboard_fab2(sch_1):\PP415\"
				( pinRef "@baseboard_fab2_lib.baseboard_fab2(sch_1):page23_i172:DDR0_DQS_DN(13)" )
				( pinRef "@baseboard_fab2_lib.baseboard_fab2(sch_1):page43_i2:DQS13N" )
				( attribute "RELATIVE_PROPAGATION_DELAY_SCOPE" "G"
					( Parent
						( matchGroupRef "@baseboard_fab2_lib.baseboard_fab2(sch_1):\MG_DQ-DQS_FAR_DIMM_NG_M_A_BYTE4\" )
					)
					( Status sCSetFlattened )
					( Origin gBackEnd )
				)
				( attribute "RELATIVE_PROPAGATION_DELAY" ",5.00 MIL"
					( Parent
						( matchGroupRef "@baseboard_fab2_lib.baseboard_fab2(sch_1):\MG_DQ-DQS_FAR_DIMM_NG_M_A_BYTE4\" )
					)
					( Units "uMatchProp" "ns" 1.000000)
					( Status sCSetFlattened )
					( Origin gBackEnd )
				)
			)
			( pinPair "@baseboard_fab2_lib.baseboard_fab2(sch_1):\PP417\"
				( pinRef "@baseboard_fab2_lib.baseboard_fab2(sch_1):page23_i172:DDR0_DQS_DN(13)" )
				( pinRef "@baseboard_fab2_lib.baseboard_fab2(sch_1):page44_i120:DQS13N" )
				( attribute "RELATIVE_PROPAGATION_DELAY_SCOPE" "G"
					( Parent
						( matchGroupRef "@baseboard_fab2_lib.baseboard_fab2(sch_1):\MG_DQ-DQS_NEAR_DIMM_NG_M_A_BYTE4\" )
					)
					( Status sCSetFlattened )
					( Origin gBackEnd )
				)
				( attribute "RELATIVE_PROPAGATION_DELAY" ",5.00 MIL"
					( Parent
						( matchGroupRef "@baseboard_fab2_lib.baseboard_fab2(sch_1):\MG_DQ-DQS_NEAR_DIMM_NG_M_A_BYTE4\" )
					)
					( Units "uMatchProp" "ns" 1.000000)
					( Status sCSetFlattened )
					( Origin gBackEnd )
				)
			)
			( pinPair "@baseboard_fab2_lib.baseboard_fab2(sch_1):\PP403\"
				( pinRef "@baseboard_fab2_lib.baseboard_fab2(sch_1):page23_i172:DDR0_DQS_DN(14)" )
				( pinRef "@baseboard_fab2_lib.baseboard_fab2(sch_1):page43_i2:DQS14N" )
				( attribute "RELATIVE_PROPAGATION_DELAY_SCOPE" "G"
					( Parent
						( matchGroupRef "@baseboard_fab2_lib.baseboard_fab2(sch_1):\MG_DQ-DQS_FAR_DIMM_NG_M_A_BYTE5\" )
					)
					( Status sCSetFlattened )
					( Origin gBackEnd )
				)
				( attribute "RELATIVE_PROPAGATION_DELAY" ",5.00 MIL"
					( Parent
						( matchGroupRef "@baseboard_fab2_lib.baseboard_fab2(sch_1):\MG_DQ-DQS_FAR_DIMM_NG_M_A_BYTE5\" )
					)
					( Units "uMatchProp" "ns" 1.000000)
					( Status sCSetFlattened )
					( Origin gBackEnd )
				)
			)
			( pinPair "@baseboard_fab2_lib.baseboard_fab2(sch_1):\PP405\"
				( pinRef "@baseboard_fab2_lib.baseboard_fab2(sch_1):page23_i172:DDR0_DQS_DN(14)" )
				( pinRef "@baseboard_fab2_lib.baseboard_fab2(sch_1):page44_i120:DQS14N" )
				( attribute "RELATIVE_PROPAGATION_DELAY_SCOPE" "G"
					( Parent
						( matchGroupRef "@baseboard_fab2_lib.baseboard_fab2(sch_1):\MG_DQ-DQS_NEAR_DIMM_NG_M_A_BYTE5\" )
					)
					( Status sCSetFlattened )
					( Origin gBackEnd )
				)
				( attribute "RELATIVE_PROPAGATION_DELAY" ",5.00 MIL"
					( Parent
						( matchGroupRef "@baseboard_fab2_lib.baseboard_fab2(sch_1):\MG_DQ-DQS_NEAR_DIMM_NG_M_A_BYTE5\" )
					)
					( Units "uMatchProp" "ns" 1.000000)
					( Status sCSetFlattened )
					( Origin gBackEnd )
				)
			)
			( pinPair "@baseboard_fab2_lib.baseboard_fab2(sch_1):\PP391\"
				( pinRef "@baseboard_fab2_lib.baseboard_fab2(sch_1):page23_i172:DDR0_DQS_DN(15)" )
				( pinRef "@baseboard_fab2_lib.baseboard_fab2(sch_1):page43_i2:DQS15N" )
				( attribute "RELATIVE_PROPAGATION_DELAY_SCOPE" "G"
					( Parent
						( matchGroupRef "@baseboard_fab2_lib.baseboard_fab2(sch_1):\MG_DQ-DQS_FAR_DIMM_NG_M_A_BYTE6\" )
					)
					( Status sCSetFlattened )
					( Origin gBackEnd )
				)
				( attribute "RELATIVE_PROPAGATION_DELAY" ",5.00 MIL"
					( Parent
						( matchGroupRef "@baseboard_fab2_lib.baseboard_fab2(sch_1):\MG_DQ-DQS_FAR_DIMM_NG_M_A_BYTE6\" )
					)
					( Units "uMatchProp" "ns" 1.000000)
					( Status sCSetFlattened )
					( Origin gBackEnd )
				)
			)
			( pinPair "@baseboard_fab2_lib.baseboard_fab2(sch_1):\PP393\"
				( pinRef "@baseboard_fab2_lib.baseboard_fab2(sch_1):page23_i172:DDR0_DQS_DN(15)" )
				( pinRef "@baseboard_fab2_lib.baseboard_fab2(sch_1):page44_i120:DQS15N" )
				( attribute "RELATIVE_PROPAGATION_DELAY_SCOPE" "G"
					( Parent
						( matchGroupRef "@baseboard_fab2_lib.baseboard_fab2(sch_1):\MG_DQ-DQS_NEAR_DIMM_NG_M_A_BYTE6\" )
					)
					( Status sCSetFlattened )
					( Origin gBackEnd )
				)
				( attribute "RELATIVE_PROPAGATION_DELAY" ",5.00 MIL"
					( Parent
						( matchGroupRef "@baseboard_fab2_lib.baseboard_fab2(sch_1):\MG_DQ-DQS_NEAR_DIMM_NG_M_A_BYTE6\" )
					)
					( Units "uMatchProp" "ns" 1.000000)
					( Status sCSetFlattened )
					( Origin gBackEnd )
				)
			)
			( pinPair "@baseboard_fab2_lib.baseboard_fab2(sch_1):\PP5193\"
				( pinRef "@baseboard_fab2_lib.baseboard_fab2(sch_1):page23_i172:DDR0_DQS_DN(16)" )
				( pinRef "@baseboard_fab2_lib.baseboard_fab2(sch_1):page43_i2:DQS16N" )
				( attribute "RELATIVE_PROPAGATION_DELAY_SCOPE" "G"
					( Parent
						( matchGroupRef "@baseboard_fab2_lib.baseboard_fab2(sch_1):\MG_DQ-DQS_FAR_DIMM_NG_M_A_BYTE7\" )
					)
					( Status sCSetFlattened )
					( Origin gBackEnd )
				)
				( attribute "RELATIVE_PROPAGATION_DELAY" ",5.00 MIL"
					( Parent
						( matchGroupRef "@baseboard_fab2_lib.baseboard_fab2(sch_1):\MG_DQ-DQS_FAR_DIMM_NG_M_A_BYTE7\" )
					)
					( Units "uMatchProp" "ns" 1.000000)
					( Status sCSetFlattened )
					( Origin gBackEnd )
				)
			)
			( pinPair "@baseboard_fab2_lib.baseboard_fab2(sch_1):\PP5195\"
				( pinRef "@baseboard_fab2_lib.baseboard_fab2(sch_1):page23_i172:DDR0_DQS_DN(16)" )
				( pinRef "@baseboard_fab2_lib.baseboard_fab2(sch_1):page44_i120:DQS16N" )
				( attribute "RELATIVE_PROPAGATION_DELAY_SCOPE" "G"
					( Parent
						( matchGroupRef "@baseboard_fab2_lib.baseboard_fab2(sch_1):\MG_DQ-DQS_NEAR_DIMM_NG_M_A_BYTE7\" )
					)
					( Status sCSetFlattened )
					( Origin gBackEnd )
				)
				( attribute "RELATIVE_PROPAGATION_DELAY" ",5.00 MIL"
					( Parent
						( matchGroupRef "@baseboard_fab2_lib.baseboard_fab2(sch_1):\MG_DQ-DQS_NEAR_DIMM_NG_M_A_BYTE7\" )
					)
					( Units "uMatchProp" "ns" 1.000000)
					( Status sCSetFlattened )
					( Origin gBackEnd )
				)
			)
			( pinPair "@baseboard_fab2_lib.baseboard_fab2(sch_1):\PP1231\"
				( pinRef "@baseboard_fab2_lib.baseboard_fab2(sch_1):page23_i172:DDR0_DQS_DN(17)" )
				( pinRef "@baseboard_fab2_lib.baseboard_fab2(sch_1):page43_i2:DQS17N" )
				( attribute "RELATIVE_PROPAGATION_DELAY_SCOPE" "G"
					( Parent
						( matchGroupRef "@baseboard_fab2_lib.baseboard_fab2(sch_1):\MG_DQ-DQS_FAR_DIMM_NG_M_A_BYTE-ECC\" )
					)
					( Status sCSetFlattened )
					( Origin gBackEnd )
				)
				( attribute "RELATIVE_PROPAGATION_DELAY" ",5.00 MIL"
					( Parent
						( matchGroupRef "@baseboard_fab2_lib.baseboard_fab2(sch_1):\MG_DQ-DQS_FAR_DIMM_NG_M_A_BYTE-ECC\" )
					)
					( Units "uMatchProp" "ns" 1.000000)
					( Status sCSetFlattened )
					( Origin gBackEnd )
				)
			)
			( pinPair "@baseboard_fab2_lib.baseboard_fab2(sch_1):\PP1233\"
				( pinRef "@baseboard_fab2_lib.baseboard_fab2(sch_1):page23_i172:DDR0_DQS_DN(17)" )
				( pinRef "@baseboard_fab2_lib.baseboard_fab2(sch_1):page44_i120:DQS17N" )
				( attribute "RELATIVE_PROPAGATION_DELAY_SCOPE" "G"
					( Parent
						( matchGroupRef "@baseboard_fab2_lib.baseboard_fab2(sch_1):\MG_DQ-DQS_NEAR_DIMM_NG_M_A_BYTE-ECC\" )
					)
					( Status sCSetFlattened )
					( Origin gBackEnd )
				)
				( attribute "RELATIVE_PROPAGATION_DELAY" ",5.00 MIL"
					( Parent
						( matchGroupRef "@baseboard_fab2_lib.baseboard_fab2(sch_1):\MG_DQ-DQS_NEAR_DIMM_NG_M_A_BYTE-ECC\" )
					)
					( Units "uMatchProp" "ns" 1.000000)
					( Status sCSetFlattened )
					( Origin gBackEnd )
				)
			)
			( pinPair "@baseboard_fab2_lib.baseboard_fab2(sch_1):\PP472\"
				( pinRef "@baseboard_fab2_lib.baseboard_fab2(sch_1):page23_i172:DDR0_DQS_DP(0)" )
				( pinRef "@baseboard_fab2_lib.baseboard_fab2(sch_1):page43_i2:DQS0P" )
				( attribute "RELATIVE_PROPAGATION_DELAY_SCOPE" "G"
					( Parent
						( matchGroupRef "@baseboard_fab2_lib.baseboard_fab2(sch_1):\MG_DQ-DQS_FAR_DIMM_NG_M_A_BYTE0\" )
					)
					( Status sCSetFlattened )
					( Origin gBackEnd )
				)
				( attribute "RELATIVE_PROPAGATION_DELAY" ",5.00 MIL"
					( Parent
						( matchGroupRef "@baseboard_fab2_lib.baseboard_fab2(sch_1):\MG_DQ-DQS_FAR_DIMM_NG_M_A_BYTE0\" )
					)
					( Units "uMatchProp" "ns" 1.000000)
					( Status sCSetFlattened )
					( Origin gBackEnd )
				)
			)
			( pinPair "@baseboard_fab2_lib.baseboard_fab2(sch_1):\PP474\"
				( pinRef "@baseboard_fab2_lib.baseboard_fab2(sch_1):page23_i172:DDR0_DQS_DP(0)" )
				( pinRef "@baseboard_fab2_lib.baseboard_fab2(sch_1):page44_i120:DQS0P" )
				( attribute "RELATIVE_PROPAGATION_DELAY_SCOPE" "G"
					( Parent
						( matchGroupRef "@baseboard_fab2_lib.baseboard_fab2(sch_1):\MG_DQ-DQS_NEAR_DIMM_NG_M_A_BYTE0\" )
					)
					( Status sCSetFlattened )
					( Origin gBackEnd )
				)
				( attribute "RELATIVE_PROPAGATION_DELAY" ",5.00 MIL"
					( Parent
						( matchGroupRef "@baseboard_fab2_lib.baseboard_fab2(sch_1):\MG_DQ-DQS_NEAR_DIMM_NG_M_A_BYTE0\" )
					)
					( Units "uMatchProp" "ns" 1.000000)
					( Status sCSetFlattened )
					( Origin gBackEnd )
				)
			)
			( pinPair "@baseboard_fab2_lib.baseboard_fab2(sch_1):\PP460\"
				( pinRef "@baseboard_fab2_lib.baseboard_fab2(sch_1):page23_i172:DDR0_DQS_DP(1)" )
				( pinRef "@baseboard_fab2_lib.baseboard_fab2(sch_1):page43_i2:DQS1P" )
				( attribute "RELATIVE_PROPAGATION_DELAY_SCOPE" "G"
					( Parent
						( matchGroupRef "@baseboard_fab2_lib.baseboard_fab2(sch_1):\MG_DQ-DQS_FAR_DIMM_NG_M_A_BYTE1\" )
					)
					( Status sCSetFlattened )
					( Origin gBackEnd )
				)
				( attribute "RELATIVE_PROPAGATION_DELAY" ",5.00 MIL"
					( Parent
						( matchGroupRef "@baseboard_fab2_lib.baseboard_fab2(sch_1):\MG_DQ-DQS_FAR_DIMM_NG_M_A_BYTE1\" )
					)
					( Units "uMatchProp" "ns" 1.000000)
					( Status sCSetFlattened )
					( Origin gBackEnd )
				)
			)
			( pinPair "@baseboard_fab2_lib.baseboard_fab2(sch_1):\PP462\"
				( pinRef "@baseboard_fab2_lib.baseboard_fab2(sch_1):page23_i172:DDR0_DQS_DP(1)" )
				( pinRef "@baseboard_fab2_lib.baseboard_fab2(sch_1):page44_i120:DQS1P" )
				( attribute "RELATIVE_PROPAGATION_DELAY_SCOPE" "G"
					( Parent
						( matchGroupRef "@baseboard_fab2_lib.baseboard_fab2(sch_1):\MG_DQ-DQS_NEAR_DIMM_NG_M_A_BYTE1\" )
					)
					( Status sCSetFlattened )
					( Origin gBackEnd )
				)
				( attribute "RELATIVE_PROPAGATION_DELAY" ",5.00 MIL"
					( Parent
						( matchGroupRef "@baseboard_fab2_lib.baseboard_fab2(sch_1):\MG_DQ-DQS_NEAR_DIMM_NG_M_A_BYTE1\" )
					)
					( Units "uMatchProp" "ns" 1.000000)
					( Status sCSetFlattened )
					( Origin gBackEnd )
				)
			)
			( pinPair "@baseboard_fab2_lib.baseboard_fab2(sch_1):\PP448\"
				( pinRef "@baseboard_fab2_lib.baseboard_fab2(sch_1):page23_i172:DDR0_DQS_DP(2)" )
				( pinRef "@baseboard_fab2_lib.baseboard_fab2(sch_1):page43_i2:DQS2P" )
				( attribute "RELATIVE_PROPAGATION_DELAY_SCOPE" "G"
					( Parent
						( matchGroupRef "@baseboard_fab2_lib.baseboard_fab2(sch_1):\MG_DQ-DQS_FAR_DIMM_NG_M_A_BYTE2\" )
					)
					( Status sCSetFlattened )
					( Origin gBackEnd )
				)
				( attribute "RELATIVE_PROPAGATION_DELAY" ",5.00 MIL"
					( Parent
						( matchGroupRef "@baseboard_fab2_lib.baseboard_fab2(sch_1):\MG_DQ-DQS_FAR_DIMM_NG_M_A_BYTE2\" )
					)
					( Units "uMatchProp" "ns" 1.000000)
					( Status sCSetFlattened )
					( Origin gBackEnd )
				)
			)
			( pinPair "@baseboard_fab2_lib.baseboard_fab2(sch_1):\PP450\"
				( pinRef "@baseboard_fab2_lib.baseboard_fab2(sch_1):page23_i172:DDR0_DQS_DP(2)" )
				( pinRef "@baseboard_fab2_lib.baseboard_fab2(sch_1):page44_i120:DQS2P" )
				( attribute "RELATIVE_PROPAGATION_DELAY_SCOPE" "G"
					( Parent
						( matchGroupRef "@baseboard_fab2_lib.baseboard_fab2(sch_1):\MG_DQ-DQS_NEAR_DIMM_NG_M_A_BYTE2\" )
					)
					( Status sCSetFlattened )
					( Origin gBackEnd )
				)
				( attribute "RELATIVE_PROPAGATION_DELAY" ",5.00 MIL"
					( Parent
						( matchGroupRef "@baseboard_fab2_lib.baseboard_fab2(sch_1):\MG_DQ-DQS_NEAR_DIMM_NG_M_A_BYTE2\" )
					)
					( Units "uMatchProp" "ns" 1.000000)
					( Status sCSetFlattened )
					( Origin gBackEnd )
				)
			)
			( pinPair "@baseboard_fab2_lib.baseboard_fab2(sch_1):\PP436\"
				( pinRef "@baseboard_fab2_lib.baseboard_fab2(sch_1):page23_i172:DDR0_DQS_DP(3)" )
				( pinRef "@baseboard_fab2_lib.baseboard_fab2(sch_1):page43_i2:DQS3P" )
				( attribute "RELATIVE_PROPAGATION_DELAY_SCOPE" "G"
					( Parent
						( matchGroupRef "@baseboard_fab2_lib.baseboard_fab2(sch_1):\MG_DQ-DQS_FAR_DIMM_NG_M_A_BYTE3\" )
					)
					( Status sCSetFlattened )
					( Origin gBackEnd )
				)
				( attribute "RELATIVE_PROPAGATION_DELAY" ",5.00 MIL"
					( Parent
						( matchGroupRef "@baseboard_fab2_lib.baseboard_fab2(sch_1):\MG_DQ-DQS_FAR_DIMM_NG_M_A_BYTE3\" )
					)
					( Units "uMatchProp" "ns" 1.000000)
					( Status sCSetFlattened )
					( Origin gBackEnd )
				)
			)
			( pinPair "@baseboard_fab2_lib.baseboard_fab2(sch_1):\PP438\"
				( pinRef "@baseboard_fab2_lib.baseboard_fab2(sch_1):page23_i172:DDR0_DQS_DP(3)" )
				( pinRef "@baseboard_fab2_lib.baseboard_fab2(sch_1):page44_i120:DQS3P" )
				( attribute "RELATIVE_PROPAGATION_DELAY_SCOPE" "G"
					( Parent
						( matchGroupRef "@baseboard_fab2_lib.baseboard_fab2(sch_1):\MG_DQ-DQS_NEAR_DIMM_NG_M_A_BYTE3\" )
					)
					( Status sCSetFlattened )
					( Origin gBackEnd )
				)
				( attribute "RELATIVE_PROPAGATION_DELAY" ",5.00 MIL"
					( Parent
						( matchGroupRef "@baseboard_fab2_lib.baseboard_fab2(sch_1):\MG_DQ-DQS_NEAR_DIMM_NG_M_A_BYTE3\" )
					)
					( Units "uMatchProp" "ns" 1.000000)
					( Status sCSetFlattened )
					( Origin gBackEnd )
				)
			)
			( pinPair "@baseboard_fab2_lib.baseboard_fab2(sch_1):\PP424\"
				( pinRef "@baseboard_fab2_lib.baseboard_fab2(sch_1):page23_i172:DDR0_DQS_DP(4)" )
				( pinRef "@baseboard_fab2_lib.baseboard_fab2(sch_1):page43_i2:DQS4P" )
				( attribute "RELATIVE_PROPAGATION_DELAY_SCOPE" "G"
					( Parent
						( matchGroupRef "@baseboard_fab2_lib.baseboard_fab2(sch_1):\MG_DQ-DQS_FAR_DIMM_NG_M_A_BYTE4\" )
					)
					( Status sCSetFlattened )
					( Origin gBackEnd )
				)
				( attribute "RELATIVE_PROPAGATION_DELAY" ",5.00 MIL"
					( Parent
						( matchGroupRef "@baseboard_fab2_lib.baseboard_fab2(sch_1):\MG_DQ-DQS_FAR_DIMM_NG_M_A_BYTE4\" )
					)
					( Units "uMatchProp" "ns" 1.000000)
					( Status sCSetFlattened )
					( Origin gBackEnd )
				)
			)
			( pinPair "@baseboard_fab2_lib.baseboard_fab2(sch_1):\PP426\"
				( pinRef "@baseboard_fab2_lib.baseboard_fab2(sch_1):page23_i172:DDR0_DQS_DP(4)" )
				( pinRef "@baseboard_fab2_lib.baseboard_fab2(sch_1):page44_i120:DQS4P" )
				( attribute "RELATIVE_PROPAGATION_DELAY_SCOPE" "G"
					( Parent
						( matchGroupRef "@baseboard_fab2_lib.baseboard_fab2(sch_1):\MG_DQ-DQS_NEAR_DIMM_NG_M_A_BYTE4\" )
					)
					( Status sCSetFlattened )
					( Origin gBackEnd )
				)
				( attribute "RELATIVE_PROPAGATION_DELAY" ",5.00 MIL"
					( Parent
						( matchGroupRef "@baseboard_fab2_lib.baseboard_fab2(sch_1):\MG_DQ-DQS_NEAR_DIMM_NG_M_A_BYTE4\" )
					)
					( Units "uMatchProp" "ns" 1.000000)
					( Status sCSetFlattened )
					( Origin gBackEnd )
				)
			)
			( pinPair "@baseboard_fab2_lib.baseboard_fab2(sch_1):\PP412\"
				( pinRef "@baseboard_fab2_lib.baseboard_fab2(sch_1):page23_i172:DDR0_DQS_DP(5)" )
				( pinRef "@baseboard_fab2_lib.baseboard_fab2(sch_1):page43_i2:DQS5P" )
				( attribute "RELATIVE_PROPAGATION_DELAY_SCOPE" "G"
					( Parent
						( matchGroupRef "@baseboard_fab2_lib.baseboard_fab2(sch_1):\MG_DQ-DQS_FAR_DIMM_NG_M_A_BYTE5\" )
					)
					( Status sCSetFlattened )
					( Origin gBackEnd )
				)
				( attribute "RELATIVE_PROPAGATION_DELAY" ",5.00 MIL"
					( Parent
						( matchGroupRef "@baseboard_fab2_lib.baseboard_fab2(sch_1):\MG_DQ-DQS_FAR_DIMM_NG_M_A_BYTE5\" )
					)
					( Units "uMatchProp" "ns" 1.000000)
					( Status sCSetFlattened )
					( Origin gBackEnd )
				)
			)
			( pinPair "@baseboard_fab2_lib.baseboard_fab2(sch_1):\PP414\"
				( pinRef "@baseboard_fab2_lib.baseboard_fab2(sch_1):page23_i172:DDR0_DQS_DP(5)" )
				( pinRef "@baseboard_fab2_lib.baseboard_fab2(sch_1):page44_i120:DQS5P" )
				( attribute "RELATIVE_PROPAGATION_DELAY_SCOPE" "G"
					( Parent
						( matchGroupRef "@baseboard_fab2_lib.baseboard_fab2(sch_1):\MG_DQ-DQS_NEAR_DIMM_NG_M_A_BYTE5\" )
					)
					( Status sCSetFlattened )
					( Origin gBackEnd )
				)
				( attribute "RELATIVE_PROPAGATION_DELAY" ",5.00 MIL"
					( Parent
						( matchGroupRef "@baseboard_fab2_lib.baseboard_fab2(sch_1):\MG_DQ-DQS_NEAR_DIMM_NG_M_A_BYTE5\" )
					)
					( Units "uMatchProp" "ns" 1.000000)
					( Status sCSetFlattened )
					( Origin gBackEnd )
				)
			)
			( pinPair "@baseboard_fab2_lib.baseboard_fab2(sch_1):\PP400\"
				( pinRef "@baseboard_fab2_lib.baseboard_fab2(sch_1):page23_i172:DDR0_DQS_DP(6)" )
				( pinRef "@baseboard_fab2_lib.baseboard_fab2(sch_1):page43_i2:DQS6P" )
				( attribute "RELATIVE_PROPAGATION_DELAY_SCOPE" "G"
					( Parent
						( matchGroupRef "@baseboard_fab2_lib.baseboard_fab2(sch_1):\MG_DQ-DQS_FAR_DIMM_NG_M_A_BYTE6\" )
					)
					( Status sCSetFlattened )
					( Origin gBackEnd )
				)
				( attribute "RELATIVE_PROPAGATION_DELAY" ",5.00 MIL"
					( Parent
						( matchGroupRef "@baseboard_fab2_lib.baseboard_fab2(sch_1):\MG_DQ-DQS_FAR_DIMM_NG_M_A_BYTE6\" )
					)
					( Units "uMatchProp" "ns" 1.000000)
					( Status sCSetFlattened )
					( Origin gBackEnd )
				)
			)
			( pinPair "@baseboard_fab2_lib.baseboard_fab2(sch_1):\PP402\"
				( pinRef "@baseboard_fab2_lib.baseboard_fab2(sch_1):page23_i172:DDR0_DQS_DP(6)" )
				( pinRef "@baseboard_fab2_lib.baseboard_fab2(sch_1):page44_i120:DQS6P" )
				( attribute "RELATIVE_PROPAGATION_DELAY_SCOPE" "G"
					( Parent
						( matchGroupRef "@baseboard_fab2_lib.baseboard_fab2(sch_1):\MG_DQ-DQS_NEAR_DIMM_NG_M_A_BYTE6\" )
					)
					( Status sCSetFlattened )
					( Origin gBackEnd )
				)
				( attribute "RELATIVE_PROPAGATION_DELAY" ",5.00 MIL"
					( Parent
						( matchGroupRef "@baseboard_fab2_lib.baseboard_fab2(sch_1):\MG_DQ-DQS_NEAR_DIMM_NG_M_A_BYTE6\" )
					)
					( Units "uMatchProp" "ns" 1.000000)
					( Status sCSetFlattened )
					( Origin gBackEnd )
				)
			)
			( pinPair "@baseboard_fab2_lib.baseboard_fab2(sch_1):\PP5190\"
				( pinRef "@baseboard_fab2_lib.baseboard_fab2(sch_1):page23_i172:DDR0_DQS_DP(7)" )
				( pinRef "@baseboard_fab2_lib.baseboard_fab2(sch_1):page43_i2:DQS7P" )
				( attribute "RELATIVE_PROPAGATION_DELAY_SCOPE" "G"
					( Parent
						( matchGroupRef "@baseboard_fab2_lib.baseboard_fab2(sch_1):\MG_DQ-DQS_FAR_DIMM_NG_M_A_BYTE7\" )
					)
					( Status sCSetFlattened )
					( Origin gBackEnd )
				)
				( attribute "RELATIVE_PROPAGATION_DELAY" ",5.00 MIL"
					( Parent
						( matchGroupRef "@baseboard_fab2_lib.baseboard_fab2(sch_1):\MG_DQ-DQS_FAR_DIMM_NG_M_A_BYTE7\" )
					)
					( Units "uMatchProp" "ns" 1.000000)
					( Status sCSetFlattened )
					( Origin gBackEnd )
				)
			)
			( pinPair "@baseboard_fab2_lib.baseboard_fab2(sch_1):\PP5192\"
				( pinRef "@baseboard_fab2_lib.baseboard_fab2(sch_1):page23_i172:DDR0_DQS_DP(7)" )
				( pinRef "@baseboard_fab2_lib.baseboard_fab2(sch_1):page44_i120:DQS7P" )
				( attribute "RELATIVE_PROPAGATION_DELAY_SCOPE" "G"
					( Parent
						( matchGroupRef "@baseboard_fab2_lib.baseboard_fab2(sch_1):\MG_DQ-DQS_NEAR_DIMM_NG_M_A_BYTE7\" )
					)
					( Status sCSetFlattened )
					( Origin gBackEnd )
				)
				( attribute "RELATIVE_PROPAGATION_DELAY" ",5.00 MIL"
					( Parent
						( matchGroupRef "@baseboard_fab2_lib.baseboard_fab2(sch_1):\MG_DQ-DQS_NEAR_DIMM_NG_M_A_BYTE7\" )
					)
					( Units "uMatchProp" "ns" 1.000000)
					( Status sCSetFlattened )
					( Origin gBackEnd )
				)
			)
			( pinPair "@baseboard_fab2_lib.baseboard_fab2(sch_1):\PP1240\"
				( pinRef "@baseboard_fab2_lib.baseboard_fab2(sch_1):page23_i172:DDR0_DQS_DP(8)" )
				( pinRef "@baseboard_fab2_lib.baseboard_fab2(sch_1):page43_i2:DQS8P" )
				( attribute "RELATIVE_PROPAGATION_DELAY_SCOPE" "G"
					( Parent
						( matchGroupRef "@baseboard_fab2_lib.baseboard_fab2(sch_1):\MG_DQ-DQS_FAR_DIMM_NG_M_A_BYTE-ECC\" )
					)
					( Status sCSetFlattened )
					( Origin gBackEnd )
				)
				( attribute "RELATIVE_PROPAGATION_DELAY" ",5.00 MIL"
					( Parent
						( matchGroupRef "@baseboard_fab2_lib.baseboard_fab2(sch_1):\MG_DQ-DQS_FAR_DIMM_NG_M_A_BYTE-ECC\" )
					)
					( Units "uMatchProp" "ns" 1.000000)
					( Status sCSetFlattened )
					( Origin gBackEnd )
				)
			)
			( pinPair "@baseboard_fab2_lib.baseboard_fab2(sch_1):\PP1242\"
				( pinRef "@baseboard_fab2_lib.baseboard_fab2(sch_1):page23_i172:DDR0_DQS_DP(8)" )
				( pinRef "@baseboard_fab2_lib.baseboard_fab2(sch_1):page44_i120:DQS8P" )
				( attribute "RELATIVE_PROPAGATION_DELAY_SCOPE" "G"
					( Parent
						( matchGroupRef "@baseboard_fab2_lib.baseboard_fab2(sch_1):\MG_DQ-DQS_NEAR_DIMM_NG_M_A_BYTE-ECC\" )
					)
					( Status sCSetFlattened )
					( Origin gBackEnd )
				)
				( attribute "RELATIVE_PROPAGATION_DELAY" ",5.00 MIL"
					( Parent
						( matchGroupRef "@baseboard_fab2_lib.baseboard_fab2(sch_1):\MG_DQ-DQS_NEAR_DIMM_NG_M_A_BYTE-ECC\" )
					)
					( Units "uMatchProp" "ns" 1.000000)
					( Status sCSetFlattened )
					( Origin gBackEnd )
				)
			)
			( pinPair "@baseboard_fab2_lib.baseboard_fab2(sch_1):\PP466\"
				( pinRef "@baseboard_fab2_lib.baseboard_fab2(sch_1):page23_i172:DDR0_DQS_DP(9)" )
				( pinRef "@baseboard_fab2_lib.baseboard_fab2(sch_1):page43_i2:DQS9P" )
				( attribute "RELATIVE_PROPAGATION_DELAY_SCOPE" "G"
					( Parent
						( matchGroupRef "@baseboard_fab2_lib.baseboard_fab2(sch_1):\MG_DQ-DQS_FAR_DIMM_NG_M_A_BYTE0\" )
					)
					( Status sCSetFlattened )
					( Origin gBackEnd )
				)
				( attribute "RELATIVE_PROPAGATION_DELAY" ",5.00 MIL"
					( Parent
						( matchGroupRef "@baseboard_fab2_lib.baseboard_fab2(sch_1):\MG_DQ-DQS_FAR_DIMM_NG_M_A_BYTE0\" )
					)
					( Units "uMatchProp" "ns" 1.000000)
					( Status sCSetFlattened )
					( Origin gBackEnd )
				)
			)
			( pinPair "@baseboard_fab2_lib.baseboard_fab2(sch_1):\PP468\"
				( pinRef "@baseboard_fab2_lib.baseboard_fab2(sch_1):page23_i172:DDR0_DQS_DP(9)" )
				( pinRef "@baseboard_fab2_lib.baseboard_fab2(sch_1):page44_i120:DQS9P" )
				( attribute "RELATIVE_PROPAGATION_DELAY_SCOPE" "G"
					( Parent
						( matchGroupRef "@baseboard_fab2_lib.baseboard_fab2(sch_1):\MG_DQ-DQS_NEAR_DIMM_NG_M_A_BYTE0\" )
					)
					( Status sCSetFlattened )
					( Origin gBackEnd )
				)
				( attribute "RELATIVE_PROPAGATION_DELAY" ",5.00 MIL"
					( Parent
						( matchGroupRef "@baseboard_fab2_lib.baseboard_fab2(sch_1):\MG_DQ-DQS_NEAR_DIMM_NG_M_A_BYTE0\" )
					)
					( Units "uMatchProp" "ns" 1.000000)
					( Status sCSetFlattened )
					( Origin gBackEnd )
				)
			)
			( pinPair "@baseboard_fab2_lib.baseboard_fab2(sch_1):\PP454\"
				( pinRef "@baseboard_fab2_lib.baseboard_fab2(sch_1):page23_i172:DDR0_DQS_DP(10)" )
				( pinRef "@baseboard_fab2_lib.baseboard_fab2(sch_1):page43_i2:DQS10P" )
				( attribute "RELATIVE_PROPAGATION_DELAY_SCOPE" "G"
					( Parent
						( matchGroupRef "@baseboard_fab2_lib.baseboard_fab2(sch_1):\MG_DQ-DQS_FAR_DIMM_NG_M_A_BYTE1\" )
					)
					( Status sCSetFlattened )
					( Origin gBackEnd )
				)
				( attribute "RELATIVE_PROPAGATION_DELAY" ",5.00 MIL"
					( Parent
						( matchGroupRef "@baseboard_fab2_lib.baseboard_fab2(sch_1):\MG_DQ-DQS_FAR_DIMM_NG_M_A_BYTE1\" )
					)
					( Units "uMatchProp" "ns" 1.000000)
					( Status sCSetFlattened )
					( Origin gBackEnd )
				)
			)
			( pinPair "@baseboard_fab2_lib.baseboard_fab2(sch_1):\PP456\"
				( pinRef "@baseboard_fab2_lib.baseboard_fab2(sch_1):page23_i172:DDR0_DQS_DP(10)" )
				( pinRef "@baseboard_fab2_lib.baseboard_fab2(sch_1):page44_i120:DQS10P" )
				( attribute "RELATIVE_PROPAGATION_DELAY_SCOPE" "G"
					( Parent
						( matchGroupRef "@baseboard_fab2_lib.baseboard_fab2(sch_1):\MG_DQ-DQS_NEAR_DIMM_NG_M_A_BYTE1\" )
					)
					( Status sCSetFlattened )
					( Origin gBackEnd )
				)
				( attribute "RELATIVE_PROPAGATION_DELAY" ",5.00 MIL"
					( Parent
						( matchGroupRef "@baseboard_fab2_lib.baseboard_fab2(sch_1):\MG_DQ-DQS_NEAR_DIMM_NG_M_A_BYTE1\" )
					)
					( Units "uMatchProp" "ns" 1.000000)
					( Status sCSetFlattened )
					( Origin gBackEnd )
				)
			)
			( pinPair "@baseboard_fab2_lib.baseboard_fab2(sch_1):\PP442\"
				( pinRef "@baseboard_fab2_lib.baseboard_fab2(sch_1):page23_i172:DDR0_DQS_DP(11)" )
				( pinRef "@baseboard_fab2_lib.baseboard_fab2(sch_1):page43_i2:DQS11P" )
				( attribute "RELATIVE_PROPAGATION_DELAY_SCOPE" "G"
					( Parent
						( matchGroupRef "@baseboard_fab2_lib.baseboard_fab2(sch_1):\MG_DQ-DQS_FAR_DIMM_NG_M_A_BYTE2\" )
					)
					( Status sCSetFlattened )
					( Origin gBackEnd )
				)
				( attribute "RELATIVE_PROPAGATION_DELAY" ",5.00 MIL"
					( Parent
						( matchGroupRef "@baseboard_fab2_lib.baseboard_fab2(sch_1):\MG_DQ-DQS_FAR_DIMM_NG_M_A_BYTE2\" )
					)
					( Units "uMatchProp" "ns" 1.000000)
					( Status sCSetFlattened )
					( Origin gBackEnd )
				)
			)
			( pinPair "@baseboard_fab2_lib.baseboard_fab2(sch_1):\PP444\"
				( pinRef "@baseboard_fab2_lib.baseboard_fab2(sch_1):page23_i172:DDR0_DQS_DP(11)" )
				( pinRef "@baseboard_fab2_lib.baseboard_fab2(sch_1):page44_i120:DQS11P" )
				( attribute "RELATIVE_PROPAGATION_DELAY_SCOPE" "G"
					( Parent
						( matchGroupRef "@baseboard_fab2_lib.baseboard_fab2(sch_1):\MG_DQ-DQS_NEAR_DIMM_NG_M_A_BYTE2\" )
					)
					( Status sCSetFlattened )
					( Origin gBackEnd )
				)
				( attribute "RELATIVE_PROPAGATION_DELAY" ",5.00 MIL"
					( Parent
						( matchGroupRef "@baseboard_fab2_lib.baseboard_fab2(sch_1):\MG_DQ-DQS_NEAR_DIMM_NG_M_A_BYTE2\" )
					)
					( Units "uMatchProp" "ns" 1.000000)
					( Status sCSetFlattened )
					( Origin gBackEnd )
				)
			)
			( pinPair "@baseboard_fab2_lib.baseboard_fab2(sch_1):\PP430\"
				( pinRef "@baseboard_fab2_lib.baseboard_fab2(sch_1):page23_i172:DDR0_DQS_DP(12)" )
				( pinRef "@baseboard_fab2_lib.baseboard_fab2(sch_1):page43_i2:DQS12P" )
				( attribute "RELATIVE_PROPAGATION_DELAY_SCOPE" "G"
					( Parent
						( matchGroupRef "@baseboard_fab2_lib.baseboard_fab2(sch_1):\MG_DQ-DQS_FAR_DIMM_NG_M_A_BYTE3\" )
					)
					( Status sCSetFlattened )
					( Origin gBackEnd )
				)
				( attribute "RELATIVE_PROPAGATION_DELAY" ",5.00 MIL"
					( Parent
						( matchGroupRef "@baseboard_fab2_lib.baseboard_fab2(sch_1):\MG_DQ-DQS_FAR_DIMM_NG_M_A_BYTE3\" )
					)
					( Units "uMatchProp" "ns" 1.000000)
					( Status sCSetFlattened )
					( Origin gBackEnd )
				)
			)
			( pinPair "@baseboard_fab2_lib.baseboard_fab2(sch_1):\PP432\"
				( pinRef "@baseboard_fab2_lib.baseboard_fab2(sch_1):page23_i172:DDR0_DQS_DP(12)" )
				( pinRef "@baseboard_fab2_lib.baseboard_fab2(sch_1):page44_i120:DQS12P" )
				( attribute "RELATIVE_PROPAGATION_DELAY_SCOPE" "G"
					( Parent
						( matchGroupRef "@baseboard_fab2_lib.baseboard_fab2(sch_1):\MG_DQ-DQS_NEAR_DIMM_NG_M_A_BYTE3\" )
					)
					( Status sCSetFlattened )
					( Origin gBackEnd )
				)
				( attribute "RELATIVE_PROPAGATION_DELAY" ",5.00 MIL"
					( Parent
						( matchGroupRef "@baseboard_fab2_lib.baseboard_fab2(sch_1):\MG_DQ-DQS_NEAR_DIMM_NG_M_A_BYTE3\" )
					)
					( Units "uMatchProp" "ns" 1.000000)
					( Status sCSetFlattened )
					( Origin gBackEnd )
				)
			)
			( pinPair "@baseboard_fab2_lib.baseboard_fab2(sch_1):\PP418\"
				( pinRef "@baseboard_fab2_lib.baseboard_fab2(sch_1):page23_i172:DDR0_DQS_DP(13)" )
				( pinRef "@baseboard_fab2_lib.baseboard_fab2(sch_1):page43_i2:DQS13P" )
				( attribute "RELATIVE_PROPAGATION_DELAY_SCOPE" "G"
					( Parent
						( matchGroupRef "@baseboard_fab2_lib.baseboard_fab2(sch_1):\MG_DQ-DQS_FAR_DIMM_NG_M_A_BYTE4\" )
					)
					( Status sCSetFlattened )
					( Origin gBackEnd )
				)
				( attribute "RELATIVE_PROPAGATION_DELAY" ",5.00 MIL"
					( Parent
						( matchGroupRef "@baseboard_fab2_lib.baseboard_fab2(sch_1):\MG_DQ-DQS_FAR_DIMM_NG_M_A_BYTE4\" )
					)
					( Units "uMatchProp" "ns" 1.000000)
					( Status sCSetFlattened )
					( Origin gBackEnd )
				)
			)
			( pinPair "@baseboard_fab2_lib.baseboard_fab2(sch_1):\PP420\"
				( pinRef "@baseboard_fab2_lib.baseboard_fab2(sch_1):page23_i172:DDR0_DQS_DP(13)" )
				( pinRef "@baseboard_fab2_lib.baseboard_fab2(sch_1):page44_i120:DQS13P" )
				( attribute "RELATIVE_PROPAGATION_DELAY_SCOPE" "G"
					( Parent
						( matchGroupRef "@baseboard_fab2_lib.baseboard_fab2(sch_1):\MG_DQ-DQS_NEAR_DIMM_NG_M_A_BYTE4\" )
					)
					( Status sCSetFlattened )
					( Origin gBackEnd )
				)
				( attribute "RELATIVE_PROPAGATION_DELAY" ",5.00 MIL"
					( Parent
						( matchGroupRef "@baseboard_fab2_lib.baseboard_fab2(sch_1):\MG_DQ-DQS_NEAR_DIMM_NG_M_A_BYTE4\" )
					)
					( Units "uMatchProp" "ns" 1.000000)
					( Status sCSetFlattened )
					( Origin gBackEnd )
				)
			)
			( pinPair "@baseboard_fab2_lib.baseboard_fab2(sch_1):\PP406\"
				( pinRef "@baseboard_fab2_lib.baseboard_fab2(sch_1):page23_i172:DDR0_DQS_DP(14)" )
				( pinRef "@baseboard_fab2_lib.baseboard_fab2(sch_1):page43_i2:DQS14P" )
				( attribute "RELATIVE_PROPAGATION_DELAY_SCOPE" "G"
					( Parent
						( matchGroupRef "@baseboard_fab2_lib.baseboard_fab2(sch_1):\MG_DQ-DQS_FAR_DIMM_NG_M_A_BYTE5\" )
					)
					( Status sCSetFlattened )
					( Origin gBackEnd )
				)
				( attribute "RELATIVE_PROPAGATION_DELAY" ",5.00 MIL"
					( Parent
						( matchGroupRef "@baseboard_fab2_lib.baseboard_fab2(sch_1):\MG_DQ-DQS_FAR_DIMM_NG_M_A_BYTE5\" )
					)
					( Units "uMatchProp" "ns" 1.000000)
					( Status sCSetFlattened )
					( Origin gBackEnd )
				)
			)
			( pinPair "@baseboard_fab2_lib.baseboard_fab2(sch_1):\PP408\"
				( pinRef "@baseboard_fab2_lib.baseboard_fab2(sch_1):page23_i172:DDR0_DQS_DP(14)" )
				( pinRef "@baseboard_fab2_lib.baseboard_fab2(sch_1):page44_i120:DQS14P" )
				( attribute "RELATIVE_PROPAGATION_DELAY_SCOPE" "G"
					( Parent
						( matchGroupRef "@baseboard_fab2_lib.baseboard_fab2(sch_1):\MG_DQ-DQS_NEAR_DIMM_NG_M_A_BYTE5\" )
					)
					( Status sCSetFlattened )
					( Origin gBackEnd )
				)
				( attribute "RELATIVE_PROPAGATION_DELAY" ",5.00 MIL"
					( Parent
						( matchGroupRef "@baseboard_fab2_lib.baseboard_fab2(sch_1):\MG_DQ-DQS_NEAR_DIMM_NG_M_A_BYTE5\" )
					)
					( Units "uMatchProp" "ns" 1.000000)
					( Status sCSetFlattened )
					( Origin gBackEnd )
				)
			)
			( pinPair "@baseboard_fab2_lib.baseboard_fab2(sch_1):\PP394\"
				( pinRef "@baseboard_fab2_lib.baseboard_fab2(sch_1):page23_i172:DDR0_DQS_DP(15)" )
				( pinRef "@baseboard_fab2_lib.baseboard_fab2(sch_1):page43_i2:DQS15P" )
				( attribute "RELATIVE_PROPAGATION_DELAY_SCOPE" "G"
					( Parent
						( matchGroupRef "@baseboard_fab2_lib.baseboard_fab2(sch_1):\MG_DQ-DQS_FAR_DIMM_NG_M_A_BYTE6\" )
					)
					( Status sCSetFlattened )
					( Origin gBackEnd )
				)
				( attribute "RELATIVE_PROPAGATION_DELAY" ",5.00 MIL"
					( Parent
						( matchGroupRef "@baseboard_fab2_lib.baseboard_fab2(sch_1):\MG_DQ-DQS_FAR_DIMM_NG_M_A_BYTE6\" )
					)
					( Units "uMatchProp" "ns" 1.000000)
					( Status sCSetFlattened )
					( Origin gBackEnd )
				)
			)
			( pinPair "@baseboard_fab2_lib.baseboard_fab2(sch_1):\PP396\"
				( pinRef "@baseboard_fab2_lib.baseboard_fab2(sch_1):page23_i172:DDR0_DQS_DP(15)" )
				( pinRef "@baseboard_fab2_lib.baseboard_fab2(sch_1):page44_i120:DQS15P" )
				( attribute "RELATIVE_PROPAGATION_DELAY_SCOPE" "G"
					( Parent
						( matchGroupRef "@baseboard_fab2_lib.baseboard_fab2(sch_1):\MG_DQ-DQS_NEAR_DIMM_NG_M_A_BYTE6\" )
					)
					( Status sCSetFlattened )
					( Origin gBackEnd )
				)
				( attribute "RELATIVE_PROPAGATION_DELAY" ",5.00 MIL"
					( Parent
						( matchGroupRef "@baseboard_fab2_lib.baseboard_fab2(sch_1):\MG_DQ-DQS_NEAR_DIMM_NG_M_A_BYTE6\" )
					)
					( Units "uMatchProp" "ns" 1.000000)
					( Status sCSetFlattened )
					( Origin gBackEnd )
				)
			)
			( pinPair "@baseboard_fab2_lib.baseboard_fab2(sch_1):\PP5196\"
				( pinRef "@baseboard_fab2_lib.baseboard_fab2(sch_1):page23_i172:DDR0_DQS_DP(16)" )
				( pinRef "@baseboard_fab2_lib.baseboard_fab2(sch_1):page43_i2:DQS16P" )
				( attribute "RELATIVE_PROPAGATION_DELAY_SCOPE" "G"
					( Parent
						( matchGroupRef "@baseboard_fab2_lib.baseboard_fab2(sch_1):\MG_DQ-DQS_FAR_DIMM_NG_M_A_BYTE7\" )
					)
					( Status sCSetFlattened )
					( Origin gBackEnd )
				)
				( attribute "RELATIVE_PROPAGATION_DELAY" ",5.00 MIL"
					( Parent
						( matchGroupRef "@baseboard_fab2_lib.baseboard_fab2(sch_1):\MG_DQ-DQS_FAR_DIMM_NG_M_A_BYTE7\" )
					)
					( Units "uMatchProp" "ns" 1.000000)
					( Status sCSetFlattened )
					( Origin gBackEnd )
				)
			)
			( pinPair "@baseboard_fab2_lib.baseboard_fab2(sch_1):\PP5198\"
				( pinRef "@baseboard_fab2_lib.baseboard_fab2(sch_1):page23_i172:DDR0_DQS_DP(16)" )
				( pinRef "@baseboard_fab2_lib.baseboard_fab2(sch_1):page44_i120:DQS16P" )
				( attribute "RELATIVE_PROPAGATION_DELAY_SCOPE" "G"
					( Parent
						( matchGroupRef "@baseboard_fab2_lib.baseboard_fab2(sch_1):\MG_DQ-DQS_NEAR_DIMM_NG_M_A_BYTE7\" )
					)
					( Status sCSetFlattened )
					( Origin gBackEnd )
				)
				( attribute "RELATIVE_PROPAGATION_DELAY" ",5.00 MIL"
					( Parent
						( matchGroupRef "@baseboard_fab2_lib.baseboard_fab2(sch_1):\MG_DQ-DQS_NEAR_DIMM_NG_M_A_BYTE7\" )
					)
					( Units "uMatchProp" "ns" 1.000000)
					( Status sCSetFlattened )
					( Origin gBackEnd )
				)
			)
			( pinPair "@baseboard_fab2_lib.baseboard_fab2(sch_1):\PP1234\"
				( pinRef "@baseboard_fab2_lib.baseboard_fab2(sch_1):page23_i172:DDR0_DQS_DP(17)" )
				( pinRef "@baseboard_fab2_lib.baseboard_fab2(sch_1):page43_i2:DQS17P" )
				( attribute "RELATIVE_PROPAGATION_DELAY_SCOPE" "G"
					( Parent
						( matchGroupRef "@baseboard_fab2_lib.baseboard_fab2(sch_1):\MG_DQ-DQS_FAR_DIMM_NG_M_A_BYTE-ECC\" )
					)
					( Status sCSetFlattened )
					( Origin gBackEnd )
				)
				( attribute "RELATIVE_PROPAGATION_DELAY" ",5.00 MIL"
					( Parent
						( matchGroupRef "@baseboard_fab2_lib.baseboard_fab2(sch_1):\MG_DQ-DQS_FAR_DIMM_NG_M_A_BYTE-ECC\" )
					)
					( Units "uMatchProp" "ns" 1.000000)
					( Status sCSetFlattened )
					( Origin gBackEnd )
				)
			)
			( pinPair "@baseboard_fab2_lib.baseboard_fab2(sch_1):\PP1236\"
				( pinRef "@baseboard_fab2_lib.baseboard_fab2(sch_1):page23_i172:DDR0_DQS_DP(17)" )
				( pinRef "@baseboard_fab2_lib.baseboard_fab2(sch_1):page44_i120:DQS17P" )
				( attribute "RELATIVE_PROPAGATION_DELAY_SCOPE" "G"
					( Parent
						( matchGroupRef "@baseboard_fab2_lib.baseboard_fab2(sch_1):\MG_DQ-DQS_NEAR_DIMM_NG_M_A_BYTE-ECC\" )
					)
					( Status sCSetFlattened )
					( Origin gBackEnd )
				)
				( attribute "RELATIVE_PROPAGATION_DELAY" ",5.00 MIL"
					( Parent
						( matchGroupRef "@baseboard_fab2_lib.baseboard_fab2(sch_1):\MG_DQ-DQS_NEAR_DIMM_NG_M_A_BYTE-ECC\" )
					)
					( Units "uMatchProp" "ns" 1.000000)
					( Status sCSetFlattened )
					( Origin gBackEnd )
				)
			)
			( pinPair "@baseboard_fab2_lib.baseboard_fab2(sch_1):\PP565\"
				( pinRef "@baseboard_fab2_lib.baseboard_fab2(sch_1):page24_i172:DDR1_DQS_DN(0)" )
				( pinRef "@baseboard_fab2_lib.baseboard_fab2(sch_1):page45_i61:DQS0N" )
				( attribute "RELATIVE_PROPAGATION_DELAY_SCOPE" "G"
					( Parent
						( matchGroupRef "@baseboard_fab2_lib.baseboard_fab2(sch_1):\MG_DQ-DQS_FAR_DIMM_NG_M_B_BYTE0\" )
					)
					( Status sCSetFlattened )
					( Origin gBackEnd )
				)
				( attribute "RELATIVE_PROPAGATION_DELAY" ",5.00 MIL"
					( Parent
						( matchGroupRef "@baseboard_fab2_lib.baseboard_fab2(sch_1):\MG_DQ-DQS_FAR_DIMM_NG_M_B_BYTE0\" )
					)
					( Units "uMatchProp" "ns" 1.000000)
					( Status sCSetFlattened )
					( Origin gBackEnd )
				)
			)
			( pinPair "@baseboard_fab2_lib.baseboard_fab2(sch_1):\PP566\"
				( pinRef "@baseboard_fab2_lib.baseboard_fab2(sch_1):page24_i172:DDR1_DQS_DN(0)" )
				( pinRef "@baseboard_fab2_lib.baseboard_fab2(sch_1):page46_i112:DQS0N" )
				( attribute "RELATIVE_PROPAGATION_DELAY_SCOPE" "G"
					( Parent
						( matchGroupRef "@baseboard_fab2_lib.baseboard_fab2(sch_1):\MG_DQ-DQS_NEAR_DIMM_NG_M_B_BYTE0\" )
					)
					( Status sCSetFlattened )
					( Origin gBackEnd )
				)
				( attribute "RELATIVE_PROPAGATION_DELAY" ",5.00 MIL"
					( Parent
						( matchGroupRef "@baseboard_fab2_lib.baseboard_fab2(sch_1):\MG_DQ-DQS_NEAR_DIMM_NG_M_B_BYTE0\" )
					)
					( Units "uMatchProp" "ns" 1.000000)
					( Status sCSetFlattened )
					( Origin gBackEnd )
				)
			)
			( pinPair "@baseboard_fab2_lib.baseboard_fab2(sch_1):\PP553\"
				( pinRef "@baseboard_fab2_lib.baseboard_fab2(sch_1):page24_i172:DDR1_DQS_DN(1)" )
				( pinRef "@baseboard_fab2_lib.baseboard_fab2(sch_1):page45_i61:DQS1N" )
				( attribute "RELATIVE_PROPAGATION_DELAY_SCOPE" "G"
					( Parent
						( matchGroupRef "@baseboard_fab2_lib.baseboard_fab2(sch_1):\MG_DQ-DQS_FAR_DIMM_NG_M_B_BYTE1\" )
					)
					( Status sCSetFlattened )
					( Origin gBackEnd )
				)
				( attribute "RELATIVE_PROPAGATION_DELAY" ",5.00 MIL"
					( Parent
						( matchGroupRef "@baseboard_fab2_lib.baseboard_fab2(sch_1):\MG_DQ-DQS_FAR_DIMM_NG_M_B_BYTE1\" )
					)
					( Units "uMatchProp" "ns" 1.000000)
					( Status sCSetFlattened )
					( Origin gBackEnd )
				)
			)
			( pinPair "@baseboard_fab2_lib.baseboard_fab2(sch_1):\PP554\"
				( pinRef "@baseboard_fab2_lib.baseboard_fab2(sch_1):page24_i172:DDR1_DQS_DN(1)" )
				( pinRef "@baseboard_fab2_lib.baseboard_fab2(sch_1):page46_i112:DQS1N" )
				( attribute "RELATIVE_PROPAGATION_DELAY_SCOPE" "G"
					( Parent
						( matchGroupRef "@baseboard_fab2_lib.baseboard_fab2(sch_1):\MG_DQ-DQS_NEAR_DIMM_NG_M_B_BYTE1\" )
					)
					( Status sCSetFlattened )
					( Origin gBackEnd )
				)
				( attribute "RELATIVE_PROPAGATION_DELAY" ",5.00 MIL"
					( Parent
						( matchGroupRef "@baseboard_fab2_lib.baseboard_fab2(sch_1):\MG_DQ-DQS_NEAR_DIMM_NG_M_B_BYTE1\" )
					)
					( Units "uMatchProp" "ns" 1.000000)
					( Status sCSetFlattened )
					( Origin gBackEnd )
				)
			)
			( pinPair "@baseboard_fab2_lib.baseboard_fab2(sch_1):\PP541\"
				( pinRef "@baseboard_fab2_lib.baseboard_fab2(sch_1):page24_i172:DDR1_DQS_DN(2)" )
				( pinRef "@baseboard_fab2_lib.baseboard_fab2(sch_1):page45_i61:DQS2N" )
				( attribute "RELATIVE_PROPAGATION_DELAY_SCOPE" "G"
					( Parent
						( matchGroupRef "@baseboard_fab2_lib.baseboard_fab2(sch_1):\MG_DQ-DQS_FAR_DIMM_NG_M_B_BYTE2\" )
					)
					( Status sCSetFlattened )
					( Origin gBackEnd )
				)
				( attribute "RELATIVE_PROPAGATION_DELAY" ",5.00 MIL"
					( Parent
						( matchGroupRef "@baseboard_fab2_lib.baseboard_fab2(sch_1):\MG_DQ-DQS_FAR_DIMM_NG_M_B_BYTE2\" )
					)
					( Units "uMatchProp" "ns" 1.000000)
					( Status sCSetFlattened )
					( Origin gBackEnd )
				)
			)
			( pinPair "@baseboard_fab2_lib.baseboard_fab2(sch_1):\PP542\"
				( pinRef "@baseboard_fab2_lib.baseboard_fab2(sch_1):page24_i172:DDR1_DQS_DN(2)" )
				( pinRef "@baseboard_fab2_lib.baseboard_fab2(sch_1):page46_i112:DQS2N" )
				( attribute "RELATIVE_PROPAGATION_DELAY_SCOPE" "G"
					( Parent
						( matchGroupRef "@baseboard_fab2_lib.baseboard_fab2(sch_1):\MG_DQ-DQS_NEAR_DIMM_NG_M_B_BYTE2\" )
					)
					( Status sCSetFlattened )
					( Origin gBackEnd )
				)
				( attribute "RELATIVE_PROPAGATION_DELAY" ",5.00 MIL"
					( Parent
						( matchGroupRef "@baseboard_fab2_lib.baseboard_fab2(sch_1):\MG_DQ-DQS_NEAR_DIMM_NG_M_B_BYTE2\" )
					)
					( Units "uMatchProp" "ns" 1.000000)
					( Status sCSetFlattened )
					( Origin gBackEnd )
				)
			)
			( pinPair "@baseboard_fab2_lib.baseboard_fab2(sch_1):\PP529\"
				( pinRef "@baseboard_fab2_lib.baseboard_fab2(sch_1):page24_i172:DDR1_DQS_DN(3)" )
				( pinRef "@baseboard_fab2_lib.baseboard_fab2(sch_1):page45_i61:DQS3N" )
				( attribute "RELATIVE_PROPAGATION_DELAY_SCOPE" "G"
					( Parent
						( matchGroupRef "@baseboard_fab2_lib.baseboard_fab2(sch_1):\MG_DQ-DQS_FAR_DIMM_NG_M_B_BYTE3\" )
					)
					( Status sCSetFlattened )
					( Origin gBackEnd )
				)
				( attribute "RELATIVE_PROPAGATION_DELAY" ",5.00 MIL"
					( Parent
						( matchGroupRef "@baseboard_fab2_lib.baseboard_fab2(sch_1):\MG_DQ-DQS_FAR_DIMM_NG_M_B_BYTE3\" )
					)
					( Units "uMatchProp" "ns" 1.000000)
					( Status sCSetFlattened )
					( Origin gBackEnd )
				)
			)
			( pinPair "@baseboard_fab2_lib.baseboard_fab2(sch_1):\PP530\"
				( pinRef "@baseboard_fab2_lib.baseboard_fab2(sch_1):page24_i172:DDR1_DQS_DN(3)" )
				( pinRef "@baseboard_fab2_lib.baseboard_fab2(sch_1):page46_i112:DQS3N" )
				( attribute "RELATIVE_PROPAGATION_DELAY_SCOPE" "G"
					( Parent
						( matchGroupRef "@baseboard_fab2_lib.baseboard_fab2(sch_1):\MG_DQ-DQS_NEAR_DIMM_NG_M_B_BYTE3\" )
					)
					( Status sCSetFlattened )
					( Origin gBackEnd )
				)
				( attribute "RELATIVE_PROPAGATION_DELAY" ",5.00 MIL"
					( Parent
						( matchGroupRef "@baseboard_fab2_lib.baseboard_fab2(sch_1):\MG_DQ-DQS_NEAR_DIMM_NG_M_B_BYTE3\" )
					)
					( Units "uMatchProp" "ns" 1.000000)
					( Status sCSetFlattened )
					( Origin gBackEnd )
				)
			)
			( pinPair "@baseboard_fab2_lib.baseboard_fab2(sch_1):\PP517\"
				( pinRef "@baseboard_fab2_lib.baseboard_fab2(sch_1):page24_i172:DDR1_DQS_DN(4)" )
				( pinRef "@baseboard_fab2_lib.baseboard_fab2(sch_1):page45_i61:DQS4N" )
				( attribute "RELATIVE_PROPAGATION_DELAY_SCOPE" "G"
					( Parent
						( matchGroupRef "@baseboard_fab2_lib.baseboard_fab2(sch_1):\MG_DQ-DQS_FAR_DIMM_NG_M_B_BYTE4\" )
					)
					( Status sCSetFlattened )
					( Origin gBackEnd )
				)
				( attribute "RELATIVE_PROPAGATION_DELAY" ",5.00 MIL"
					( Parent
						( matchGroupRef "@baseboard_fab2_lib.baseboard_fab2(sch_1):\MG_DQ-DQS_FAR_DIMM_NG_M_B_BYTE4\" )
					)
					( Units "uMatchProp" "ns" 1.000000)
					( Status sCSetFlattened )
					( Origin gBackEnd )
				)
			)
			( pinPair "@baseboard_fab2_lib.baseboard_fab2(sch_1):\PP519\"
				( pinRef "@baseboard_fab2_lib.baseboard_fab2(sch_1):page24_i172:DDR1_DQS_DN(4)" )
				( pinRef "@baseboard_fab2_lib.baseboard_fab2(sch_1):page46_i112:DQS4N" )
				( attribute "RELATIVE_PROPAGATION_DELAY_SCOPE" "G"
					( Parent
						( matchGroupRef "@baseboard_fab2_lib.baseboard_fab2(sch_1):\MG_DQ-DQS_NEAR_DIMM_NG_M_B_BYTE4\" )
					)
					( Status sCSetFlattened )
					( Origin gBackEnd )
				)
				( attribute "RELATIVE_PROPAGATION_DELAY" ",5.00 MIL"
					( Parent
						( matchGroupRef "@baseboard_fab2_lib.baseboard_fab2(sch_1):\MG_DQ-DQS_NEAR_DIMM_NG_M_B_BYTE4\" )
					)
					( Units "uMatchProp" "ns" 1.000000)
					( Status sCSetFlattened )
					( Origin gBackEnd )
				)
			)
			( pinPair "@baseboard_fab2_lib.baseboard_fab2(sch_1):\PP505\"
				( pinRef "@baseboard_fab2_lib.baseboard_fab2(sch_1):page24_i172:DDR1_DQS_DN(5)" )
				( pinRef "@baseboard_fab2_lib.baseboard_fab2(sch_1):page45_i61:DQS5N" )
				( attribute "RELATIVE_PROPAGATION_DELAY_SCOPE" "G"
					( Parent
						( matchGroupRef "@baseboard_fab2_lib.baseboard_fab2(sch_1):\MG_DQ-DQS_FAR_DIMM_NG_M_B_BYTE5\" )
					)
					( Status sCSetFlattened )
					( Origin gBackEnd )
				)
				( attribute "RELATIVE_PROPAGATION_DELAY" ",5.00 MIL"
					( Parent
						( matchGroupRef "@baseboard_fab2_lib.baseboard_fab2(sch_1):\MG_DQ-DQS_FAR_DIMM_NG_M_B_BYTE5\" )
					)
					( Units "uMatchProp" "ns" 1.000000)
					( Status sCSetFlattened )
					( Origin gBackEnd )
				)
			)
			( pinPair "@baseboard_fab2_lib.baseboard_fab2(sch_1):\PP506\"
				( pinRef "@baseboard_fab2_lib.baseboard_fab2(sch_1):page24_i172:DDR1_DQS_DN(5)" )
				( pinRef "@baseboard_fab2_lib.baseboard_fab2(sch_1):page46_i112:DQS5N" )
				( attribute "RELATIVE_PROPAGATION_DELAY_SCOPE" "G"
					( Parent
						( matchGroupRef "@baseboard_fab2_lib.baseboard_fab2(sch_1):\MG_DQ-DQS_NEAR_DIMM_NG_M_B_BYTE5\" )
					)
					( Status sCSetFlattened )
					( Origin gBackEnd )
				)
				( attribute "RELATIVE_PROPAGATION_DELAY" ",5.00 MIL"
					( Parent
						( matchGroupRef "@baseboard_fab2_lib.baseboard_fab2(sch_1):\MG_DQ-DQS_NEAR_DIMM_NG_M_B_BYTE5\" )
					)
					( Units "uMatchProp" "ns" 1.000000)
					( Status sCSetFlattened )
					( Origin gBackEnd )
				)
			)
			( pinPair "@baseboard_fab2_lib.baseboard_fab2(sch_1):\PP493\"
				( pinRef "@baseboard_fab2_lib.baseboard_fab2(sch_1):page24_i172:DDR1_DQS_DN(6)" )
				( pinRef "@baseboard_fab2_lib.baseboard_fab2(sch_1):page45_i61:DQS6N" )
				( attribute "RELATIVE_PROPAGATION_DELAY_SCOPE" "G"
					( Parent
						( matchGroupRef "@baseboard_fab2_lib.baseboard_fab2(sch_1):\MG_DQ-DQS_FAR_DIMM_NG_M_B_BYTE6\" )
					)
					( Status sCSetFlattened )
					( Origin gBackEnd )
				)
				( attribute "RELATIVE_PROPAGATION_DELAY" ",5.00 MIL"
					( Parent
						( matchGroupRef "@baseboard_fab2_lib.baseboard_fab2(sch_1):\MG_DQ-DQS_FAR_DIMM_NG_M_B_BYTE6\" )
					)
					( Units "uMatchProp" "ns" 1.000000)
					( Status sCSetFlattened )
					( Origin gBackEnd )
				)
			)
			( pinPair "@baseboard_fab2_lib.baseboard_fab2(sch_1):\PP494\"
				( pinRef "@baseboard_fab2_lib.baseboard_fab2(sch_1):page24_i172:DDR1_DQS_DN(6)" )
				( pinRef "@baseboard_fab2_lib.baseboard_fab2(sch_1):page46_i112:DQS6N" )
				( attribute "RELATIVE_PROPAGATION_DELAY_SCOPE" "G"
					( Parent
						( matchGroupRef "@baseboard_fab2_lib.baseboard_fab2(sch_1):\MG_DQ-DQS_NEAR_DIMM_NG_M_B_BYTE6\" )
					)
					( Status sCSetFlattened )
					( Origin gBackEnd )
				)
				( attribute "RELATIVE_PROPAGATION_DELAY" ",5.00 MIL"
					( Parent
						( matchGroupRef "@baseboard_fab2_lib.baseboard_fab2(sch_1):\MG_DQ-DQS_NEAR_DIMM_NG_M_B_BYTE6\" )
					)
					( Units "uMatchProp" "ns" 1.000000)
					( Status sCSetFlattened )
					( Origin gBackEnd )
				)
			)
			( pinPair "@baseboard_fab2_lib.baseboard_fab2(sch_1):\PP481\"
				( pinRef "@baseboard_fab2_lib.baseboard_fab2(sch_1):page24_i172:DDR1_DQS_DN(7)" )
				( pinRef "@baseboard_fab2_lib.baseboard_fab2(sch_1):page45_i61:DQS7N" )
				( attribute "RELATIVE_PROPAGATION_DELAY_SCOPE" "G"
					( Parent
						( matchGroupRef "@baseboard_fab2_lib.baseboard_fab2(sch_1):\MG_DQ-DQS_FAR_DIMM_NG_M_B_BYTE7\" )
					)
					( Status sCSetFlattened )
					( Origin gBackEnd )
				)
				( attribute "RELATIVE_PROPAGATION_DELAY" ",5.00 MIL"
					( Parent
						( matchGroupRef "@baseboard_fab2_lib.baseboard_fab2(sch_1):\MG_DQ-DQS_FAR_DIMM_NG_M_B_BYTE7\" )
					)
					( Units "uMatchProp" "ns" 1.000000)
					( Status sCSetFlattened )
					( Origin gBackEnd )
				)
			)
			( pinPair "@baseboard_fab2_lib.baseboard_fab2(sch_1):\PP483\"
				( pinRef "@baseboard_fab2_lib.baseboard_fab2(sch_1):page24_i172:DDR1_DQS_DN(7)" )
				( pinRef "@baseboard_fab2_lib.baseboard_fab2(sch_1):page46_i112:DQS7N" )
				( attribute "RELATIVE_PROPAGATION_DELAY_SCOPE" "G"
					( Parent
						( matchGroupRef "@baseboard_fab2_lib.baseboard_fab2(sch_1):\MG_DQ-DQS_NEAR_DIMM_NG_M_B_BYTE7\" )
					)
					( Status sCSetFlattened )
					( Origin gBackEnd )
				)
				( attribute "RELATIVE_PROPAGATION_DELAY" ",5.00 MIL"
					( Parent
						( matchGroupRef "@baseboard_fab2_lib.baseboard_fab2(sch_1):\MG_DQ-DQS_NEAR_DIMM_NG_M_B_BYTE7\" )
					)
					( Units "uMatchProp" "ns" 1.000000)
					( Status sCSetFlattened )
					( Origin gBackEnd )
				)
			)
			( pinPair "@baseboard_fab2_lib.baseboard_fab2(sch_1):\PP1225\"
				( pinRef "@baseboard_fab2_lib.baseboard_fab2(sch_1):page24_i172:DDR1_DQS_DN(8)" )
				( pinRef "@baseboard_fab2_lib.baseboard_fab2(sch_1):page45_i61:DQS8N" )
				( attribute "RELATIVE_PROPAGATION_DELAY_SCOPE" "G"
					( Parent
						( matchGroupRef "@baseboard_fab2_lib.baseboard_fab2(sch_1):\MG_DQ-DQS_FAR_DIMM_NG_M_B_BYTE-ECC\" )
					)
					( Status sCSetFlattened )
					( Origin gBackEnd )
				)
				( attribute "RELATIVE_PROPAGATION_DELAY" ",5.00 MIL"
					( Parent
						( matchGroupRef "@baseboard_fab2_lib.baseboard_fab2(sch_1):\MG_DQ-DQS_FAR_DIMM_NG_M_B_BYTE-ECC\" )
					)
					( Units "uMatchProp" "ns" 1.000000)
					( Status sCSetFlattened )
					( Origin gBackEnd )
				)
			)
			( pinPair "@baseboard_fab2_lib.baseboard_fab2(sch_1):\PP1226\"
				( pinRef "@baseboard_fab2_lib.baseboard_fab2(sch_1):page24_i172:DDR1_DQS_DN(8)" )
				( pinRef "@baseboard_fab2_lib.baseboard_fab2(sch_1):page46_i112:DQS8N" )
				( attribute "RELATIVE_PROPAGATION_DELAY_SCOPE" "G"
					( Parent
						( matchGroupRef "@baseboard_fab2_lib.baseboard_fab2(sch_1):\MG_DQ-DQS_NEAR_DIMM_NG_M_B_BYTE-ECC\" )
					)
					( Status sCSetFlattened )
					( Origin gBackEnd )
				)
				( attribute "RELATIVE_PROPAGATION_DELAY" ",5.00 MIL"
					( Parent
						( matchGroupRef "@baseboard_fab2_lib.baseboard_fab2(sch_1):\MG_DQ-DQS_NEAR_DIMM_NG_M_B_BYTE-ECC\" )
					)
					( Units "uMatchProp" "ns" 1.000000)
					( Status sCSetFlattened )
					( Origin gBackEnd )
				)
			)
			( pinPair "@baseboard_fab2_lib.baseboard_fab2(sch_1):\PP559\"
				( pinRef "@baseboard_fab2_lib.baseboard_fab2(sch_1):page24_i172:DDR1_DQS_DN(9)" )
				( pinRef "@baseboard_fab2_lib.baseboard_fab2(sch_1):page45_i61:DQS9N" )
				( attribute "RELATIVE_PROPAGATION_DELAY_SCOPE" "G"
					( Parent
						( matchGroupRef "@baseboard_fab2_lib.baseboard_fab2(sch_1):\MG_DQ-DQS_FAR_DIMM_NG_M_B_BYTE0\" )
					)
					( Status sCSetFlattened )
					( Origin gBackEnd )
				)
				( attribute "RELATIVE_PROPAGATION_DELAY" ",5.00 MIL"
					( Parent
						( matchGroupRef "@baseboard_fab2_lib.baseboard_fab2(sch_1):\MG_DQ-DQS_FAR_DIMM_NG_M_B_BYTE0\" )
					)
					( Units "uMatchProp" "ns" 1.000000)
					( Status sCSetFlattened )
					( Origin gBackEnd )
				)
			)
			( pinPair "@baseboard_fab2_lib.baseboard_fab2(sch_1):\PP560\"
				( pinRef "@baseboard_fab2_lib.baseboard_fab2(sch_1):page24_i172:DDR1_DQS_DN(9)" )
				( pinRef "@baseboard_fab2_lib.baseboard_fab2(sch_1):page46_i112:DQS9N" )
				( attribute "RELATIVE_PROPAGATION_DELAY_SCOPE" "G"
					( Parent
						( matchGroupRef "@baseboard_fab2_lib.baseboard_fab2(sch_1):\MG_DQ-DQS_NEAR_DIMM_NG_M_B_BYTE0\" )
					)
					( Status sCSetFlattened )
					( Origin gBackEnd )
				)
				( attribute "RELATIVE_PROPAGATION_DELAY" ",5.00 MIL"
					( Parent
						( matchGroupRef "@baseboard_fab2_lib.baseboard_fab2(sch_1):\MG_DQ-DQS_NEAR_DIMM_NG_M_B_BYTE0\" )
					)
					( Units "uMatchProp" "ns" 1.000000)
					( Status sCSetFlattened )
					( Origin gBackEnd )
				)
			)
			( pinPair "@baseboard_fab2_lib.baseboard_fab2(sch_1):\PP547\"
				( pinRef "@baseboard_fab2_lib.baseboard_fab2(sch_1):page24_i172:DDR1_DQS_DN(10)" )
				( pinRef "@baseboard_fab2_lib.baseboard_fab2(sch_1):page45_i61:DQS10N" )
				( attribute "RELATIVE_PROPAGATION_DELAY_SCOPE" "G"
					( Parent
						( matchGroupRef "@baseboard_fab2_lib.baseboard_fab2(sch_1):\MG_DQ-DQS_FAR_DIMM_NG_M_B_BYTE1\" )
					)
					( Status sCSetFlattened )
					( Origin gBackEnd )
				)
				( attribute "RELATIVE_PROPAGATION_DELAY" ",5.00 MIL"
					( Parent
						( matchGroupRef "@baseboard_fab2_lib.baseboard_fab2(sch_1):\MG_DQ-DQS_FAR_DIMM_NG_M_B_BYTE1\" )
					)
					( Units "uMatchProp" "ns" 1.000000)
					( Status sCSetFlattened )
					( Origin gBackEnd )
				)
			)
			( pinPair "@baseboard_fab2_lib.baseboard_fab2(sch_1):\PP548\"
				( pinRef "@baseboard_fab2_lib.baseboard_fab2(sch_1):page24_i172:DDR1_DQS_DN(10)" )
				( pinRef "@baseboard_fab2_lib.baseboard_fab2(sch_1):page46_i112:DQS10N" )
				( attribute "RELATIVE_PROPAGATION_DELAY_SCOPE" "G"
					( Parent
						( matchGroupRef "@baseboard_fab2_lib.baseboard_fab2(sch_1):\MG_DQ-DQS_NEAR_DIMM_NG_M_B_BYTE1\" )
					)
					( Status sCSetFlattened )
					( Origin gBackEnd )
				)
				( attribute "RELATIVE_PROPAGATION_DELAY" ",5.00 MIL"
					( Parent
						( matchGroupRef "@baseboard_fab2_lib.baseboard_fab2(sch_1):\MG_DQ-DQS_NEAR_DIMM_NG_M_B_BYTE1\" )
					)
					( Units "uMatchProp" "ns" 1.000000)
					( Status sCSetFlattened )
					( Origin gBackEnd )
				)
			)
			( pinPair "@baseboard_fab2_lib.baseboard_fab2(sch_1):\PP535\"
				( pinRef "@baseboard_fab2_lib.baseboard_fab2(sch_1):page24_i172:DDR1_DQS_DN(11)" )
				( pinRef "@baseboard_fab2_lib.baseboard_fab2(sch_1):page45_i61:DQS11N" )
				( attribute "RELATIVE_PROPAGATION_DELAY_SCOPE" "G"
					( Parent
						( matchGroupRef "@baseboard_fab2_lib.baseboard_fab2(sch_1):\MG_DQ-DQS_FAR_DIMM_NG_M_B_BYTE2\" )
					)
					( Status sCSetFlattened )
					( Origin gBackEnd )
				)
				( attribute "RELATIVE_PROPAGATION_DELAY" ",5.00 MIL"
					( Parent
						( matchGroupRef "@baseboard_fab2_lib.baseboard_fab2(sch_1):\MG_DQ-DQS_FAR_DIMM_NG_M_B_BYTE2\" )
					)
					( Units "uMatchProp" "ns" 1.000000)
					( Status sCSetFlattened )
					( Origin gBackEnd )
				)
			)
			( pinPair "@baseboard_fab2_lib.baseboard_fab2(sch_1):\PP536\"
				( pinRef "@baseboard_fab2_lib.baseboard_fab2(sch_1):page24_i172:DDR1_DQS_DN(11)" )
				( pinRef "@baseboard_fab2_lib.baseboard_fab2(sch_1):page46_i112:DQS11N" )
				( attribute "RELATIVE_PROPAGATION_DELAY_SCOPE" "G"
					( Parent
						( matchGroupRef "@baseboard_fab2_lib.baseboard_fab2(sch_1):\MG_DQ-DQS_NEAR_DIMM_NG_M_B_BYTE2\" )
					)
					( Status sCSetFlattened )
					( Origin gBackEnd )
				)
				( attribute "RELATIVE_PROPAGATION_DELAY" ",5.00 MIL"
					( Parent
						( matchGroupRef "@baseboard_fab2_lib.baseboard_fab2(sch_1):\MG_DQ-DQS_NEAR_DIMM_NG_M_B_BYTE2\" )
					)
					( Units "uMatchProp" "ns" 1.000000)
					( Status sCSetFlattened )
					( Origin gBackEnd )
				)
			)
			( pinPair "@baseboard_fab2_lib.baseboard_fab2(sch_1):\PP523\"
				( pinRef "@baseboard_fab2_lib.baseboard_fab2(sch_1):page24_i172:DDR1_DQS_DN(12)" )
				( pinRef "@baseboard_fab2_lib.baseboard_fab2(sch_1):page45_i61:DQS12N" )
				( attribute "RELATIVE_PROPAGATION_DELAY_SCOPE" "G"
					( Parent
						( matchGroupRef "@baseboard_fab2_lib.baseboard_fab2(sch_1):\MG_DQ-DQS_FAR_DIMM_NG_M_B_BYTE3\" )
					)
					( Status sCSetFlattened )
					( Origin gBackEnd )
				)
				( attribute "RELATIVE_PROPAGATION_DELAY" ",5.00 MIL"
					( Parent
						( matchGroupRef "@baseboard_fab2_lib.baseboard_fab2(sch_1):\MG_DQ-DQS_FAR_DIMM_NG_M_B_BYTE3\" )
					)
					( Units "uMatchProp" "ns" 1.000000)
					( Status sCSetFlattened )
					( Origin gBackEnd )
				)
			)
			( pinPair "@baseboard_fab2_lib.baseboard_fab2(sch_1):\PP524\"
				( pinRef "@baseboard_fab2_lib.baseboard_fab2(sch_1):page24_i172:DDR1_DQS_DN(12)" )
				( pinRef "@baseboard_fab2_lib.baseboard_fab2(sch_1):page46_i112:DQS12N" )
				( attribute "RELATIVE_PROPAGATION_DELAY_SCOPE" "G"
					( Parent
						( matchGroupRef "@baseboard_fab2_lib.baseboard_fab2(sch_1):\MG_DQ-DQS_NEAR_DIMM_NG_M_B_BYTE3\" )
					)
					( Status sCSetFlattened )
					( Origin gBackEnd )
				)
				( attribute "RELATIVE_PROPAGATION_DELAY" ",5.00 MIL"
					( Parent
						( matchGroupRef "@baseboard_fab2_lib.baseboard_fab2(sch_1):\MG_DQ-DQS_NEAR_DIMM_NG_M_B_BYTE3\" )
					)
					( Units "uMatchProp" "ns" 1.000000)
					( Status sCSetFlattened )
					( Origin gBackEnd )
				)
			)
			( pinPair "@baseboard_fab2_lib.baseboard_fab2(sch_1):\PP511\"
				( pinRef "@baseboard_fab2_lib.baseboard_fab2(sch_1):page24_i172:DDR1_DQS_DN(13)" )
				( pinRef "@baseboard_fab2_lib.baseboard_fab2(sch_1):page45_i61:DQS13N" )
				( attribute "RELATIVE_PROPAGATION_DELAY_SCOPE" "G"
					( Parent
						( matchGroupRef "@baseboard_fab2_lib.baseboard_fab2(sch_1):\MG_DQ-DQS_FAR_DIMM_NG_M_B_BYTE4\" )
					)
					( Status sCSetFlattened )
					( Origin gBackEnd )
				)
				( attribute "RELATIVE_PROPAGATION_DELAY" ",5.00 MIL"
					( Parent
						( matchGroupRef "@baseboard_fab2_lib.baseboard_fab2(sch_1):\MG_DQ-DQS_FAR_DIMM_NG_M_B_BYTE4\" )
					)
					( Units "uMatchProp" "ns" 1.000000)
					( Status sCSetFlattened )
					( Origin gBackEnd )
				)
			)
			( pinPair "@baseboard_fab2_lib.baseboard_fab2(sch_1):\PP513\"
				( pinRef "@baseboard_fab2_lib.baseboard_fab2(sch_1):page24_i172:DDR1_DQS_DN(13)" )
				( pinRef "@baseboard_fab2_lib.baseboard_fab2(sch_1):page46_i112:DQS13N" )
				( attribute "RELATIVE_PROPAGATION_DELAY_SCOPE" "G"
					( Parent
						( matchGroupRef "@baseboard_fab2_lib.baseboard_fab2(sch_1):\MG_DQ-DQS_NEAR_DIMM_NG_M_B_BYTE4\" )
					)
					( Status sCSetFlattened )
					( Origin gBackEnd )
				)
				( attribute "RELATIVE_PROPAGATION_DELAY" ",5.00 MIL"
					( Parent
						( matchGroupRef "@baseboard_fab2_lib.baseboard_fab2(sch_1):\MG_DQ-DQS_NEAR_DIMM_NG_M_B_BYTE4\" )
					)
					( Units "uMatchProp" "ns" 1.000000)
					( Status sCSetFlattened )
					( Origin gBackEnd )
				)
			)
			( pinPair "@baseboard_fab2_lib.baseboard_fab2(sch_1):\PP499\"
				( pinRef "@baseboard_fab2_lib.baseboard_fab2(sch_1):page24_i172:DDR1_DQS_DN(14)" )
				( pinRef "@baseboard_fab2_lib.baseboard_fab2(sch_1):page45_i61:DQS14N" )
				( attribute "RELATIVE_PROPAGATION_DELAY_SCOPE" "G"
					( Parent
						( matchGroupRef "@baseboard_fab2_lib.baseboard_fab2(sch_1):\MG_DQ-DQS_FAR_DIMM_NG_M_B_BYTE5\" )
					)
					( Status sCSetFlattened )
					( Origin gBackEnd )
				)
				( attribute "RELATIVE_PROPAGATION_DELAY" ",5.00 MIL"
					( Parent
						( matchGroupRef "@baseboard_fab2_lib.baseboard_fab2(sch_1):\MG_DQ-DQS_FAR_DIMM_NG_M_B_BYTE5\" )
					)
					( Units "uMatchProp" "ns" 1.000000)
					( Status sCSetFlattened )
					( Origin gBackEnd )
				)
			)
			( pinPair "@baseboard_fab2_lib.baseboard_fab2(sch_1):\PP500\"
				( pinRef "@baseboard_fab2_lib.baseboard_fab2(sch_1):page24_i172:DDR1_DQS_DN(14)" )
				( pinRef "@baseboard_fab2_lib.baseboard_fab2(sch_1):page46_i112:DQS14N" )
				( attribute "RELATIVE_PROPAGATION_DELAY_SCOPE" "G"
					( Parent
						( matchGroupRef "@baseboard_fab2_lib.baseboard_fab2(sch_1):\MG_DQ-DQS_NEAR_DIMM_NG_M_B_BYTE5\" )
					)
					( Status sCSetFlattened )
					( Origin gBackEnd )
				)
				( attribute "RELATIVE_PROPAGATION_DELAY" ",5.00 MIL"
					( Parent
						( matchGroupRef "@baseboard_fab2_lib.baseboard_fab2(sch_1):\MG_DQ-DQS_NEAR_DIMM_NG_M_B_BYTE5\" )
					)
					( Units "uMatchProp" "ns" 1.000000)
					( Status sCSetFlattened )
					( Origin gBackEnd )
				)
			)
			( pinPair "@baseboard_fab2_lib.baseboard_fab2(sch_1):\PP487\"
				( pinRef "@baseboard_fab2_lib.baseboard_fab2(sch_1):page24_i172:DDR1_DQS_DN(15)" )
				( pinRef "@baseboard_fab2_lib.baseboard_fab2(sch_1):page45_i61:DQS15N" )
				( attribute "RELATIVE_PROPAGATION_DELAY_SCOPE" "G"
					( Parent
						( matchGroupRef "@baseboard_fab2_lib.baseboard_fab2(sch_1):\MG_DQ-DQS_FAR_DIMM_NG_M_B_BYTE6\" )
					)
					( Status sCSetFlattened )
					( Origin gBackEnd )
				)
				( attribute "RELATIVE_PROPAGATION_DELAY" ",5.00 MIL"
					( Parent
						( matchGroupRef "@baseboard_fab2_lib.baseboard_fab2(sch_1):\MG_DQ-DQS_FAR_DIMM_NG_M_B_BYTE6\" )
					)
					( Units "uMatchProp" "ns" 1.000000)
					( Status sCSetFlattened )
					( Origin gBackEnd )
				)
			)
			( pinPair "@baseboard_fab2_lib.baseboard_fab2(sch_1):\PP488\"
				( pinRef "@baseboard_fab2_lib.baseboard_fab2(sch_1):page24_i172:DDR1_DQS_DN(15)" )
				( pinRef "@baseboard_fab2_lib.baseboard_fab2(sch_1):page46_i112:DQS15N" )
				( attribute "RELATIVE_PROPAGATION_DELAY_SCOPE" "G"
					( Parent
						( matchGroupRef "@baseboard_fab2_lib.baseboard_fab2(sch_1):\MG_DQ-DQS_NEAR_DIMM_NG_M_B_BYTE6\" )
					)
					( Status sCSetFlattened )
					( Origin gBackEnd )
				)
				( attribute "RELATIVE_PROPAGATION_DELAY" ",5.00 MIL"
					( Parent
						( matchGroupRef "@baseboard_fab2_lib.baseboard_fab2(sch_1):\MG_DQ-DQS_NEAR_DIMM_NG_M_B_BYTE6\" )
					)
					( Units "uMatchProp" "ns" 1.000000)
					( Status sCSetFlattened )
					( Origin gBackEnd )
				)
			)
			( pinPair "@baseboard_fab2_lib.baseboard_fab2(sch_1):\PP3073\"
				( pinRef "@baseboard_fab2_lib.baseboard_fab2(sch_1):page32_i89:PE3_RX_DP(0)" )
				( pinRef "@baseboard_fab2_lib.baseboard_fab2(sch_1):page187_i119:IO61" )
				( attribute "PROPAGATION_DELAY_MIN" "3000.00 MIL"
					( Units "uMaxMinProp" "ns" 1.000000)
					( Status sCSetFlattened )
					( Origin gBackEnd )
				)
				( attribute "PROPAGATION_DELAY_MAX" "16000.00 MIL"
					( Units "uMaxMinProp" "ns" 1.000000)
					( Status sCSetFlattened )
					( Origin gBackEnd )
				)
				( attribute "RELATIVE_PROPAGATION_DELAY_SCOPE" "G"
					( Parent
						( matchGroupRef "@baseboard_fab2_lib.baseboard_fab2(sch_1):\MG_P3E_CPU0_PE3_OCP_RX0001\" )
					)
					( Status sCSetFlattened )
					( Origin gBackEnd )
				)
				( attribute "RELATIVE_PROPAGATION_DELAY" ",500.00 MIL"
					( Parent
						( matchGroupRef "@baseboard_fab2_lib.baseboard_fab2(sch_1):\MG_P3E_CPU0_PE3_OCP_RX0001\" )
					)
					( Units "uMatchProp" "ns" 1.000000)
					( Status sCSetFlattened )
					( Origin gBackEnd )
				)
			)
			( pinPair "@baseboard_fab2_lib.baseboard_fab2(sch_1):\PP3071\"
				( pinRef "@baseboard_fab2_lib.baseboard_fab2(sch_1):page32_i89:PE3_RX_DN(0)" )
				( pinRef "@baseboard_fab2_lib.baseboard_fab2(sch_1):page187_i119:IO63" )
				( attribute "PROPAGATION_DELAY_MIN" "3000.00 MIL"
					( Units "uMaxMinProp" "ns" 1.000000)
					( Status sCSetFlattened )
					( Origin gBackEnd )
				)
				( attribute "PROPAGATION_DELAY_MAX" "16000.00 MIL"
					( Units "uMaxMinProp" "ns" 1.000000)
					( Status sCSetFlattened )
					( Origin gBackEnd )
				)
				( attribute "RELATIVE_PROPAGATION_DELAY_SCOPE" "G"
					( Parent
						( matchGroupRef "@baseboard_fab2_lib.baseboard_fab2(sch_1):\MG_P3E_CPU0_PE3_OCP_RX0001\" )
					)
					( Status sCSetFlattened )
					( Origin gBackEnd )
				)
				( attribute "RELATIVE_PROPAGATION_DELAY" ",500.00 MIL"
					( Parent
						( matchGroupRef "@baseboard_fab2_lib.baseboard_fab2(sch_1):\MG_P3E_CPU0_PE3_OCP_RX0001\" )
					)
					( Units "uMatchProp" "ns" 1.000000)
					( Status sCSetFlattened )
					( Origin gBackEnd )
				)
			)
			( pinPair "@baseboard_fab2_lib.baseboard_fab2(sch_1):\PP3074\"
				( pinRef "@baseboard_fab2_lib.baseboard_fab2(sch_1):page32_i89:PE3_RX_DP(1)" )
				( pinRef "@baseboard_fab2_lib.baseboard_fab2(sch_1):page187_i119:IO53" )
				( attribute "PROPAGATION_DELAY_MIN" "3000.00 MIL"
					( Units "uMaxMinProp" "ns" 1.000000)
					( Status sCSetFlattened )
					( Origin gBackEnd )
				)
				( attribute "PROPAGATION_DELAY_MAX" "16000.00 MIL"
					( Units "uMaxMinProp" "ns" 1.000000)
					( Status sCSetFlattened )
					( Origin gBackEnd )
				)
				( attribute "RELATIVE_PROPAGATION_DELAY_SCOPE" "G"
					( Parent
						( matchGroupRef "@baseboard_fab2_lib.baseboard_fab2(sch_1):\MG_P3E_CPU0_PE3_OCP_RX0001\" )
					)
					( Status sCSetFlattened )
					( Origin gBackEnd )
				)
				( attribute "RELATIVE_PROPAGATION_DELAY" ",500.00 MIL"
					( Parent
						( matchGroupRef "@baseboard_fab2_lib.baseboard_fab2(sch_1):\MG_P3E_CPU0_PE3_OCP_RX0001\" )
					)
					( Units "uMatchProp" "ns" 1.000000)
					( Status sCSetFlattened )
					( Origin gBackEnd )
				)
			)
			( pinPair "@baseboard_fab2_lib.baseboard_fab2(sch_1):\PP3072\"
				( pinRef "@baseboard_fab2_lib.baseboard_fab2(sch_1):page32_i89:PE3_RX_DN(1)" )
				( pinRef "@baseboard_fab2_lib.baseboard_fab2(sch_1):page187_i119:IO55" )
				( attribute "PROPAGATION_DELAY_MIN" "3000.00 MIL"
					( Units "uMaxMinProp" "ns" 1.000000)
					( Status sCSetFlattened )
					( Origin gBackEnd )
				)
				( attribute "PROPAGATION_DELAY_MAX" "16000.00 MIL"
					( Units "uMaxMinProp" "ns" 1.000000)
					( Status sCSetFlattened )
					( Origin gBackEnd )
				)
				( attribute "RELATIVE_PROPAGATION_DELAY_SCOPE" "G"
					( Parent
						( matchGroupRef "@baseboard_fab2_lib.baseboard_fab2(sch_1):\MG_P3E_CPU0_PE3_OCP_RX0001\" )
					)
					( Status sCSetFlattened )
					( Origin gBackEnd )
				)
				( attribute "RELATIVE_PROPAGATION_DELAY" ",500.00 MIL"
					( Parent
						( matchGroupRef "@baseboard_fab2_lib.baseboard_fab2(sch_1):\MG_P3E_CPU0_PE3_OCP_RX0001\" )
					)
					( Units "uMatchProp" "ns" 1.000000)
					( Status sCSetFlattened )
					( Origin gBackEnd )
				)
			)
			( pinPair "@baseboard_fab2_lib.baseboard_fab2(sch_1):\PP3069\"
				( pinRef "@baseboard_fab2_lib.baseboard_fab2(sch_1):page32_i89:PE3_RX_DP(2)" )
				( pinRef "@baseboard_fab2_lib.baseboard_fab2(sch_1):page187_i119:IO45" )
				( attribute "PROPAGATION_DELAY_MIN" "3000.00 MIL"
					( Units "uMaxMinProp" "ns" 1.000000)
					( Status sCSetFlattened )
					( Origin gBackEnd )
				)
				( attribute "PROPAGATION_DELAY_MAX" "16000.00 MIL"
					( Units "uMaxMinProp" "ns" 1.000000)
					( Status sCSetFlattened )
					( Origin gBackEnd )
				)
				( attribute "RELATIVE_PROPAGATION_DELAY_SCOPE" "G"
					( Parent
						( matchGroupRef "@baseboard_fab2_lib.baseboard_fab2(sch_1):\MG_P3E_CPU0_PE3_OCP_RX0203\" )
					)
					( Status sCSetFlattened )
					( Origin gBackEnd )
				)
				( attribute "RELATIVE_PROPAGATION_DELAY" ",500.00 MIL"
					( Parent
						( matchGroupRef "@baseboard_fab2_lib.baseboard_fab2(sch_1):\MG_P3E_CPU0_PE3_OCP_RX0203\" )
					)
					( Units "uMatchProp" "ns" 1.000000)
					( Status sCSetFlattened )
					( Origin gBackEnd )
				)
			)
			( pinPair "@baseboard_fab2_lib.baseboard_fab2(sch_1):\PP3067\"
				( pinRef "@baseboard_fab2_lib.baseboard_fab2(sch_1):page32_i89:PE3_RX_DN(2)" )
				( pinRef "@baseboard_fab2_lib.baseboard_fab2(sch_1):page187_i119:IO47" )
				( attribute "PROPAGATION_DELAY_MIN" "3000.00 MIL"
					( Units "uMaxMinProp" "ns" 1.000000)
					( Status sCSetFlattened )
					( Origin gBackEnd )
				)
				( attribute "PROPAGATION_DELAY_MAX" "16000.00 MIL"
					( Units "uMaxMinProp" "ns" 1.000000)
					( Status sCSetFlattened )
					( Origin gBackEnd )
				)
				( attribute "RELATIVE_PROPAGATION_DELAY_SCOPE" "G"
					( Parent
						( matchGroupRef "@baseboard_fab2_lib.baseboard_fab2(sch_1):\MG_P3E_CPU0_PE3_OCP_RX0203\" )
					)
					( Status sCSetFlattened )
					( Origin gBackEnd )
				)
				( attribute "RELATIVE_PROPAGATION_DELAY" ",500.00 MIL"
					( Parent
						( matchGroupRef "@baseboard_fab2_lib.baseboard_fab2(sch_1):\MG_P3E_CPU0_PE3_OCP_RX0203\" )
					)
					( Units "uMatchProp" "ns" 1.000000)
					( Status sCSetFlattened )
					( Origin gBackEnd )
				)
			)
			( pinPair "@baseboard_fab2_lib.baseboard_fab2(sch_1):\PP3070\"
				( pinRef "@baseboard_fab2_lib.baseboard_fab2(sch_1):page32_i89:PE3_RX_DP(3)" )
				( pinRef "@baseboard_fab2_lib.baseboard_fab2(sch_1):page187_i119:IO37" )
				( attribute "PROPAGATION_DELAY_MIN" "3000.00 MIL"
					( Units "uMaxMinProp" "ns" 1.000000)
					( Status sCSetFlattened )
					( Origin gBackEnd )
				)
				( attribute "PROPAGATION_DELAY_MAX" "16000.00 MIL"
					( Units "uMaxMinProp" "ns" 1.000000)
					( Status sCSetFlattened )
					( Origin gBackEnd )
				)
				( attribute "RELATIVE_PROPAGATION_DELAY_SCOPE" "G"
					( Parent
						( matchGroupRef "@baseboard_fab2_lib.baseboard_fab2(sch_1):\MG_P3E_CPU0_PE3_OCP_RX0203\" )
					)
					( Status sCSetFlattened )
					( Origin gBackEnd )
				)
				( attribute "RELATIVE_PROPAGATION_DELAY" ",500.00 MIL"
					( Parent
						( matchGroupRef "@baseboard_fab2_lib.baseboard_fab2(sch_1):\MG_P3E_CPU0_PE3_OCP_RX0203\" )
					)
					( Units "uMatchProp" "ns" 1.000000)
					( Status sCSetFlattened )
					( Origin gBackEnd )
				)
			)
			( pinPair "@baseboard_fab2_lib.baseboard_fab2(sch_1):\PP3068\"
				( pinRef "@baseboard_fab2_lib.baseboard_fab2(sch_1):page32_i89:PE3_RX_DN(3)" )
				( pinRef "@baseboard_fab2_lib.baseboard_fab2(sch_1):page187_i119:IO39" )
				( attribute "PROPAGATION_DELAY_MIN" "3000.00 MIL"
					( Units "uMaxMinProp" "ns" 1.000000)
					( Status sCSetFlattened )
					( Origin gBackEnd )
				)
				( attribute "PROPAGATION_DELAY_MAX" "16000.00 MIL"
					( Units "uMaxMinProp" "ns" 1.000000)
					( Status sCSetFlattened )
					( Origin gBackEnd )
				)
				( attribute "RELATIVE_PROPAGATION_DELAY_SCOPE" "G"
					( Parent
						( matchGroupRef "@baseboard_fab2_lib.baseboard_fab2(sch_1):\MG_P3E_CPU0_PE3_OCP_RX0203\" )
					)
					( Status sCSetFlattened )
					( Origin gBackEnd )
				)
				( attribute "RELATIVE_PROPAGATION_DELAY" ",500.00 MIL"
					( Parent
						( matchGroupRef "@baseboard_fab2_lib.baseboard_fab2(sch_1):\MG_P3E_CPU0_PE3_OCP_RX0203\" )
					)
					( Units "uMatchProp" "ns" 1.000000)
					( Status sCSetFlattened )
					( Origin gBackEnd )
				)
			)
			( pinPair "@baseboard_fab2_lib.baseboard_fab2(sch_1):\PP3061\"
				( pinRef "@baseboard_fab2_lib.baseboard_fab2(sch_1):page32_i89:PE3_RX_DP(6)" )
				( pinRef "@baseboard_fab2_lib.baseboard_fab2(sch_1):page187_i119:IO15" )
				( attribute "PROPAGATION_DELAY_MIN" "3000.00 MIL"
					( Units "uMaxMinProp" "ns" 1.000000)
					( Status sCSetFlattened )
					( Origin gBackEnd )
				)
				( attribute "PROPAGATION_DELAY_MAX" "16000.00 MIL"
					( Units "uMaxMinProp" "ns" 1.000000)
					( Status sCSetFlattened )
					( Origin gBackEnd )
				)
				( attribute "RELATIVE_PROPAGATION_DELAY_SCOPE" "G"
					( Parent
						( matchGroupRef "@baseboard_fab2_lib.baseboard_fab2(sch_1):\MG_P3E_CPU0_PE3_OCP_RX0607\" )
					)
					( Status sCSetFlattened )
					( Origin gBackEnd )
				)
				( attribute "RELATIVE_PROPAGATION_DELAY" ",500.00 MIL"
					( Parent
						( matchGroupRef "@baseboard_fab2_lib.baseboard_fab2(sch_1):\MG_P3E_CPU0_PE3_OCP_RX0607\" )
					)
					( Units "uMatchProp" "ns" 1.000000)
					( Status sCSetFlattened )
					( Origin gBackEnd )
				)
			)
			( pinPair "@baseboard_fab2_lib.baseboard_fab2(sch_1):\PP3059\"
				( pinRef "@baseboard_fab2_lib.baseboard_fab2(sch_1):page32_i89:PE3_RX_DN(6)" )
				( pinRef "@baseboard_fab2_lib.baseboard_fab2(sch_1):page187_i119:IO13" )
				( attribute "PROPAGATION_DELAY_MIN" "3000.00 MIL"
					( Units "uMaxMinProp" "ns" 1.000000)
					( Status sCSetFlattened )
					( Origin gBackEnd )
				)
				( attribute "PROPAGATION_DELAY_MAX" "16000.00 MIL"
					( Units "uMaxMinProp" "ns" 1.000000)
					( Status sCSetFlattened )
					( Origin gBackEnd )
				)
				( attribute "RELATIVE_PROPAGATION_DELAY_SCOPE" "G"
					( Parent
						( matchGroupRef "@baseboard_fab2_lib.baseboard_fab2(sch_1):\MG_P3E_CPU0_PE3_OCP_RX0607\" )
					)
					( Status sCSetFlattened )
					( Origin gBackEnd )
				)
				( attribute "RELATIVE_PROPAGATION_DELAY" ",500.00 MIL"
					( Parent
						( matchGroupRef "@baseboard_fab2_lib.baseboard_fab2(sch_1):\MG_P3E_CPU0_PE3_OCP_RX0607\" )
					)
					( Units "uMatchProp" "ns" 1.000000)
					( Status sCSetFlattened )
					( Origin gBackEnd )
				)
			)
			( pinPair "@baseboard_fab2_lib.baseboard_fab2(sch_1):\PP3062\"
				( pinRef "@baseboard_fab2_lib.baseboard_fab2(sch_1):page32_i89:PE3_RX_DP(7)" )
				( pinRef "@baseboard_fab2_lib.baseboard_fab2(sch_1):page187_i119:IO5" )
				( attribute "PROPAGATION_DELAY_MIN" "3000.00 MIL"
					( Units "uMaxMinProp" "ns" 1.000000)
					( Status sCSetFlattened )
					( Origin gBackEnd )
				)
				( attribute "PROPAGATION_DELAY_MAX" "16000.00 MIL"
					( Units "uMaxMinProp" "ns" 1.000000)
					( Status sCSetFlattened )
					( Origin gBackEnd )
				)
				( attribute "RELATIVE_PROPAGATION_DELAY_SCOPE" "G"
					( Parent
						( matchGroupRef "@baseboard_fab2_lib.baseboard_fab2(sch_1):\MG_P3E_CPU0_PE3_OCP_RX0607\" )
					)
					( Status sCSetFlattened )
					( Origin gBackEnd )
				)
				( attribute "RELATIVE_PROPAGATION_DELAY" ",500.00 MIL"
					( Parent
						( matchGroupRef "@baseboard_fab2_lib.baseboard_fab2(sch_1):\MG_P3E_CPU0_PE3_OCP_RX0607\" )
					)
					( Units "uMatchProp" "ns" 1.000000)
					( Status sCSetFlattened )
					( Origin gBackEnd )
				)
			)
			( pinPair "@baseboard_fab2_lib.baseboard_fab2(sch_1):\PP3060\"
				( pinRef "@baseboard_fab2_lib.baseboard_fab2(sch_1):page32_i89:PE3_RX_DN(7)" )
				( pinRef "@baseboard_fab2_lib.baseboard_fab2(sch_1):page187_i119:IO7" )
				( attribute "PROPAGATION_DELAY_MIN" "3000.00 MIL"
					( Units "uMaxMinProp" "ns" 1.000000)
					( Status sCSetFlattened )
					( Origin gBackEnd )
				)
				( attribute "PROPAGATION_DELAY_MAX" "16000.00 MIL"
					( Units "uMaxMinProp" "ns" 1.000000)
					( Status sCSetFlattened )
					( Origin gBackEnd )
				)
				( attribute "RELATIVE_PROPAGATION_DELAY_SCOPE" "G"
					( Parent
						( matchGroupRef "@baseboard_fab2_lib.baseboard_fab2(sch_1):\MG_P3E_CPU0_PE3_OCP_RX0607\" )
					)
					( Status sCSetFlattened )
					( Origin gBackEnd )
				)
				( attribute "RELATIVE_PROPAGATION_DELAY" ",500.00 MIL"
					( Parent
						( matchGroupRef "@baseboard_fab2_lib.baseboard_fab2(sch_1):\MG_P3E_CPU0_PE3_OCP_RX0607\" )
					)
					( Units "uMatchProp" "ns" 1.000000)
					( Status sCSetFlattened )
					( Origin gBackEnd )
				)
			)
			( pinPair "@baseboard_fab2_lib.baseboard_fab2(sch_1):\PP3057\"
				( pinRef "@baseboard_fab2_lib.baseboard_fab2(sch_1):page32_i89:PE3_RX_DP(8)" )
				( pinRef "@baseboard_fab2_lib.baseboard_fab2(sch_1):page186_i336:IO115" )
				( attribute "PROPAGATION_DELAY_MIN" "3000.00 MIL"
					( Units "uMaxMinProp" "ns" 1.000000)
					( Status sCSetFlattened )
					( Origin gBackEnd )
				)
				( attribute "PROPAGATION_DELAY_MAX" "16000.00 MIL"
					( Units "uMaxMinProp" "ns" 1.000000)
					( Status sCSetFlattened )
					( Origin gBackEnd )
				)
				( attribute "RELATIVE_PROPAGATION_DELAY_SCOPE" "G"
					( Parent
						( matchGroupRef "@baseboard_fab2_lib.baseboard_fab2(sch_1):\MG_P3E_CPU0_PE3_OCP_RX0809\" )
					)
					( Status sCSetFlattened )
					( Origin gBackEnd )
				)
				( attribute "RELATIVE_PROPAGATION_DELAY" ",500.00 MIL"
					( Parent
						( matchGroupRef "@baseboard_fab2_lib.baseboard_fab2(sch_1):\MG_P3E_CPU0_PE3_OCP_RX0809\" )
					)
					( Units "uMatchProp" "ns" 1.000000)
					( Status sCSetFlattened )
					( Origin gBackEnd )
				)
			)
			( pinPair "@baseboard_fab2_lib.baseboard_fab2(sch_1):\PP3055\"
				( pinRef "@baseboard_fab2_lib.baseboard_fab2(sch_1):page32_i89:PE3_RX_DN(8)" )
				( pinRef "@baseboard_fab2_lib.baseboard_fab2(sch_1):page186_i336:IO117" )
				( attribute "PROPAGATION_DELAY_MIN" "3000.00 MIL"
					( Units "uMaxMinProp" "ns" 1.000000)
					( Status sCSetFlattened )
					( Origin gBackEnd )
				)
				( attribute "PROPAGATION_DELAY_MAX" "16000.00 MIL"
					( Units "uMaxMinProp" "ns" 1.000000)
					( Status sCSetFlattened )
					( Origin gBackEnd )
				)
				( attribute "RELATIVE_PROPAGATION_DELAY_SCOPE" "G"
					( Parent
						( matchGroupRef "@baseboard_fab2_lib.baseboard_fab2(sch_1):\MG_P3E_CPU0_PE3_OCP_RX0809\" )
					)
					( Status sCSetFlattened )
					( Origin gBackEnd )
				)
				( attribute "RELATIVE_PROPAGATION_DELAY" ",500.00 MIL"
					( Parent
						( matchGroupRef "@baseboard_fab2_lib.baseboard_fab2(sch_1):\MG_P3E_CPU0_PE3_OCP_RX0809\" )
					)
					( Units "uMatchProp" "ns" 1.000000)
					( Status sCSetFlattened )
					( Origin gBackEnd )
				)
			)
			( pinPair "@baseboard_fab2_lib.baseboard_fab2(sch_1):\PP3058\"
				( pinRef "@baseboard_fab2_lib.baseboard_fab2(sch_1):page32_i89:PE3_RX_DP(9)" )
				( pinRef "@baseboard_fab2_lib.baseboard_fab2(sch_1):page186_i336:IO107" )
				( attribute "PROPAGATION_DELAY_MIN" "3000.00 MIL"
					( Units "uMaxMinProp" "ns" 1.000000)
					( Status sCSetFlattened )
					( Origin gBackEnd )
				)
				( attribute "PROPAGATION_DELAY_MAX" "16000.00 MIL"
					( Units "uMaxMinProp" "ns" 1.000000)
					( Status sCSetFlattened )
					( Origin gBackEnd )
				)
				( attribute "RELATIVE_PROPAGATION_DELAY_SCOPE" "G"
					( Parent
						( matchGroupRef "@baseboard_fab2_lib.baseboard_fab2(sch_1):\MG_P3E_CPU0_PE3_OCP_RX0809\" )
					)
					( Status sCSetFlattened )
					( Origin gBackEnd )
				)
				( attribute "RELATIVE_PROPAGATION_DELAY" ",500.00 MIL"
					( Parent
						( matchGroupRef "@baseboard_fab2_lib.baseboard_fab2(sch_1):\MG_P3E_CPU0_PE3_OCP_RX0809\" )
					)
					( Units "uMatchProp" "ns" 1.000000)
					( Status sCSetFlattened )
					( Origin gBackEnd )
				)
			)
			( pinPair "@baseboard_fab2_lib.baseboard_fab2(sch_1):\PP3056\"
				( pinRef "@baseboard_fab2_lib.baseboard_fab2(sch_1):page32_i89:PE3_RX_DN(9)" )
				( pinRef "@baseboard_fab2_lib.baseboard_fab2(sch_1):page186_i336:IO109" )
				( attribute "PROPAGATION_DELAY_MIN" "3000.00 MIL"
					( Units "uMaxMinProp" "ns" 1.000000)
					( Status sCSetFlattened )
					( Origin gBackEnd )
				)
				( attribute "PROPAGATION_DELAY_MAX" "16000.00 MIL"
					( Units "uMaxMinProp" "ns" 1.000000)
					( Status sCSetFlattened )
					( Origin gBackEnd )
				)
				( attribute "RELATIVE_PROPAGATION_DELAY_SCOPE" "G"
					( Parent
						( matchGroupRef "@baseboard_fab2_lib.baseboard_fab2(sch_1):\MG_P3E_CPU0_PE3_OCP_RX0809\" )
					)
					( Status sCSetFlattened )
					( Origin gBackEnd )
				)
				( attribute "RELATIVE_PROPAGATION_DELAY" ",500.00 MIL"
					( Parent
						( matchGroupRef "@baseboard_fab2_lib.baseboard_fab2(sch_1):\MG_P3E_CPU0_PE3_OCP_RX0809\" )
					)
					( Units "uMatchProp" "ns" 1.000000)
					( Status sCSetFlattened )
					( Origin gBackEnd )
				)
			)
			( pinPair "@baseboard_fab2_lib.baseboard_fab2(sch_1):\PP3053\"
				( pinRef "@baseboard_fab2_lib.baseboard_fab2(sch_1):page32_i89:PE3_RX_DP(10)" )
				( pinRef "@baseboard_fab2_lib.baseboard_fab2(sch_1):page186_i336:IO99" )
				( attribute "PROPAGATION_DELAY_MIN" "3000.00 MIL"
					( Units "uMaxMinProp" "ns" 1.000000)
					( Status sCSetFlattened )
					( Origin gBackEnd )
				)
				( attribute "PROPAGATION_DELAY_MAX" "16000.00 MIL"
					( Units "uMaxMinProp" "ns" 1.000000)
					( Status sCSetFlattened )
					( Origin gBackEnd )
				)
				( attribute "RELATIVE_PROPAGATION_DELAY_SCOPE" "G"
					( Parent
						( matchGroupRef "@baseboard_fab2_lib.baseboard_fab2(sch_1):\MG_P3E_CPU0_PE3_OCP_RX1011\" )
					)
					( Status sCSetFlattened )
					( Origin gBackEnd )
				)
				( attribute "RELATIVE_PROPAGATION_DELAY" ",500.00 MIL"
					( Parent
						( matchGroupRef "@baseboard_fab2_lib.baseboard_fab2(sch_1):\MG_P3E_CPU0_PE3_OCP_RX1011\" )
					)
					( Units "uMatchProp" "ns" 1.000000)
					( Status sCSetFlattened )
					( Origin gBackEnd )
				)
			)
			( pinPair "@baseboard_fab2_lib.baseboard_fab2(sch_1):\PP3051\"
				( pinRef "@baseboard_fab2_lib.baseboard_fab2(sch_1):page32_i89:PE3_RX_DN(10)" )
				( pinRef "@baseboard_fab2_lib.baseboard_fab2(sch_1):page186_i336:IO101" )
				( attribute "PROPAGATION_DELAY_MIN" "3000.00 MIL"
					( Units "uMaxMinProp" "ns" 1.000000)
					( Status sCSetFlattened )
					( Origin gBackEnd )
				)
				( attribute "PROPAGATION_DELAY_MAX" "16000.00 MIL"
					( Units "uMaxMinProp" "ns" 1.000000)
					( Status sCSetFlattened )
					( Origin gBackEnd )
				)
				( attribute "RELATIVE_PROPAGATION_DELAY_SCOPE" "G"
					( Parent
						( matchGroupRef "@baseboard_fab2_lib.baseboard_fab2(sch_1):\MG_P3E_CPU0_PE3_OCP_RX1011\" )
					)
					( Status sCSetFlattened )
					( Origin gBackEnd )
				)
				( attribute "RELATIVE_PROPAGATION_DELAY" ",500.00 MIL"
					( Parent
						( matchGroupRef "@baseboard_fab2_lib.baseboard_fab2(sch_1):\MG_P3E_CPU0_PE3_OCP_RX1011\" )
					)
					( Units "uMatchProp" "ns" 1.000000)
					( Status sCSetFlattened )
					( Origin gBackEnd )
				)
			)
			( pinPair "@baseboard_fab2_lib.baseboard_fab2(sch_1):\PP3054\"
				( pinRef "@baseboard_fab2_lib.baseboard_fab2(sch_1):page32_i89:PE3_RX_DP(11)" )
				( pinRef "@baseboard_fab2_lib.baseboard_fab2(sch_1):page186_i336:IO91" )
				( attribute "PROPAGATION_DELAY_MIN" "3000.00 MIL"
					( Units "uMaxMinProp" "ns" 1.000000)
					( Status sCSetFlattened )
					( Origin gBackEnd )
				)
				( attribute "PROPAGATION_DELAY_MAX" "16000.00 MIL"
					( Units "uMaxMinProp" "ns" 1.000000)
					( Status sCSetFlattened )
					( Origin gBackEnd )
				)
				( attribute "RELATIVE_PROPAGATION_DELAY_SCOPE" "G"
					( Parent
						( matchGroupRef "@baseboard_fab2_lib.baseboard_fab2(sch_1):\MG_P3E_CPU0_PE3_OCP_RX1011\" )
					)
					( Status sCSetFlattened )
					( Origin gBackEnd )
				)
				( attribute "RELATIVE_PROPAGATION_DELAY" ",500.00 MIL"
					( Parent
						( matchGroupRef "@baseboard_fab2_lib.baseboard_fab2(sch_1):\MG_P3E_CPU0_PE3_OCP_RX1011\" )
					)
					( Units "uMatchProp" "ns" 1.000000)
					( Status sCSetFlattened )
					( Origin gBackEnd )
				)
			)
			( pinPair "@baseboard_fab2_lib.baseboard_fab2(sch_1):\PP3052\"
				( pinRef "@baseboard_fab2_lib.baseboard_fab2(sch_1):page32_i89:PE3_RX_DN(11)" )
				( pinRef "@baseboard_fab2_lib.baseboard_fab2(sch_1):page186_i336:IO93" )
				( attribute "PROPAGATION_DELAY_MIN" "3000.00 MIL"
					( Units "uMaxMinProp" "ns" 1.000000)
					( Status sCSetFlattened )
					( Origin gBackEnd )
				)
				( attribute "PROPAGATION_DELAY_MAX" "16000.00 MIL"
					( Units "uMaxMinProp" "ns" 1.000000)
					( Status sCSetFlattened )
					( Origin gBackEnd )
				)
				( attribute "RELATIVE_PROPAGATION_DELAY_SCOPE" "G"
					( Parent
						( matchGroupRef "@baseboard_fab2_lib.baseboard_fab2(sch_1):\MG_P3E_CPU0_PE3_OCP_RX1011\" )
					)
					( Status sCSetFlattened )
					( Origin gBackEnd )
				)
				( attribute "RELATIVE_PROPAGATION_DELAY" ",500.00 MIL"
					( Parent
						( matchGroupRef "@baseboard_fab2_lib.baseboard_fab2(sch_1):\MG_P3E_CPU0_PE3_OCP_RX1011\" )
					)
					( Units "uMatchProp" "ns" 1.000000)
					( Status sCSetFlattened )
					( Origin gBackEnd )
				)
			)
			( pinPair "@baseboard_fab2_lib.baseboard_fab2(sch_1):\PP3049\"
				( pinRef "@baseboard_fab2_lib.baseboard_fab2(sch_1):page32_i89:PE3_RX_DP(12)" )
				( pinRef "@baseboard_fab2_lib.baseboard_fab2(sch_1):page186_i336:IO83" )
				( attribute "PROPAGATION_DELAY_MIN" "3000.00 MIL"
					( Units "uMaxMinProp" "ns" 1.000000)
					( Status sCSetFlattened )
					( Origin gBackEnd )
				)
				( attribute "PROPAGATION_DELAY_MAX" "16000.00 MIL"
					( Units "uMaxMinProp" "ns" 1.000000)
					( Status sCSetFlattened )
					( Origin gBackEnd )
				)
				( attribute "RELATIVE_PROPAGATION_DELAY_SCOPE" "G"
					( Parent
						( matchGroupRef "@baseboard_fab2_lib.baseboard_fab2(sch_1):\MG_P3E_CPU0_PE3_OCP_RX1213\" )
					)
					( Status sCSetFlattened )
					( Origin gBackEnd )
				)
				( attribute "RELATIVE_PROPAGATION_DELAY" ",500.00 MIL"
					( Parent
						( matchGroupRef "@baseboard_fab2_lib.baseboard_fab2(sch_1):\MG_P3E_CPU0_PE3_OCP_RX1213\" )
					)
					( Units "uMatchProp" "ns" 1.000000)
					( Status sCSetFlattened )
					( Origin gBackEnd )
				)
			)
			( pinPair "@baseboard_fab2_lib.baseboard_fab2(sch_1):\PP3047\"
				( pinRef "@baseboard_fab2_lib.baseboard_fab2(sch_1):page32_i89:PE3_RX_DN(12)" )
				( pinRef "@baseboard_fab2_lib.baseboard_fab2(sch_1):page186_i336:IO85" )
				( attribute "PROPAGATION_DELAY_MIN" "3000.00 MIL"
					( Units "uMaxMinProp" "ns" 1.000000)
					( Status sCSetFlattened )
					( Origin gBackEnd )
				)
				( attribute "PROPAGATION_DELAY_MAX" "16000.00 MIL"
					( Units "uMaxMinProp" "ns" 1.000000)
					( Status sCSetFlattened )
					( Origin gBackEnd )
				)
				( attribute "RELATIVE_PROPAGATION_DELAY_SCOPE" "G"
					( Parent
						( matchGroupRef "@baseboard_fab2_lib.baseboard_fab2(sch_1):\MG_P3E_CPU0_PE3_OCP_RX1213\" )
					)
					( Status sCSetFlattened )
					( Origin gBackEnd )
				)
				( attribute "RELATIVE_PROPAGATION_DELAY" ",500.00 MIL"
					( Parent
						( matchGroupRef "@baseboard_fab2_lib.baseboard_fab2(sch_1):\MG_P3E_CPU0_PE3_OCP_RX1213\" )
					)
					( Units "uMatchProp" "ns" 1.000000)
					( Status sCSetFlattened )
					( Origin gBackEnd )
				)
			)
			( pinPair "@baseboard_fab2_lib.baseboard_fab2(sch_1):\PP3050\"
				( pinRef "@baseboard_fab2_lib.baseboard_fab2(sch_1):page32_i89:PE3_RX_DP(13)" )
				( pinRef "@baseboard_fab2_lib.baseboard_fab2(sch_1):page186_i336:IO75" )
				( attribute "PROPAGATION_DELAY_MIN" "3000.00 MIL"
					( Units "uMaxMinProp" "ns" 1.000000)
					( Status sCSetFlattened )
					( Origin gBackEnd )
				)
				( attribute "PROPAGATION_DELAY_MAX" "16000.00 MIL"
					( Units "uMaxMinProp" "ns" 1.000000)
					( Status sCSetFlattened )
					( Origin gBackEnd )
				)
				( attribute "RELATIVE_PROPAGATION_DELAY_SCOPE" "G"
					( Parent
						( matchGroupRef "@baseboard_fab2_lib.baseboard_fab2(sch_1):\MG_P3E_CPU0_PE3_OCP_RX1213\" )
					)
					( Status sCSetFlattened )
					( Origin gBackEnd )
				)
				( attribute "RELATIVE_PROPAGATION_DELAY" ",500.00 MIL"
					( Parent
						( matchGroupRef "@baseboard_fab2_lib.baseboard_fab2(sch_1):\MG_P3E_CPU0_PE3_OCP_RX1213\" )
					)
					( Units "uMatchProp" "ns" 1.000000)
					( Status sCSetFlattened )
					( Origin gBackEnd )
				)
			)
			( pinPair "@baseboard_fab2_lib.baseboard_fab2(sch_1):\PP3048\"
				( pinRef "@baseboard_fab2_lib.baseboard_fab2(sch_1):page32_i89:PE3_RX_DN(13)" )
				( pinRef "@baseboard_fab2_lib.baseboard_fab2(sch_1):page186_i336:IO77" )
				( attribute "PROPAGATION_DELAY_MIN" "3000.00 MIL"
					( Units "uMaxMinProp" "ns" 1.000000)
					( Status sCSetFlattened )
					( Origin gBackEnd )
				)
				( attribute "PROPAGATION_DELAY_MAX" "16000.00 MIL"
					( Units "uMaxMinProp" "ns" 1.000000)
					( Status sCSetFlattened )
					( Origin gBackEnd )
				)
				( attribute "RELATIVE_PROPAGATION_DELAY_SCOPE" "G"
					( Parent
						( matchGroupRef "@baseboard_fab2_lib.baseboard_fab2(sch_1):\MG_P3E_CPU0_PE3_OCP_RX1213\" )
					)
					( Status sCSetFlattened )
					( Origin gBackEnd )
				)
				( attribute "RELATIVE_PROPAGATION_DELAY" ",500.00 MIL"
					( Parent
						( matchGroupRef "@baseboard_fab2_lib.baseboard_fab2(sch_1):\MG_P3E_CPU0_PE3_OCP_RX1213\" )
					)
					( Units "uMatchProp" "ns" 1.000000)
					( Status sCSetFlattened )
					( Origin gBackEnd )
				)
			)
			( pinPair "@baseboard_fab2_lib.baseboard_fab2(sch_1):\PP3045\"
				( pinRef "@baseboard_fab2_lib.baseboard_fab2(sch_1):page32_i89:PE3_RX_DP(14)" )
				( pinRef "@baseboard_fab2_lib.baseboard_fab2(sch_1):page186_i336:IO67" )
				( attribute "PROPAGATION_DELAY_MIN" "3000.00 MIL"
					( Units "uMaxMinProp" "ns" 1.000000)
					( Status sCSetFlattened )
					( Origin gBackEnd )
				)
				( attribute "PROPAGATION_DELAY_MAX" "16000.00 MIL"
					( Units "uMaxMinProp" "ns" 1.000000)
					( Status sCSetFlattened )
					( Origin gBackEnd )
				)
				( attribute "RELATIVE_PROPAGATION_DELAY_SCOPE" "G"
					( Parent
						( matchGroupRef "@baseboard_fab2_lib.baseboard_fab2(sch_1):\MG_P3E_CPU0_PE3_OCP_RX1415\" )
					)
					( Status sCSetFlattened )
					( Origin gBackEnd )
				)
				( attribute "RELATIVE_PROPAGATION_DELAY" ",500.00 MIL"
					( Parent
						( matchGroupRef "@baseboard_fab2_lib.baseboard_fab2(sch_1):\MG_P3E_CPU0_PE3_OCP_RX1415\" )
					)
					( Units "uMatchProp" "ns" 1.000000)
					( Status sCSetFlattened )
					( Origin gBackEnd )
				)
			)
			( pinPair "@baseboard_fab2_lib.baseboard_fab2(sch_1):\PP3043\"
				( pinRef "@baseboard_fab2_lib.baseboard_fab2(sch_1):page32_i89:PE3_RX_DN(14)" )
				( pinRef "@baseboard_fab2_lib.baseboard_fab2(sch_1):page186_i336:IO69" )
				( attribute "PROPAGATION_DELAY_MIN" "3000.00 MIL"
					( Units "uMaxMinProp" "ns" 1.000000)
					( Status sCSetFlattened )
					( Origin gBackEnd )
				)
				( attribute "PROPAGATION_DELAY_MAX" "16000.00 MIL"
					( Units "uMaxMinProp" "ns" 1.000000)
					( Status sCSetFlattened )
					( Origin gBackEnd )
				)
				( attribute "RELATIVE_PROPAGATION_DELAY_SCOPE" "G"
					( Parent
						( matchGroupRef "@baseboard_fab2_lib.baseboard_fab2(sch_1):\MG_P3E_CPU0_PE3_OCP_RX1415\" )
					)
					( Status sCSetFlattened )
					( Origin gBackEnd )
				)
				( attribute "RELATIVE_PROPAGATION_DELAY" ",500.00 MIL"
					( Parent
						( matchGroupRef "@baseboard_fab2_lib.baseboard_fab2(sch_1):\MG_P3E_CPU0_PE3_OCP_RX1415\" )
					)
					( Units "uMatchProp" "ns" 1.000000)
					( Status sCSetFlattened )
					( Origin gBackEnd )
				)
			)
			( pinPair "@baseboard_fab2_lib.baseboard_fab2(sch_1):\PP3046\"
				( pinRef "@baseboard_fab2_lib.baseboard_fab2(sch_1):page32_i89:PE3_RX_DP(15)" )
				( pinRef "@baseboard_fab2_lib.baseboard_fab2(sch_1):page186_i336:IO59" )
				( attribute "PROPAGATION_DELAY_MIN" "3000.00 MIL"
					( Units "uMaxMinProp" "ns" 1.000000)
					( Status sCSetFlattened )
					( Origin gBackEnd )
				)
				( attribute "PROPAGATION_DELAY_MAX" "16000.00 MIL"
					( Units "uMaxMinProp" "ns" 1.000000)
					( Status sCSetFlattened )
					( Origin gBackEnd )
				)
				( attribute "RELATIVE_PROPAGATION_DELAY_SCOPE" "G"
					( Parent
						( matchGroupRef "@baseboard_fab2_lib.baseboard_fab2(sch_1):\MG_P3E_CPU0_PE3_OCP_RX1415\" )
					)
					( Status sCSetFlattened )
					( Origin gBackEnd )
				)
				( attribute "RELATIVE_PROPAGATION_DELAY" ",500.00 MIL"
					( Parent
						( matchGroupRef "@baseboard_fab2_lib.baseboard_fab2(sch_1):\MG_P3E_CPU0_PE3_OCP_RX1415\" )
					)
					( Units "uMatchProp" "ns" 1.000000)
					( Status sCSetFlattened )
					( Origin gBackEnd )
				)
			)
			( pinPair "@baseboard_fab2_lib.baseboard_fab2(sch_1):\PP3044\"
				( pinRef "@baseboard_fab2_lib.baseboard_fab2(sch_1):page32_i89:PE3_RX_DN(15)" )
				( pinRef "@baseboard_fab2_lib.baseboard_fab2(sch_1):page186_i336:IO61" )
				( attribute "PROPAGATION_DELAY_MIN" "3000.00 MIL"
					( Units "uMaxMinProp" "ns" 1.000000)
					( Status sCSetFlattened )
					( Origin gBackEnd )
				)
				( attribute "PROPAGATION_DELAY_MAX" "16000.00 MIL"
					( Units "uMaxMinProp" "ns" 1.000000)
					( Status sCSetFlattened )
					( Origin gBackEnd )
				)
				( attribute "RELATIVE_PROPAGATION_DELAY_SCOPE" "G"
					( Parent
						( matchGroupRef "@baseboard_fab2_lib.baseboard_fab2(sch_1):\MG_P3E_CPU0_PE3_OCP_RX1415\" )
					)
					( Status sCSetFlattened )
					( Origin gBackEnd )
				)
				( attribute "RELATIVE_PROPAGATION_DELAY" ",500.00 MIL"
					( Parent
						( matchGroupRef "@baseboard_fab2_lib.baseboard_fab2(sch_1):\MG_P3E_CPU0_PE3_OCP_RX1415\" )
					)
					( Units "uMatchProp" "ns" 1.000000)
					( Status sCSetFlattened )
					( Origin gBackEnd )
				)
			)
			( pinPair "@baseboard_fab2_lib.baseboard_fab2(sch_1):\PP3037\"
				( pinRef "@baseboard_fab2_lib.baseboard_fab2(sch_1):page182_i15:B" )
				( pinRef "@baseboard_fab2_lib.baseboard_fab2(sch_1):page66_i84:PE3_TX_DN(10)" )
				( attribute "RELATIVE_PROPAGATION_DELAY_SCOPE" "L"
					( Parent
						( matchGroupRef "@baseboard_fab2_lib.baseboard_fab2(sch_1):\MG_PCIE_L1\" )
					)
					( Status sCSetFlattened )
					( Origin gBackEnd )
				)
				( attribute "RELATIVE_PROPAGATION_DELAY" ",5.00 MIL"
					( Parent
						( matchGroupRef "@baseboard_fab2_lib.baseboard_fab2(sch_1):\MG_PCIE_L1\" )
					)
					( Units "uMatchProp" "ns" 1.000000)
					( Status sCSetFlattened )
					( Origin gBackEnd )
				)
			)
			( pinPair "@baseboard_fab2_lib.baseboard_fab2(sch_1):\PP3038\"
				( pinRef "@baseboard_fab2_lib.baseboard_fab2(sch_1):page182_i18:IOI8" )
				( pinRef "@baseboard_fab2_lib.baseboard_fab2(sch_1):page182_i15:A" )
				( attribute "RELATIVE_PROPAGATION_DELAY_SCOPE" "L"
					( Parent
						( matchGroupRef "@baseboard_fab2_lib.baseboard_fab2(sch_1):\MG_PCIE_L0\" )
					)
					( Status sCSetFlattened )
					( Origin gBackEnd )
				)
				( attribute "RELATIVE_PROPAGATION_DELAY" ",5.00 MIL"
					( Parent
						( matchGroupRef "@baseboard_fab2_lib.baseboard_fab2(sch_1):\MG_PCIE_L0\" )
					)
					( Units "uMatchProp" "ns" 1.000000)
					( Status sCSetFlattened )
					( Origin gBackEnd )
				)
			)
			( pinPair "@baseboard_fab2_lib.baseboard_fab2(sch_1):\PP5832\"
				( pinRef "@baseboard_fab2_lib.baseboard_fab2(sch_1):page66_i84:PE3_TX_DN(10)" )
				( pinRef "@baseboard_fab2_lib.baseboard_fab2(sch_1):page182_i18:IOI8" )
				( attribute "PROPAGATION_DELAY_MIN" "3000.00 MIL"
					( Units "uMaxMinProp" "ns" 1.000000)
					( Status sCSetFlattened )
					( Origin gBackEnd )
				)
				( attribute "PROPAGATION_DELAY_MAX" "16000.00 MIL"
					( Units "uMaxMinProp" "ns" 1.000000)
					( Status sCSetFlattened )
					( Origin gBackEnd )
				)
				( attribute "RELATIVE_PROPAGATION_DELAY_SCOPE" "G"
					( Parent
						( matchGroupRef "@baseboard_fab2_lib.baseboard_fab2(sch_1):\MG_P3E_CPU1_PE3_MP_TX1011\" )
					)
					( Status sCSetFlattened )
					( Origin gBackEnd )
				)
				( attribute "RELATIVE_PROPAGATION_DELAY" ",500.00 MIL"
					( Parent
						( matchGroupRef "@baseboard_fab2_lib.baseboard_fab2(sch_1):\MG_P3E_CPU1_PE3_MP_TX1011\" )
					)
					( Units "uMatchProp" "ns" 1.000000)
					( Status sCSetFlattened )
					( Origin gBackEnd )
				)
			)
			( pinPair "@baseboard_fab2_lib.baseboard_fab2(sch_1):\PP3035\"
				( pinRef "@baseboard_fab2_lib.baseboard_fab2(sch_1):page182_i18:IOH8" )
				( pinRef "@baseboard_fab2_lib.baseboard_fab2(sch_1):page182_i14:A" )
				( attribute "RELATIVE_PROPAGATION_DELAY_SCOPE" "L"
					( Parent
						( matchGroupRef "@baseboard_fab2_lib.baseboard_fab2(sch_1):\MG_PCIE_L0\" )
					)
					( Status sCSetFlattened )
					( Origin gBackEnd )
				)
				( attribute "RELATIVE_PROPAGATION_DELAY" ",5.00 MIL"
					( Parent
						( matchGroupRef "@baseboard_fab2_lib.baseboard_fab2(sch_1):\MG_PCIE_L0\" )
					)
					( Units "uMatchProp" "ns" 1.000000)
					( Status sCSetFlattened )
					( Origin gBackEnd )
				)
			)
			( pinPair "@baseboard_fab2_lib.baseboard_fab2(sch_1):\PP3036\"
				( pinRef "@baseboard_fab2_lib.baseboard_fab2(sch_1):page66_i84:PE3_TX_DP(10)" )
				( pinRef "@baseboard_fab2_lib.baseboard_fab2(sch_1):page182_i14:B" )
				( attribute "RELATIVE_PROPAGATION_DELAY_SCOPE" "L"
					( Parent
						( matchGroupRef "@baseboard_fab2_lib.baseboard_fab2(sch_1):\MG_PCIE_L1\" )
					)
					( Status sCSetFlattened )
					( Origin gBackEnd )
				)
				( attribute "RELATIVE_PROPAGATION_DELAY" ",5.00 MIL"
					( Parent
						( matchGroupRef "@baseboard_fab2_lib.baseboard_fab2(sch_1):\MG_PCIE_L1\" )
					)
					( Units "uMatchProp" "ns" 1.000000)
					( Status sCSetFlattened )
					( Origin gBackEnd )
				)
			)
			( pinPair "@baseboard_fab2_lib.baseboard_fab2(sch_1):\PP5828\"
				( pinRef "@baseboard_fab2_lib.baseboard_fab2(sch_1):page66_i84:PE3_TX_DP(10)" )
				( pinRef "@baseboard_fab2_lib.baseboard_fab2(sch_1):page182_i18:IOH8" )
				( attribute "PROPAGATION_DELAY_MIN" "3000.00 MIL"
					( Units "uMaxMinProp" "ns" 1.000000)
					( Status sCSetFlattened )
					( Origin gBackEnd )
				)
				( attribute "PROPAGATION_DELAY_MAX" "16000.00 MIL"
					( Units "uMaxMinProp" "ns" 1.000000)
					( Status sCSetFlattened )
					( Origin gBackEnd )
				)
				( attribute "RELATIVE_PROPAGATION_DELAY_SCOPE" "G"
					( Parent
						( matchGroupRef "@baseboard_fab2_lib.baseboard_fab2(sch_1):\MG_P3E_CPU1_PE3_MP_TX1011\" )
					)
					( Status sCSetFlattened )
					( Origin gBackEnd )
				)
				( attribute "RELATIVE_PROPAGATION_DELAY" ",500.00 MIL"
					( Parent
						( matchGroupRef "@baseboard_fab2_lib.baseboard_fab2(sch_1):\MG_P3E_CPU1_PE3_MP_TX1011\" )
					)
					( Units "uMatchProp" "ns" 1.000000)
					( Status sCSetFlattened )
					( Origin gBackEnd )
				)
			)
			( pinPair "@baseboard_fab2_lib.baseboard_fab2(sch_1):\PP5692\"
				( pinRef "@baseboard_fab2_lib.baseboard_fab2(sch_1):page176_i52:AC2" )
				( pinRef "@baseboard_fab2_lib.baseboard_fab2(sch_1):page176_i69:STDA_SSRXN" )
				( attribute "PROPAGATION_DELAY_MAX" "500.00 MIL"
					( Units "uMaxMinProp" "ns" 1.000000)
					( Origin gBackEnd )
				)
			)
			( pinPair "@baseboard_fab2_lib.baseboard_fab2(sch_1):\PP5693\"
				( pinRef "@baseboard_fab2_lib.baseboard_fab2(sch_1):page176_i69:STDA_SSRXN" )
				( pinRef "@baseboard_fab2_lib.baseboard_fab2(sch_1):page176_i51:\2\" )
				( attribute "PROPAGATION_DELAY_MAX" "600.00 MIL"
					( Units "uMaxMinProp" "ns" 1.000000)
					( Origin gBackEnd )
				)
			)
			( pinPair "@baseboard_fab2_lib.baseboard_fab2(sch_1):\PP5694\"
				( pinRef "@baseboard_fab2_lib.baseboard_fab2(sch_1):page176_i69:STDA_SSRXP" )
				( pinRef "@baseboard_fab2_lib.baseboard_fab2(sch_1):page176_i51:\3\" )
				( attribute "PROPAGATION_DELAY_MAX" "500.00 MIL"
					( Units "uMaxMinProp" "ns" 1.000000)
					( Origin gBackEnd )
				)
			)
			( pinPair "@baseboard_fab2_lib.baseboard_fab2(sch_1):\PP5695\"
				( pinRef "@baseboard_fab2_lib.baseboard_fab2(sch_1):page176_i52:AC3" )
				( pinRef "@baseboard_fab2_lib.baseboard_fab2(sch_1):page176_i69:STDA_SSRXP" )
				( attribute "PROPAGATION_DELAY_MAX" "500.00 MIL"
					( Units "uMaxMinProp" "ns" 1.000000)
					( Origin gBackEnd )
				)
			)
			( pinPair "@baseboard_fab2_lib.baseboard_fab2(sch_1):\PP3063\"
				( pinRef "@baseboard_fab2_lib.baseboard_fab2(sch_1):page32_i89:PE3_RX_DN(4)" )
				( pinRef "@baseboard_fab2_lib.baseboard_fab2(sch_1):page187_i119:IO29" )
				( attribute "PROPAGATION_DELAY_MIN" "3000.00 MIL"
					( Units "uMaxMinProp" "ns" 1.000000)
					( Status sCSetFlattened )
					( Origin gBackEnd )
				)
				( attribute "PROPAGATION_DELAY_MAX" "16000.00 MIL"
					( Units "uMaxMinProp" "ns" 1.000000)
					( Status sCSetFlattened )
					( Origin gBackEnd )
				)
				( attribute "RELATIVE_PROPAGATION_DELAY_SCOPE" "G"
					( Parent
						( matchGroupRef "@baseboard_fab2_lib.baseboard_fab2(sch_1):\MG_P3E_CPU0_PE3_OCP_RX0405\" )
					)
					( Status sCSetFlattened )
					( Origin gBackEnd )
				)
				( attribute "RELATIVE_PROPAGATION_DELAY" ",500.00 MIL"
					( Parent
						( matchGroupRef "@baseboard_fab2_lib.baseboard_fab2(sch_1):\MG_P3E_CPU0_PE3_OCP_RX0405\" )
					)
					( Units "uMatchProp" "ns" 1.000000)
					( Status sCSetFlattened )
					( Origin gBackEnd )
				)
			)
			( pinPair "@baseboard_fab2_lib.baseboard_fab2(sch_1):\PP3065\"
				( pinRef "@baseboard_fab2_lib.baseboard_fab2(sch_1):page32_i89:PE3_RX_DP(4)" )
				( pinRef "@baseboard_fab2_lib.baseboard_fab2(sch_1):page187_i119:IO31" )
				( attribute "PROPAGATION_DELAY_MIN" "3000.00 MIL"
					( Units "uMaxMinProp" "ns" 1.000000)
					( Status sCSetFlattened )
					( Origin gBackEnd )
				)
				( attribute "PROPAGATION_DELAY_MAX" "16000.00 MIL"
					( Units "uMaxMinProp" "ns" 1.000000)
					( Status sCSetFlattened )
					( Origin gBackEnd )
				)
				( attribute "RELATIVE_PROPAGATION_DELAY_SCOPE" "G"
					( Parent
						( matchGroupRef "@baseboard_fab2_lib.baseboard_fab2(sch_1):\MG_P3E_CPU0_PE3_OCP_RX0405\" )
					)
					( Status sCSetFlattened )
					( Origin gBackEnd )
				)
				( attribute "RELATIVE_PROPAGATION_DELAY" ",500.00 MIL"
					( Parent
						( matchGroupRef "@baseboard_fab2_lib.baseboard_fab2(sch_1):\MG_P3E_CPU0_PE3_OCP_RX0405\" )
					)
					( Units "uMatchProp" "ns" 1.000000)
					( Status sCSetFlattened )
					( Origin gBackEnd )
				)
			)
			( pinPair "@baseboard_fab2_lib.baseboard_fab2(sch_1):\PP3064\"
				( pinRef "@baseboard_fab2_lib.baseboard_fab2(sch_1):page32_i89:PE3_RX_DN(5)" )
				( pinRef "@baseboard_fab2_lib.baseboard_fab2(sch_1):page187_i119:IO21" )
				( attribute "PROPAGATION_DELAY_MIN" "3000.00 MIL"
					( Units "uMaxMinProp" "ns" 1.000000)
					( Status sCSetFlattened )
					( Origin gBackEnd )
				)
				( attribute "PROPAGATION_DELAY_MAX" "16000.00 MIL"
					( Units "uMaxMinProp" "ns" 1.000000)
					( Status sCSetFlattened )
					( Origin gBackEnd )
				)
				( attribute "RELATIVE_PROPAGATION_DELAY_SCOPE" "G"
					( Parent
						( matchGroupRef "@baseboard_fab2_lib.baseboard_fab2(sch_1):\MG_P3E_CPU0_PE3_OCP_RX0405\" )
					)
					( Status sCSetFlattened )
					( Origin gBackEnd )
				)
				( attribute "RELATIVE_PROPAGATION_DELAY" ",500.00 MIL"
					( Parent
						( matchGroupRef "@baseboard_fab2_lib.baseboard_fab2(sch_1):\MG_P3E_CPU0_PE3_OCP_RX0405\" )
					)
					( Units "uMatchProp" "ns" 1.000000)
					( Status sCSetFlattened )
					( Origin gBackEnd )
				)
			)
			( pinPair "@baseboard_fab2_lib.baseboard_fab2(sch_1):\PP3066\"
				( pinRef "@baseboard_fab2_lib.baseboard_fab2(sch_1):page32_i89:PE3_RX_DP(5)" )
				( pinRef "@baseboard_fab2_lib.baseboard_fab2(sch_1):page187_i119:IO23" )
				( attribute "PROPAGATION_DELAY_MIN" "3000.00 MIL"
					( Units "uMaxMinProp" "ns" 1.000000)
					( Status sCSetFlattened )
					( Origin gBackEnd )
				)
				( attribute "PROPAGATION_DELAY_MAX" "16000.00 MIL"
					( Units "uMaxMinProp" "ns" 1.000000)
					( Status sCSetFlattened )
					( Origin gBackEnd )
				)
				( attribute "RELATIVE_PROPAGATION_DELAY_SCOPE" "G"
					( Parent
						( matchGroupRef "@baseboard_fab2_lib.baseboard_fab2(sch_1):\MG_P3E_CPU0_PE3_OCP_RX0405\" )
					)
					( Status sCSetFlattened )
					( Origin gBackEnd )
				)
				( attribute "RELATIVE_PROPAGATION_DELAY" ",500.00 MIL"
					( Parent
						( matchGroupRef "@baseboard_fab2_lib.baseboard_fab2(sch_1):\MG_P3E_CPU0_PE3_OCP_RX0405\" )
					)
					( Units "uMatchProp" "ns" 1.000000)
					( Status sCSetFlattened )
					( Origin gBackEnd )
				)
			)
			( pinPair "@baseboard_fab2_lib.baseboard_fab2(sch_1):\PP2993\"
				( pinRef "@baseboard_fab2_lib.baseboard_fab2(sch_1):page117_i9:PCIEUP_10_TXN" )
				( pinRef "@baseboard_fab2_lib.baseboard_fab2(sch_1):page105_i223:A" )
				( attribute "RELATIVE_PROPAGATION_DELAY_SCOPE" "L"
					( Parent
						( matchGroupRef "@baseboard_fab2_lib.baseboard_fab2(sch_1):\MG_PCIE_L1\" )
					)
					( Status sCSetFlattened )
					( Origin gBackEnd )
				)
				( attribute "RELATIVE_PROPAGATION_DELAY" ",5.00 MIL"
					( Parent
						( matchGroupRef "@baseboard_fab2_lib.baseboard_fab2(sch_1):\MG_PCIE_L1\" )
					)
					( Units "uMatchProp" "ns" 1.000000)
					( Status sCSetFlattened )
					( Origin gBackEnd )
				)
			)
			( pinPair "@baseboard_fab2_lib.baseboard_fab2(sch_1):\PP2994\"
				( pinRef "@baseboard_fab2_lib.baseboard_fab2(sch_1):page105_i223:B" )
				( pinRef "@baseboard_fab2_lib.baseboard_fab2(sch_1):page30_i84:PE1_RX_DN(10)" )
				( attribute "RELATIVE_PROPAGATION_DELAY_SCOPE" "L"
					( Parent
						( matchGroupRef "@baseboard_fab2_lib.baseboard_fab2(sch_1):\MG_PCIE_L0\" )
					)
					( Status sCSetFlattened )
					( Origin gBackEnd )
				)
				( attribute "RELATIVE_PROPAGATION_DELAY" ",5.00 MIL"
					( Parent
						( matchGroupRef "@baseboard_fab2_lib.baseboard_fab2(sch_1):\MG_PCIE_L0\" )
					)
					( Units "uMatchProp" "ns" 1.000000)
					( Status sCSetFlattened )
					( Origin gBackEnd )
				)
			)
			( pinPair "@baseboard_fab2_lib.baseboard_fab2(sch_1):\PP5838\"
				( pinRef "@baseboard_fab2_lib.baseboard_fab2(sch_1):page117_i9:PCIEUP_10_TXN" )
				( pinRef "@baseboard_fab2_lib.baseboard_fab2(sch_1):page30_i84:PE1_RX_DN(10)" )
				( attribute "PROPAGATION_DELAY_MIN" "3000.00 MIL"
					( Units "uMaxMinProp" "ns" 1.000000)
					( Status sCSetFlattened )
					( Origin gBackEnd )
				)
				( attribute "PROPAGATION_DELAY_MAX" "17000.00 MIL"
					( Units "uMaxMinProp" "ns" 1.000000)
					( Status sCSetFlattened )
					( Origin gBackEnd )
				)
				( attribute "RELATIVE_PROPAGATION_DELAY_SCOPE" "G"
					( Parent
						( matchGroupRef "@baseboard_fab2_lib.baseboard_fab2(sch_1):\MG_P3E_CPU0_PE1_PCH_PCIEUP_RX1011\" )
					)
					( Status sCSetFlattened )
					( Origin gBackEnd )
				)
				( attribute "RELATIVE_PROPAGATION_DELAY" ",500.00 MIL"
					( Parent
						( matchGroupRef "@baseboard_fab2_lib.baseboard_fab2(sch_1):\MG_P3E_CPU0_PE1_PCH_PCIEUP_RX1011\" )
					)
					( Units "uMatchProp" "ns" 1.000000)
					( Status sCSetFlattened )
					( Origin gBackEnd )
				)
			)
			( pinPair "@baseboard_fab2_lib.baseboard_fab2(sch_1):\PP2991\"
				( pinRef "@baseboard_fab2_lib.baseboard_fab2(sch_1):page117_i9:PCIEUP_10_TXP" )
				( pinRef "@baseboard_fab2_lib.baseboard_fab2(sch_1):page105_i212:A" )
				( attribute "RELATIVE_PROPAGATION_DELAY_SCOPE" "L"
					( Parent
						( matchGroupRef "@baseboard_fab2_lib.baseboard_fab2(sch_1):\MG_PCIE_L1\" )
					)
					( Status sCSetFlattened )
					( Origin gBackEnd )
				)
				( attribute "RELATIVE_PROPAGATION_DELAY" ",5.00 MIL"
					( Parent
						( matchGroupRef "@baseboard_fab2_lib.baseboard_fab2(sch_1):\MG_PCIE_L1\" )
					)
					( Units "uMatchProp" "ns" 1.000000)
					( Status sCSetFlattened )
					( Origin gBackEnd )
				)
			)
			( pinPair "@baseboard_fab2_lib.baseboard_fab2(sch_1):\PP2992\"
				( pinRef "@baseboard_fab2_lib.baseboard_fab2(sch_1):page105_i212:B" )
				( pinRef "@baseboard_fab2_lib.baseboard_fab2(sch_1):page30_i84:PE1_RX_DP(10)" )
				( attribute "RELATIVE_PROPAGATION_DELAY_SCOPE" "L"
					( Parent
						( matchGroupRef "@baseboard_fab2_lib.baseboard_fab2(sch_1):\MG_PCIE_L0\" )
					)
					( Status sCSetFlattened )
					( Origin gBackEnd )
				)
				( attribute "RELATIVE_PROPAGATION_DELAY" ",5.00 MIL"
					( Parent
						( matchGroupRef "@baseboard_fab2_lib.baseboard_fab2(sch_1):\MG_PCIE_L0\" )
					)
					( Units "uMatchProp" "ns" 1.000000)
					( Status sCSetFlattened )
					( Origin gBackEnd )
				)
			)
			( pinPair "@baseboard_fab2_lib.baseboard_fab2(sch_1):\PP5839\"
				( pinRef "@baseboard_fab2_lib.baseboard_fab2(sch_1):page117_i9:PCIEUP_10_TXP" )
				( pinRef "@baseboard_fab2_lib.baseboard_fab2(sch_1):page30_i84:PE1_RX_DP(10)" )
				( attribute "PROPAGATION_DELAY_MIN" "3000.00 MIL"
					( Units "uMaxMinProp" "ns" 1.000000)
					( Status sCSetFlattened )
					( Origin gBackEnd )
				)
				( attribute "PROPAGATION_DELAY_MAX" "17000.00 MIL"
					( Units "uMaxMinProp" "ns" 1.000000)
					( Status sCSetFlattened )
					( Origin gBackEnd )
				)
				( attribute "RELATIVE_PROPAGATION_DELAY_SCOPE" "G"
					( Parent
						( matchGroupRef "@baseboard_fab2_lib.baseboard_fab2(sch_1):\MG_P3E_CPU0_PE1_PCH_PCIEUP_RX1011\" )
					)
					( Status sCSetFlattened )
					( Origin gBackEnd )
				)
				( attribute "RELATIVE_PROPAGATION_DELAY" ",500.00 MIL"
					( Parent
						( matchGroupRef "@baseboard_fab2_lib.baseboard_fab2(sch_1):\MG_P3E_CPU0_PE1_PCH_PCIEUP_RX1011\" )
					)
					( Units "uMatchProp" "ns" 1.000000)
					( Status sCSetFlattened )
					( Origin gBackEnd )
				)
			)
			( pinPair "@baseboard_fab2_lib.baseboard_fab2(sch_1):\PP2989\"
				( pinRef "@baseboard_fab2_lib.baseboard_fab2(sch_1):page117_i9:PCIEUP_11_TXN" )
				( pinRef "@baseboard_fab2_lib.baseboard_fab2(sch_1):page105_i229:A" )
				( attribute "RELATIVE_PROPAGATION_DELAY_SCOPE" "L"
					( Parent
						( matchGroupRef "@baseboard_fab2_lib.baseboard_fab2(sch_1):\MG_PCIE_L1\" )
					)
					( Status sCSetFlattened )
					( Origin gBackEnd )
				)
				( attribute "RELATIVE_PROPAGATION_DELAY" ",5.00 MIL"
					( Parent
						( matchGroupRef "@baseboard_fab2_lib.baseboard_fab2(sch_1):\MG_PCIE_L1\" )
					)
					( Units "uMatchProp" "ns" 1.000000)
					( Status sCSetFlattened )
					( Origin gBackEnd )
				)
			)
			( pinPair "@baseboard_fab2_lib.baseboard_fab2(sch_1):\PP2990\"
				( pinRef "@baseboard_fab2_lib.baseboard_fab2(sch_1):page105_i229:B" )
				( pinRef "@baseboard_fab2_lib.baseboard_fab2(sch_1):page30_i84:PE1_RX_DN(11)" )
				( attribute "RELATIVE_PROPAGATION_DELAY_SCOPE" "L"
					( Parent
						( matchGroupRef "@baseboard_fab2_lib.baseboard_fab2(sch_1):\MG_PCIE_L0\" )
					)
					( Status sCSetFlattened )
					( Origin gBackEnd )
				)
				( attribute "RELATIVE_PROPAGATION_DELAY" ",5.00 MIL"
					( Parent
						( matchGroupRef "@baseboard_fab2_lib.baseboard_fab2(sch_1):\MG_PCIE_L0\" )
					)
					( Units "uMatchProp" "ns" 1.000000)
					( Status sCSetFlattened )
					( Origin gBackEnd )
				)
			)
			( pinPair "@baseboard_fab2_lib.baseboard_fab2(sch_1):\PP5840\"
				( pinRef "@baseboard_fab2_lib.baseboard_fab2(sch_1):page117_i9:PCIEUP_11_TXN" )
				( pinRef "@baseboard_fab2_lib.baseboard_fab2(sch_1):page30_i84:PE1_RX_DN(11)" )
				( attribute "PROPAGATION_DELAY_MIN" "3000.00 MIL"
					( Units "uMaxMinProp" "ns" 1.000000)
					( Status sCSetFlattened )
					( Origin gBackEnd )
				)
				( attribute "PROPAGATION_DELAY_MAX" "17000.00 MIL"
					( Units "uMaxMinProp" "ns" 1.000000)
					( Status sCSetFlattened )
					( Origin gBackEnd )
				)
				( attribute "RELATIVE_PROPAGATION_DELAY_SCOPE" "G"
					( Parent
						( matchGroupRef "@baseboard_fab2_lib.baseboard_fab2(sch_1):\MG_P3E_CPU0_PE1_PCH_PCIEUP_RX1011\" )
					)
					( Status sCSetFlattened )
					( Origin gBackEnd )
				)
				( attribute "RELATIVE_PROPAGATION_DELAY" ",500.00 MIL"
					( Parent
						( matchGroupRef "@baseboard_fab2_lib.baseboard_fab2(sch_1):\MG_P3E_CPU0_PE1_PCH_PCIEUP_RX1011\" )
					)
					( Units "uMatchProp" "ns" 1.000000)
					( Status sCSetFlattened )
					( Origin gBackEnd )
				)
			)
			( pinPair "@baseboard_fab2_lib.baseboard_fab2(sch_1):\PP2987\"
				( pinRef "@baseboard_fab2_lib.baseboard_fab2(sch_1):page117_i9:PCIEUP_11_TXP" )
				( pinRef "@baseboard_fab2_lib.baseboard_fab2(sch_1):page105_i205:A" )
				( attribute "RELATIVE_PROPAGATION_DELAY_SCOPE" "L"
					( Parent
						( matchGroupRef "@baseboard_fab2_lib.baseboard_fab2(sch_1):\MG_PCIE_L1\" )
					)
					( Status sCSetFlattened )
					( Origin gBackEnd )
				)
				( attribute "RELATIVE_PROPAGATION_DELAY" ",5.00 MIL"
					( Parent
						( matchGroupRef "@baseboard_fab2_lib.baseboard_fab2(sch_1):\MG_PCIE_L1\" )
					)
					( Units "uMatchProp" "ns" 1.000000)
					( Status sCSetFlattened )
					( Origin gBackEnd )
				)
			)
			( pinPair "@baseboard_fab2_lib.baseboard_fab2(sch_1):\PP2988\"
				( pinRef "@baseboard_fab2_lib.baseboard_fab2(sch_1):page105_i205:B" )
				( pinRef "@baseboard_fab2_lib.baseboard_fab2(sch_1):page30_i84:PE1_RX_DP(11)" )
				( attribute "RELATIVE_PROPAGATION_DELAY_SCOPE" "L"
					( Parent
						( matchGroupRef "@baseboard_fab2_lib.baseboard_fab2(sch_1):\MG_PCIE_L0\" )
					)
					( Status sCSetFlattened )
					( Origin gBackEnd )
				)
				( attribute "RELATIVE_PROPAGATION_DELAY" ",5.00 MIL"
					( Parent
						( matchGroupRef "@baseboard_fab2_lib.baseboard_fab2(sch_1):\MG_PCIE_L0\" )
					)
					( Units "uMatchProp" "ns" 1.000000)
					( Status sCSetFlattened )
					( Origin gBackEnd )
				)
			)
			( pinPair "@baseboard_fab2_lib.baseboard_fab2(sch_1):\PP5833\"
				( pinRef "@baseboard_fab2_lib.baseboard_fab2(sch_1):page117_i9:PCIEUP_11_TXP" )
				( pinRef "@baseboard_fab2_lib.baseboard_fab2(sch_1):page30_i84:PE1_RX_DP(11)" )
				( attribute "PROPAGATION_DELAY_MIN" "3000.00 MIL"
					( Units "uMaxMinProp" "ns" 1.000000)
					( Status sCSetFlattened )
					( Origin gBackEnd )
				)
				( attribute "PROPAGATION_DELAY_MAX" "17000.00 MIL"
					( Units "uMaxMinProp" "ns" 1.000000)
					( Status sCSetFlattened )
					( Origin gBackEnd )
				)
				( attribute "RELATIVE_PROPAGATION_DELAY_SCOPE" "G"
					( Parent
						( matchGroupRef "@baseboard_fab2_lib.baseboard_fab2(sch_1):\MG_P3E_CPU0_PE1_PCH_PCIEUP_RX1011\" )
					)
					( Status sCSetFlattened )
					( Origin gBackEnd )
				)
				( attribute "RELATIVE_PROPAGATION_DELAY" ",500.00 MIL"
					( Parent
						( matchGroupRef "@baseboard_fab2_lib.baseboard_fab2(sch_1):\MG_P3E_CPU0_PE1_PCH_PCIEUP_RX1011\" )
					)
					( Units "uMatchProp" "ns" 1.000000)
					( Status sCSetFlattened )
					( Origin gBackEnd )
				)
			)
			( pinPair "@baseboard_fab2_lib.baseboard_fab2(sch_1):\PP2985\"
				( pinRef "@baseboard_fab2_lib.baseboard_fab2(sch_1):page117_i9:PCIEUP_12_TXN" )
				( pinRef "@baseboard_fab2_lib.baseboard_fab2(sch_1):page105_i244:A" )
				( attribute "RELATIVE_PROPAGATION_DELAY_SCOPE" "L"
					( Parent
						( matchGroupRef "@baseboard_fab2_lib.baseboard_fab2(sch_1):\MG_PCIE_L1\" )
					)
					( Status sCSetFlattened )
					( Origin gBackEnd )
				)
				( attribute "RELATIVE_PROPAGATION_DELAY" ",5.00 MIL"
					( Parent
						( matchGroupRef "@baseboard_fab2_lib.baseboard_fab2(sch_1):\MG_PCIE_L1\" )
					)
					( Units "uMatchProp" "ns" 1.000000)
					( Status sCSetFlattened )
					( Origin gBackEnd )
				)
			)
			( pinPair "@baseboard_fab2_lib.baseboard_fab2(sch_1):\PP2986\"
				( pinRef "@baseboard_fab2_lib.baseboard_fab2(sch_1):page105_i244:B" )
				( pinRef "@baseboard_fab2_lib.baseboard_fab2(sch_1):page30_i84:PE1_RX_DN(12)" )
				( attribute "RELATIVE_PROPAGATION_DELAY_SCOPE" "L"
					( Parent
						( matchGroupRef "@baseboard_fab2_lib.baseboard_fab2(sch_1):\MG_PCIE_L0\" )
					)
					( Status sCSetFlattened )
					( Origin gBackEnd )
				)
				( attribute "RELATIVE_PROPAGATION_DELAY" ",5.00 MIL"
					( Parent
						( matchGroupRef "@baseboard_fab2_lib.baseboard_fab2(sch_1):\MG_PCIE_L0\" )
					)
					( Units "uMatchProp" "ns" 1.000000)
					( Status sCSetFlattened )
					( Origin gBackEnd )
				)
			)
			( pinPair "@baseboard_fab2_lib.baseboard_fab2(sch_1):\PP5834\"
				( pinRef "@baseboard_fab2_lib.baseboard_fab2(sch_1):page117_i9:PCIEUP_12_TXN" )
				( pinRef "@baseboard_fab2_lib.baseboard_fab2(sch_1):page30_i84:PE1_RX_DN(12)" )
				( attribute "PROPAGATION_DELAY_MIN" "3000.00 MIL"
					( Units "uMaxMinProp" "ns" 1.000000)
					( Status sCSetFlattened )
					( Origin gBackEnd )
				)
				( attribute "PROPAGATION_DELAY_MAX" "17000.00 MIL"
					( Units "uMaxMinProp" "ns" 1.000000)
					( Status sCSetFlattened )
					( Origin gBackEnd )
				)
				( attribute "RELATIVE_PROPAGATION_DELAY_SCOPE" "G"
					( Parent
						( matchGroupRef "@baseboard_fab2_lib.baseboard_fab2(sch_1):\MG_P3E_CPU0_PE1_PCH_PCIEUP_RX1213\" )
					)
					( Status sCSetFlattened )
					( Origin gBackEnd )
				)
				( attribute "RELATIVE_PROPAGATION_DELAY" ",500.00 MIL"
					( Parent
						( matchGroupRef "@baseboard_fab2_lib.baseboard_fab2(sch_1):\MG_P3E_CPU0_PE1_PCH_PCIEUP_RX1213\" )
					)
					( Units "uMatchProp" "ns" 1.000000)
					( Status sCSetFlattened )
					( Origin gBackEnd )
				)
			)
			( pinPair "@baseboard_fab2_lib.baseboard_fab2(sch_1):\PP2983\"
				( pinRef "@baseboard_fab2_lib.baseboard_fab2(sch_1):page117_i9:PCIEUP_12_TXP" )
				( pinRef "@baseboard_fab2_lib.baseboard_fab2(sch_1):page105_i232:A" )
				( attribute "RELATIVE_PROPAGATION_DELAY_SCOPE" "L"
					( Parent
						( matchGroupRef "@baseboard_fab2_lib.baseboard_fab2(sch_1):\MG_PCIE_L1\" )
					)
					( Status sCSetFlattened )
					( Origin gBackEnd )
				)
				( attribute "RELATIVE_PROPAGATION_DELAY" ",5.00 MIL"
					( Parent
						( matchGroupRef "@baseboard_fab2_lib.baseboard_fab2(sch_1):\MG_PCIE_L1\" )
					)
					( Units "uMatchProp" "ns" 1.000000)
					( Status sCSetFlattened )
					( Origin gBackEnd )
				)
			)
			( pinPair "@baseboard_fab2_lib.baseboard_fab2(sch_1):\PP2984\"
				( pinRef "@baseboard_fab2_lib.baseboard_fab2(sch_1):page105_i232:B" )
				( pinRef "@baseboard_fab2_lib.baseboard_fab2(sch_1):page30_i84:PE1_RX_DP(12)" )
				( attribute "RELATIVE_PROPAGATION_DELAY_SCOPE" "L"
					( Parent
						( matchGroupRef "@baseboard_fab2_lib.baseboard_fab2(sch_1):\MG_PCIE_L0\" )
					)
					( Status sCSetFlattened )
					( Origin gBackEnd )
				)
				( attribute "RELATIVE_PROPAGATION_DELAY" ",5.00 MIL"
					( Parent
						( matchGroupRef "@baseboard_fab2_lib.baseboard_fab2(sch_1):\MG_PCIE_L0\" )
					)
					( Units "uMatchProp" "ns" 1.000000)
					( Status sCSetFlattened )
					( Origin gBackEnd )
				)
			)
			( pinPair "@baseboard_fab2_lib.baseboard_fab2(sch_1):\PP5844\"
				( pinRef "@baseboard_fab2_lib.baseboard_fab2(sch_1):page117_i9:PCIEUP_12_TXP" )
				( pinRef "@baseboard_fab2_lib.baseboard_fab2(sch_1):page30_i84:PE1_RX_DP(12)" )
				( attribute "PROPAGATION_DELAY_MIN" "3000.00 MIL"
					( Units "uMaxMinProp" "ns" 1.000000)
					( Status sCSetFlattened )
					( Origin gBackEnd )
				)
				( attribute "PROPAGATION_DELAY_MAX" "17000.00 MIL"
					( Units "uMaxMinProp" "ns" 1.000000)
					( Status sCSetFlattened )
					( Origin gBackEnd )
				)
				( attribute "RELATIVE_PROPAGATION_DELAY_SCOPE" "G"
					( Parent
						( matchGroupRef "@baseboard_fab2_lib.baseboard_fab2(sch_1):\MG_P3E_CPU0_PE1_PCH_PCIEUP_RX1213\" )
					)
					( Status sCSetFlattened )
					( Origin gBackEnd )
				)
				( attribute "RELATIVE_PROPAGATION_DELAY" ",500.00 MIL"
					( Parent
						( matchGroupRef "@baseboard_fab2_lib.baseboard_fab2(sch_1):\MG_P3E_CPU0_PE1_PCH_PCIEUP_RX1213\" )
					)
					( Units "uMatchProp" "ns" 1.000000)
					( Status sCSetFlattened )
					( Origin gBackEnd )
				)
			)
			( pinPair "@baseboard_fab2_lib.baseboard_fab2(sch_1):\PP2981\"
				( pinRef "@baseboard_fab2_lib.baseboard_fab2(sch_1):page117_i9:PCIEUP_13_TXN" )
				( pinRef "@baseboard_fab2_lib.baseboard_fab2(sch_1):page105_i253:A" )
				( attribute "RELATIVE_PROPAGATION_DELAY_SCOPE" "L"
					( Parent
						( matchGroupRef "@baseboard_fab2_lib.baseboard_fab2(sch_1):\MG_PCIE_L1\" )
					)
					( Status sCSetFlattened )
					( Origin gBackEnd )
				)
				( attribute "RELATIVE_PROPAGATION_DELAY" ",5.00 MIL"
					( Parent
						( matchGroupRef "@baseboard_fab2_lib.baseboard_fab2(sch_1):\MG_PCIE_L1\" )
					)
					( Units "uMatchProp" "ns" 1.000000)
					( Status sCSetFlattened )
					( Origin gBackEnd )
				)
			)
			( pinPair "@baseboard_fab2_lib.baseboard_fab2(sch_1):\PP2982\"
				( pinRef "@baseboard_fab2_lib.baseboard_fab2(sch_1):page105_i253:B" )
				( pinRef "@baseboard_fab2_lib.baseboard_fab2(sch_1):page30_i84:PE1_RX_DN(13)" )
				( attribute "RELATIVE_PROPAGATION_DELAY_SCOPE" "L"
					( Parent
						( matchGroupRef "@baseboard_fab2_lib.baseboard_fab2(sch_1):\MG_PCIE_L0\" )
					)
					( Status sCSetFlattened )
					( Origin gBackEnd )
				)
				( attribute "RELATIVE_PROPAGATION_DELAY" ",5.00 MIL"
					( Parent
						( matchGroupRef "@baseboard_fab2_lib.baseboard_fab2(sch_1):\MG_PCIE_L0\" )
					)
					( Units "uMatchProp" "ns" 1.000000)
					( Status sCSetFlattened )
					( Origin gBackEnd )
				)
			)
			( pinPair "@baseboard_fab2_lib.baseboard_fab2(sch_1):\PP5843\"
				( pinRef "@baseboard_fab2_lib.baseboard_fab2(sch_1):page117_i9:PCIEUP_13_TXN" )
				( pinRef "@baseboard_fab2_lib.baseboard_fab2(sch_1):page30_i84:PE1_RX_DN(13)" )
				( attribute "PROPAGATION_DELAY_MIN" "3000.00 MIL"
					( Units "uMaxMinProp" "ns" 1.000000)
					( Status sCSetFlattened )
					( Origin gBackEnd )
				)
				( attribute "PROPAGATION_DELAY_MAX" "17000.00 MIL"
					( Units "uMaxMinProp" "ns" 1.000000)
					( Status sCSetFlattened )
					( Origin gBackEnd )
				)
				( attribute "RELATIVE_PROPAGATION_DELAY_SCOPE" "G"
					( Parent
						( matchGroupRef "@baseboard_fab2_lib.baseboard_fab2(sch_1):\MG_P3E_CPU0_PE1_PCH_PCIEUP_RX1213\" )
					)
					( Status sCSetFlattened )
					( Origin gBackEnd )
				)
				( attribute "RELATIVE_PROPAGATION_DELAY" ",500.00 MIL"
					( Parent
						( matchGroupRef "@baseboard_fab2_lib.baseboard_fab2(sch_1):\MG_P3E_CPU0_PE1_PCH_PCIEUP_RX1213\" )
					)
					( Units "uMatchProp" "ns" 1.000000)
					( Status sCSetFlattened )
					( Origin gBackEnd )
				)
			)
			( pinPair "@baseboard_fab2_lib.baseboard_fab2(sch_1):\PP2979\"
				( pinRef "@baseboard_fab2_lib.baseboard_fab2(sch_1):page117_i9:PCIEUP_13_TXP" )
				( pinRef "@baseboard_fab2_lib.baseboard_fab2(sch_1):page105_i239:A" )
				( attribute "RELATIVE_PROPAGATION_DELAY_SCOPE" "L"
					( Parent
						( matchGroupRef "@baseboard_fab2_lib.baseboard_fab2(sch_1):\MG_PCIE_L1\" )
					)
					( Status sCSetFlattened )
					( Origin gBackEnd )
				)
				( attribute "RELATIVE_PROPAGATION_DELAY" ",5.00 MIL"
					( Parent
						( matchGroupRef "@baseboard_fab2_lib.baseboard_fab2(sch_1):\MG_PCIE_L1\" )
					)
					( Units "uMatchProp" "ns" 1.000000)
					( Status sCSetFlattened )
					( Origin gBackEnd )
				)
			)
			( pinPair "@baseboard_fab2_lib.baseboard_fab2(sch_1):\PP2980\"
				( pinRef "@baseboard_fab2_lib.baseboard_fab2(sch_1):page105_i239:B" )
				( pinRef "@baseboard_fab2_lib.baseboard_fab2(sch_1):page30_i84:PE1_RX_DP(13)" )
				( attribute "RELATIVE_PROPAGATION_DELAY_SCOPE" "L"
					( Parent
						( matchGroupRef "@baseboard_fab2_lib.baseboard_fab2(sch_1):\MG_PCIE_L0\" )
					)
					( Status sCSetFlattened )
					( Origin gBackEnd )
				)
				( attribute "RELATIVE_PROPAGATION_DELAY" ",5.00 MIL"
					( Parent
						( matchGroupRef "@baseboard_fab2_lib.baseboard_fab2(sch_1):\MG_PCIE_L0\" )
					)
					( Units "uMatchProp" "ns" 1.000000)
					( Status sCSetFlattened )
					( Origin gBackEnd )
				)
			)
			( pinPair "@baseboard_fab2_lib.baseboard_fab2(sch_1):\PP5845\"
				( pinRef "@baseboard_fab2_lib.baseboard_fab2(sch_1):page117_i9:PCIEUP_13_TXP" )
				( pinRef "@baseboard_fab2_lib.baseboard_fab2(sch_1):page30_i84:PE1_RX_DP(13)" )
				( attribute "PROPAGATION_DELAY_MIN" "3000.00 MIL"
					( Units "uMaxMinProp" "ns" 1.000000)
					( Status sCSetFlattened )
					( Origin gBackEnd )
				)
				( attribute "PROPAGATION_DELAY_MAX" "17000.00 MIL"
					( Units "uMaxMinProp" "ns" 1.000000)
					( Status sCSetFlattened )
					( Origin gBackEnd )
				)
				( attribute "RELATIVE_PROPAGATION_DELAY_SCOPE" "G"
					( Parent
						( matchGroupRef "@baseboard_fab2_lib.baseboard_fab2(sch_1):\MG_P3E_CPU0_PE1_PCH_PCIEUP_RX1213\" )
					)
					( Status sCSetFlattened )
					( Origin gBackEnd )
				)
				( attribute "RELATIVE_PROPAGATION_DELAY" ",500.00 MIL"
					( Parent
						( matchGroupRef "@baseboard_fab2_lib.baseboard_fab2(sch_1):\MG_P3E_CPU0_PE1_PCH_PCIEUP_RX1213\" )
					)
					( Units "uMatchProp" "ns" 1.000000)
					( Status sCSetFlattened )
					( Origin gBackEnd )
				)
			)
			( pinPair "@baseboard_fab2_lib.baseboard_fab2(sch_1):\PP2977\"
				( pinRef "@baseboard_fab2_lib.baseboard_fab2(sch_1):page117_i9:PCIEUP_14_TXN" )
				( pinRef "@baseboard_fab2_lib.baseboard_fab2(sch_1):page105_i246:A" )
				( attribute "RELATIVE_PROPAGATION_DELAY_SCOPE" "L"
					( Parent
						( matchGroupRef "@baseboard_fab2_lib.baseboard_fab2(sch_1):\MG_PCIE_L1\" )
					)
					( Status sCSetFlattened )
					( Origin gBackEnd )
				)
				( attribute "RELATIVE_PROPAGATION_DELAY" ",5.00 MIL"
					( Parent
						( matchGroupRef "@baseboard_fab2_lib.baseboard_fab2(sch_1):\MG_PCIE_L1\" )
					)
					( Units "uMatchProp" "ns" 1.000000)
					( Status sCSetFlattened )
					( Origin gBackEnd )
				)
			)
			( pinPair "@baseboard_fab2_lib.baseboard_fab2(sch_1):\PP2978\"
				( pinRef "@baseboard_fab2_lib.baseboard_fab2(sch_1):page105_i246:B" )
				( pinRef "@baseboard_fab2_lib.baseboard_fab2(sch_1):page30_i84:PE1_RX_DN(14)" )
				( attribute "RELATIVE_PROPAGATION_DELAY_SCOPE" "L"
					( Parent
						( matchGroupRef "@baseboard_fab2_lib.baseboard_fab2(sch_1):\MG_PCIE_L0\" )
					)
					( Status sCSetFlattened )
					( Origin gBackEnd )
				)
				( attribute "RELATIVE_PROPAGATION_DELAY" ",5.00 MIL"
					( Parent
						( matchGroupRef "@baseboard_fab2_lib.baseboard_fab2(sch_1):\MG_PCIE_L0\" )
					)
					( Units "uMatchProp" "ns" 1.000000)
					( Status sCSetFlattened )
					( Origin gBackEnd )
				)
			)
			( pinPair "@baseboard_fab2_lib.baseboard_fab2(sch_1):\PP5846\"
				( pinRef "@baseboard_fab2_lib.baseboard_fab2(sch_1):page117_i9:PCIEUP_14_TXN" )
				( pinRef "@baseboard_fab2_lib.baseboard_fab2(sch_1):page30_i84:PE1_RX_DN(14)" )
				( attribute "PROPAGATION_DELAY_MIN" "3000.00 MIL"
					( Units "uMaxMinProp" "ns" 1.000000)
					( Status sCSetFlattened )
					( Origin gBackEnd )
				)
				( attribute "PROPAGATION_DELAY_MAX" "17000.00 MIL"
					( Units "uMaxMinProp" "ns" 1.000000)
					( Status sCSetFlattened )
					( Origin gBackEnd )
				)
				( attribute "RELATIVE_PROPAGATION_DELAY_SCOPE" "G"
					( Parent
						( matchGroupRef "@baseboard_fab2_lib.baseboard_fab2(sch_1):\MG_P3E_CPU0_PE1_PCH_PCIEUP_RX1415\" )
					)
					( Status sCSetFlattened )
					( Origin gBackEnd )
				)
				( attribute "RELATIVE_PROPAGATION_DELAY" ",500.00 MIL"
					( Parent
						( matchGroupRef "@baseboard_fab2_lib.baseboard_fab2(sch_1):\MG_P3E_CPU0_PE1_PCH_PCIEUP_RX1415\" )
					)
					( Units "uMatchProp" "ns" 1.000000)
					( Status sCSetFlattened )
					( Origin gBackEnd )
				)
			)
			( pinPair "@baseboard_fab2_lib.baseboard_fab2(sch_1):\PP2975\"
				( pinRef "@baseboard_fab2_lib.baseboard_fab2(sch_1):page117_i9:PCIEUP_14_TXP" )
				( pinRef "@baseboard_fab2_lib.baseboard_fab2(sch_1):page105_i234:A" )
				( attribute "RELATIVE_PROPAGATION_DELAY_SCOPE" "L"
					( Parent
						( matchGroupRef "@baseboard_fab2_lib.baseboard_fab2(sch_1):\MG_PCIE_L1\" )
					)
					( Status sCSetFlattened )
					( Origin gBackEnd )
				)
				( attribute "RELATIVE_PROPAGATION_DELAY" ",5.00 MIL"
					( Parent
						( matchGroupRef "@baseboard_fab2_lib.baseboard_fab2(sch_1):\MG_PCIE_L1\" )
					)
					( Units "uMatchProp" "ns" 1.000000)
					( Status sCSetFlattened )
					( Origin gBackEnd )
				)
			)
			( pinPair "@baseboard_fab2_lib.baseboard_fab2(sch_1):\PP2976\"
				( pinRef "@baseboard_fab2_lib.baseboard_fab2(sch_1):page105_i234:B" )
				( pinRef "@baseboard_fab2_lib.baseboard_fab2(sch_1):page30_i84:PE1_RX_DP(14)" )
				( attribute "RELATIVE_PROPAGATION_DELAY_SCOPE" "L"
					( Parent
						( matchGroupRef "@baseboard_fab2_lib.baseboard_fab2(sch_1):\MG_PCIE_L0\" )
					)
					( Status sCSetFlattened )
					( Origin gBackEnd )
				)
				( attribute "RELATIVE_PROPAGATION_DELAY" ",5.00 MIL"
					( Parent
						( matchGroupRef "@baseboard_fab2_lib.baseboard_fab2(sch_1):\MG_PCIE_L0\" )
					)
					( Units "uMatchProp" "ns" 1.000000)
					( Status sCSetFlattened )
					( Origin gBackEnd )
				)
			)
			( pinPair "@baseboard_fab2_lib.baseboard_fab2(sch_1):\PP5847\"
				( pinRef "@baseboard_fab2_lib.baseboard_fab2(sch_1):page117_i9:PCIEUP_14_TXP" )
				( pinRef "@baseboard_fab2_lib.baseboard_fab2(sch_1):page30_i84:PE1_RX_DP(14)" )
				( attribute "PROPAGATION_DELAY_MIN" "3000.00 MIL"
					( Units "uMaxMinProp" "ns" 1.000000)
					( Status sCSetFlattened )
					( Origin gBackEnd )
				)
				( attribute "PROPAGATION_DELAY_MAX" "17000.00 MIL"
					( Units "uMaxMinProp" "ns" 1.000000)
					( Status sCSetFlattened )
					( Origin gBackEnd )
				)
				( attribute "RELATIVE_PROPAGATION_DELAY_SCOPE" "G"
					( Parent
						( matchGroupRef "@baseboard_fab2_lib.baseboard_fab2(sch_1):\MG_P3E_CPU0_PE1_PCH_PCIEUP_RX1415\" )
					)
					( Status sCSetFlattened )
					( Origin gBackEnd )
				)
				( attribute "RELATIVE_PROPAGATION_DELAY" ",500.00 MIL"
					( Parent
						( matchGroupRef "@baseboard_fab2_lib.baseboard_fab2(sch_1):\MG_P3E_CPU0_PE1_PCH_PCIEUP_RX1415\" )
					)
					( Units "uMatchProp" "ns" 1.000000)
					( Status sCSetFlattened )
					( Origin gBackEnd )
				)
			)
			( pinPair "@baseboard_fab2_lib.baseboard_fab2(sch_1):\PP2973\"
				( pinRef "@baseboard_fab2_lib.baseboard_fab2(sch_1):page117_i9:PCIEUP_15_TXN" )
				( pinRef "@baseboard_fab2_lib.baseboard_fab2(sch_1):page105_i255:A" )
				( attribute "RELATIVE_PROPAGATION_DELAY_SCOPE" "L"
					( Parent
						( matchGroupRef "@baseboard_fab2_lib.baseboard_fab2(sch_1):\MG_PCIE_L1\" )
					)
					( Status sCSetFlattened )
					( Origin gBackEnd )
				)
				( attribute "RELATIVE_PROPAGATION_DELAY" ",5.00 MIL"
					( Parent
						( matchGroupRef "@baseboard_fab2_lib.baseboard_fab2(sch_1):\MG_PCIE_L1\" )
					)
					( Units "uMatchProp" "ns" 1.000000)
					( Status sCSetFlattened )
					( Origin gBackEnd )
				)
			)
			( pinPair "@baseboard_fab2_lib.baseboard_fab2(sch_1):\PP2974\"
				( pinRef "@baseboard_fab2_lib.baseboard_fab2(sch_1):page105_i255:B" )
				( pinRef "@baseboard_fab2_lib.baseboard_fab2(sch_1):page30_i84:PE1_RX_DN(15)" )
				( attribute "RELATIVE_PROPAGATION_DELAY_SCOPE" "L"
					( Parent
						( matchGroupRef "@baseboard_fab2_lib.baseboard_fab2(sch_1):\MG_PCIE_L0\" )
					)
					( Status sCSetFlattened )
					( Origin gBackEnd )
				)
				( attribute "RELATIVE_PROPAGATION_DELAY" ",5.00 MIL"
					( Parent
						( matchGroupRef "@baseboard_fab2_lib.baseboard_fab2(sch_1):\MG_PCIE_L0\" )
					)
					( Units "uMatchProp" "ns" 1.000000)
					( Status sCSetFlattened )
					( Origin gBackEnd )
				)
			)
			( pinPair "@baseboard_fab2_lib.baseboard_fab2(sch_1):\PP5848\"
				( pinRef "@baseboard_fab2_lib.baseboard_fab2(sch_1):page117_i9:PCIEUP_15_TXN" )
				( pinRef "@baseboard_fab2_lib.baseboard_fab2(sch_1):page30_i84:PE1_RX_DN(15)" )
				( attribute "PROPAGATION_DELAY_MIN" "3000.00 MIL"
					( Units "uMaxMinProp" "ns" 1.000000)
					( Status sCSetFlattened )
					( Origin gBackEnd )
				)
				( attribute "PROPAGATION_DELAY_MAX" "17000.00 MIL"
					( Units "uMaxMinProp" "ns" 1.000000)
					( Status sCSetFlattened )
					( Origin gBackEnd )
				)
				( attribute "RELATIVE_PROPAGATION_DELAY_SCOPE" "G"
					( Parent
						( matchGroupRef "@baseboard_fab2_lib.baseboard_fab2(sch_1):\MG_P3E_CPU0_PE1_PCH_PCIEUP_RX1415\" )
					)
					( Status sCSetFlattened )
					( Origin gBackEnd )
				)
				( attribute "RELATIVE_PROPAGATION_DELAY" ",500.00 MIL"
					( Parent
						( matchGroupRef "@baseboard_fab2_lib.baseboard_fab2(sch_1):\MG_P3E_CPU0_PE1_PCH_PCIEUP_RX1415\" )
					)
					( Units "uMatchProp" "ns" 1.000000)
					( Status sCSetFlattened )
					( Origin gBackEnd )
				)
			)
			( pinPair "@baseboard_fab2_lib.baseboard_fab2(sch_1):\PP2971\"
				( pinRef "@baseboard_fab2_lib.baseboard_fab2(sch_1):page117_i9:PCIEUP_15_TXP" )
				( pinRef "@baseboard_fab2_lib.baseboard_fab2(sch_1):page105_i247:A" )
				( attribute "RELATIVE_PROPAGATION_DELAY_SCOPE" "L"
					( Parent
						( matchGroupRef "@baseboard_fab2_lib.baseboard_fab2(sch_1):\MG_PCIE_L1\" )
					)
					( Status sCSetFlattened )
					( Origin gBackEnd )
				)
				( attribute "RELATIVE_PROPAGATION_DELAY" ",5.00 MIL"
					( Parent
						( matchGroupRef "@baseboard_fab2_lib.baseboard_fab2(sch_1):\MG_PCIE_L1\" )
					)
					( Units "uMatchProp" "ns" 1.000000)
					( Status sCSetFlattened )
					( Origin gBackEnd )
				)
			)
			( pinPair "@baseboard_fab2_lib.baseboard_fab2(sch_1):\PP2972\"
				( pinRef "@baseboard_fab2_lib.baseboard_fab2(sch_1):page105_i247:B" )
				( pinRef "@baseboard_fab2_lib.baseboard_fab2(sch_1):page30_i84:PE1_RX_DP(15)" )
				( attribute "RELATIVE_PROPAGATION_DELAY_SCOPE" "L"
					( Parent
						( matchGroupRef "@baseboard_fab2_lib.baseboard_fab2(sch_1):\MG_PCIE_L0\" )
					)
					( Status sCSetFlattened )
					( Origin gBackEnd )
				)
				( attribute "RELATIVE_PROPAGATION_DELAY" ",5.00 MIL"
					( Parent
						( matchGroupRef "@baseboard_fab2_lib.baseboard_fab2(sch_1):\MG_PCIE_L0\" )
					)
					( Units "uMatchProp" "ns" 1.000000)
					( Status sCSetFlattened )
					( Origin gBackEnd )
				)
			)
			( pinPair "@baseboard_fab2_lib.baseboard_fab2(sch_1):\PP5841\"
				( pinRef "@baseboard_fab2_lib.baseboard_fab2(sch_1):page117_i9:PCIEUP_15_TXP" )
				( pinRef "@baseboard_fab2_lib.baseboard_fab2(sch_1):page30_i84:PE1_RX_DP(15)" )
				( attribute "PROPAGATION_DELAY_MIN" "3000.00 MIL"
					( Units "uMaxMinProp" "ns" 1.000000)
					( Status sCSetFlattened )
					( Origin gBackEnd )
				)
				( attribute "PROPAGATION_DELAY_MAX" "17000.00 MIL"
					( Units "uMaxMinProp" "ns" 1.000000)
					( Status sCSetFlattened )
					( Origin gBackEnd )
				)
				( attribute "RELATIVE_PROPAGATION_DELAY_SCOPE" "G"
					( Parent
						( matchGroupRef "@baseboard_fab2_lib.baseboard_fab2(sch_1):\MG_P3E_CPU0_PE1_PCH_PCIEUP_RX1415\" )
					)
					( Status sCSetFlattened )
					( Origin gBackEnd )
				)
				( attribute "RELATIVE_PROPAGATION_DELAY" ",500.00 MIL"
					( Parent
						( matchGroupRef "@baseboard_fab2_lib.baseboard_fab2(sch_1):\MG_P3E_CPU0_PE1_PCH_PCIEUP_RX1415\" )
					)
					( Units "uMatchProp" "ns" 1.000000)
					( Status sCSetFlattened )
					( Origin gBackEnd )
				)
			)
			( pinPair "@baseboard_fab2_lib.baseboard_fab2(sch_1):\PP3041\"
				( pinRef "@baseboard_fab2_lib.baseboard_fab2(sch_1):page182_i9:B" )
				( pinRef "@baseboard_fab2_lib.baseboard_fab2(sch_1):page66_i84:PE3_TX_DN(8)" )
				( attribute "RELATIVE_PROPAGATION_DELAY_SCOPE" "L"
					( Parent
						( matchGroupRef "@baseboard_fab2_lib.baseboard_fab2(sch_1):\MG_PCIE_L1\" )
					)
					( Status sCSetFlattened )
					( Origin gBackEnd )
				)
				( attribute "RELATIVE_PROPAGATION_DELAY" ",5.00 MIL"
					( Parent
						( matchGroupRef "@baseboard_fab2_lib.baseboard_fab2(sch_1):\MG_PCIE_L1\" )
					)
					( Units "uMatchProp" "ns" 1.000000)
					( Status sCSetFlattened )
					( Origin gBackEnd )
				)
			)
			( pinPair "@baseboard_fab2_lib.baseboard_fab2(sch_1):\PP3042\"
				( pinRef "@baseboard_fab2_lib.baseboard_fab2(sch_1):page182_i18:IOB8" )
				( pinRef "@baseboard_fab2_lib.baseboard_fab2(sch_1):page182_i9:A" )
				( attribute "RELATIVE_PROPAGATION_DELAY_SCOPE" "L"
					( Parent
						( matchGroupRef "@baseboard_fab2_lib.baseboard_fab2(sch_1):\MG_PCIE_L0\" )
					)
					( Status sCSetFlattened )
					( Origin gBackEnd )
				)
				( attribute "RELATIVE_PROPAGATION_DELAY" ",5.00 MIL"
					( Parent
						( matchGroupRef "@baseboard_fab2_lib.baseboard_fab2(sch_1):\MG_PCIE_L0\" )
					)
					( Units "uMatchProp" "ns" 1.000000)
					( Status sCSetFlattened )
					( Origin gBackEnd )
				)
			)
			( pinPair "@baseboard_fab2_lib.baseboard_fab2(sch_1):\PP5830\"
				( pinRef "@baseboard_fab2_lib.baseboard_fab2(sch_1):page66_i84:PE3_TX_DN(8)" )
				( pinRef "@baseboard_fab2_lib.baseboard_fab2(sch_1):page182_i18:IOB8" )
				( attribute "PROPAGATION_DELAY_MIN" "3000.00 MIL"
					( Units "uMaxMinProp" "ns" 1.000000)
					( Status sCSetFlattened )
					( Origin gBackEnd )
				)
				( attribute "PROPAGATION_DELAY_MAX" "16000.00 MIL"
					( Units "uMaxMinProp" "ns" 1.000000)
					( Status sCSetFlattened )
					( Origin gBackEnd )
				)
				( attribute "RELATIVE_PROPAGATION_DELAY_SCOPE" "G"
					( Parent
						( matchGroupRef "@baseboard_fab2_lib.baseboard_fab2(sch_1):\MG_P3E_CPU1_PE3_MP_TX0809\" )
					)
					( Status sCSetFlattened )
					( Origin gBackEnd )
				)
				( attribute "RELATIVE_PROPAGATION_DELAY" ",500.00 MIL"
					( Parent
						( matchGroupRef "@baseboard_fab2_lib.baseboard_fab2(sch_1):\MG_P3E_CPU1_PE3_MP_TX0809\" )
					)
					( Units "uMatchProp" "ns" 1.000000)
					( Status sCSetFlattened )
					( Origin gBackEnd )
				)
			)
			( pinPair "@baseboard_fab2_lib.baseboard_fab2(sch_1):\PP3039\"
				( pinRef "@baseboard_fab2_lib.baseboard_fab2(sch_1):page182_i18:IOC8" )
				( pinRef "@baseboard_fab2_lib.baseboard_fab2(sch_1):page182_i12:A" )
				( attribute "RELATIVE_PROPAGATION_DELAY_SCOPE" "L"
					( Parent
						( matchGroupRef "@baseboard_fab2_lib.baseboard_fab2(sch_1):\MG_PCIE_L0\" )
					)
					( Status sCSetFlattened )
					( Origin gBackEnd )
				)
				( attribute "RELATIVE_PROPAGATION_DELAY" ",5.00 MIL"
					( Parent
						( matchGroupRef "@baseboard_fab2_lib.baseboard_fab2(sch_1):\MG_PCIE_L0\" )
					)
					( Units "uMatchProp" "ns" 1.000000)
					( Status sCSetFlattened )
					( Origin gBackEnd )
				)
			)
			( pinPair "@baseboard_fab2_lib.baseboard_fab2(sch_1):\PP3040\"
				( pinRef "@baseboard_fab2_lib.baseboard_fab2(sch_1):page182_i12:B" )
				( pinRef "@baseboard_fab2_lib.baseboard_fab2(sch_1):page66_i84:PE3_TX_DP(8)" )
				( attribute "RELATIVE_PROPAGATION_DELAY_SCOPE" "L"
					( Parent
						( matchGroupRef "@baseboard_fab2_lib.baseboard_fab2(sch_1):\MG_PCIE_L1\" )
					)
					( Status sCSetFlattened )
					( Origin gBackEnd )
				)
				( attribute "RELATIVE_PROPAGATION_DELAY" ",5.00 MIL"
					( Parent
						( matchGroupRef "@baseboard_fab2_lib.baseboard_fab2(sch_1):\MG_PCIE_L1\" )
					)
					( Units "uMatchProp" "ns" 1.000000)
					( Status sCSetFlattened )
					( Origin gBackEnd )
				)
			)
			( pinPair "@baseboard_fab2_lib.baseboard_fab2(sch_1):\PP5831\"
				( pinRef "@baseboard_fab2_lib.baseboard_fab2(sch_1):page66_i84:PE3_TX_DP(8)" )
				( pinRef "@baseboard_fab2_lib.baseboard_fab2(sch_1):page182_i18:IOC8" )
				( attribute "PROPAGATION_DELAY_MIN" "3000.00 MIL"
					( Units "uMaxMinProp" "ns" 1.000000)
					( Status sCSetFlattened )
					( Origin gBackEnd )
				)
				( attribute "PROPAGATION_DELAY_MAX" "16000.00 MIL"
					( Units "uMaxMinProp" "ns" 1.000000)
					( Status sCSetFlattened )
					( Origin gBackEnd )
				)
				( attribute "RELATIVE_PROPAGATION_DELAY_SCOPE" "G"
					( Parent
						( matchGroupRef "@baseboard_fab2_lib.baseboard_fab2(sch_1):\MG_P3E_CPU1_PE3_MP_TX0809\" )
					)
					( Status sCSetFlattened )
					( Origin gBackEnd )
				)
				( attribute "RELATIVE_PROPAGATION_DELAY" ",500.00 MIL"
					( Parent
						( matchGroupRef "@baseboard_fab2_lib.baseboard_fab2(sch_1):\MG_P3E_CPU1_PE3_MP_TX0809\" )
					)
					( Units "uMatchProp" "ns" 1.000000)
					( Status sCSetFlattened )
					( Origin gBackEnd )
				)
			)
			( pinPair "@baseboard_fab2_lib.baseboard_fab2(sch_1):\PP163\"
				( pinRef "@baseboard_fab2_lib.baseboard_fab2(sch_1):page117_i9:PCIEUP_7_TXN" )
				( pinRef "@baseboard_fab2_lib.baseboard_fab2(sch_1):page107_i294:A" )
				( attribute "RELATIVE_PROPAGATION_DELAY_SCOPE" "L"
					( Parent
						( matchGroupRef "@baseboard_fab2_lib.baseboard_fab2(sch_1):\MG_PCIE_L1\" )
					)
					( Status sCSetFlattened )
					( Origin gBackEnd )
				)
				( attribute "RELATIVE_PROPAGATION_DELAY" ",5.00 MIL"
					( Parent
						( matchGroupRef "@baseboard_fab2_lib.baseboard_fab2(sch_1):\MG_PCIE_L1\" )
					)
					( Units "uMatchProp" "ns" 1.000000)
					( Status sCSetFlattened )
					( Origin gBackEnd )
				)
			)
			( pinPair "@baseboard_fab2_lib.baseboard_fab2(sch_1):\PP164\"
				( pinRef "@baseboard_fab2_lib.baseboard_fab2(sch_1):page109_i243:IO102" )
				( pinRef "@baseboard_fab2_lib.baseboard_fab2(sch_1):page107_i458:A" )
				( attribute "RELATIVE_PROPAGATION_DELAY_SCOPE" "L"
					( Parent
						( matchGroupRef "@baseboard_fab2_lib.baseboard_fab2(sch_1):\MG_PCIE_L0\" )
					)
					( Status sCSetFlattened )
					( Origin gBackEnd )
				)
				( attribute "RELATIVE_PROPAGATION_DELAY" ",5.00 MIL"
					( Parent
						( matchGroupRef "@baseboard_fab2_lib.baseboard_fab2(sch_1):\MG_PCIE_L0\" )
					)
					( Units "uMatchProp" "ns" 1.000000)
					( Status sCSetFlattened )
					( Origin gBackEnd )
				)
			)
			( pinPair "@baseboard_fab2_lib.baseboard_fab2(sch_1):\PP5994\"
				( pinRef "@baseboard_fab2_lib.baseboard_fab2(sch_1):page30_i84:PE1_RX_DN(7)" )
				( pinRef "@baseboard_fab2_lib.baseboard_fab2(sch_1):page107_i458:A" )
				( attribute "RELATIVE_PROPAGATION_DELAY_SCOPE" "L"
					( Parent
						( matchGroupRef "@baseboard_fab2_lib.baseboard_fab2(sch_1):\MG_PCIE_L2\" )
					)
					( Status sCSetFlattened )
					( Origin gBackEnd )
				)
				( attribute "RELATIVE_PROPAGATION_DELAY" ",5.00 MIL"
					( Parent
						( matchGroupRef "@baseboard_fab2_lib.baseboard_fab2(sch_1):\MG_PCIE_L2\" )
					)
					( Units "uMatchProp" "ns" 1.000000)
					( Status sCSetFlattened )
					( Origin gBackEnd )
				)
			)
			( pinPair "@baseboard_fab2_lib.baseboard_fab2(sch_1):\PP5995\"
				( pinRef "@baseboard_fab2_lib.baseboard_fab2(sch_1):page30_i84:PE1_RX_DN(7)" )
				( pinRef "@baseboard_fab2_lib.baseboard_fab2(sch_1):page117_i9:PCIEUP_7_TXN" )
				( attribute "PROPAGATION_DELAY_MIN" "3000.00 MIL"
					( Units "uMaxMinProp" "ns" 1.000000)
					( Status sCSetFlattened )
					( Origin gBackEnd )
				)
				( attribute "PROPAGATION_DELAY_MAX" "17000.00 MIL"
					( Units "uMaxMinProp" "ns" 1.000000)
					( Status sCSetFlattened )
					( Origin gBackEnd )
				)
				( attribute "RELATIVE_PROPAGATION_DELAY_SCOPE" "L"
					( Parent
						( matchGroupRef "@baseboard_fab2_lib.baseboard_fab2(sch_1):\MG_PCIE_ALL1\" )
					)
					( Status sCSetFlattened )
					( Origin gBackEnd )
				)
				( attribute "RELATIVE_PROPAGATION_DELAY" ",5.00 MIL"
					( Parent
						( matchGroupRef "@baseboard_fab2_lib.baseboard_fab2(sch_1):\MG_PCIE_ALL1\" )
					)
					( Units "uMatchProp" "ns" 1.000000)
					( Status sCSetFlattened )
					( Origin gBackEnd )
				)
			)
			( pinPair "@baseboard_fab2_lib.baseboard_fab2(sch_1):\PP5996\"
				( pinRef "@baseboard_fab2_lib.baseboard_fab2(sch_1):page30_i84:PE1_RX_DN(7)" )
				( pinRef "@baseboard_fab2_lib.baseboard_fab2(sch_1):page109_i243:IO102" )
				( attribute "PROPAGATION_DELAY_MIN" "3000.00 MIL"
					( Units "uMaxMinProp" "ns" 1.000000)
					( Status sCSetFlattened )
					( Origin gBackEnd )
				)
				( attribute "PROPAGATION_DELAY_MAX" "16000.00 MIL"
					( Units "uMaxMinProp" "ns" 1.000000)
					( Status sCSetFlattened )
					( Origin gBackEnd )
				)
				( attribute "RELATIVE_PROPAGATION_DELAY_SCOPE" "L"
					( Parent
						( matchGroupRef "@baseboard_fab2_lib.baseboard_fab2(sch_1):\MG_PCIE_ALL0\" )
					)
					( Status sCSetFlattened )
					( Origin gBackEnd )
				)
				( attribute "RELATIVE_PROPAGATION_DELAY" ",5.00 MIL"
					( Parent
						( matchGroupRef "@baseboard_fab2_lib.baseboard_fab2(sch_1):\MG_PCIE_ALL0\" )
					)
					( Units "uMatchProp" "ns" 1.000000)
					( Status sCSetFlattened )
					( Origin gBackEnd )
				)
			)
			( pinPair "@baseboard_fab2_lib.baseboard_fab2(sch_1):\PP165\"
				( pinRef "@baseboard_fab2_lib.baseboard_fab2(sch_1):page108_i258:IO100" )
				( pinRef "@baseboard_fab2_lib.baseboard_fab2(sch_1):page107_i473:A" )
				( attribute "RELATIVE_PROPAGATION_DELAY_SCOPE" "L"
					( Parent
						( matchGroupRef "@baseboard_fab2_lib.baseboard_fab2(sch_1):\MG_PCIE_L0\" )
					)
					( Status sCSetFlattened )
					( Origin gBackEnd )
				)
				( attribute "RELATIVE_PROPAGATION_DELAY" ",5.00 MIL"
					( Parent
						( matchGroupRef "@baseboard_fab2_lib.baseboard_fab2(sch_1):\MG_PCIE_L0\" )
					)
					( Units "uMatchProp" "ns" 1.000000)
					( Status sCSetFlattened )
					( Origin gBackEnd )
				)
			)
			( pinPair "@baseboard_fab2_lib.baseboard_fab2(sch_1):\PP166\"
				( pinRef "@baseboard_fab2_lib.baseboard_fab2(sch_1):page117_i9:PCIEUP_7_TXP" )
				( pinRef "@baseboard_fab2_lib.baseboard_fab2(sch_1):page107_i300:A" )
				( attribute "RELATIVE_PROPAGATION_DELAY_SCOPE" "L"
					( Parent
						( matchGroupRef "@baseboard_fab2_lib.baseboard_fab2(sch_1):\MG_PCIE_L1\" )
					)
					( Status sCSetFlattened )
					( Origin gBackEnd )
				)
				( attribute "RELATIVE_PROPAGATION_DELAY" ",5.00 MIL"
					( Parent
						( matchGroupRef "@baseboard_fab2_lib.baseboard_fab2(sch_1):\MG_PCIE_L1\" )
					)
					( Units "uMatchProp" "ns" 1.000000)
					( Status sCSetFlattened )
					( Origin gBackEnd )
				)
			)
			( pinPair "@baseboard_fab2_lib.baseboard_fab2(sch_1):\PP5991\"
				( pinRef "@baseboard_fab2_lib.baseboard_fab2(sch_1):page30_i84:PE1_RX_DP(7)" )
				( pinRef "@baseboard_fab2_lib.baseboard_fab2(sch_1):page107_i473:A" )
				( attribute "RELATIVE_PROPAGATION_DELAY_SCOPE" "L"
					( Parent
						( matchGroupRef "@baseboard_fab2_lib.baseboard_fab2(sch_1):\MG_PCIE_L2\" )
					)
					( Status sCSetFlattened )
					( Origin gBackEnd )
				)
				( attribute "RELATIVE_PROPAGATION_DELAY" ",5.00 MIL"
					( Parent
						( matchGroupRef "@baseboard_fab2_lib.baseboard_fab2(sch_1):\MG_PCIE_L2\" )
					)
					( Units "uMatchProp" "ns" 1.000000)
					( Status sCSetFlattened )
					( Origin gBackEnd )
				)
			)
			( pinPair "@baseboard_fab2_lib.baseboard_fab2(sch_1):\PP5992\"
				( pinRef "@baseboard_fab2_lib.baseboard_fab2(sch_1):page30_i84:PE1_RX_DP(7)" )
				( pinRef "@baseboard_fab2_lib.baseboard_fab2(sch_1):page117_i9:PCIEUP_7_TXP" )
				( attribute "PROPAGATION_DELAY_MIN" "3000.00 MIL"
					( Units "uMaxMinProp" "ns" 1.000000)
					( Status sCSetFlattened )
					( Origin gBackEnd )
				)
				( attribute "PROPAGATION_DELAY_MAX" "17000.00 MIL"
					( Units "uMaxMinProp" "ns" 1.000000)
					( Status sCSetFlattened )
					( Origin gBackEnd )
				)
				( attribute "RELATIVE_PROPAGATION_DELAY_SCOPE" "L"
					( Parent
						( matchGroupRef "@baseboard_fab2_lib.baseboard_fab2(sch_1):\MG_PCIE_ALL1\" )
					)
					( Status sCSetFlattened )
					( Origin gBackEnd )
				)
				( attribute "RELATIVE_PROPAGATION_DELAY" ",5.00 MIL"
					( Parent
						( matchGroupRef "@baseboard_fab2_lib.baseboard_fab2(sch_1):\MG_PCIE_ALL1\" )
					)
					( Units "uMatchProp" "ns" 1.000000)
					( Status sCSetFlattened )
					( Origin gBackEnd )
				)
			)
			( pinPair "@baseboard_fab2_lib.baseboard_fab2(sch_1):\PP5993\"
				( pinRef "@baseboard_fab2_lib.baseboard_fab2(sch_1):page30_i84:PE1_RX_DP(7)" )
				( pinRef "@baseboard_fab2_lib.baseboard_fab2(sch_1):page108_i258:IO100" )
				( attribute "PROPAGATION_DELAY_MIN" "3000.00 MIL"
					( Units "uMaxMinProp" "ns" 1.000000)
					( Status sCSetFlattened )
					( Origin gBackEnd )
				)
				( attribute "PROPAGATION_DELAY_MAX" "16000.00 MIL"
					( Units "uMaxMinProp" "ns" 1.000000)
					( Status sCSetFlattened )
					( Origin gBackEnd )
				)
				( attribute "RELATIVE_PROPAGATION_DELAY_SCOPE" "L"
					( Parent
						( matchGroupRef "@baseboard_fab2_lib.baseboard_fab2(sch_1):\MG_PCIE_ALL0\" )
					)
					( Status sCSetFlattened )
					( Origin gBackEnd )
				)
				( attribute "RELATIVE_PROPAGATION_DELAY" ",5.00 MIL"
					( Parent
						( matchGroupRef "@baseboard_fab2_lib.baseboard_fab2(sch_1):\MG_PCIE_ALL0\" )
					)
					( Units "uMatchProp" "ns" 1.000000)
					( Status sCSetFlattened )
					( Origin gBackEnd )
				)
			)
			( pinPair "@baseboard_fab2_lib.baseboard_fab2(sch_1):\PP387\"
				( pinRef "@baseboard_fab2_lib.baseboard_fab2(sch_1):page30_i84:PE1_TX_DN(8)" )
				( pinRef "@baseboard_fab2_lib.baseboard_fab2(sch_1):page105_i160:A" )
				( attribute "RELATIVE_PROPAGATION_DELAY_SCOPE" "L"
					( Parent
						( matchGroupRef "@baseboard_fab2_lib.baseboard_fab2(sch_1):\MG_PCIE_L1\" )
					)
					( Status sCSetFlattened )
					( Origin gBackEnd )
				)
				( attribute "RELATIVE_PROPAGATION_DELAY" ",5.00 MIL"
					( Parent
						( matchGroupRef "@baseboard_fab2_lib.baseboard_fab2(sch_1):\MG_PCIE_L1\" )
					)
					( Units "uMatchProp" "ns" 1.000000)
					( Status sCSetFlattened )
					( Origin gBackEnd )
				)
			)
			( pinPair "@baseboard_fab2_lib.baseboard_fab2(sch_1):\PP388\"
				( pinRef "@baseboard_fab2_lib.baseboard_fab2(sch_1):page105_i160:B" )
				( pinRef "@baseboard_fab2_lib.baseboard_fab2(sch_1):page117_i9:PCIEUP_8_RXP" )
				( attribute "RELATIVE_PROPAGATION_DELAY_SCOPE" "L"
					( Parent
						( matchGroupRef "@baseboard_fab2_lib.baseboard_fab2(sch_1):\MG_PCIE_L0\" )
					)
					( Status sCSetFlattened )
					( Origin gBackEnd )
				)
				( attribute "RELATIVE_PROPAGATION_DELAY" ",5.00 MIL"
					( Parent
						( matchGroupRef "@baseboard_fab2_lib.baseboard_fab2(sch_1):\MG_PCIE_L0\" )
					)
					( Units "uMatchProp" "ns" 1.000000)
					( Status sCSetFlattened )
					( Origin gBackEnd )
				)
			)
			( pinPair "@baseboard_fab2_lib.baseboard_fab2(sch_1):\PP5852\"
				( pinRef "@baseboard_fab2_lib.baseboard_fab2(sch_1):page30_i84:PE1_TX_DN(8)" )
				( pinRef "@baseboard_fab2_lib.baseboard_fab2(sch_1):page117_i9:PCIEUP_8_RXP" )
				( attribute "PROPAGATION_DELAY_MIN" "3000.00 MIL"
					( Units "uMaxMinProp" "ns" 1.000000)
					( Status sCSetFlattened )
					( Origin gBackEnd )
				)
				( attribute "PROPAGATION_DELAY_MAX" "17000.00 MIL"
					( Units "uMaxMinProp" "ns" 1.000000)
					( Status sCSetFlattened )
					( Origin gBackEnd )
				)
				( attribute "RELATIVE_PROPAGATION_DELAY_SCOPE" "G"
					( Parent
						( matchGroupRef "@baseboard_fab2_lib.baseboard_fab2(sch_1):\MG_P3E_CPU0_PE1_PCH_PCIEUP_TX0809\" )
					)
					( Status sCSetFlattened )
					( Origin gBackEnd )
				)
				( attribute "RELATIVE_PROPAGATION_DELAY" ",500.00 MIL"
					( Parent
						( matchGroupRef "@baseboard_fab2_lib.baseboard_fab2(sch_1):\MG_P3E_CPU0_PE1_PCH_PCIEUP_TX0809\" )
					)
					( Units "uMatchProp" "ns" 1.000000)
					( Status sCSetFlattened )
					( Origin gBackEnd )
				)
			)
			( pinPair "@baseboard_fab2_lib.baseboard_fab2(sch_1):\PP389\"
				( pinRef "@baseboard_fab2_lib.baseboard_fab2(sch_1):page105_i173:B" )
				( pinRef "@baseboard_fab2_lib.baseboard_fab2(sch_1):page117_i9:PCIEUP_8_RXN" )
				( attribute "RELATIVE_PROPAGATION_DELAY_SCOPE" "L"
					( Parent
						( matchGroupRef "@baseboard_fab2_lib.baseboard_fab2(sch_1):\MG_PCIE_L0\" )
					)
					( Status sCSetFlattened )
					( Origin gBackEnd )
				)
				( attribute "RELATIVE_PROPAGATION_DELAY" ",5.00 MIL"
					( Parent
						( matchGroupRef "@baseboard_fab2_lib.baseboard_fab2(sch_1):\MG_PCIE_L0\" )
					)
					( Units "uMatchProp" "ns" 1.000000)
					( Status sCSetFlattened )
					( Origin gBackEnd )
				)
			)
			( pinPair "@baseboard_fab2_lib.baseboard_fab2(sch_1):\PP390\"
				( pinRef "@baseboard_fab2_lib.baseboard_fab2(sch_1):page30_i84:PE1_TX_DP(8)" )
				( pinRef "@baseboard_fab2_lib.baseboard_fab2(sch_1):page105_i173:A" )
				( attribute "RELATIVE_PROPAGATION_DELAY_SCOPE" "L"
					( Parent
						( matchGroupRef "@baseboard_fab2_lib.baseboard_fab2(sch_1):\MG_PCIE_L1\" )
					)
					( Status sCSetFlattened )
					( Origin gBackEnd )
				)
				( attribute "RELATIVE_PROPAGATION_DELAY" ",5.00 MIL"
					( Parent
						( matchGroupRef "@baseboard_fab2_lib.baseboard_fab2(sch_1):\MG_PCIE_L1\" )
					)
					( Units "uMatchProp" "ns" 1.000000)
					( Status sCSetFlattened )
					( Origin gBackEnd )
				)
			)
			( pinPair "@baseboard_fab2_lib.baseboard_fab2(sch_1):\PP5842\"
				( pinRef "@baseboard_fab2_lib.baseboard_fab2(sch_1):page30_i84:PE1_TX_DP(8)" )
				( pinRef "@baseboard_fab2_lib.baseboard_fab2(sch_1):page117_i9:PCIEUP_8_RXN" )
				( attribute "PROPAGATION_DELAY_MIN" "3000.00 MIL"
					( Units "uMaxMinProp" "ns" 1.000000)
					( Status sCSetFlattened )
					( Origin gBackEnd )
				)
				( attribute "PROPAGATION_DELAY_MAX" "17000.00 MIL"
					( Units "uMaxMinProp" "ns" 1.000000)
					( Status sCSetFlattened )
					( Origin gBackEnd )
				)
				( attribute "RELATIVE_PROPAGATION_DELAY_SCOPE" "G"
					( Parent
						( matchGroupRef "@baseboard_fab2_lib.baseboard_fab2(sch_1):\MG_P3E_CPU0_PE1_PCH_PCIEUP_TX0809\" )
					)
					( Status sCSetFlattened )
					( Origin gBackEnd )
				)
				( attribute "RELATIVE_PROPAGATION_DELAY" ",500.00 MIL"
					( Parent
						( matchGroupRef "@baseboard_fab2_lib.baseboard_fab2(sch_1):\MG_P3E_CPU0_PE1_PCH_PCIEUP_TX0809\" )
					)
					( Units "uMatchProp" "ns" 1.000000)
					( Status sCSetFlattened )
					( Origin gBackEnd )
				)
			)
			( pinPair "@baseboard_fab2_lib.baseboard_fab2(sch_1):\PP383\"
				( pinRef "@baseboard_fab2_lib.baseboard_fab2(sch_1):page30_i84:PE1_TX_DN(9)" )
				( pinRef "@baseboard_fab2_lib.baseboard_fab2(sch_1):page105_i175:A" )
				( attribute "RELATIVE_PROPAGATION_DELAY_SCOPE" "L"
					( Parent
						( matchGroupRef "@baseboard_fab2_lib.baseboard_fab2(sch_1):\MG_PCIE_L1\" )
					)
					( Status sCSetFlattened )
					( Origin gBackEnd )
				)
				( attribute "RELATIVE_PROPAGATION_DELAY" ",5.00 MIL"
					( Parent
						( matchGroupRef "@baseboard_fab2_lib.baseboard_fab2(sch_1):\MG_PCIE_L1\" )
					)
					( Units "uMatchProp" "ns" 1.000000)
					( Status sCSetFlattened )
					( Origin gBackEnd )
				)
			)
			( pinPair "@baseboard_fab2_lib.baseboard_fab2(sch_1):\PP384\"
				( pinRef "@baseboard_fab2_lib.baseboard_fab2(sch_1):page105_i175:B" )
				( pinRef "@baseboard_fab2_lib.baseboard_fab2(sch_1):page117_i9:PCIEUP_9_RXP" )
				( attribute "RELATIVE_PROPAGATION_DELAY_SCOPE" "L"
					( Parent
						( matchGroupRef "@baseboard_fab2_lib.baseboard_fab2(sch_1):\MG_PCIE_L0\" )
					)
					( Status sCSetFlattened )
					( Origin gBackEnd )
				)
				( attribute "RELATIVE_PROPAGATION_DELAY" ",5.00 MIL"
					( Parent
						( matchGroupRef "@baseboard_fab2_lib.baseboard_fab2(sch_1):\MG_PCIE_L0\" )
					)
					( Units "uMatchProp" "ns" 1.000000)
					( Status sCSetFlattened )
					( Origin gBackEnd )
				)
			)
			( pinPair "@baseboard_fab2_lib.baseboard_fab2(sch_1):\PP5853\"
				( pinRef "@baseboard_fab2_lib.baseboard_fab2(sch_1):page30_i84:PE1_TX_DN(9)" )
				( pinRef "@baseboard_fab2_lib.baseboard_fab2(sch_1):page117_i9:PCIEUP_9_RXP" )
				( attribute "PROPAGATION_DELAY_MIN" "3000.00 MIL"
					( Units "uMaxMinProp" "ns" 1.000000)
					( Status sCSetFlattened )
					( Origin gBackEnd )
				)
				( attribute "PROPAGATION_DELAY_MAX" "17000.00 MIL"
					( Units "uMaxMinProp" "ns" 1.000000)
					( Status sCSetFlattened )
					( Origin gBackEnd )
				)
				( attribute "RELATIVE_PROPAGATION_DELAY_SCOPE" "G"
					( Parent
						( matchGroupRef "@baseboard_fab2_lib.baseboard_fab2(sch_1):\MG_P3E_CPU0_PE1_PCH_PCIEUP_TX0809\" )
					)
					( Status sCSetFlattened )
					( Origin gBackEnd )
				)
				( attribute "RELATIVE_PROPAGATION_DELAY" ",500.00 MIL"
					( Parent
						( matchGroupRef "@baseboard_fab2_lib.baseboard_fab2(sch_1):\MG_P3E_CPU0_PE1_PCH_PCIEUP_TX0809\" )
					)
					( Units "uMatchProp" "ns" 1.000000)
					( Status sCSetFlattened )
					( Origin gBackEnd )
				)
			)
			( pinPair "@baseboard_fab2_lib.baseboard_fab2(sch_1):\PP385\"
				( pinRef "@baseboard_fab2_lib.baseboard_fab2(sch_1):page105_i153:B" )
				( pinRef "@baseboard_fab2_lib.baseboard_fab2(sch_1):page117_i9:PCIEUP_9_RXN" )
				( attribute "RELATIVE_PROPAGATION_DELAY_SCOPE" "L"
					( Parent
						( matchGroupRef "@baseboard_fab2_lib.baseboard_fab2(sch_1):\MG_PCIE_L0\" )
					)
					( Status sCSetFlattened )
					( Origin gBackEnd )
				)
				( attribute "RELATIVE_PROPAGATION_DELAY" ",5.00 MIL"
					( Parent
						( matchGroupRef "@baseboard_fab2_lib.baseboard_fab2(sch_1):\MG_PCIE_L0\" )
					)
					( Units "uMatchProp" "ns" 1.000000)
					( Status sCSetFlattened )
					( Origin gBackEnd )
				)
			)
			( pinPair "@baseboard_fab2_lib.baseboard_fab2(sch_1):\PP386\"
				( pinRef "@baseboard_fab2_lib.baseboard_fab2(sch_1):page30_i84:PE1_TX_DP(9)" )
				( pinRef "@baseboard_fab2_lib.baseboard_fab2(sch_1):page105_i153:A" )
				( attribute "RELATIVE_PROPAGATION_DELAY_SCOPE" "L"
					( Parent
						( matchGroupRef "@baseboard_fab2_lib.baseboard_fab2(sch_1):\MG_PCIE_L1\" )
					)
					( Status sCSetFlattened )
					( Origin gBackEnd )
				)
				( attribute "RELATIVE_PROPAGATION_DELAY" ",5.00 MIL"
					( Parent
						( matchGroupRef "@baseboard_fab2_lib.baseboard_fab2(sch_1):\MG_PCIE_L1\" )
					)
					( Units "uMatchProp" "ns" 1.000000)
					( Status sCSetFlattened )
					( Origin gBackEnd )
				)
			)
			( pinPair "@baseboard_fab2_lib.baseboard_fab2(sch_1):\PP5851\"
				( pinRef "@baseboard_fab2_lib.baseboard_fab2(sch_1):page30_i84:PE1_TX_DP(9)" )
				( pinRef "@baseboard_fab2_lib.baseboard_fab2(sch_1):page117_i9:PCIEUP_9_RXN" )
				( attribute "PROPAGATION_DELAY_MIN" "3000.00 MIL"
					( Units "uMaxMinProp" "ns" 1.000000)
					( Status sCSetFlattened )
					( Origin gBackEnd )
				)
				( attribute "PROPAGATION_DELAY_MAX" "17000.00 MIL"
					( Units "uMaxMinProp" "ns" 1.000000)
					( Status sCSetFlattened )
					( Origin gBackEnd )
				)
				( attribute "RELATIVE_PROPAGATION_DELAY_SCOPE" "G"
					( Parent
						( matchGroupRef "@baseboard_fab2_lib.baseboard_fab2(sch_1):\MG_P3E_CPU0_PE1_PCH_PCIEUP_TX0809\" )
					)
					( Status sCSetFlattened )
					( Origin gBackEnd )
				)
				( attribute "RELATIVE_PROPAGATION_DELAY" ",500.00 MIL"
					( Parent
						( matchGroupRef "@baseboard_fab2_lib.baseboard_fab2(sch_1):\MG_P3E_CPU0_PE1_PCH_PCIEUP_TX0809\" )
					)
					( Units "uMatchProp" "ns" 1.000000)
					( Status sCSetFlattened )
					( Origin gBackEnd )
				)
			)
			( pinPair "@baseboard_fab2_lib.baseboard_fab2(sch_1):\PP379\"
				( pinRef "@baseboard_fab2_lib.baseboard_fab2(sch_1):page30_i84:PE1_TX_DN(10)" )
				( pinRef "@baseboard_fab2_lib.baseboard_fab2(sch_1):page105_i163:A" )
				( attribute "RELATIVE_PROPAGATION_DELAY_SCOPE" "L"
					( Parent
						( matchGroupRef "@baseboard_fab2_lib.baseboard_fab2(sch_1):\MG_PCIE_L1\" )
					)
					( Status sCSetFlattened )
					( Origin gBackEnd )
				)
				( attribute "RELATIVE_PROPAGATION_DELAY" ",5.00 MIL"
					( Parent
						( matchGroupRef "@baseboard_fab2_lib.baseboard_fab2(sch_1):\MG_PCIE_L1\" )
					)
					( Units "uMatchProp" "ns" 1.000000)
					( Status sCSetFlattened )
					( Origin gBackEnd )
				)
			)
			( pinPair "@baseboard_fab2_lib.baseboard_fab2(sch_1):\PP380\"
				( pinRef "@baseboard_fab2_lib.baseboard_fab2(sch_1):page105_i163:B" )
				( pinRef "@baseboard_fab2_lib.baseboard_fab2(sch_1):page117_i9:PCIEUP_10_RXP" )
				( attribute "RELATIVE_PROPAGATION_DELAY_SCOPE" "L"
					( Parent
						( matchGroupRef "@baseboard_fab2_lib.baseboard_fab2(sch_1):\MG_PCIE_L0\" )
					)
					( Status sCSetFlattened )
					( Origin gBackEnd )
				)
				( attribute "RELATIVE_PROPAGATION_DELAY" ",5.00 MIL"
					( Parent
						( matchGroupRef "@baseboard_fab2_lib.baseboard_fab2(sch_1):\MG_PCIE_L0\" )
					)
					( Units "uMatchProp" "ns" 1.000000)
					( Status sCSetFlattened )
					( Origin gBackEnd )
				)
			)
			( pinPair "@baseboard_fab2_lib.baseboard_fab2(sch_1):\PP5855\"
				( pinRef "@baseboard_fab2_lib.baseboard_fab2(sch_1):page30_i84:PE1_TX_DN(10)" )
				( pinRef "@baseboard_fab2_lib.baseboard_fab2(sch_1):page117_i9:PCIEUP_10_RXP" )
				( attribute "PROPAGATION_DELAY_MIN" "3000.00 MIL"
					( Units "uMaxMinProp" "ns" 1.000000)
					( Status sCSetFlattened )
					( Origin gBackEnd )
				)
				( attribute "PROPAGATION_DELAY_MAX" "17000.00 MIL"
					( Units "uMaxMinProp" "ns" 1.000000)
					( Status sCSetFlattened )
					( Origin gBackEnd )
				)
				( attribute "RELATIVE_PROPAGATION_DELAY_SCOPE" "G"
					( Parent
						( matchGroupRef "@baseboard_fab2_lib.baseboard_fab2(sch_1):\MG_P3E_CPU0_PE1_PCH_PCIEUP_TX1011\" )
					)
					( Status sCSetFlattened )
					( Origin gBackEnd )
				)
				( attribute "RELATIVE_PROPAGATION_DELAY" ",500.00 MIL"
					( Parent
						( matchGroupRef "@baseboard_fab2_lib.baseboard_fab2(sch_1):\MG_P3E_CPU0_PE1_PCH_PCIEUP_TX1011\" )
					)
					( Units "uMatchProp" "ns" 1.000000)
					( Status sCSetFlattened )
					( Origin gBackEnd )
				)
			)
			( pinPair "@baseboard_fab2_lib.baseboard_fab2(sch_1):\PP381\"
				( pinRef "@baseboard_fab2_lib.baseboard_fab2(sch_1):page105_i180:B" )
				( pinRef "@baseboard_fab2_lib.baseboard_fab2(sch_1):page117_i9:PCIEUP_10_RXN" )
				( attribute "RELATIVE_PROPAGATION_DELAY_SCOPE" "L"
					( Parent
						( matchGroupRef "@baseboard_fab2_lib.baseboard_fab2(sch_1):\MG_PCIE_L0\" )
					)
					( Status sCSetFlattened )
					( Origin gBackEnd )
				)
				( attribute "RELATIVE_PROPAGATION_DELAY" ",5.00 MIL"
					( Parent
						( matchGroupRef "@baseboard_fab2_lib.baseboard_fab2(sch_1):\MG_PCIE_L0\" )
					)
					( Units "uMatchProp" "ns" 1.000000)
					( Status sCSetFlattened )
					( Origin gBackEnd )
				)
			)
			( pinPair "@baseboard_fab2_lib.baseboard_fab2(sch_1):\PP382\"
				( pinRef "@baseboard_fab2_lib.baseboard_fab2(sch_1):page30_i84:PE1_TX_DP(10)" )
				( pinRef "@baseboard_fab2_lib.baseboard_fab2(sch_1):page105_i180:A" )
				( attribute "RELATIVE_PROPAGATION_DELAY_SCOPE" "L"
					( Parent
						( matchGroupRef "@baseboard_fab2_lib.baseboard_fab2(sch_1):\MG_PCIE_L1\" )
					)
					( Status sCSetFlattened )
					( Origin gBackEnd )
				)
				( attribute "RELATIVE_PROPAGATION_DELAY" ",5.00 MIL"
					( Parent
						( matchGroupRef "@baseboard_fab2_lib.baseboard_fab2(sch_1):\MG_PCIE_L1\" )
					)
					( Units "uMatchProp" "ns" 1.000000)
					( Status sCSetFlattened )
					( Origin gBackEnd )
				)
			)
			( pinPair "@baseboard_fab2_lib.baseboard_fab2(sch_1):\PP5854\"
				( pinRef "@baseboard_fab2_lib.baseboard_fab2(sch_1):page30_i84:PE1_TX_DP(10)" )
				( pinRef "@baseboard_fab2_lib.baseboard_fab2(sch_1):page117_i9:PCIEUP_10_RXN" )
				( attribute "PROPAGATION_DELAY_MIN" "3000.00 MIL"
					( Units "uMaxMinProp" "ns" 1.000000)
					( Status sCSetFlattened )
					( Origin gBackEnd )
				)
				( attribute "PROPAGATION_DELAY_MAX" "17000.00 MIL"
					( Units "uMaxMinProp" "ns" 1.000000)
					( Status sCSetFlattened )
					( Origin gBackEnd )
				)
				( attribute "RELATIVE_PROPAGATION_DELAY_SCOPE" "G"
					( Parent
						( matchGroupRef "@baseboard_fab2_lib.baseboard_fab2(sch_1):\MG_P3E_CPU0_PE1_PCH_PCIEUP_TX1011\" )
					)
					( Status sCSetFlattened )
					( Origin gBackEnd )
				)
				( attribute "RELATIVE_PROPAGATION_DELAY" ",500.00 MIL"
					( Parent
						( matchGroupRef "@baseboard_fab2_lib.baseboard_fab2(sch_1):\MG_P3E_CPU0_PE1_PCH_PCIEUP_TX1011\" )
					)
					( Units "uMatchProp" "ns" 1.000000)
					( Status sCSetFlattened )
					( Origin gBackEnd )
				)
			)
			( pinPair "@baseboard_fab2_lib.baseboard_fab2(sch_1):\PP375\"
				( pinRef "@baseboard_fab2_lib.baseboard_fab2(sch_1):page30_i84:PE1_TX_DN(11)" )
				( pinRef "@baseboard_fab2_lib.baseboard_fab2(sch_1):page105_i181:A" )
				( attribute "RELATIVE_PROPAGATION_DELAY_SCOPE" "L"
					( Parent
						( matchGroupRef "@baseboard_fab2_lib.baseboard_fab2(sch_1):\MG_PCIE_L1\" )
					)
					( Status sCSetFlattened )
					( Origin gBackEnd )
				)
				( attribute "RELATIVE_PROPAGATION_DELAY" ",5.00 MIL"
					( Parent
						( matchGroupRef "@baseboard_fab2_lib.baseboard_fab2(sch_1):\MG_PCIE_L1\" )
					)
					( Units "uMatchProp" "ns" 1.000000)
					( Status sCSetFlattened )
					( Origin gBackEnd )
				)
			)
			( pinPair "@baseboard_fab2_lib.baseboard_fab2(sch_1):\PP376\"
				( pinRef "@baseboard_fab2_lib.baseboard_fab2(sch_1):page105_i181:B" )
				( pinRef "@baseboard_fab2_lib.baseboard_fab2(sch_1):page117_i9:PCIEUP_11_RXN" )
				( attribute "RELATIVE_PROPAGATION_DELAY_SCOPE" "L"
					( Parent
						( matchGroupRef "@baseboard_fab2_lib.baseboard_fab2(sch_1):\MG_PCIE_L0\" )
					)
					( Status sCSetFlattened )
					( Origin gBackEnd )
				)
				( attribute "RELATIVE_PROPAGATION_DELAY" ",5.00 MIL"
					( Parent
						( matchGroupRef "@baseboard_fab2_lib.baseboard_fab2(sch_1):\MG_PCIE_L0\" )
					)
					( Units "uMatchProp" "ns" 1.000000)
					( Status sCSetFlattened )
					( Origin gBackEnd )
				)
			)
			( pinPair "@baseboard_fab2_lib.baseboard_fab2(sch_1):\PP5849\"
				( pinRef "@baseboard_fab2_lib.baseboard_fab2(sch_1):page30_i84:PE1_TX_DN(11)" )
				( pinRef "@baseboard_fab2_lib.baseboard_fab2(sch_1):page117_i9:PCIEUP_11_RXN" )
				( attribute "PROPAGATION_DELAY_MIN" "3000.00 MIL"
					( Units "uMaxMinProp" "ns" 1.000000)
					( Status sCSetFlattened )
					( Origin gBackEnd )
				)
				( attribute "PROPAGATION_DELAY_MAX" "17000.00 MIL"
					( Units "uMaxMinProp" "ns" 1.000000)
					( Status sCSetFlattened )
					( Origin gBackEnd )
				)
				( attribute "RELATIVE_PROPAGATION_DELAY_SCOPE" "G"
					( Parent
						( matchGroupRef "@baseboard_fab2_lib.baseboard_fab2(sch_1):\MG_P3E_CPU0_PE1_PCH_PCIEUP_TX1011\" )
					)
					( Status sCSetFlattened )
					( Origin gBackEnd )
				)
				( attribute "RELATIVE_PROPAGATION_DELAY" ",500.00 MIL"
					( Parent
						( matchGroupRef "@baseboard_fab2_lib.baseboard_fab2(sch_1):\MG_P3E_CPU0_PE1_PCH_PCIEUP_TX1011\" )
					)
					( Units "uMatchProp" "ns" 1.000000)
					( Status sCSetFlattened )
					( Origin gBackEnd )
				)
			)
			( pinPair "@baseboard_fab2_lib.baseboard_fab2(sch_1):\PP377\"
				( pinRef "@baseboard_fab2_lib.baseboard_fab2(sch_1):page105_i189:B" )
				( pinRef "@baseboard_fab2_lib.baseboard_fab2(sch_1):page117_i9:PCIEUP_11_RXP" )
				( attribute "RELATIVE_PROPAGATION_DELAY_SCOPE" "L"
					( Parent
						( matchGroupRef "@baseboard_fab2_lib.baseboard_fab2(sch_1):\MG_PCIE_L0\" )
					)
					( Status sCSetFlattened )
					( Origin gBackEnd )
				)
				( attribute "RELATIVE_PROPAGATION_DELAY" ",5.00 MIL"
					( Parent
						( matchGroupRef "@baseboard_fab2_lib.baseboard_fab2(sch_1):\MG_PCIE_L0\" )
					)
					( Units "uMatchProp" "ns" 1.000000)
					( Status sCSetFlattened )
					( Origin gBackEnd )
				)
			)
			( pinPair "@baseboard_fab2_lib.baseboard_fab2(sch_1):\PP378\"
				( pinRef "@baseboard_fab2_lib.baseboard_fab2(sch_1):page30_i84:PE1_TX_DP(11)" )
				( pinRef "@baseboard_fab2_lib.baseboard_fab2(sch_1):page105_i189:A" )
				( attribute "RELATIVE_PROPAGATION_DELAY_SCOPE" "L"
					( Parent
						( matchGroupRef "@baseboard_fab2_lib.baseboard_fab2(sch_1):\MG_PCIE_L1\" )
					)
					( Status sCSetFlattened )
					( Origin gBackEnd )
				)
				( attribute "RELATIVE_PROPAGATION_DELAY" ",5.00 MIL"
					( Parent
						( matchGroupRef "@baseboard_fab2_lib.baseboard_fab2(sch_1):\MG_PCIE_L1\" )
					)
					( Units "uMatchProp" "ns" 1.000000)
					( Status sCSetFlattened )
					( Origin gBackEnd )
				)
			)
			( pinPair "@baseboard_fab2_lib.baseboard_fab2(sch_1):\PP5856\"
				( pinRef "@baseboard_fab2_lib.baseboard_fab2(sch_1):page30_i84:PE1_TX_DP(11)" )
				( pinRef "@baseboard_fab2_lib.baseboard_fab2(sch_1):page117_i9:PCIEUP_11_RXP" )
				( attribute "PROPAGATION_DELAY_MIN" "3000.00 MIL"
					( Units "uMaxMinProp" "ns" 1.000000)
					( Status sCSetFlattened )
					( Origin gBackEnd )
				)
				( attribute "PROPAGATION_DELAY_MAX" "17000.00 MIL"
					( Units "uMaxMinProp" "ns" 1.000000)
					( Status sCSetFlattened )
					( Origin gBackEnd )
				)
				( attribute "RELATIVE_PROPAGATION_DELAY_SCOPE" "G"
					( Parent
						( matchGroupRef "@baseboard_fab2_lib.baseboard_fab2(sch_1):\MG_P3E_CPU0_PE1_PCH_PCIEUP_TX1011\" )
					)
					( Status sCSetFlattened )
					( Origin gBackEnd )
				)
				( attribute "RELATIVE_PROPAGATION_DELAY" ",500.00 MIL"
					( Parent
						( matchGroupRef "@baseboard_fab2_lib.baseboard_fab2(sch_1):\MG_P3E_CPU0_PE1_PCH_PCIEUP_TX1011\" )
					)
					( Units "uMatchProp" "ns" 1.000000)
					( Status sCSetFlattened )
					( Origin gBackEnd )
				)
			)
			( pinPair "@baseboard_fab2_lib.baseboard_fab2(sch_1):\PP371\"
				( pinRef "@baseboard_fab2_lib.baseboard_fab2(sch_1):page30_i84:PE1_TX_DN(12)" )
				( pinRef "@baseboard_fab2_lib.baseboard_fab2(sch_1):page105_i166:A" )
				( attribute "RELATIVE_PROPAGATION_DELAY_SCOPE" "L"
					( Parent
						( matchGroupRef "@baseboard_fab2_lib.baseboard_fab2(sch_1):\MG_PCIE_L1\" )
					)
					( Status sCSetFlattened )
					( Origin gBackEnd )
				)
				( attribute "RELATIVE_PROPAGATION_DELAY" ",5.00 MIL"
					( Parent
						( matchGroupRef "@baseboard_fab2_lib.baseboard_fab2(sch_1):\MG_PCIE_L1\" )
					)
					( Units "uMatchProp" "ns" 1.000000)
					( Status sCSetFlattened )
					( Origin gBackEnd )
				)
			)
			( pinPair "@baseboard_fab2_lib.baseboard_fab2(sch_1):\PP372\"
				( pinRef "@baseboard_fab2_lib.baseboard_fab2(sch_1):page105_i166:B" )
				( pinRef "@baseboard_fab2_lib.baseboard_fab2(sch_1):page117_i9:PCIEUP_12_RXP" )
				( attribute "RELATIVE_PROPAGATION_DELAY_SCOPE" "L"
					( Parent
						( matchGroupRef "@baseboard_fab2_lib.baseboard_fab2(sch_1):\MG_PCIE_L0\" )
					)
					( Status sCSetFlattened )
					( Origin gBackEnd )
				)
				( attribute "RELATIVE_PROPAGATION_DELAY" ",5.00 MIL"
					( Parent
						( matchGroupRef "@baseboard_fab2_lib.baseboard_fab2(sch_1):\MG_PCIE_L0\" )
					)
					( Units "uMatchProp" "ns" 1.000000)
					( Status sCSetFlattened )
					( Origin gBackEnd )
				)
			)
			( pinPair "@baseboard_fab2_lib.baseboard_fab2(sch_1):\PP5859\"
				( pinRef "@baseboard_fab2_lib.baseboard_fab2(sch_1):page30_i84:PE1_TX_DN(12)" )
				( pinRef "@baseboard_fab2_lib.baseboard_fab2(sch_1):page117_i9:PCIEUP_12_RXP" )
				( attribute "PROPAGATION_DELAY_MIN" "3000.00 MIL"
					( Units "uMaxMinProp" "ns" 1.000000)
					( Status sCSetFlattened )
					( Origin gBackEnd )
				)
				( attribute "PROPAGATION_DELAY_MAX" "17000.00 MIL"
					( Units "uMaxMinProp" "ns" 1.000000)
					( Status sCSetFlattened )
					( Origin gBackEnd )
				)
				( attribute "RELATIVE_PROPAGATION_DELAY_SCOPE" "G"
					( Parent
						( matchGroupRef "@baseboard_fab2_lib.baseboard_fab2(sch_1):\MG_P3E_CPU0_PE1_PCH_PCIEUP_TX1213\" )
					)
					( Status sCSetFlattened )
					( Origin gBackEnd )
				)
				( attribute "RELATIVE_PROPAGATION_DELAY" ",500.00 MIL"
					( Parent
						( matchGroupRef "@baseboard_fab2_lib.baseboard_fab2(sch_1):\MG_P3E_CPU0_PE1_PCH_PCIEUP_TX1213\" )
					)
					( Units "uMatchProp" "ns" 1.000000)
					( Status sCSetFlattened )
					( Origin gBackEnd )
				)
			)
			( pinPair "@baseboard_fab2_lib.baseboard_fab2(sch_1):\PP373\"
				( pinRef "@baseboard_fab2_lib.baseboard_fab2(sch_1):page105_i187:B" )
				( pinRef "@baseboard_fab2_lib.baseboard_fab2(sch_1):page117_i9:PCIEUP_12_RXN" )
				( attribute "RELATIVE_PROPAGATION_DELAY_SCOPE" "L"
					( Parent
						( matchGroupRef "@baseboard_fab2_lib.baseboard_fab2(sch_1):\MG_PCIE_L0\" )
					)
					( Status sCSetFlattened )
					( Origin gBackEnd )
				)
				( attribute "RELATIVE_PROPAGATION_DELAY" ",5.00 MIL"
					( Parent
						( matchGroupRef "@baseboard_fab2_lib.baseboard_fab2(sch_1):\MG_PCIE_L0\" )
					)
					( Units "uMatchProp" "ns" 1.000000)
					( Status sCSetFlattened )
					( Origin gBackEnd )
				)
			)
			( pinPair "@baseboard_fab2_lib.baseboard_fab2(sch_1):\PP374\"
				( pinRef "@baseboard_fab2_lib.baseboard_fab2(sch_1):page30_i84:PE1_TX_DP(12)" )
				( pinRef "@baseboard_fab2_lib.baseboard_fab2(sch_1):page105_i187:A" )
				( attribute "RELATIVE_PROPAGATION_DELAY_SCOPE" "L"
					( Parent
						( matchGroupRef "@baseboard_fab2_lib.baseboard_fab2(sch_1):\MG_PCIE_L1\" )
					)
					( Status sCSetFlattened )
					( Origin gBackEnd )
				)
				( attribute "RELATIVE_PROPAGATION_DELAY" ",5.00 MIL"
					( Parent
						( matchGroupRef "@baseboard_fab2_lib.baseboard_fab2(sch_1):\MG_PCIE_L1\" )
					)
					( Units "uMatchProp" "ns" 1.000000)
					( Status sCSetFlattened )
					( Origin gBackEnd )
				)
			)
			( pinPair "@baseboard_fab2_lib.baseboard_fab2(sch_1):\PP5850\"
				( pinRef "@baseboard_fab2_lib.baseboard_fab2(sch_1):page30_i84:PE1_TX_DP(12)" )
				( pinRef "@baseboard_fab2_lib.baseboard_fab2(sch_1):page117_i9:PCIEUP_12_RXN" )
				( attribute "PROPAGATION_DELAY_MIN" "3000.00 MIL"
					( Units "uMaxMinProp" "ns" 1.000000)
					( Status sCSetFlattened )
					( Origin gBackEnd )
				)
				( attribute "PROPAGATION_DELAY_MAX" "17000.00 MIL"
					( Units "uMaxMinProp" "ns" 1.000000)
					( Status sCSetFlattened )
					( Origin gBackEnd )
				)
				( attribute "RELATIVE_PROPAGATION_DELAY_SCOPE" "G"
					( Parent
						( matchGroupRef "@baseboard_fab2_lib.baseboard_fab2(sch_1):\MG_P3E_CPU0_PE1_PCH_PCIEUP_TX1213\" )
					)
					( Status sCSetFlattened )
					( Origin gBackEnd )
				)
				( attribute "RELATIVE_PROPAGATION_DELAY" ",500.00 MIL"
					( Parent
						( matchGroupRef "@baseboard_fab2_lib.baseboard_fab2(sch_1):\MG_P3E_CPU0_PE1_PCH_PCIEUP_TX1213\" )
					)
					( Units "uMatchProp" "ns" 1.000000)
					( Status sCSetFlattened )
					( Origin gBackEnd )
				)
			)
			( pinPair "@baseboard_fab2_lib.baseboard_fab2(sch_1):\PP367\"
				( pinRef "@baseboard_fab2_lib.baseboard_fab2(sch_1):page30_i84:PE1_TX_DN(13)" )
				( pinRef "@baseboard_fab2_lib.baseboard_fab2(sch_1):page105_i185:A" )
				( attribute "RELATIVE_PROPAGATION_DELAY_SCOPE" "L"
					( Parent
						( matchGroupRef "@baseboard_fab2_lib.baseboard_fab2(sch_1):\MG_PCIE_L1\" )
					)
					( Status sCSetFlattened )
					( Origin gBackEnd )
				)
				( attribute "RELATIVE_PROPAGATION_DELAY" ",5.00 MIL"
					( Parent
						( matchGroupRef "@baseboard_fab2_lib.baseboard_fab2(sch_1):\MG_PCIE_L1\" )
					)
					( Units "uMatchProp" "ns" 1.000000)
					( Status sCSetFlattened )
					( Origin gBackEnd )
				)
			)
			( pinPair "@baseboard_fab2_lib.baseboard_fab2(sch_1):\PP368\"
				( pinRef "@baseboard_fab2_lib.baseboard_fab2(sch_1):page105_i185:B" )
				( pinRef "@baseboard_fab2_lib.baseboard_fab2(sch_1):page117_i9:PCIEUP_13_RXP" )
				( attribute "RELATIVE_PROPAGATION_DELAY_SCOPE" "L"
					( Parent
						( matchGroupRef "@baseboard_fab2_lib.baseboard_fab2(sch_1):\MG_PCIE_L0\" )
					)
					( Status sCSetFlattened )
					( Origin gBackEnd )
				)
				( attribute "RELATIVE_PROPAGATION_DELAY" ",5.00 MIL"
					( Parent
						( matchGroupRef "@baseboard_fab2_lib.baseboard_fab2(sch_1):\MG_PCIE_L0\" )
					)
					( Units "uMatchProp" "ns" 1.000000)
					( Status sCSetFlattened )
					( Origin gBackEnd )
				)
			)
			( pinPair "@baseboard_fab2_lib.baseboard_fab2(sch_1):\PP5860\"
				( pinRef "@baseboard_fab2_lib.baseboard_fab2(sch_1):page30_i84:PE1_TX_DN(13)" )
				( pinRef "@baseboard_fab2_lib.baseboard_fab2(sch_1):page117_i9:PCIEUP_13_RXP" )
				( attribute "PROPAGATION_DELAY_MIN" "3000.00 MIL"
					( Units "uMaxMinProp" "ns" 1.000000)
					( Status sCSetFlattened )
					( Origin gBackEnd )
				)
				( attribute "PROPAGATION_DELAY_MAX" "17000.00 MIL"
					( Units "uMaxMinProp" "ns" 1.000000)
					( Status sCSetFlattened )
					( Origin gBackEnd )
				)
				( attribute "RELATIVE_PROPAGATION_DELAY_SCOPE" "G"
					( Parent
						( matchGroupRef "@baseboard_fab2_lib.baseboard_fab2(sch_1):\MG_P3E_CPU0_PE1_PCH_PCIEUP_TX1213\" )
					)
					( Status sCSetFlattened )
					( Origin gBackEnd )
				)
				( attribute "RELATIVE_PROPAGATION_DELAY" ",500.00 MIL"
					( Parent
						( matchGroupRef "@baseboard_fab2_lib.baseboard_fab2(sch_1):\MG_P3E_CPU0_PE1_PCH_PCIEUP_TX1213\" )
					)
					( Units "uMatchProp" "ns" 1.000000)
					( Status sCSetFlattened )
					( Origin gBackEnd )
				)
			)
			( pinPair "@baseboard_fab2_lib.baseboard_fab2(sch_1):\PP369\"
				( pinRef "@baseboard_fab2_lib.baseboard_fab2(sch_1):page105_i193:B" )
				( pinRef "@baseboard_fab2_lib.baseboard_fab2(sch_1):page117_i9:PCIEUP_13_RXN" )
				( attribute "RELATIVE_PROPAGATION_DELAY_SCOPE" "L"
					( Parent
						( matchGroupRef "@baseboard_fab2_lib.baseboard_fab2(sch_1):\MG_PCIE_L0\" )
					)
					( Status sCSetFlattened )
					( Origin gBackEnd )
				)
				( attribute "RELATIVE_PROPAGATION_DELAY" ",5.00 MIL"
					( Parent
						( matchGroupRef "@baseboard_fab2_lib.baseboard_fab2(sch_1):\MG_PCIE_L0\" )
					)
					( Units "uMatchProp" "ns" 1.000000)
					( Status sCSetFlattened )
					( Origin gBackEnd )
				)
			)
			( pinPair "@baseboard_fab2_lib.baseboard_fab2(sch_1):\PP370\"
				( pinRef "@baseboard_fab2_lib.baseboard_fab2(sch_1):page30_i84:PE1_TX_DP(13)" )
				( pinRef "@baseboard_fab2_lib.baseboard_fab2(sch_1):page105_i193:A" )
				( attribute "RELATIVE_PROPAGATION_DELAY_SCOPE" "L"
					( Parent
						( matchGroupRef "@baseboard_fab2_lib.baseboard_fab2(sch_1):\MG_PCIE_L1\" )
					)
					( Status sCSetFlattened )
					( Origin gBackEnd )
				)
				( attribute "RELATIVE_PROPAGATION_DELAY" ",5.00 MIL"
					( Parent
						( matchGroupRef "@baseboard_fab2_lib.baseboard_fab2(sch_1):\MG_PCIE_L1\" )
					)
					( Units "uMatchProp" "ns" 1.000000)
					( Status sCSetFlattened )
					( Origin gBackEnd )
				)
			)
			( pinPair "@baseboard_fab2_lib.baseboard_fab2(sch_1):\PP5858\"
				( pinRef "@baseboard_fab2_lib.baseboard_fab2(sch_1):page30_i84:PE1_TX_DP(13)" )
				( pinRef "@baseboard_fab2_lib.baseboard_fab2(sch_1):page117_i9:PCIEUP_13_RXN" )
				( attribute "PROPAGATION_DELAY_MIN" "3000.00 MIL"
					( Units "uMaxMinProp" "ns" 1.000000)
					( Status sCSetFlattened )
					( Origin gBackEnd )
				)
				( attribute "PROPAGATION_DELAY_MAX" "17000.00 MIL"
					( Units "uMaxMinProp" "ns" 1.000000)
					( Status sCSetFlattened )
					( Origin gBackEnd )
				)
				( attribute "RELATIVE_PROPAGATION_DELAY_SCOPE" "G"
					( Parent
						( matchGroupRef "@baseboard_fab2_lib.baseboard_fab2(sch_1):\MG_P3E_CPU0_PE1_PCH_PCIEUP_TX1213\" )
					)
					( Status sCSetFlattened )
					( Origin gBackEnd )
				)
				( attribute "RELATIVE_PROPAGATION_DELAY" ",500.00 MIL"
					( Parent
						( matchGroupRef "@baseboard_fab2_lib.baseboard_fab2(sch_1):\MG_P3E_CPU0_PE1_PCH_PCIEUP_TX1213\" )
					)
					( Units "uMatchProp" "ns" 1.000000)
					( Status sCSetFlattened )
					( Origin gBackEnd )
				)
			)
			( pinPair "@baseboard_fab2_lib.baseboard_fab2(sch_1):\PP363\"
				( pinRef "@baseboard_fab2_lib.baseboard_fab2(sch_1):page30_i84:PE1_TX_DN(14)" )
				( pinRef "@baseboard_fab2_lib.baseboard_fab2(sch_1):page105_i169:A" )
				( attribute "RELATIVE_PROPAGATION_DELAY_SCOPE" "L"
					( Parent
						( matchGroupRef "@baseboard_fab2_lib.baseboard_fab2(sch_1):\MG_PCIE_L1\" )
					)
					( Status sCSetFlattened )
					( Origin gBackEnd )
				)
				( attribute "RELATIVE_PROPAGATION_DELAY" ",5.00 MIL"
					( Parent
						( matchGroupRef "@baseboard_fab2_lib.baseboard_fab2(sch_1):\MG_PCIE_L1\" )
					)
					( Units "uMatchProp" "ns" 1.000000)
					( Status sCSetFlattened )
					( Origin gBackEnd )
				)
			)
			( pinPair "@baseboard_fab2_lib.baseboard_fab2(sch_1):\PP364\"
				( pinRef "@baseboard_fab2_lib.baseboard_fab2(sch_1):page105_i169:B" )
				( pinRef "@baseboard_fab2_lib.baseboard_fab2(sch_1):page117_i9:PCIEUP_14_RXP" )
				( attribute "RELATIVE_PROPAGATION_DELAY_SCOPE" "L"
					( Parent
						( matchGroupRef "@baseboard_fab2_lib.baseboard_fab2(sch_1):\MG_PCIE_L0\" )
					)
					( Status sCSetFlattened )
					( Origin gBackEnd )
				)
				( attribute "RELATIVE_PROPAGATION_DELAY" ",5.00 MIL"
					( Parent
						( matchGroupRef "@baseboard_fab2_lib.baseboard_fab2(sch_1):\MG_PCIE_L0\" )
					)
					( Units "uMatchProp" "ns" 1.000000)
					( Status sCSetFlattened )
					( Origin gBackEnd )
				)
			)
			( pinPair "@baseboard_fab2_lib.baseboard_fab2(sch_1):\PP5863\"
				( pinRef "@baseboard_fab2_lib.baseboard_fab2(sch_1):page30_i84:PE1_TX_DN(14)" )
				( pinRef "@baseboard_fab2_lib.baseboard_fab2(sch_1):page117_i9:PCIEUP_14_RXP" )
				( attribute "PROPAGATION_DELAY_MIN" "3000.00 MIL"
					( Units "uMaxMinProp" "ns" 1.000000)
					( Status sCSetFlattened )
					( Origin gBackEnd )
				)
				( attribute "PROPAGATION_DELAY_MAX" "17000.00 MIL"
					( Units "uMaxMinProp" "ns" 1.000000)
					( Status sCSetFlattened )
					( Origin gBackEnd )
				)
				( attribute "RELATIVE_PROPAGATION_DELAY_SCOPE" "G"
					( Parent
						( matchGroupRef "@baseboard_fab2_lib.baseboard_fab2(sch_1):\MG_P3E_CPU0_PE1_PCH_PCIEUP_TX1415\" )
					)
					( Status sCSetFlattened )
					( Origin gBackEnd )
				)
				( attribute "RELATIVE_PROPAGATION_DELAY" ",500.00 MIL"
					( Parent
						( matchGroupRef "@baseboard_fab2_lib.baseboard_fab2(sch_1):\MG_P3E_CPU0_PE1_PCH_PCIEUP_TX1415\" )
					)
					( Units "uMatchProp" "ns" 1.000000)
					( Status sCSetFlattened )
					( Origin gBackEnd )
				)
			)
			( pinPair "@baseboard_fab2_lib.baseboard_fab2(sch_1):\PP365\"
				( pinRef "@baseboard_fab2_lib.baseboard_fab2(sch_1):page105_i198:B" )
				( pinRef "@baseboard_fab2_lib.baseboard_fab2(sch_1):page117_i9:PCIEUP_14_RXN" )
				( attribute "RELATIVE_PROPAGATION_DELAY_SCOPE" "L"
					( Parent
						( matchGroupRef "@baseboard_fab2_lib.baseboard_fab2(sch_1):\MG_PCIE_L0\" )
					)
					( Status sCSetFlattened )
					( Origin gBackEnd )
				)
				( attribute "RELATIVE_PROPAGATION_DELAY" ",5.00 MIL"
					( Parent
						( matchGroupRef "@baseboard_fab2_lib.baseboard_fab2(sch_1):\MG_PCIE_L0\" )
					)
					( Units "uMatchProp" "ns" 1.000000)
					( Status sCSetFlattened )
					( Origin gBackEnd )
				)
			)
			( pinPair "@baseboard_fab2_lib.baseboard_fab2(sch_1):\PP366\"
				( pinRef "@baseboard_fab2_lib.baseboard_fab2(sch_1):page30_i84:PE1_TX_DP(14)" )
				( pinRef "@baseboard_fab2_lib.baseboard_fab2(sch_1):page105_i198:A" )
				( attribute "RELATIVE_PROPAGATION_DELAY_SCOPE" "L"
					( Parent
						( matchGroupRef "@baseboard_fab2_lib.baseboard_fab2(sch_1):\MG_PCIE_L1\" )
					)
					( Status sCSetFlattened )
					( Origin gBackEnd )
				)
				( attribute "RELATIVE_PROPAGATION_DELAY" ",5.00 MIL"
					( Parent
						( matchGroupRef "@baseboard_fab2_lib.baseboard_fab2(sch_1):\MG_PCIE_L1\" )
					)
					( Units "uMatchProp" "ns" 1.000000)
					( Status sCSetFlattened )
					( Origin gBackEnd )
				)
			)
			( pinPair "@baseboard_fab2_lib.baseboard_fab2(sch_1):\PP5861\"
				( pinRef "@baseboard_fab2_lib.baseboard_fab2(sch_1):page30_i84:PE1_TX_DP(14)" )
				( pinRef "@baseboard_fab2_lib.baseboard_fab2(sch_1):page117_i9:PCIEUP_14_RXN" )
				( attribute "PROPAGATION_DELAY_MIN" "3000.00 MIL"
					( Units "uMaxMinProp" "ns" 1.000000)
					( Status sCSetFlattened )
					( Origin gBackEnd )
				)
				( attribute "PROPAGATION_DELAY_MAX" "17000.00 MIL"
					( Units "uMaxMinProp" "ns" 1.000000)
					( Status sCSetFlattened )
					( Origin gBackEnd )
				)
				( attribute "RELATIVE_PROPAGATION_DELAY_SCOPE" "G"
					( Parent
						( matchGroupRef "@baseboard_fab2_lib.baseboard_fab2(sch_1):\MG_P3E_CPU0_PE1_PCH_PCIEUP_TX1415\" )
					)
					( Status sCSetFlattened )
					( Origin gBackEnd )
				)
				( attribute "RELATIVE_PROPAGATION_DELAY" ",500.00 MIL"
					( Parent
						( matchGroupRef "@baseboard_fab2_lib.baseboard_fab2(sch_1):\MG_P3E_CPU0_PE1_PCH_PCIEUP_TX1415\" )
					)
					( Units "uMatchProp" "ns" 1.000000)
					( Status sCSetFlattened )
					( Origin gBackEnd )
				)
			)
			( pinPair "@baseboard_fab2_lib.baseboard_fab2(sch_1):\PP359\"
				( pinRef "@baseboard_fab2_lib.baseboard_fab2(sch_1):page30_i84:PE1_TX_DN(15)" )
				( pinRef "@baseboard_fab2_lib.baseboard_fab2(sch_1):page105_i196:A" )
				( attribute "RELATIVE_PROPAGATION_DELAY_SCOPE" "L"
					( Parent
						( matchGroupRef "@baseboard_fab2_lib.baseboard_fab2(sch_1):\MG_PCIE_L1\" )
					)
					( Status sCSetFlattened )
					( Origin gBackEnd )
				)
				( attribute "RELATIVE_PROPAGATION_DELAY" ",5.00 MIL"
					( Parent
						( matchGroupRef "@baseboard_fab2_lib.baseboard_fab2(sch_1):\MG_PCIE_L1\" )
					)
					( Units "uMatchProp" "ns" 1.000000)
					( Status sCSetFlattened )
					( Origin gBackEnd )
				)
			)
			( pinPair "@baseboard_fab2_lib.baseboard_fab2(sch_1):\PP360\"
				( pinRef "@baseboard_fab2_lib.baseboard_fab2(sch_1):page105_i196:B" )
				( pinRef "@baseboard_fab2_lib.baseboard_fab2(sch_1):page117_i9:PCIEUP_15_RXP" )
				( attribute "RELATIVE_PROPAGATION_DELAY_SCOPE" "L"
					( Parent
						( matchGroupRef "@baseboard_fab2_lib.baseboard_fab2(sch_1):\MG_PCIE_L0\" )
					)
					( Status sCSetFlattened )
					( Origin gBackEnd )
				)
				( attribute "RELATIVE_PROPAGATION_DELAY" ",5.00 MIL"
					( Parent
						( matchGroupRef "@baseboard_fab2_lib.baseboard_fab2(sch_1):\MG_PCIE_L0\" )
					)
					( Units "uMatchProp" "ns" 1.000000)
					( Status sCSetFlattened )
					( Origin gBackEnd )
				)
			)
			( pinPair "@baseboard_fab2_lib.baseboard_fab2(sch_1):\PP5867\"
				( pinRef "@baseboard_fab2_lib.baseboard_fab2(sch_1):page30_i84:PE1_TX_DN(15)" )
				( pinRef "@baseboard_fab2_lib.baseboard_fab2(sch_1):page117_i9:PCIEUP_15_RXP" )
				( attribute "PROPAGATION_DELAY_MIN" "3000.00 MIL"
					( Units "uMaxMinProp" "ns" 1.000000)
					( Status sCSetFlattened )
					( Origin gBackEnd )
				)
				( attribute "PROPAGATION_DELAY_MAX" "17000.00 MIL"
					( Units "uMaxMinProp" "ns" 1.000000)
					( Status sCSetFlattened )
					( Origin gBackEnd )
				)
				( attribute "RELATIVE_PROPAGATION_DELAY_SCOPE" "G"
					( Parent
						( matchGroupRef "@baseboard_fab2_lib.baseboard_fab2(sch_1):\MG_P3E_CPU0_PE1_PCH_PCIEUP_TX1415\" )
					)
					( Status sCSetFlattened )
					( Origin gBackEnd )
				)
				( attribute "RELATIVE_PROPAGATION_DELAY" ",500.00 MIL"
					( Parent
						( matchGroupRef "@baseboard_fab2_lib.baseboard_fab2(sch_1):\MG_P3E_CPU0_PE1_PCH_PCIEUP_TX1415\" )
					)
					( Units "uMatchProp" "ns" 1.000000)
					( Status sCSetFlattened )
					( Origin gBackEnd )
				)
			)
			( pinPair "@baseboard_fab2_lib.baseboard_fab2(sch_1):\PP361\"
				( pinRef "@baseboard_fab2_lib.baseboard_fab2(sch_1):page105_i201:B" )
				( pinRef "@baseboard_fab2_lib.baseboard_fab2(sch_1):page117_i9:PCIEUP_15_RXN" )
				( attribute "RELATIVE_PROPAGATION_DELAY_SCOPE" "L"
					( Parent
						( matchGroupRef "@baseboard_fab2_lib.baseboard_fab2(sch_1):\MG_PCIE_L0\" )
					)
					( Status sCSetFlattened )
					( Origin gBackEnd )
				)
				( attribute "RELATIVE_PROPAGATION_DELAY" ",5.00 MIL"
					( Parent
						( matchGroupRef "@baseboard_fab2_lib.baseboard_fab2(sch_1):\MG_PCIE_L0\" )
					)
					( Units "uMatchProp" "ns" 1.000000)
					( Status sCSetFlattened )
					( Origin gBackEnd )
				)
			)
			( pinPair "@baseboard_fab2_lib.baseboard_fab2(sch_1):\PP362\"
				( pinRef "@baseboard_fab2_lib.baseboard_fab2(sch_1):page30_i84:PE1_TX_DP(15)" )
				( pinRef "@baseboard_fab2_lib.baseboard_fab2(sch_1):page105_i201:A" )
				( attribute "RELATIVE_PROPAGATION_DELAY_SCOPE" "L"
					( Parent
						( matchGroupRef "@baseboard_fab2_lib.baseboard_fab2(sch_1):\MG_PCIE_L1\" )
					)
					( Status sCSetFlattened )
					( Origin gBackEnd )
				)
				( attribute "RELATIVE_PROPAGATION_DELAY" ",5.00 MIL"
					( Parent
						( matchGroupRef "@baseboard_fab2_lib.baseboard_fab2(sch_1):\MG_PCIE_L1\" )
					)
					( Units "uMatchProp" "ns" 1.000000)
					( Status sCSetFlattened )
					( Origin gBackEnd )
				)
			)
			( pinPair "@baseboard_fab2_lib.baseboard_fab2(sch_1):\PP5862\"
				( pinRef "@baseboard_fab2_lib.baseboard_fab2(sch_1):page30_i84:PE1_TX_DP(15)" )
				( pinRef "@baseboard_fab2_lib.baseboard_fab2(sch_1):page117_i9:PCIEUP_15_RXN" )
				( attribute "PROPAGATION_DELAY_MIN" "3000.00 MIL"
					( Units "uMaxMinProp" "ns" 1.000000)
					( Status sCSetFlattened )
					( Origin gBackEnd )
				)
				( attribute "PROPAGATION_DELAY_MAX" "17000.00 MIL"
					( Units "uMaxMinProp" "ns" 1.000000)
					( Status sCSetFlattened )
					( Origin gBackEnd )
				)
				( attribute "RELATIVE_PROPAGATION_DELAY_SCOPE" "G"
					( Parent
						( matchGroupRef "@baseboard_fab2_lib.baseboard_fab2(sch_1):\MG_P3E_CPU0_PE1_PCH_PCIEUP_TX1415\" )
					)
					( Status sCSetFlattened )
					( Origin gBackEnd )
				)
				( attribute "RELATIVE_PROPAGATION_DELAY" ",500.00 MIL"
					( Parent
						( matchGroupRef "@baseboard_fab2_lib.baseboard_fab2(sch_1):\MG_P3E_CPU0_PE1_PCH_PCIEUP_TX1415\" )
					)
					( Units "uMatchProp" "ns" 1.000000)
					( Status sCSetFlattened )
					( Origin gBackEnd )
				)
			)
			( pinPair "@baseboard_fab2_lib.baseboard_fab2(sch_1):\PP355\"
				( pinRef "@baseboard_fab2_lib.baseboard_fab2(sch_1):page117_i9:PCIEUP_0_RXN" )
				( pinRef "@baseboard_fab2_lib.baseboard_fab2(sch_1):page107_i207:B" )
				( attribute "RELATIVE_PROPAGATION_DELAY_SCOPE" "L"
					( Parent
						( matchGroupRef "@baseboard_fab2_lib.baseboard_fab2(sch_1):\MG_PCIE_L1\" )
					)
					( Status sCSetFlattened )
					( Origin gBackEnd )
				)
				( attribute "RELATIVE_PROPAGATION_DELAY" ",5.00 MIL"
					( Parent
						( matchGroupRef "@baseboard_fab2_lib.baseboard_fab2(sch_1):\MG_PCIE_L1\" )
					)
					( Units "uMatchProp" "ns" 1.000000)
					( Status sCSetFlattened )
					( Origin gBackEnd )
				)
			)
			( pinPair "@baseboard_fab2_lib.baseboard_fab2(sch_1):\PP356\"
				( pinRef "@baseboard_fab2_lib.baseboard_fab2(sch_1):page108_i258:IO53" )
				( pinRef "@baseboard_fab2_lib.baseboard_fab2(sch_1):page107_i415:B" )
				( attribute "RELATIVE_PROPAGATION_DELAY_SCOPE" "L"
					( Parent
						( matchGroupRef "@baseboard_fab2_lib.baseboard_fab2(sch_1):\MG_PCIE_L0\" )
					)
					( Status sCSetFlattened )
					( Origin gBackEnd )
				)
				( attribute "RELATIVE_PROPAGATION_DELAY" ",5.00 MIL"
					( Parent
						( matchGroupRef "@baseboard_fab2_lib.baseboard_fab2(sch_1):\MG_PCIE_L0\" )
					)
					( Units "uMatchProp" "ns" 1.000000)
					( Status sCSetFlattened )
					( Origin gBackEnd )
				)
			)
			( pinPair "@baseboard_fab2_lib.baseboard_fab2(sch_1):\PP5877\"
				( pinRef "@baseboard_fab2_lib.baseboard_fab2(sch_1):page30_i84:PE1_TX_DN(0)" )
				( pinRef "@baseboard_fab2_lib.baseboard_fab2(sch_1):page107_i415:B" )
				( attribute "RELATIVE_PROPAGATION_DELAY_SCOPE" "L"
					( Parent
						( matchGroupRef "@baseboard_fab2_lib.baseboard_fab2(sch_1):\MG_PCIE_L2\" )
					)
					( Status sCSetFlattened )
					( Origin gBackEnd )
				)
				( attribute "RELATIVE_PROPAGATION_DELAY" ",5.00 MIL"
					( Parent
						( matchGroupRef "@baseboard_fab2_lib.baseboard_fab2(sch_1):\MG_PCIE_L2\" )
					)
					( Units "uMatchProp" "ns" 1.000000)
					( Status sCSetFlattened )
					( Origin gBackEnd )
				)
			)
			( pinPair "@baseboard_fab2_lib.baseboard_fab2(sch_1):\PP5878\"
				( pinRef "@baseboard_fab2_lib.baseboard_fab2(sch_1):page30_i84:PE1_TX_DN(0)" )
				( pinRef "@baseboard_fab2_lib.baseboard_fab2(sch_1):page117_i9:PCIEUP_0_RXN" )
				( attribute "PROPAGATION_DELAY_MIN" "3000.00 MIL"
					( Units "uMaxMinProp" "ns" 1.000000)
					( Status sCSetFlattened )
					( Origin gBackEnd )
				)
				( attribute "PROPAGATION_DELAY_MAX" "17000.00 MIL"
					( Units "uMaxMinProp" "ns" 1.000000)
					( Status sCSetFlattened )
					( Origin gBackEnd )
				)
				( attribute "RELATIVE_PROPAGATION_DELAY_SCOPE" "L"
					( Parent
						( matchGroupRef "@baseboard_fab2_lib.baseboard_fab2(sch_1):\MG_PCIE_ALL1\" )
					)
					( Status sCSetFlattened )
					( Origin gBackEnd )
				)
				( attribute "RELATIVE_PROPAGATION_DELAY" ",5.00 MIL"
					( Parent
						( matchGroupRef "@baseboard_fab2_lib.baseboard_fab2(sch_1):\MG_PCIE_ALL1\" )
					)
					( Units "uMatchProp" "ns" 1.000000)
					( Status sCSetFlattened )
					( Origin gBackEnd )
				)
			)
			( pinPair "@baseboard_fab2_lib.baseboard_fab2(sch_1):\PP5879\"
				( pinRef "@baseboard_fab2_lib.baseboard_fab2(sch_1):page30_i84:PE1_TX_DN(0)" )
				( pinRef "@baseboard_fab2_lib.baseboard_fab2(sch_1):page108_i258:IO53" )
				( attribute "PROPAGATION_DELAY_MIN" "3000.00 MIL"
					( Units "uMaxMinProp" "ns" 1.000000)
					( Status sCSetFlattened )
					( Origin gBackEnd )
				)
				( attribute "PROPAGATION_DELAY_MAX" "16000.00 MIL"
					( Units "uMaxMinProp" "ns" 1.000000)
					( Status sCSetFlattened )
					( Origin gBackEnd )
				)
				( attribute "RELATIVE_PROPAGATION_DELAY_SCOPE" "L"
					( Parent
						( matchGroupRef "@baseboard_fab2_lib.baseboard_fab2(sch_1):\MG_PCIE_ALL0\" )
					)
					( Status sCSetFlattened )
					( Origin gBackEnd )
				)
				( attribute "RELATIVE_PROPAGATION_DELAY" ",5.00 MIL"
					( Parent
						( matchGroupRef "@baseboard_fab2_lib.baseboard_fab2(sch_1):\MG_PCIE_ALL0\" )
					)
					( Units "uMatchProp" "ns" 1.000000)
					( Status sCSetFlattened )
					( Origin gBackEnd )
				)
			)
			( pinPair "@baseboard_fab2_lib.baseboard_fab2(sch_1):\PP357\"
				( pinRef "@baseboard_fab2_lib.baseboard_fab2(sch_1):page108_i258:IO51" )
				( pinRef "@baseboard_fab2_lib.baseboard_fab2(sch_1):page107_i417:B" )
				( attribute "RELATIVE_PROPAGATION_DELAY_SCOPE" "L"
					( Parent
						( matchGroupRef "@baseboard_fab2_lib.baseboard_fab2(sch_1):\MG_PCIE_L0\" )
					)
					( Status sCSetFlattened )
					( Origin gBackEnd )
				)
				( attribute "RELATIVE_PROPAGATION_DELAY" ",5.00 MIL"
					( Parent
						( matchGroupRef "@baseboard_fab2_lib.baseboard_fab2(sch_1):\MG_PCIE_L0\" )
					)
					( Units "uMatchProp" "ns" 1.000000)
					( Status sCSetFlattened )
					( Origin gBackEnd )
				)
			)
			( pinPair "@baseboard_fab2_lib.baseboard_fab2(sch_1):\PP358\"
				( pinRef "@baseboard_fab2_lib.baseboard_fab2(sch_1):page117_i9:PCIEUP_0_RXP" )
				( pinRef "@baseboard_fab2_lib.baseboard_fab2(sch_1):page107_i212:B" )
				( attribute "RELATIVE_PROPAGATION_DELAY_SCOPE" "L"
					( Parent
						( matchGroupRef "@baseboard_fab2_lib.baseboard_fab2(sch_1):\MG_PCIE_L1\" )
					)
					( Status sCSetFlattened )
					( Origin gBackEnd )
				)
				( attribute "RELATIVE_PROPAGATION_DELAY" ",5.00 MIL"
					( Parent
						( matchGroupRef "@baseboard_fab2_lib.baseboard_fab2(sch_1):\MG_PCIE_L1\" )
					)
					( Units "uMatchProp" "ns" 1.000000)
					( Status sCSetFlattened )
					( Origin gBackEnd )
				)
			)
			( pinPair "@baseboard_fab2_lib.baseboard_fab2(sch_1):\PP5864\"
				( pinRef "@baseboard_fab2_lib.baseboard_fab2(sch_1):page30_i84:PE1_TX_DP(0)" )
				( pinRef "@baseboard_fab2_lib.baseboard_fab2(sch_1):page107_i417:B" )
				( attribute "RELATIVE_PROPAGATION_DELAY_SCOPE" "L"
					( Parent
						( matchGroupRef "@baseboard_fab2_lib.baseboard_fab2(sch_1):\MG_PCIE_L2\" )
					)
					( Status sCSetFlattened )
					( Origin gBackEnd )
				)
				( attribute "RELATIVE_PROPAGATION_DELAY" ",5.00 MIL"
					( Parent
						( matchGroupRef "@baseboard_fab2_lib.baseboard_fab2(sch_1):\MG_PCIE_L2\" )
					)
					( Units "uMatchProp" "ns" 1.000000)
					( Status sCSetFlattened )
					( Origin gBackEnd )
				)
			)
			( pinPair "@baseboard_fab2_lib.baseboard_fab2(sch_1):\PP5865\"
				( pinRef "@baseboard_fab2_lib.baseboard_fab2(sch_1):page30_i84:PE1_TX_DP(0)" )
				( pinRef "@baseboard_fab2_lib.baseboard_fab2(sch_1):page117_i9:PCIEUP_0_RXP" )
				( attribute "PROPAGATION_DELAY_MIN" "3000.00 MIL"
					( Units "uMaxMinProp" "ns" 1.000000)
					( Status sCSetFlattened )
					( Origin gBackEnd )
				)
				( attribute "PROPAGATION_DELAY_MAX" "17000.00 MIL"
					( Units "uMaxMinProp" "ns" 1.000000)
					( Status sCSetFlattened )
					( Origin gBackEnd )
				)
				( attribute "RELATIVE_PROPAGATION_DELAY_SCOPE" "L"
					( Parent
						( matchGroupRef "@baseboard_fab2_lib.baseboard_fab2(sch_1):\MG_PCIE_ALL1\" )
					)
					( Status sCSetFlattened )
					( Origin gBackEnd )
				)
				( attribute "RELATIVE_PROPAGATION_DELAY" ",5.00 MIL"
					( Parent
						( matchGroupRef "@baseboard_fab2_lib.baseboard_fab2(sch_1):\MG_PCIE_ALL1\" )
					)
					( Units "uMatchProp" "ns" 1.000000)
					( Status sCSetFlattened )
					( Origin gBackEnd )
				)
			)
			( pinPair "@baseboard_fab2_lib.baseboard_fab2(sch_1):\PP5866\"
				( pinRef "@baseboard_fab2_lib.baseboard_fab2(sch_1):page30_i84:PE1_TX_DP(0)" )
				( pinRef "@baseboard_fab2_lib.baseboard_fab2(sch_1):page108_i258:IO51" )
				( attribute "PROPAGATION_DELAY_MIN" "3000.00 MIL"
					( Units "uMaxMinProp" "ns" 1.000000)
					( Status sCSetFlattened )
					( Origin gBackEnd )
				)
				( attribute "PROPAGATION_DELAY_MAX" "16000.00 MIL"
					( Units "uMaxMinProp" "ns" 1.000000)
					( Status sCSetFlattened )
					( Origin gBackEnd )
				)
				( attribute "RELATIVE_PROPAGATION_DELAY_SCOPE" "L"
					( Parent
						( matchGroupRef "@baseboard_fab2_lib.baseboard_fab2(sch_1):\MG_PCIE_ALL0\" )
					)
					( Status sCSetFlattened )
					( Origin gBackEnd )
				)
				( attribute "RELATIVE_PROPAGATION_DELAY" ",5.00 MIL"
					( Parent
						( matchGroupRef "@baseboard_fab2_lib.baseboard_fab2(sch_1):\MG_PCIE_ALL0\" )
					)
					( Units "uMatchProp" "ns" 1.000000)
					( Status sCSetFlattened )
					( Origin gBackEnd )
				)
			)
			( pinPair "@baseboard_fab2_lib.baseboard_fab2(sch_1):\PP351\"
				( pinRef "@baseboard_fab2_lib.baseboard_fab2(sch_1):page117_i9:PCIEUP_1_RXN" )
				( pinRef "@baseboard_fab2_lib.baseboard_fab2(sch_1):page107_i208:B" )
				( attribute "RELATIVE_PROPAGATION_DELAY_SCOPE" "L"
					( Parent
						( matchGroupRef "@baseboard_fab2_lib.baseboard_fab2(sch_1):\MG_PCIE_L1\" )
					)
					( Status sCSetFlattened )
					( Origin gBackEnd )
				)
				( attribute "RELATIVE_PROPAGATION_DELAY" ",5.00 MIL"
					( Parent
						( matchGroupRef "@baseboard_fab2_lib.baseboard_fab2(sch_1):\MG_PCIE_L1\" )
					)
					( Units "uMatchProp" "ns" 1.000000)
					( Status sCSetFlattened )
					( Origin gBackEnd )
				)
			)
			( pinPair "@baseboard_fab2_lib.baseboard_fab2(sch_1):\PP352\"
				( pinRef "@baseboard_fab2_lib.baseboard_fab2(sch_1):page108_i258:IO59" )
				( pinRef "@baseboard_fab2_lib.baseboard_fab2(sch_1):page107_i422:B" )
				( attribute "RELATIVE_PROPAGATION_DELAY_SCOPE" "L"
					( Parent
						( matchGroupRef "@baseboard_fab2_lib.baseboard_fab2(sch_1):\MG_PCIE_L0\" )
					)
					( Status sCSetFlattened )
					( Origin gBackEnd )
				)
				( attribute "RELATIVE_PROPAGATION_DELAY" ",5.00 MIL"
					( Parent
						( matchGroupRef "@baseboard_fab2_lib.baseboard_fab2(sch_1):\MG_PCIE_L0\" )
					)
					( Units "uMatchProp" "ns" 1.000000)
					( Status sCSetFlattened )
					( Origin gBackEnd )
				)
			)
			( pinPair "@baseboard_fab2_lib.baseboard_fab2(sch_1):\PP5880\"
				( pinRef "@baseboard_fab2_lib.baseboard_fab2(sch_1):page30_i84:PE1_TX_DN(1)" )
				( pinRef "@baseboard_fab2_lib.baseboard_fab2(sch_1):page107_i422:B" )
				( attribute "RELATIVE_PROPAGATION_DELAY_SCOPE" "L"
					( Parent
						( matchGroupRef "@baseboard_fab2_lib.baseboard_fab2(sch_1):\MG_PCIE_L2\" )
					)
					( Status sCSetFlattened )
					( Origin gBackEnd )
				)
				( attribute "RELATIVE_PROPAGATION_DELAY" ",5.00 MIL"
					( Parent
						( matchGroupRef "@baseboard_fab2_lib.baseboard_fab2(sch_1):\MG_PCIE_L2\" )
					)
					( Units "uMatchProp" "ns" 1.000000)
					( Status sCSetFlattened )
					( Origin gBackEnd )
				)
			)
			( pinPair "@baseboard_fab2_lib.baseboard_fab2(sch_1):\PP5881\"
				( pinRef "@baseboard_fab2_lib.baseboard_fab2(sch_1):page30_i84:PE1_TX_DN(1)" )
				( pinRef "@baseboard_fab2_lib.baseboard_fab2(sch_1):page117_i9:PCIEUP_1_RXN" )
				( attribute "PROPAGATION_DELAY_MIN" "3000.00 MIL"
					( Units "uMaxMinProp" "ns" 1.000000)
					( Status sCSetFlattened )
					( Origin gBackEnd )
				)
				( attribute "PROPAGATION_DELAY_MAX" "17000.00 MIL"
					( Units "uMaxMinProp" "ns" 1.000000)
					( Status sCSetFlattened )
					( Origin gBackEnd )
				)
				( attribute "RELATIVE_PROPAGATION_DELAY_SCOPE" "L"
					( Parent
						( matchGroupRef "@baseboard_fab2_lib.baseboard_fab2(sch_1):\MG_PCIE_ALL1\" )
					)
					( Status sCSetFlattened )
					( Origin gBackEnd )
				)
				( attribute "RELATIVE_PROPAGATION_DELAY" ",5.00 MIL"
					( Parent
						( matchGroupRef "@baseboard_fab2_lib.baseboard_fab2(sch_1):\MG_PCIE_ALL1\" )
					)
					( Units "uMatchProp" "ns" 1.000000)
					( Status sCSetFlattened )
					( Origin gBackEnd )
				)
			)
			( pinPair "@baseboard_fab2_lib.baseboard_fab2(sch_1):\PP5882\"
				( pinRef "@baseboard_fab2_lib.baseboard_fab2(sch_1):page30_i84:PE1_TX_DN(1)" )
				( pinRef "@baseboard_fab2_lib.baseboard_fab2(sch_1):page108_i258:IO59" )
				( attribute "PROPAGATION_DELAY_MIN" "3000.00 MIL"
					( Units "uMaxMinProp" "ns" 1.000000)
					( Status sCSetFlattened )
					( Origin gBackEnd )
				)
				( attribute "PROPAGATION_DELAY_MAX" "16000.00 MIL"
					( Units "uMaxMinProp" "ns" 1.000000)
					( Status sCSetFlattened )
					( Origin gBackEnd )
				)
				( attribute "RELATIVE_PROPAGATION_DELAY_SCOPE" "L"
					( Parent
						( matchGroupRef "@baseboard_fab2_lib.baseboard_fab2(sch_1):\MG_PCIE_ALL0\" )
					)
					( Status sCSetFlattened )
					( Origin gBackEnd )
				)
				( attribute "RELATIVE_PROPAGATION_DELAY" ",5.00 MIL"
					( Parent
						( matchGroupRef "@baseboard_fab2_lib.baseboard_fab2(sch_1):\MG_PCIE_ALL0\" )
					)
					( Units "uMatchProp" "ns" 1.000000)
					( Status sCSetFlattened )
					( Origin gBackEnd )
				)
			)
			( pinPair "@baseboard_fab2_lib.baseboard_fab2(sch_1):\PP353\"
				( pinRef "@baseboard_fab2_lib.baseboard_fab2(sch_1):page108_i258:IO57" )
				( pinRef "@baseboard_fab2_lib.baseboard_fab2(sch_1):page107_i431:B" )
				( attribute "RELATIVE_PROPAGATION_DELAY_SCOPE" "L"
					( Parent
						( matchGroupRef "@baseboard_fab2_lib.baseboard_fab2(sch_1):\MG_PCIE_L0\" )
					)
					( Status sCSetFlattened )
					( Origin gBackEnd )
				)
				( attribute "RELATIVE_PROPAGATION_DELAY" ",5.00 MIL"
					( Parent
						( matchGroupRef "@baseboard_fab2_lib.baseboard_fab2(sch_1):\MG_PCIE_L0\" )
					)
					( Units "uMatchProp" "ns" 1.000000)
					( Status sCSetFlattened )
					( Origin gBackEnd )
				)
			)
			( pinPair "@baseboard_fab2_lib.baseboard_fab2(sch_1):\PP354\"
				( pinRef "@baseboard_fab2_lib.baseboard_fab2(sch_1):page117_i9:PCIEUP_1_RXP" )
				( pinRef "@baseboard_fab2_lib.baseboard_fab2(sch_1):page107_i226:B" )
				( attribute "RELATIVE_PROPAGATION_DELAY_SCOPE" "L"
					( Parent
						( matchGroupRef "@baseboard_fab2_lib.baseboard_fab2(sch_1):\MG_PCIE_L1\" )
					)
					( Status sCSetFlattened )
					( Origin gBackEnd )
				)
				( attribute "RELATIVE_PROPAGATION_DELAY" ",5.00 MIL"
					( Parent
						( matchGroupRef "@baseboard_fab2_lib.baseboard_fab2(sch_1):\MG_PCIE_L1\" )
					)
					( Units "uMatchProp" "ns" 1.000000)
					( Status sCSetFlattened )
					( Origin gBackEnd )
				)
			)
			( pinPair "@baseboard_fab2_lib.baseboard_fab2(sch_1):\PP5874\"
				( pinRef "@baseboard_fab2_lib.baseboard_fab2(sch_1):page30_i84:PE1_TX_DP(1)" )
				( pinRef "@baseboard_fab2_lib.baseboard_fab2(sch_1):page107_i431:B" )
				( attribute "RELATIVE_PROPAGATION_DELAY_SCOPE" "L"
					( Parent
						( matchGroupRef "@baseboard_fab2_lib.baseboard_fab2(sch_1):\MG_PCIE_L2\" )
					)
					( Status sCSetFlattened )
					( Origin gBackEnd )
				)
				( attribute "RELATIVE_PROPAGATION_DELAY" ",5.00 MIL"
					( Parent
						( matchGroupRef "@baseboard_fab2_lib.baseboard_fab2(sch_1):\MG_PCIE_L2\" )
					)
					( Units "uMatchProp" "ns" 1.000000)
					( Status sCSetFlattened )
					( Origin gBackEnd )
				)
			)
			( pinPair "@baseboard_fab2_lib.baseboard_fab2(sch_1):\PP5875\"
				( pinRef "@baseboard_fab2_lib.baseboard_fab2(sch_1):page30_i84:PE1_TX_DP(1)" )
				( pinRef "@baseboard_fab2_lib.baseboard_fab2(sch_1):page117_i9:PCIEUP_1_RXP" )
				( attribute "PROPAGATION_DELAY_MIN" "3000.00 MIL"
					( Units "uMaxMinProp" "ns" 1.000000)
					( Status sCSetFlattened )
					( Origin gBackEnd )
				)
				( attribute "PROPAGATION_DELAY_MAX" "17000.00 MIL"
					( Units "uMaxMinProp" "ns" 1.000000)
					( Status sCSetFlattened )
					( Origin gBackEnd )
				)
				( attribute "RELATIVE_PROPAGATION_DELAY_SCOPE" "L"
					( Parent
						( matchGroupRef "@baseboard_fab2_lib.baseboard_fab2(sch_1):\MG_PCIE_ALL1\" )
					)
					( Status sCSetFlattened )
					( Origin gBackEnd )
				)
				( attribute "RELATIVE_PROPAGATION_DELAY" ",5.00 MIL"
					( Parent
						( matchGroupRef "@baseboard_fab2_lib.baseboard_fab2(sch_1):\MG_PCIE_ALL1\" )
					)
					( Units "uMatchProp" "ns" 1.000000)
					( Status sCSetFlattened )
					( Origin gBackEnd )
				)
			)
			( pinPair "@baseboard_fab2_lib.baseboard_fab2(sch_1):\PP5876\"
				( pinRef "@baseboard_fab2_lib.baseboard_fab2(sch_1):page30_i84:PE1_TX_DP(1)" )
				( pinRef "@baseboard_fab2_lib.baseboard_fab2(sch_1):page108_i258:IO57" )
				( attribute "PROPAGATION_DELAY_MIN" "3000.00 MIL"
					( Units "uMaxMinProp" "ns" 1.000000)
					( Status sCSetFlattened )
					( Origin gBackEnd )
				)
				( attribute "PROPAGATION_DELAY_MAX" "16000.00 MIL"
					( Units "uMaxMinProp" "ns" 1.000000)
					( Status sCSetFlattened )
					( Origin gBackEnd )
				)
				( attribute "RELATIVE_PROPAGATION_DELAY_SCOPE" "L"
					( Parent
						( matchGroupRef "@baseboard_fab2_lib.baseboard_fab2(sch_1):\MG_PCIE_ALL0\" )
					)
					( Status sCSetFlattened )
					( Origin gBackEnd )
				)
				( attribute "RELATIVE_PROPAGATION_DELAY" ",5.00 MIL"
					( Parent
						( matchGroupRef "@baseboard_fab2_lib.baseboard_fab2(sch_1):\MG_PCIE_ALL0\" )
					)
					( Units "uMatchProp" "ns" 1.000000)
					( Status sCSetFlattened )
					( Origin gBackEnd )
				)
			)
			( pinPair "@baseboard_fab2_lib.baseboard_fab2(sch_1):\PP347\"
				( pinRef "@baseboard_fab2_lib.baseboard_fab2(sch_1):page108_i258:IO69" )
				( pinRef "@baseboard_fab2_lib.baseboard_fab2(sch_1):page107_i423:B" )
				( attribute "RELATIVE_PROPAGATION_DELAY_SCOPE" "L"
					( Parent
						( matchGroupRef "@baseboard_fab2_lib.baseboard_fab2(sch_1):\MG_PCIE_L0\" )
					)
					( Status sCSetFlattened )
					( Origin gBackEnd )
				)
				( attribute "RELATIVE_PROPAGATION_DELAY" ",5.00 MIL"
					( Parent
						( matchGroupRef "@baseboard_fab2_lib.baseboard_fab2(sch_1):\MG_PCIE_L0\" )
					)
					( Units "uMatchProp" "ns" 1.000000)
					( Status sCSetFlattened )
					( Origin gBackEnd )
				)
			)
			( pinPair "@baseboard_fab2_lib.baseboard_fab2(sch_1):\PP348\"
				( pinRef "@baseboard_fab2_lib.baseboard_fab2(sch_1):page117_i9:PCIEUP_2_RXN" )
				( pinRef "@baseboard_fab2_lib.baseboard_fab2(sch_1):page107_i215:B" )
				( attribute "RELATIVE_PROPAGATION_DELAY_SCOPE" "L"
					( Parent
						( matchGroupRef "@baseboard_fab2_lib.baseboard_fab2(sch_1):\MG_PCIE_L1\" )
					)
					( Status sCSetFlattened )
					( Origin gBackEnd )
				)
				( attribute "RELATIVE_PROPAGATION_DELAY" ",5.00 MIL"
					( Parent
						( matchGroupRef "@baseboard_fab2_lib.baseboard_fab2(sch_1):\MG_PCIE_L1\" )
					)
					( Units "uMatchProp" "ns" 1.000000)
					( Status sCSetFlattened )
					( Origin gBackEnd )
				)
			)
			( pinPair "@baseboard_fab2_lib.baseboard_fab2(sch_1):\PP5886\"
				( pinRef "@baseboard_fab2_lib.baseboard_fab2(sch_1):page30_i84:PE1_TX_DN(2)" )
				( pinRef "@baseboard_fab2_lib.baseboard_fab2(sch_1):page107_i423:B" )
				( attribute "RELATIVE_PROPAGATION_DELAY_SCOPE" "L"
					( Parent
						( matchGroupRef "@baseboard_fab2_lib.baseboard_fab2(sch_1):\MG_PCIE_L2\" )
					)
					( Status sCSetFlattened )
					( Origin gBackEnd )
				)
				( attribute "RELATIVE_PROPAGATION_DELAY" ",5.00 MIL"
					( Parent
						( matchGroupRef "@baseboard_fab2_lib.baseboard_fab2(sch_1):\MG_PCIE_L2\" )
					)
					( Units "uMatchProp" "ns" 1.000000)
					( Status sCSetFlattened )
					( Origin gBackEnd )
				)
			)
			( pinPair "@baseboard_fab2_lib.baseboard_fab2(sch_1):\PP5887\"
				( pinRef "@baseboard_fab2_lib.baseboard_fab2(sch_1):page30_i84:PE1_TX_DN(2)" )
				( pinRef "@baseboard_fab2_lib.baseboard_fab2(sch_1):page117_i9:PCIEUP_2_RXN" )
				( attribute "PROPAGATION_DELAY_MIN" "3000.00 MIL"
					( Units "uMaxMinProp" "ns" 1.000000)
					( Status sCSetFlattened )
					( Origin gBackEnd )
				)
				( attribute "PROPAGATION_DELAY_MAX" "17000.00 MIL"
					( Units "uMaxMinProp" "ns" 1.000000)
					( Status sCSetFlattened )
					( Origin gBackEnd )
				)
				( attribute "RELATIVE_PROPAGATION_DELAY_SCOPE" "L"
					( Parent
						( matchGroupRef "@baseboard_fab2_lib.baseboard_fab2(sch_1):\MG_PCIE_ALL1\" )
					)
					( Status sCSetFlattened )
					( Origin gBackEnd )
				)
				( attribute "RELATIVE_PROPAGATION_DELAY" ",5.00 MIL"
					( Parent
						( matchGroupRef "@baseboard_fab2_lib.baseboard_fab2(sch_1):\MG_PCIE_ALL1\" )
					)
					( Units "uMatchProp" "ns" 1.000000)
					( Status sCSetFlattened )
					( Origin gBackEnd )
				)
			)
			( pinPair "@baseboard_fab2_lib.baseboard_fab2(sch_1):\PP5888\"
				( pinRef "@baseboard_fab2_lib.baseboard_fab2(sch_1):page30_i84:PE1_TX_DN(2)" )
				( pinRef "@baseboard_fab2_lib.baseboard_fab2(sch_1):page108_i258:IO69" )
				( attribute "PROPAGATION_DELAY_MIN" "3000.00 MIL"
					( Units "uMaxMinProp" "ns" 1.000000)
					( Status sCSetFlattened )
					( Origin gBackEnd )
				)
				( attribute "PROPAGATION_DELAY_MAX" "16000.00 MIL"
					( Units "uMaxMinProp" "ns" 1.000000)
					( Status sCSetFlattened )
					( Origin gBackEnd )
				)
				( attribute "RELATIVE_PROPAGATION_DELAY_SCOPE" "L"
					( Parent
						( matchGroupRef "@baseboard_fab2_lib.baseboard_fab2(sch_1):\MG_PCIE_ALL0\" )
					)
					( Status sCSetFlattened )
					( Origin gBackEnd )
				)
				( attribute "RELATIVE_PROPAGATION_DELAY" ",5.00 MIL"
					( Parent
						( matchGroupRef "@baseboard_fab2_lib.baseboard_fab2(sch_1):\MG_PCIE_ALL0\" )
					)
					( Units "uMatchProp" "ns" 1.000000)
					( Status sCSetFlattened )
					( Origin gBackEnd )
				)
			)
			( pinPair "@baseboard_fab2_lib.baseboard_fab2(sch_1):\PP349\"
				( pinRef "@baseboard_fab2_lib.baseboard_fab2(sch_1):page108_i258:IO67" )
				( pinRef "@baseboard_fab2_lib.baseboard_fab2(sch_1):page107_i427:B" )
				( attribute "RELATIVE_PROPAGATION_DELAY_SCOPE" "L"
					( Parent
						( matchGroupRef "@baseboard_fab2_lib.baseboard_fab2(sch_1):\MG_PCIE_L0\" )
					)
					( Status sCSetFlattened )
					( Origin gBackEnd )
				)
				( attribute "RELATIVE_PROPAGATION_DELAY" ",5.00 MIL"
					( Parent
						( matchGroupRef "@baseboard_fab2_lib.baseboard_fab2(sch_1):\MG_PCIE_L0\" )
					)
					( Units "uMatchProp" "ns" 1.000000)
					( Status sCSetFlattened )
					( Origin gBackEnd )
				)
			)
			( pinPair "@baseboard_fab2_lib.baseboard_fab2(sch_1):\PP350\"
				( pinRef "@baseboard_fab2_lib.baseboard_fab2(sch_1):page117_i9:PCIEUP_2_RXP" )
				( pinRef "@baseboard_fab2_lib.baseboard_fab2(sch_1):page107_i219:B" )
				( attribute "RELATIVE_PROPAGATION_DELAY_SCOPE" "L"
					( Parent
						( matchGroupRef "@baseboard_fab2_lib.baseboard_fab2(sch_1):\MG_PCIE_L1\" )
					)
					( Status sCSetFlattened )
					( Origin gBackEnd )
				)
				( attribute "RELATIVE_PROPAGATION_DELAY" ",5.00 MIL"
					( Parent
						( matchGroupRef "@baseboard_fab2_lib.baseboard_fab2(sch_1):\MG_PCIE_L1\" )
					)
					( Units "uMatchProp" "ns" 1.000000)
					( Status sCSetFlattened )
					( Origin gBackEnd )
				)
			)
			( pinPair "@baseboard_fab2_lib.baseboard_fab2(sch_1):\PP5883\"
				( pinRef "@baseboard_fab2_lib.baseboard_fab2(sch_1):page30_i84:PE1_TX_DP(2)" )
				( pinRef "@baseboard_fab2_lib.baseboard_fab2(sch_1):page107_i427:B" )
				( attribute "RELATIVE_PROPAGATION_DELAY_SCOPE" "L"
					( Parent
						( matchGroupRef "@baseboard_fab2_lib.baseboard_fab2(sch_1):\MG_PCIE_L2\" )
					)
					( Status sCSetFlattened )
					( Origin gBackEnd )
				)
				( attribute "RELATIVE_PROPAGATION_DELAY" ",5.00 MIL"
					( Parent
						( matchGroupRef "@baseboard_fab2_lib.baseboard_fab2(sch_1):\MG_PCIE_L2\" )
					)
					( Units "uMatchProp" "ns" 1.000000)
					( Status sCSetFlattened )
					( Origin gBackEnd )
				)
			)
			( pinPair "@baseboard_fab2_lib.baseboard_fab2(sch_1):\PP5884\"
				( pinRef "@baseboard_fab2_lib.baseboard_fab2(sch_1):page30_i84:PE1_TX_DP(2)" )
				( pinRef "@baseboard_fab2_lib.baseboard_fab2(sch_1):page117_i9:PCIEUP_2_RXP" )
				( attribute "PROPAGATION_DELAY_MIN" "3000.00 MIL"
					( Units "uMaxMinProp" "ns" 1.000000)
					( Status sCSetFlattened )
					( Origin gBackEnd )
				)
				( attribute "PROPAGATION_DELAY_MAX" "17000.00 MIL"
					( Units "uMaxMinProp" "ns" 1.000000)
					( Status sCSetFlattened )
					( Origin gBackEnd )
				)
				( attribute "RELATIVE_PROPAGATION_DELAY_SCOPE" "L"
					( Parent
						( matchGroupRef "@baseboard_fab2_lib.baseboard_fab2(sch_1):\MG_PCIE_ALL1\" )
					)
					( Status sCSetFlattened )
					( Origin gBackEnd )
				)
				( attribute "RELATIVE_PROPAGATION_DELAY" ",5.00 MIL"
					( Parent
						( matchGroupRef "@baseboard_fab2_lib.baseboard_fab2(sch_1):\MG_PCIE_ALL1\" )
					)
					( Units "uMatchProp" "ns" 1.000000)
					( Status sCSetFlattened )
					( Origin gBackEnd )
				)
			)
			( pinPair "@baseboard_fab2_lib.baseboard_fab2(sch_1):\PP5885\"
				( pinRef "@baseboard_fab2_lib.baseboard_fab2(sch_1):page30_i84:PE1_TX_DP(2)" )
				( pinRef "@baseboard_fab2_lib.baseboard_fab2(sch_1):page108_i258:IO67" )
				( attribute "PROPAGATION_DELAY_MIN" "3000.00 MIL"
					( Units "uMaxMinProp" "ns" 1.000000)
					( Status sCSetFlattened )
					( Origin gBackEnd )
				)
				( attribute "PROPAGATION_DELAY_MAX" "16000.00 MIL"
					( Units "uMaxMinProp" "ns" 1.000000)
					( Status sCSetFlattened )
					( Origin gBackEnd )
				)
				( attribute "RELATIVE_PROPAGATION_DELAY_SCOPE" "L"
					( Parent
						( matchGroupRef "@baseboard_fab2_lib.baseboard_fab2(sch_1):\MG_PCIE_ALL0\" )
					)
					( Status sCSetFlattened )
					( Origin gBackEnd )
				)
				( attribute "RELATIVE_PROPAGATION_DELAY" ",5.00 MIL"
					( Parent
						( matchGroupRef "@baseboard_fab2_lib.baseboard_fab2(sch_1):\MG_PCIE_ALL0\" )
					)
					( Units "uMatchProp" "ns" 1.000000)
					( Status sCSetFlattened )
					( Origin gBackEnd )
				)
			)
			( pinPair "@baseboard_fab2_lib.baseboard_fab2(sch_1):\PP343\"
				( pinRef "@baseboard_fab2_lib.baseboard_fab2(sch_1):page108_i258:IO75" )
				( pinRef "@baseboard_fab2_lib.baseboard_fab2(sch_1):page107_i424:B" )
				( attribute "RELATIVE_PROPAGATION_DELAY_SCOPE" "L"
					( Parent
						( matchGroupRef "@baseboard_fab2_lib.baseboard_fab2(sch_1):\MG_PCIE_L0\" )
					)
					( Status sCSetFlattened )
					( Origin gBackEnd )
				)
				( attribute "RELATIVE_PROPAGATION_DELAY" ",5.00 MIL"
					( Parent
						( matchGroupRef "@baseboard_fab2_lib.baseboard_fab2(sch_1):\MG_PCIE_L0\" )
					)
					( Units "uMatchProp" "ns" 1.000000)
					( Status sCSetFlattened )
					( Origin gBackEnd )
				)
			)
			( pinPair "@baseboard_fab2_lib.baseboard_fab2(sch_1):\PP344\"
				( pinRef "@baseboard_fab2_lib.baseboard_fab2(sch_1):page117_i9:PCIEUP_3_RXN" )
				( pinRef "@baseboard_fab2_lib.baseboard_fab2(sch_1):page107_i216:B" )
				( attribute "RELATIVE_PROPAGATION_DELAY_SCOPE" "L"
					( Parent
						( matchGroupRef "@baseboard_fab2_lib.baseboard_fab2(sch_1):\MG_PCIE_L1\" )
					)
					( Status sCSetFlattened )
					( Origin gBackEnd )
				)
				( attribute "RELATIVE_PROPAGATION_DELAY" ",5.00 MIL"
					( Parent
						( matchGroupRef "@baseboard_fab2_lib.baseboard_fab2(sch_1):\MG_PCIE_L1\" )
					)
					( Units "uMatchProp" "ns" 1.000000)
					( Status sCSetFlattened )
					( Origin gBackEnd )
				)
			)
			( pinPair "@baseboard_fab2_lib.baseboard_fab2(sch_1):\PP5868\"
				( pinRef "@baseboard_fab2_lib.baseboard_fab2(sch_1):page30_i84:PE1_TX_DN(3)" )
				( pinRef "@baseboard_fab2_lib.baseboard_fab2(sch_1):page107_i424:B" )
				( attribute "RELATIVE_PROPAGATION_DELAY_SCOPE" "L"
					( Parent
						( matchGroupRef "@baseboard_fab2_lib.baseboard_fab2(sch_1):\MG_PCIE_L2\" )
					)
					( Status sCSetFlattened )
					( Origin gBackEnd )
				)
				( attribute "RELATIVE_PROPAGATION_DELAY" ",5.00 MIL"
					( Parent
						( matchGroupRef "@baseboard_fab2_lib.baseboard_fab2(sch_1):\MG_PCIE_L2\" )
					)
					( Units "uMatchProp" "ns" 1.000000)
					( Status sCSetFlattened )
					( Origin gBackEnd )
				)
			)
			( pinPair "@baseboard_fab2_lib.baseboard_fab2(sch_1):\PP5869\"
				( pinRef "@baseboard_fab2_lib.baseboard_fab2(sch_1):page30_i84:PE1_TX_DN(3)" )
				( pinRef "@baseboard_fab2_lib.baseboard_fab2(sch_1):page117_i9:PCIEUP_3_RXN" )
				( attribute "PROPAGATION_DELAY_MIN" "3000.00 MIL"
					( Units "uMaxMinProp" "ns" 1.000000)
					( Status sCSetFlattened )
					( Origin gBackEnd )
				)
				( attribute "PROPAGATION_DELAY_MAX" "17000.00 MIL"
					( Units "uMaxMinProp" "ns" 1.000000)
					( Status sCSetFlattened )
					( Origin gBackEnd )
				)
				( attribute "RELATIVE_PROPAGATION_DELAY_SCOPE" "L"
					( Parent
						( matchGroupRef "@baseboard_fab2_lib.baseboard_fab2(sch_1):\MG_PCIE_ALL1\" )
					)
					( Status sCSetFlattened )
					( Origin gBackEnd )
				)
				( attribute "RELATIVE_PROPAGATION_DELAY" ",5.00 MIL"
					( Parent
						( matchGroupRef "@baseboard_fab2_lib.baseboard_fab2(sch_1):\MG_PCIE_ALL1\" )
					)
					( Units "uMatchProp" "ns" 1.000000)
					( Status sCSetFlattened )
					( Origin gBackEnd )
				)
			)
			( pinPair "@baseboard_fab2_lib.baseboard_fab2(sch_1):\PP5870\"
				( pinRef "@baseboard_fab2_lib.baseboard_fab2(sch_1):page30_i84:PE1_TX_DN(3)" )
				( pinRef "@baseboard_fab2_lib.baseboard_fab2(sch_1):page108_i258:IO75" )
				( attribute "PROPAGATION_DELAY_MIN" "3000.00 MIL"
					( Units "uMaxMinProp" "ns" 1.000000)
					( Status sCSetFlattened )
					( Origin gBackEnd )
				)
				( attribute "PROPAGATION_DELAY_MAX" "16000.00 MIL"
					( Units "uMaxMinProp" "ns" 1.000000)
					( Status sCSetFlattened )
					( Origin gBackEnd )
				)
				( attribute "RELATIVE_PROPAGATION_DELAY_SCOPE" "L"
					( Parent
						( matchGroupRef "@baseboard_fab2_lib.baseboard_fab2(sch_1):\MG_PCIE_ALL0\" )
					)
					( Status sCSetFlattened )
					( Origin gBackEnd )
				)
				( attribute "RELATIVE_PROPAGATION_DELAY" ",5.00 MIL"
					( Parent
						( matchGroupRef "@baseboard_fab2_lib.baseboard_fab2(sch_1):\MG_PCIE_ALL0\" )
					)
					( Units "uMatchProp" "ns" 1.000000)
					( Status sCSetFlattened )
					( Origin gBackEnd )
				)
			)
			( pinPair "@baseboard_fab2_lib.baseboard_fab2(sch_1):\PP345\"
				( pinRef "@baseboard_fab2_lib.baseboard_fab2(sch_1):page108_i258:IO73" )
				( pinRef "@baseboard_fab2_lib.baseboard_fab2(sch_1):page107_i435:B" )
				( attribute "RELATIVE_PROPAGATION_DELAY_SCOPE" "L"
					( Parent
						( matchGroupRef "@baseboard_fab2_lib.baseboard_fab2(sch_1):\MG_PCIE_L0\" )
					)
					( Status sCSetFlattened )
					( Origin gBackEnd )
				)
				( attribute "RELATIVE_PROPAGATION_DELAY" ",5.00 MIL"
					( Parent
						( matchGroupRef "@baseboard_fab2_lib.baseboard_fab2(sch_1):\MG_PCIE_L0\" )
					)
					( Units "uMatchProp" "ns" 1.000000)
					( Status sCSetFlattened )
					( Origin gBackEnd )
				)
			)
			( pinPair "@baseboard_fab2_lib.baseboard_fab2(sch_1):\PP346\"
				( pinRef "@baseboard_fab2_lib.baseboard_fab2(sch_1):page117_i9:PCIEUP_3_RXP" )
				( pinRef "@baseboard_fab2_lib.baseboard_fab2(sch_1):page107_i229:B" )
				( attribute "RELATIVE_PROPAGATION_DELAY_SCOPE" "L"
					( Parent
						( matchGroupRef "@baseboard_fab2_lib.baseboard_fab2(sch_1):\MG_PCIE_L1\" )
					)
					( Status sCSetFlattened )
					( Origin gBackEnd )
				)
				( attribute "RELATIVE_PROPAGATION_DELAY" ",5.00 MIL"
					( Parent
						( matchGroupRef "@baseboard_fab2_lib.baseboard_fab2(sch_1):\MG_PCIE_L1\" )
					)
					( Units "uMatchProp" "ns" 1.000000)
					( Status sCSetFlattened )
					( Origin gBackEnd )
				)
			)
			( pinPair "@baseboard_fab2_lib.baseboard_fab2(sch_1):\PP5889\"
				( pinRef "@baseboard_fab2_lib.baseboard_fab2(sch_1):page30_i84:PE1_TX_DP(3)" )
				( pinRef "@baseboard_fab2_lib.baseboard_fab2(sch_1):page107_i435:B" )
				( attribute "RELATIVE_PROPAGATION_DELAY_SCOPE" "L"
					( Parent
						( matchGroupRef "@baseboard_fab2_lib.baseboard_fab2(sch_1):\MG_PCIE_L2\" )
					)
					( Status sCSetFlattened )
					( Origin gBackEnd )
				)
				( attribute "RELATIVE_PROPAGATION_DELAY" ",5.00 MIL"
					( Parent
						( matchGroupRef "@baseboard_fab2_lib.baseboard_fab2(sch_1):\MG_PCIE_L2\" )
					)
					( Units "uMatchProp" "ns" 1.000000)
					( Status sCSetFlattened )
					( Origin gBackEnd )
				)
			)
			( pinPair "@baseboard_fab2_lib.baseboard_fab2(sch_1):\PP5890\"
				( pinRef "@baseboard_fab2_lib.baseboard_fab2(sch_1):page30_i84:PE1_TX_DP(3)" )
				( pinRef "@baseboard_fab2_lib.baseboard_fab2(sch_1):page117_i9:PCIEUP_3_RXP" )
				( attribute "PROPAGATION_DELAY_MIN" "3000.00 MIL"
					( Units "uMaxMinProp" "ns" 1.000000)
					( Status sCSetFlattened )
					( Origin gBackEnd )
				)
				( attribute "PROPAGATION_DELAY_MAX" "17000.00 MIL"
					( Units "uMaxMinProp" "ns" 1.000000)
					( Status sCSetFlattened )
					( Origin gBackEnd )
				)
				( attribute "RELATIVE_PROPAGATION_DELAY_SCOPE" "L"
					( Parent
						( matchGroupRef "@baseboard_fab2_lib.baseboard_fab2(sch_1):\MG_PCIE_ALL1\" )
					)
					( Status sCSetFlattened )
					( Origin gBackEnd )
				)
				( attribute "RELATIVE_PROPAGATION_DELAY" ",5.00 MIL"
					( Parent
						( matchGroupRef "@baseboard_fab2_lib.baseboard_fab2(sch_1):\MG_PCIE_ALL1\" )
					)
					( Units "uMatchProp" "ns" 1.000000)
					( Status sCSetFlattened )
					( Origin gBackEnd )
				)
			)
			( pinPair "@baseboard_fab2_lib.baseboard_fab2(sch_1):\PP5891\"
				( pinRef "@baseboard_fab2_lib.baseboard_fab2(sch_1):page30_i84:PE1_TX_DP(3)" )
				( pinRef "@baseboard_fab2_lib.baseboard_fab2(sch_1):page108_i258:IO73" )
				( attribute "PROPAGATION_DELAY_MIN" "3000.00 MIL"
					( Units "uMaxMinProp" "ns" 1.000000)
					( Status sCSetFlattened )
					( Origin gBackEnd )
				)
				( attribute "PROPAGATION_DELAY_MAX" "16000.00 MIL"
					( Units "uMaxMinProp" "ns" 1.000000)
					( Status sCSetFlattened )
					( Origin gBackEnd )
				)
				( attribute "RELATIVE_PROPAGATION_DELAY_SCOPE" "L"
					( Parent
						( matchGroupRef "@baseboard_fab2_lib.baseboard_fab2(sch_1):\MG_PCIE_ALL0\" )
					)
					( Status sCSetFlattened )
					( Origin gBackEnd )
				)
				( attribute "RELATIVE_PROPAGATION_DELAY" ",5.00 MIL"
					( Parent
						( matchGroupRef "@baseboard_fab2_lib.baseboard_fab2(sch_1):\MG_PCIE_ALL0\" )
					)
					( Units "uMatchProp" "ns" 1.000000)
					( Status sCSetFlattened )
					( Origin gBackEnd )
				)
			)
			( pinPair "@baseboard_fab2_lib.baseboard_fab2(sch_1):\PP339\"
				( pinRef "@baseboard_fab2_lib.baseboard_fab2(sch_1):page117_i9:PCIEUP_4_RXN" )
				( pinRef "@baseboard_fab2_lib.baseboard_fab2(sch_1):page107_i232:B" )
				( attribute "RELATIVE_PROPAGATION_DELAY_SCOPE" "L"
					( Parent
						( matchGroupRef "@baseboard_fab2_lib.baseboard_fab2(sch_1):\MG_PCIE_L1\" )
					)
					( Status sCSetFlattened )
					( Origin gBackEnd )
				)
				( attribute "RELATIVE_PROPAGATION_DELAY" ",5.00 MIL"
					( Parent
						( matchGroupRef "@baseboard_fab2_lib.baseboard_fab2(sch_1):\MG_PCIE_L1\" )
					)
					( Units "uMatchProp" "ns" 1.000000)
					( Status sCSetFlattened )
					( Origin gBackEnd )
				)
			)
			( pinPair "@baseboard_fab2_lib.baseboard_fab2(sch_1):\PP340\"
				( pinRef "@baseboard_fab2_lib.baseboard_fab2(sch_1):page108_i258:IO81" )
				( pinRef "@baseboard_fab2_lib.baseboard_fab2(sch_1):page107_i437:B" )
				( attribute "RELATIVE_PROPAGATION_DELAY_SCOPE" "L"
					( Parent
						( matchGroupRef "@baseboard_fab2_lib.baseboard_fab2(sch_1):\MG_PCIE_L0\" )
					)
					( Status sCSetFlattened )
					( Origin gBackEnd )
				)
				( attribute "RELATIVE_PROPAGATION_DELAY" ",5.00 MIL"
					( Parent
						( matchGroupRef "@baseboard_fab2_lib.baseboard_fab2(sch_1):\MG_PCIE_L0\" )
					)
					( Units "uMatchProp" "ns" 1.000000)
					( Status sCSetFlattened )
					( Origin gBackEnd )
				)
			)
			( pinPair "@baseboard_fab2_lib.baseboard_fab2(sch_1):\PP5822\"
				( pinRef "@baseboard_fab2_lib.baseboard_fab2(sch_1):page30_i84:PE1_TX_DN(4)" )
				( pinRef "@baseboard_fab2_lib.baseboard_fab2(sch_1):page107_i437:B" )
				( attribute "RELATIVE_PROPAGATION_DELAY_SCOPE" "L"
					( Parent
						( matchGroupRef "@baseboard_fab2_lib.baseboard_fab2(sch_1):\MG_PCIE_L2\" )
					)
					( Status sCSetFlattened )
					( Origin gBackEnd )
				)
				( attribute "RELATIVE_PROPAGATION_DELAY" ",5.00 MIL"
					( Parent
						( matchGroupRef "@baseboard_fab2_lib.baseboard_fab2(sch_1):\MG_PCIE_L2\" )
					)
					( Units "uMatchProp" "ns" 1.000000)
					( Status sCSetFlattened )
					( Origin gBackEnd )
				)
			)
			( pinPair "@baseboard_fab2_lib.baseboard_fab2(sch_1):\PP5823\"
				( pinRef "@baseboard_fab2_lib.baseboard_fab2(sch_1):page30_i84:PE1_TX_DN(4)" )
				( pinRef "@baseboard_fab2_lib.baseboard_fab2(sch_1):page117_i9:PCIEUP_4_RXN" )
				( attribute "PROPAGATION_DELAY_MIN" "3000.00 MIL"
					( Units "uMaxMinProp" "ns" 1.000000)
					( Status sCSetFlattened )
					( Origin gBackEnd )
				)
				( attribute "PROPAGATION_DELAY_MAX" "17000.00 MIL"
					( Units "uMaxMinProp" "ns" 1.000000)
					( Status sCSetFlattened )
					( Origin gBackEnd )
				)
				( attribute "RELATIVE_PROPAGATION_DELAY_SCOPE" "L"
					( Parent
						( matchGroupRef "@baseboard_fab2_lib.baseboard_fab2(sch_1):\MG_PCIE_ALL1\" )
					)
					( Status sCSetFlattened )
					( Origin gBackEnd )
				)
				( attribute "RELATIVE_PROPAGATION_DELAY" ",5.00 MIL"
					( Parent
						( matchGroupRef "@baseboard_fab2_lib.baseboard_fab2(sch_1):\MG_PCIE_ALL1\" )
					)
					( Units "uMatchProp" "ns" 1.000000)
					( Status sCSetFlattened )
					( Origin gBackEnd )
				)
			)
			( pinPair "@baseboard_fab2_lib.baseboard_fab2(sch_1):\PP5824\"
				( pinRef "@baseboard_fab2_lib.baseboard_fab2(sch_1):page30_i84:PE1_TX_DN(4)" )
				( pinRef "@baseboard_fab2_lib.baseboard_fab2(sch_1):page108_i258:IO81" )
				( attribute "PROPAGATION_DELAY_MIN" "3000.00 MIL"
					( Units "uMaxMinProp" "ns" 1.000000)
					( Status sCSetFlattened )
					( Origin gBackEnd )
				)
				( attribute "PROPAGATION_DELAY_MAX" "16000.00 MIL"
					( Units "uMaxMinProp" "ns" 1.000000)
					( Status sCSetFlattened )
					( Origin gBackEnd )
				)
				( attribute "RELATIVE_PROPAGATION_DELAY_SCOPE" "L"
					( Parent
						( matchGroupRef "@baseboard_fab2_lib.baseboard_fab2(sch_1):\MG_PCIE_ALL0\" )
					)
					( Status sCSetFlattened )
					( Origin gBackEnd )
				)
				( attribute "RELATIVE_PROPAGATION_DELAY" ",5.00 MIL"
					( Parent
						( matchGroupRef "@baseboard_fab2_lib.baseboard_fab2(sch_1):\MG_PCIE_ALL0\" )
					)
					( Units "uMatchProp" "ns" 1.000000)
					( Status sCSetFlattened )
					( Origin gBackEnd )
				)
			)
			( pinPair "@baseboard_fab2_lib.baseboard_fab2(sch_1):\PP341\"
				( pinRef "@baseboard_fab2_lib.baseboard_fab2(sch_1):page108_i258:IO79" )
				( pinRef "@baseboard_fab2_lib.baseboard_fab2(sch_1):page107_i444:B" )
				( attribute "RELATIVE_PROPAGATION_DELAY_SCOPE" "L"
					( Parent
						( matchGroupRef "@baseboard_fab2_lib.baseboard_fab2(sch_1):\MG_PCIE_L0\" )
					)
					( Status sCSetFlattened )
					( Origin gBackEnd )
				)
				( attribute "RELATIVE_PROPAGATION_DELAY" ",5.00 MIL"
					( Parent
						( matchGroupRef "@baseboard_fab2_lib.baseboard_fab2(sch_1):\MG_PCIE_L0\" )
					)
					( Units "uMatchProp" "ns" 1.000000)
					( Status sCSetFlattened )
					( Origin gBackEnd )
				)
			)
			( pinPair "@baseboard_fab2_lib.baseboard_fab2(sch_1):\PP342\"
				( pinRef "@baseboard_fab2_lib.baseboard_fab2(sch_1):page117_i9:PCIEUP_4_RXP" )
				( pinRef "@baseboard_fab2_lib.baseboard_fab2(sch_1):page107_i223:B" )
				( attribute "RELATIVE_PROPAGATION_DELAY_SCOPE" "L"
					( Parent
						( matchGroupRef "@baseboard_fab2_lib.baseboard_fab2(sch_1):\MG_PCIE_L1\" )
					)
					( Status sCSetFlattened )
					( Origin gBackEnd )
				)
				( attribute "RELATIVE_PROPAGATION_DELAY" ",5.00 MIL"
					( Parent
						( matchGroupRef "@baseboard_fab2_lib.baseboard_fab2(sch_1):\MG_PCIE_L1\" )
					)
					( Units "uMatchProp" "ns" 1.000000)
					( Status sCSetFlattened )
					( Origin gBackEnd )
				)
			)
			( pinPair "@baseboard_fab2_lib.baseboard_fab2(sch_1):\PP5871\"
				( pinRef "@baseboard_fab2_lib.baseboard_fab2(sch_1):page30_i84:PE1_TX_DP(4)" )
				( pinRef "@baseboard_fab2_lib.baseboard_fab2(sch_1):page107_i444:B" )
				( attribute "RELATIVE_PROPAGATION_DELAY_SCOPE" "L"
					( Parent
						( matchGroupRef "@baseboard_fab2_lib.baseboard_fab2(sch_1):\MG_PCIE_L2\" )
					)
					( Status sCSetFlattened )
					( Origin gBackEnd )
				)
				( attribute "RELATIVE_PROPAGATION_DELAY" ",5.00 MIL"
					( Parent
						( matchGroupRef "@baseboard_fab2_lib.baseboard_fab2(sch_1):\MG_PCIE_L2\" )
					)
					( Units "uMatchProp" "ns" 1.000000)
					( Status sCSetFlattened )
					( Origin gBackEnd )
				)
			)
			( pinPair "@baseboard_fab2_lib.baseboard_fab2(sch_1):\PP5872\"
				( pinRef "@baseboard_fab2_lib.baseboard_fab2(sch_1):page30_i84:PE1_TX_DP(4)" )
				( pinRef "@baseboard_fab2_lib.baseboard_fab2(sch_1):page117_i9:PCIEUP_4_RXP" )
				( attribute "PROPAGATION_DELAY_MIN" "3000.00 MIL"
					( Units "uMaxMinProp" "ns" 1.000000)
					( Status sCSetFlattened )
					( Origin gBackEnd )
				)
				( attribute "PROPAGATION_DELAY_MAX" "17000.00 MIL"
					( Units "uMaxMinProp" "ns" 1.000000)
					( Status sCSetFlattened )
					( Origin gBackEnd )
				)
				( attribute "RELATIVE_PROPAGATION_DELAY_SCOPE" "L"
					( Parent
						( matchGroupRef "@baseboard_fab2_lib.baseboard_fab2(sch_1):\MG_PCIE_ALL1\" )
					)
					( Status sCSetFlattened )
					( Origin gBackEnd )
				)
				( attribute "RELATIVE_PROPAGATION_DELAY" ",5.00 MIL"
					( Parent
						( matchGroupRef "@baseboard_fab2_lib.baseboard_fab2(sch_1):\MG_PCIE_ALL1\" )
					)
					( Units "uMatchProp" "ns" 1.000000)
					( Status sCSetFlattened )
					( Origin gBackEnd )
				)
			)
			( pinPair "@baseboard_fab2_lib.baseboard_fab2(sch_1):\PP5873\"
				( pinRef "@baseboard_fab2_lib.baseboard_fab2(sch_1):page30_i84:PE1_TX_DP(4)" )
				( pinRef "@baseboard_fab2_lib.baseboard_fab2(sch_1):page108_i258:IO79" )
				( attribute "PROPAGATION_DELAY_MIN" "3000.00 MIL"
					( Units "uMaxMinProp" "ns" 1.000000)
					( Status sCSetFlattened )
					( Origin gBackEnd )
				)
				( attribute "PROPAGATION_DELAY_MAX" "16000.00 MIL"
					( Units "uMaxMinProp" "ns" 1.000000)
					( Status sCSetFlattened )
					( Origin gBackEnd )
				)
				( attribute "RELATIVE_PROPAGATION_DELAY_SCOPE" "L"
					( Parent
						( matchGroupRef "@baseboard_fab2_lib.baseboard_fab2(sch_1):\MG_PCIE_ALL0\" )
					)
					( Status sCSetFlattened )
					( Origin gBackEnd )
				)
				( attribute "RELATIVE_PROPAGATION_DELAY" ",5.00 MIL"
					( Parent
						( matchGroupRef "@baseboard_fab2_lib.baseboard_fab2(sch_1):\MG_PCIE_ALL0\" )
					)
					( Units "uMatchProp" "ns" 1.000000)
					( Status sCSetFlattened )
					( Origin gBackEnd )
				)
			)
			( pinPair "@baseboard_fab2_lib.baseboard_fab2(sch_1):\PP335\"
				( pinRef "@baseboard_fab2_lib.baseboard_fab2(sch_1):page108_i258:IO87" )
				( pinRef "@baseboard_fab2_lib.baseboard_fab2(sch_1):page107_i439:B" )
				( attribute "RELATIVE_PROPAGATION_DELAY_SCOPE" "L"
					( Parent
						( matchGroupRef "@baseboard_fab2_lib.baseboard_fab2(sch_1):\MG_PCIE_L0\" )
					)
					( Status sCSetFlattened )
					( Origin gBackEnd )
				)
				( attribute "RELATIVE_PROPAGATION_DELAY" ",5.00 MIL"
					( Parent
						( matchGroupRef "@baseboard_fab2_lib.baseboard_fab2(sch_1):\MG_PCIE_L0\" )
					)
					( Units "uMatchProp" "ns" 1.000000)
					( Status sCSetFlattened )
					( Origin gBackEnd )
				)
			)
			( pinPair "@baseboard_fab2_lib.baseboard_fab2(sch_1):\PP336\"
				( pinRef "@baseboard_fab2_lib.baseboard_fab2(sch_1):page117_i9:PCIEUP_5_RXN" )
				( pinRef "@baseboard_fab2_lib.baseboard_fab2(sch_1):page107_i234:B" )
				( attribute "RELATIVE_PROPAGATION_DELAY_SCOPE" "L"
					( Parent
						( matchGroupRef "@baseboard_fab2_lib.baseboard_fab2(sch_1):\MG_PCIE_L1\" )
					)
					( Status sCSetFlattened )
					( Origin gBackEnd )
				)
				( attribute "RELATIVE_PROPAGATION_DELAY" ",5.00 MIL"
					( Parent
						( matchGroupRef "@baseboard_fab2_lib.baseboard_fab2(sch_1):\MG_PCIE_L1\" )
					)
					( Units "uMatchProp" "ns" 1.000000)
					( Status sCSetFlattened )
					( Origin gBackEnd )
				)
			)
			( pinPair "@baseboard_fab2_lib.baseboard_fab2(sch_1):\PP5897\"
				( pinRef "@baseboard_fab2_lib.baseboard_fab2(sch_1):page30_i84:PE1_TX_DN(5)" )
				( pinRef "@baseboard_fab2_lib.baseboard_fab2(sch_1):page107_i439:B" )
				( attribute "RELATIVE_PROPAGATION_DELAY_SCOPE" "L"
					( Parent
						( matchGroupRef "@baseboard_fab2_lib.baseboard_fab2(sch_1):\MG_PCIE_L2\" )
					)
					( Status sCSetFlattened )
					( Origin gBackEnd )
				)
				( attribute "RELATIVE_PROPAGATION_DELAY" ",5.00 MIL"
					( Parent
						( matchGroupRef "@baseboard_fab2_lib.baseboard_fab2(sch_1):\MG_PCIE_L2\" )
					)
					( Units "uMatchProp" "ns" 1.000000)
					( Status sCSetFlattened )
					( Origin gBackEnd )
				)
			)
			( pinPair "@baseboard_fab2_lib.baseboard_fab2(sch_1):\PP5898\"
				( pinRef "@baseboard_fab2_lib.baseboard_fab2(sch_1):page30_i84:PE1_TX_DN(5)" )
				( pinRef "@baseboard_fab2_lib.baseboard_fab2(sch_1):page117_i9:PCIEUP_5_RXN" )
				( attribute "PROPAGATION_DELAY_MIN" "3000.00 MIL"
					( Units "uMaxMinProp" "ns" 1.000000)
					( Status sCSetFlattened )
					( Origin gBackEnd )
				)
				( attribute "PROPAGATION_DELAY_MAX" "17000.00 MIL"
					( Units "uMaxMinProp" "ns" 1.000000)
					( Status sCSetFlattened )
					( Origin gBackEnd )
				)
				( attribute "RELATIVE_PROPAGATION_DELAY_SCOPE" "L"
					( Parent
						( matchGroupRef "@baseboard_fab2_lib.baseboard_fab2(sch_1):\MG_PCIE_ALL1\" )
					)
					( Status sCSetFlattened )
					( Origin gBackEnd )
				)
				( attribute "RELATIVE_PROPAGATION_DELAY" ",5.00 MIL"
					( Parent
						( matchGroupRef "@baseboard_fab2_lib.baseboard_fab2(sch_1):\MG_PCIE_ALL1\" )
					)
					( Units "uMatchProp" "ns" 1.000000)
					( Status sCSetFlattened )
					( Origin gBackEnd )
				)
			)
			( pinPair "@baseboard_fab2_lib.baseboard_fab2(sch_1):\PP5899\"
				( pinRef "@baseboard_fab2_lib.baseboard_fab2(sch_1):page30_i84:PE1_TX_DN(5)" )
				( pinRef "@baseboard_fab2_lib.baseboard_fab2(sch_1):page108_i258:IO87" )
				( attribute "PROPAGATION_DELAY_MIN" "3000.00 MIL"
					( Units "uMaxMinProp" "ns" 1.000000)
					( Status sCSetFlattened )
					( Origin gBackEnd )
				)
				( attribute "PROPAGATION_DELAY_MAX" "16000.00 MIL"
					( Units "uMaxMinProp" "ns" 1.000000)
					( Status sCSetFlattened )
					( Origin gBackEnd )
				)
				( attribute "RELATIVE_PROPAGATION_DELAY_SCOPE" "L"
					( Parent
						( matchGroupRef "@baseboard_fab2_lib.baseboard_fab2(sch_1):\MG_PCIE_ALL0\" )
					)
					( Status sCSetFlattened )
					( Origin gBackEnd )
				)
				( attribute "RELATIVE_PROPAGATION_DELAY" ",5.00 MIL"
					( Parent
						( matchGroupRef "@baseboard_fab2_lib.baseboard_fab2(sch_1):\MG_PCIE_ALL0\" )
					)
					( Units "uMatchProp" "ns" 1.000000)
					( Status sCSetFlattened )
					( Origin gBackEnd )
				)
			)
			( pinPair "@baseboard_fab2_lib.baseboard_fab2(sch_1):\PP337\"
				( pinRef "@baseboard_fab2_lib.baseboard_fab2(sch_1):page108_i258:IO85" )
				( pinRef "@baseboard_fab2_lib.baseboard_fab2(sch_1):page107_i452:B" )
				( attribute "RELATIVE_PROPAGATION_DELAY_SCOPE" "L"
					( Parent
						( matchGroupRef "@baseboard_fab2_lib.baseboard_fab2(sch_1):\MG_PCIE_L0\" )
					)
					( Status sCSetFlattened )
					( Origin gBackEnd )
				)
				( attribute "RELATIVE_PROPAGATION_DELAY" ",5.00 MIL"
					( Parent
						( matchGroupRef "@baseboard_fab2_lib.baseboard_fab2(sch_1):\MG_PCIE_L0\" )
					)
					( Units "uMatchProp" "ns" 1.000000)
					( Status sCSetFlattened )
					( Origin gBackEnd )
				)
			)
			( pinPair "@baseboard_fab2_lib.baseboard_fab2(sch_1):\PP338\"
				( pinRef "@baseboard_fab2_lib.baseboard_fab2(sch_1):page117_i9:PCIEUP_5_RXP" )
				( pinRef "@baseboard_fab2_lib.baseboard_fab2(sch_1):page107_i245:B" )
				( attribute "RELATIVE_PROPAGATION_DELAY_SCOPE" "L"
					( Parent
						( matchGroupRef "@baseboard_fab2_lib.baseboard_fab2(sch_1):\MG_PCIE_L1\" )
					)
					( Status sCSetFlattened )
					( Origin gBackEnd )
				)
				( attribute "RELATIVE_PROPAGATION_DELAY" ",5.00 MIL"
					( Parent
						( matchGroupRef "@baseboard_fab2_lib.baseboard_fab2(sch_1):\MG_PCIE_L1\" )
					)
					( Units "uMatchProp" "ns" 1.000000)
					( Status sCSetFlattened )
					( Origin gBackEnd )
				)
			)
			( pinPair "@baseboard_fab2_lib.baseboard_fab2(sch_1):\PP5816\"
				( pinRef "@baseboard_fab2_lib.baseboard_fab2(sch_1):page30_i84:PE1_TX_DP(5)" )
				( pinRef "@baseboard_fab2_lib.baseboard_fab2(sch_1):page107_i452:B" )
				( attribute "RELATIVE_PROPAGATION_DELAY_SCOPE" "L"
					( Parent
						( matchGroupRef "@baseboard_fab2_lib.baseboard_fab2(sch_1):\MG_PCIE_L2\" )
					)
					( Status sCSetFlattened )
					( Origin gBackEnd )
				)
				( attribute "RELATIVE_PROPAGATION_DELAY" ",5.00 MIL"
					( Parent
						( matchGroupRef "@baseboard_fab2_lib.baseboard_fab2(sch_1):\MG_PCIE_L2\" )
					)
					( Units "uMatchProp" "ns" 1.000000)
					( Status sCSetFlattened )
					( Origin gBackEnd )
				)
			)
			( pinPair "@baseboard_fab2_lib.baseboard_fab2(sch_1):\PP5817\"
				( pinRef "@baseboard_fab2_lib.baseboard_fab2(sch_1):page30_i84:PE1_TX_DP(5)" )
				( pinRef "@baseboard_fab2_lib.baseboard_fab2(sch_1):page117_i9:PCIEUP_5_RXP" )
				( attribute "PROPAGATION_DELAY_MIN" "3000.00 MIL"
					( Units "uMaxMinProp" "ns" 1.000000)
					( Status sCSetFlattened )
					( Origin gBackEnd )
				)
				( attribute "PROPAGATION_DELAY_MAX" "17000.00 MIL"
					( Units "uMaxMinProp" "ns" 1.000000)
					( Status sCSetFlattened )
					( Origin gBackEnd )
				)
				( attribute "RELATIVE_PROPAGATION_DELAY_SCOPE" "L"
					( Parent
						( matchGroupRef "@baseboard_fab2_lib.baseboard_fab2(sch_1):\MG_PCIE_ALL1\" )
					)
					( Status sCSetFlattened )
					( Origin gBackEnd )
				)
				( attribute "RELATIVE_PROPAGATION_DELAY" ",5.00 MIL"
					( Parent
						( matchGroupRef "@baseboard_fab2_lib.baseboard_fab2(sch_1):\MG_PCIE_ALL1\" )
					)
					( Units "uMatchProp" "ns" 1.000000)
					( Status sCSetFlattened )
					( Origin gBackEnd )
				)
			)
			( pinPair "@baseboard_fab2_lib.baseboard_fab2(sch_1):\PP5818\"
				( pinRef "@baseboard_fab2_lib.baseboard_fab2(sch_1):page30_i84:PE1_TX_DP(5)" )
				( pinRef "@baseboard_fab2_lib.baseboard_fab2(sch_1):page108_i258:IO85" )
				( attribute "PROPAGATION_DELAY_MIN" "3000.00 MIL"
					( Units "uMaxMinProp" "ns" 1.000000)
					( Status sCSetFlattened )
					( Origin gBackEnd )
				)
				( attribute "PROPAGATION_DELAY_MAX" "16000.00 MIL"
					( Units "uMaxMinProp" "ns" 1.000000)
					( Status sCSetFlattened )
					( Origin gBackEnd )
				)
				( attribute "RELATIVE_PROPAGATION_DELAY_SCOPE" "L"
					( Parent
						( matchGroupRef "@baseboard_fab2_lib.baseboard_fab2(sch_1):\MG_PCIE_ALL0\" )
					)
					( Status sCSetFlattened )
					( Origin gBackEnd )
				)
				( attribute "RELATIVE_PROPAGATION_DELAY" ",5.00 MIL"
					( Parent
						( matchGroupRef "@baseboard_fab2_lib.baseboard_fab2(sch_1):\MG_PCIE_ALL0\" )
					)
					( Units "uMatchProp" "ns" 1.000000)
					( Status sCSetFlattened )
					( Origin gBackEnd )
				)
			)
			( pinPair "@baseboard_fab2_lib.baseboard_fab2(sch_1):\PP331\"
				( pinRef "@baseboard_fab2_lib.baseboard_fab2(sch_1):page108_i258:IO93" )
				( pinRef "@baseboard_fab2_lib.baseboard_fab2(sch_1):page107_i438:B" )
				( attribute "RELATIVE_PROPAGATION_DELAY_SCOPE" "L"
					( Parent
						( matchGroupRef "@baseboard_fab2_lib.baseboard_fab2(sch_1):\MG_PCIE_L0\" )
					)
					( Status sCSetFlattened )
					( Origin gBackEnd )
				)
				( attribute "RELATIVE_PROPAGATION_DELAY" ",5.00 MIL"
					( Parent
						( matchGroupRef "@baseboard_fab2_lib.baseboard_fab2(sch_1):\MG_PCIE_L0\" )
					)
					( Units "uMatchProp" "ns" 1.000000)
					( Status sCSetFlattened )
					( Origin gBackEnd )
				)
			)
			( pinPair "@baseboard_fab2_lib.baseboard_fab2(sch_1):\PP332\"
				( pinRef "@baseboard_fab2_lib.baseboard_fab2(sch_1):page117_i9:PCIEUP_6_RXN" )
				( pinRef "@baseboard_fab2_lib.baseboard_fab2(sch_1):page107_i235:B" )
				( attribute "RELATIVE_PROPAGATION_DELAY_SCOPE" "L"
					( Parent
						( matchGroupRef "@baseboard_fab2_lib.baseboard_fab2(sch_1):\MG_PCIE_L1\" )
					)
					( Status sCSetFlattened )
					( Origin gBackEnd )
				)
				( attribute "RELATIVE_PROPAGATION_DELAY" ",5.00 MIL"
					( Parent
						( matchGroupRef "@baseboard_fab2_lib.baseboard_fab2(sch_1):\MG_PCIE_L1\" )
					)
					( Units "uMatchProp" "ns" 1.000000)
					( Status sCSetFlattened )
					( Origin gBackEnd )
				)
			)
			( pinPair "@baseboard_fab2_lib.baseboard_fab2(sch_1):\PP5901\"
				( pinRef "@baseboard_fab2_lib.baseboard_fab2(sch_1):page30_i84:PE1_TX_DN(6)" )
				( pinRef "@baseboard_fab2_lib.baseboard_fab2(sch_1):page107_i438:B" )
				( attribute "RELATIVE_PROPAGATION_DELAY_SCOPE" "L"
					( Parent
						( matchGroupRef "@baseboard_fab2_lib.baseboard_fab2(sch_1):\MG_PCIE_L2\" )
					)
					( Status sCSetFlattened )
					( Origin gBackEnd )
				)
				( attribute "RELATIVE_PROPAGATION_DELAY" ",5.00 MIL"
					( Parent
						( matchGroupRef "@baseboard_fab2_lib.baseboard_fab2(sch_1):\MG_PCIE_L2\" )
					)
					( Units "uMatchProp" "ns" 1.000000)
					( Status sCSetFlattened )
					( Origin gBackEnd )
				)
			)
			( pinPair "@baseboard_fab2_lib.baseboard_fab2(sch_1):\PP5902\"
				( pinRef "@baseboard_fab2_lib.baseboard_fab2(sch_1):page30_i84:PE1_TX_DN(6)" )
				( pinRef "@baseboard_fab2_lib.baseboard_fab2(sch_1):page117_i9:PCIEUP_6_RXN" )
				( attribute "PROPAGATION_DELAY_MIN" "3000.00 MIL"
					( Units "uMaxMinProp" "ns" 1.000000)
					( Status sCSetFlattened )
					( Origin gBackEnd )
				)
				( attribute "PROPAGATION_DELAY_MAX" "17000.00 MIL"
					( Units "uMaxMinProp" "ns" 1.000000)
					( Status sCSetFlattened )
					( Origin gBackEnd )
				)
				( attribute "RELATIVE_PROPAGATION_DELAY_SCOPE" "L"
					( Parent
						( matchGroupRef "@baseboard_fab2_lib.baseboard_fab2(sch_1):\MG_PCIE_ALL1\" )
					)
					( Status sCSetFlattened )
					( Origin gBackEnd )
				)
				( attribute "RELATIVE_PROPAGATION_DELAY" ",5.00 MIL"
					( Parent
						( matchGroupRef "@baseboard_fab2_lib.baseboard_fab2(sch_1):\MG_PCIE_ALL1\" )
					)
					( Units "uMatchProp" "ns" 1.000000)
					( Status sCSetFlattened )
					( Origin gBackEnd )
				)
			)
			( pinPair "@baseboard_fab2_lib.baseboard_fab2(sch_1):\PP5903\"
				( pinRef "@baseboard_fab2_lib.baseboard_fab2(sch_1):page30_i84:PE1_TX_DN(6)" )
				( pinRef "@baseboard_fab2_lib.baseboard_fab2(sch_1):page108_i258:IO93" )
				( attribute "PROPAGATION_DELAY_MIN" "3000.00 MIL"
					( Units "uMaxMinProp" "ns" 1.000000)
					( Status sCSetFlattened )
					( Origin gBackEnd )
				)
				( attribute "PROPAGATION_DELAY_MAX" "16000.00 MIL"
					( Units "uMaxMinProp" "ns" 1.000000)
					( Status sCSetFlattened )
					( Origin gBackEnd )
				)
				( attribute "RELATIVE_PROPAGATION_DELAY_SCOPE" "L"
					( Parent
						( matchGroupRef "@baseboard_fab2_lib.baseboard_fab2(sch_1):\MG_PCIE_ALL0\" )
					)
					( Status sCSetFlattened )
					( Origin gBackEnd )
				)
				( attribute "RELATIVE_PROPAGATION_DELAY" ",5.00 MIL"
					( Parent
						( matchGroupRef "@baseboard_fab2_lib.baseboard_fab2(sch_1):\MG_PCIE_ALL0\" )
					)
					( Units "uMatchProp" "ns" 1.000000)
					( Status sCSetFlattened )
					( Origin gBackEnd )
				)
			)
			( pinPair "@baseboard_fab2_lib.baseboard_fab2(sch_1):\PP333\"
				( pinRef "@baseboard_fab2_lib.baseboard_fab2(sch_1):page108_i258:IO91" )
				( pinRef "@baseboard_fab2_lib.baseboard_fab2(sch_1):page107_i447:B" )
				( attribute "RELATIVE_PROPAGATION_DELAY_SCOPE" "L"
					( Parent
						( matchGroupRef "@baseboard_fab2_lib.baseboard_fab2(sch_1):\MG_PCIE_L0\" )
					)
					( Status sCSetFlattened )
					( Origin gBackEnd )
				)
				( attribute "RELATIVE_PROPAGATION_DELAY" ",5.00 MIL"
					( Parent
						( matchGroupRef "@baseboard_fab2_lib.baseboard_fab2(sch_1):\MG_PCIE_L0\" )
					)
					( Units "uMatchProp" "ns" 1.000000)
					( Status sCSetFlattened )
					( Origin gBackEnd )
				)
			)
			( pinPair "@baseboard_fab2_lib.baseboard_fab2(sch_1):\PP334\"
				( pinRef "@baseboard_fab2_lib.baseboard_fab2(sch_1):page117_i9:PCIEUP_6_RXP" )
				( pinRef "@baseboard_fab2_lib.baseboard_fab2(sch_1):page107_i240:B" )
				( attribute "RELATIVE_PROPAGATION_DELAY_SCOPE" "L"
					( Parent
						( matchGroupRef "@baseboard_fab2_lib.baseboard_fab2(sch_1):\MG_PCIE_L1\" )
					)
					( Status sCSetFlattened )
					( Origin gBackEnd )
				)
				( attribute "RELATIVE_PROPAGATION_DELAY" ",5.00 MIL"
					( Parent
						( matchGroupRef "@baseboard_fab2_lib.baseboard_fab2(sch_1):\MG_PCIE_L1\" )
					)
					( Units "uMatchProp" "ns" 1.000000)
					( Status sCSetFlattened )
					( Origin gBackEnd )
				)
			)
			( pinPair "@baseboard_fab2_lib.baseboard_fab2(sch_1):\PP5894\"
				( pinRef "@baseboard_fab2_lib.baseboard_fab2(sch_1):page30_i84:PE1_TX_DP(6)" )
				( pinRef "@baseboard_fab2_lib.baseboard_fab2(sch_1):page107_i447:B" )
				( attribute "RELATIVE_PROPAGATION_DELAY_SCOPE" "L"
					( Parent
						( matchGroupRef "@baseboard_fab2_lib.baseboard_fab2(sch_1):\MG_PCIE_L2\" )
					)
					( Status sCSetFlattened )
					( Origin gBackEnd )
				)
				( attribute "RELATIVE_PROPAGATION_DELAY" ",5.00 MIL"
					( Parent
						( matchGroupRef "@baseboard_fab2_lib.baseboard_fab2(sch_1):\MG_PCIE_L2\" )
					)
					( Units "uMatchProp" "ns" 1.000000)
					( Status sCSetFlattened )
					( Origin gBackEnd )
				)
			)
			( pinPair "@baseboard_fab2_lib.baseboard_fab2(sch_1):\PP5895\"
				( pinRef "@baseboard_fab2_lib.baseboard_fab2(sch_1):page30_i84:PE1_TX_DP(6)" )
				( pinRef "@baseboard_fab2_lib.baseboard_fab2(sch_1):page117_i9:PCIEUP_6_RXP" )
				( attribute "PROPAGATION_DELAY_MIN" "3000.00 MIL"
					( Units "uMaxMinProp" "ns" 1.000000)
					( Status sCSetFlattened )
					( Origin gBackEnd )
				)
				( attribute "PROPAGATION_DELAY_MAX" "17000.00 MIL"
					( Units "uMaxMinProp" "ns" 1.000000)
					( Status sCSetFlattened )
					( Origin gBackEnd )
				)
				( attribute "RELATIVE_PROPAGATION_DELAY_SCOPE" "L"
					( Parent
						( matchGroupRef "@baseboard_fab2_lib.baseboard_fab2(sch_1):\MG_PCIE_ALL1\" )
					)
					( Status sCSetFlattened )
					( Origin gBackEnd )
				)
				( attribute "RELATIVE_PROPAGATION_DELAY" ",5.00 MIL"
					( Parent
						( matchGroupRef "@baseboard_fab2_lib.baseboard_fab2(sch_1):\MG_PCIE_ALL1\" )
					)
					( Units "uMatchProp" "ns" 1.000000)
					( Status sCSetFlattened )
					( Origin gBackEnd )
				)
			)
			( pinPair "@baseboard_fab2_lib.baseboard_fab2(sch_1):\PP5896\"
				( pinRef "@baseboard_fab2_lib.baseboard_fab2(sch_1):page30_i84:PE1_TX_DP(6)" )
				( pinRef "@baseboard_fab2_lib.baseboard_fab2(sch_1):page108_i258:IO91" )
				( attribute "PROPAGATION_DELAY_MIN" "3000.00 MIL"
					( Units "uMaxMinProp" "ns" 1.000000)
					( Status sCSetFlattened )
					( Origin gBackEnd )
				)
				( attribute "PROPAGATION_DELAY_MAX" "16000.00 MIL"
					( Units "uMaxMinProp" "ns" 1.000000)
					( Status sCSetFlattened )
					( Origin gBackEnd )
				)
				( attribute "RELATIVE_PROPAGATION_DELAY_SCOPE" "L"
					( Parent
						( matchGroupRef "@baseboard_fab2_lib.baseboard_fab2(sch_1):\MG_PCIE_ALL0\" )
					)
					( Status sCSetFlattened )
					( Origin gBackEnd )
				)
				( attribute "RELATIVE_PROPAGATION_DELAY" ",5.00 MIL"
					( Parent
						( matchGroupRef "@baseboard_fab2_lib.baseboard_fab2(sch_1):\MG_PCIE_ALL0\" )
					)
					( Units "uMatchProp" "ns" 1.000000)
					( Status sCSetFlattened )
					( Origin gBackEnd )
				)
			)
			( pinPair "@baseboard_fab2_lib.baseboard_fab2(sch_1):\PP327\"
				( pinRef "@baseboard_fab2_lib.baseboard_fab2(sch_1):page108_i258:IO99" )
				( pinRef "@baseboard_fab2_lib.baseboard_fab2(sch_1):page107_i448:B" )
				( attribute "RELATIVE_PROPAGATION_DELAY_SCOPE" "L"
					( Parent
						( matchGroupRef "@baseboard_fab2_lib.baseboard_fab2(sch_1):\MG_PCIE_L0\" )
					)
					( Status sCSetFlattened )
					( Origin gBackEnd )
				)
				( attribute "RELATIVE_PROPAGATION_DELAY" ",5.00 MIL"
					( Parent
						( matchGroupRef "@baseboard_fab2_lib.baseboard_fab2(sch_1):\MG_PCIE_L0\" )
					)
					( Units "uMatchProp" "ns" 1.000000)
					( Status sCSetFlattened )
					( Origin gBackEnd )
				)
			)
			( pinPair "@baseboard_fab2_lib.baseboard_fab2(sch_1):\PP328\"
				( pinRef "@baseboard_fab2_lib.baseboard_fab2(sch_1):page117_i9:PCIEUP_7_RXN" )
				( pinRef "@baseboard_fab2_lib.baseboard_fab2(sch_1):page107_i241:B" )
				( attribute "RELATIVE_PROPAGATION_DELAY_SCOPE" "L"
					( Parent
						( matchGroupRef "@baseboard_fab2_lib.baseboard_fab2(sch_1):\MG_PCIE_L1\" )
					)
					( Status sCSetFlattened )
					( Origin gBackEnd )
				)
				( attribute "RELATIVE_PROPAGATION_DELAY" ",5.00 MIL"
					( Parent
						( matchGroupRef "@baseboard_fab2_lib.baseboard_fab2(sch_1):\MG_PCIE_L1\" )
					)
					( Units "uMatchProp" "ns" 1.000000)
					( Status sCSetFlattened )
					( Origin gBackEnd )
				)
			)
			( pinPair "@baseboard_fab2_lib.baseboard_fab2(sch_1):\PP5907\"
				( pinRef "@baseboard_fab2_lib.baseboard_fab2(sch_1):page30_i84:PE1_TX_DN(7)" )
				( pinRef "@baseboard_fab2_lib.baseboard_fab2(sch_1):page107_i448:B" )
				( attribute "RELATIVE_PROPAGATION_DELAY_SCOPE" "L"
					( Parent
						( matchGroupRef "@baseboard_fab2_lib.baseboard_fab2(sch_1):\MG_PCIE_L2\" )
					)
					( Status sCSetFlattened )
					( Origin gBackEnd )
				)
				( attribute "RELATIVE_PROPAGATION_DELAY" ",5.00 MIL"
					( Parent
						( matchGroupRef "@baseboard_fab2_lib.baseboard_fab2(sch_1):\MG_PCIE_L2\" )
					)
					( Units "uMatchProp" "ns" 1.000000)
					( Status sCSetFlattened )
					( Origin gBackEnd )
				)
			)
			( pinPair "@baseboard_fab2_lib.baseboard_fab2(sch_1):\PP5908\"
				( pinRef "@baseboard_fab2_lib.baseboard_fab2(sch_1):page30_i84:PE1_TX_DN(7)" )
				( pinRef "@baseboard_fab2_lib.baseboard_fab2(sch_1):page117_i9:PCIEUP_7_RXN" )
				( attribute "PROPAGATION_DELAY_MIN" "3000.00 MIL"
					( Units "uMaxMinProp" "ns" 1.000000)
					( Status sCSetFlattened )
					( Origin gBackEnd )
				)
				( attribute "PROPAGATION_DELAY_MAX" "17000.00 MIL"
					( Units "uMaxMinProp" "ns" 1.000000)
					( Status sCSetFlattened )
					( Origin gBackEnd )
				)
				( attribute "RELATIVE_PROPAGATION_DELAY_SCOPE" "L"
					( Parent
						( matchGroupRef "@baseboard_fab2_lib.baseboard_fab2(sch_1):\MG_PCIE_ALL1\" )
					)
					( Status sCSetFlattened )
					( Origin gBackEnd )
				)
				( attribute "RELATIVE_PROPAGATION_DELAY" ",5.00 MIL"
					( Parent
						( matchGroupRef "@baseboard_fab2_lib.baseboard_fab2(sch_1):\MG_PCIE_ALL1\" )
					)
					( Units "uMatchProp" "ns" 1.000000)
					( Status sCSetFlattened )
					( Origin gBackEnd )
				)
			)
			( pinPair "@baseboard_fab2_lib.baseboard_fab2(sch_1):\PP5909\"
				( pinRef "@baseboard_fab2_lib.baseboard_fab2(sch_1):page30_i84:PE1_TX_DN(7)" )
				( pinRef "@baseboard_fab2_lib.baseboard_fab2(sch_1):page108_i258:IO99" )
				( attribute "PROPAGATION_DELAY_MIN" "3000.00 MIL"
					( Units "uMaxMinProp" "ns" 1.000000)
					( Status sCSetFlattened )
					( Origin gBackEnd )
				)
				( attribute "PROPAGATION_DELAY_MAX" "16000.00 MIL"
					( Units "uMaxMinProp" "ns" 1.000000)
					( Status sCSetFlattened )
					( Origin gBackEnd )
				)
				( attribute "RELATIVE_PROPAGATION_DELAY_SCOPE" "L"
					( Parent
						( matchGroupRef "@baseboard_fab2_lib.baseboard_fab2(sch_1):\MG_PCIE_ALL0\" )
					)
					( Status sCSetFlattened )
					( Origin gBackEnd )
				)
				( attribute "RELATIVE_PROPAGATION_DELAY" ",5.00 MIL"
					( Parent
						( matchGroupRef "@baseboard_fab2_lib.baseboard_fab2(sch_1):\MG_PCIE_ALL0\" )
					)
					( Units "uMatchProp" "ns" 1.000000)
					( Status sCSetFlattened )
					( Origin gBackEnd )
				)
			)
			( pinPair "@baseboard_fab2_lib.baseboard_fab2(sch_1):\PP329\"
				( pinRef "@baseboard_fab2_lib.baseboard_fab2(sch_1):page108_i258:IO97" )
				( pinRef "@baseboard_fab2_lib.baseboard_fab2(sch_1):page107_i455:B" )
				( attribute "RELATIVE_PROPAGATION_DELAY_SCOPE" "L"
					( Parent
						( matchGroupRef "@baseboard_fab2_lib.baseboard_fab2(sch_1):\MG_PCIE_L0\" )
					)
					( Status sCSetFlattened )
					( Origin gBackEnd )
				)
				( attribute "RELATIVE_PROPAGATION_DELAY" ",5.00 MIL"
					( Parent
						( matchGroupRef "@baseboard_fab2_lib.baseboard_fab2(sch_1):\MG_PCIE_L0\" )
					)
					( Units "uMatchProp" "ns" 1.000000)
					( Status sCSetFlattened )
					( Origin gBackEnd )
				)
			)
			( pinPair "@baseboard_fab2_lib.baseboard_fab2(sch_1):\PP330\"
				( pinRef "@baseboard_fab2_lib.baseboard_fab2(sch_1):page117_i9:PCIEUP_7_RXP" )
				( pinRef "@baseboard_fab2_lib.baseboard_fab2(sch_1):page107_i248:B" )
				( attribute "RELATIVE_PROPAGATION_DELAY_SCOPE" "L"
					( Parent
						( matchGroupRef "@baseboard_fab2_lib.baseboard_fab2(sch_1):\MG_PCIE_L1\" )
					)
					( Status sCSetFlattened )
					( Origin gBackEnd )
				)
				( attribute "RELATIVE_PROPAGATION_DELAY" ",5.00 MIL"
					( Parent
						( matchGroupRef "@baseboard_fab2_lib.baseboard_fab2(sch_1):\MG_PCIE_L1\" )
					)
					( Units "uMatchProp" "ns" 1.000000)
					( Status sCSetFlattened )
					( Origin gBackEnd )
				)
			)
			( pinPair "@baseboard_fab2_lib.baseboard_fab2(sch_1):\PP5904\"
				( pinRef "@baseboard_fab2_lib.baseboard_fab2(sch_1):page30_i84:PE1_TX_DP(7)" )
				( pinRef "@baseboard_fab2_lib.baseboard_fab2(sch_1):page107_i455:B" )
				( attribute "RELATIVE_PROPAGATION_DELAY_SCOPE" "L"
					( Parent
						( matchGroupRef "@baseboard_fab2_lib.baseboard_fab2(sch_1):\MG_PCIE_L2\" )
					)
					( Status sCSetFlattened )
					( Origin gBackEnd )
				)
				( attribute "RELATIVE_PROPAGATION_DELAY" ",5.00 MIL"
					( Parent
						( matchGroupRef "@baseboard_fab2_lib.baseboard_fab2(sch_1):\MG_PCIE_L2\" )
					)
					( Units "uMatchProp" "ns" 1.000000)
					( Status sCSetFlattened )
					( Origin gBackEnd )
				)
			)
			( pinPair "@baseboard_fab2_lib.baseboard_fab2(sch_1):\PP5905\"
				( pinRef "@baseboard_fab2_lib.baseboard_fab2(sch_1):page30_i84:PE1_TX_DP(7)" )
				( pinRef "@baseboard_fab2_lib.baseboard_fab2(sch_1):page117_i9:PCIEUP_7_RXP" )
				( attribute "PROPAGATION_DELAY_MIN" "3000.00 MIL"
					( Units "uMaxMinProp" "ns" 1.000000)
					( Status sCSetFlattened )
					( Origin gBackEnd )
				)
				( attribute "PROPAGATION_DELAY_MAX" "17000.00 MIL"
					( Units "uMaxMinProp" "ns" 1.000000)
					( Status sCSetFlattened )
					( Origin gBackEnd )
				)
				( attribute "RELATIVE_PROPAGATION_DELAY_SCOPE" "L"
					( Parent
						( matchGroupRef "@baseboard_fab2_lib.baseboard_fab2(sch_1):\MG_PCIE_ALL1\" )
					)
					( Status sCSetFlattened )
					( Origin gBackEnd )
				)
				( attribute "RELATIVE_PROPAGATION_DELAY" ",5.00 MIL"
					( Parent
						( matchGroupRef "@baseboard_fab2_lib.baseboard_fab2(sch_1):\MG_PCIE_ALL1\" )
					)
					( Units "uMatchProp" "ns" 1.000000)
					( Status sCSetFlattened )
					( Origin gBackEnd )
				)
			)
			( pinPair "@baseboard_fab2_lib.baseboard_fab2(sch_1):\PP5906\"
				( pinRef "@baseboard_fab2_lib.baseboard_fab2(sch_1):page30_i84:PE1_TX_DP(7)" )
				( pinRef "@baseboard_fab2_lib.baseboard_fab2(sch_1):page108_i258:IO97" )
				( attribute "PROPAGATION_DELAY_MIN" "3000.00 MIL"
					( Units "uMaxMinProp" "ns" 1.000000)
					( Status sCSetFlattened )
					( Origin gBackEnd )
				)
				( attribute "PROPAGATION_DELAY_MAX" "16000.00 MIL"
					( Units "uMaxMinProp" "ns" 1.000000)
					( Status sCSetFlattened )
					( Origin gBackEnd )
				)
				( attribute "RELATIVE_PROPAGATION_DELAY_SCOPE" "L"
					( Parent
						( matchGroupRef "@baseboard_fab2_lib.baseboard_fab2(sch_1):\MG_PCIE_ALL0\" )
					)
					( Status sCSetFlattened )
					( Origin gBackEnd )
				)
				( attribute "RELATIVE_PROPAGATION_DELAY" ",5.00 MIL"
					( Parent
						( matchGroupRef "@baseboard_fab2_lib.baseboard_fab2(sch_1):\MG_PCIE_ALL0\" )
					)
					( Units "uMatchProp" "ns" 1.000000)
					( Status sCSetFlattened )
					( Origin gBackEnd )
				)
			)
			( pinPair "@baseboard_fab2_lib.baseboard_fab2(sch_1):\PP323\"
				( pinRef "@baseboard_fab2_lib.baseboard_fab2(sch_1):page31_i106:PE2_TX_DN(0)" )
				( pinRef "@baseboard_fab2_lib.baseboard_fab2(sch_1):page105_i96:A" )
				( attribute "RELATIVE_PROPAGATION_DELAY_SCOPE" "L"
					( Parent
						( matchGroupRef "@baseboard_fab2_lib.baseboard_fab2(sch_1):\MG_PCIE_L1\" )
					)
					( Status sCSetFlattened )
					( Origin gBackEnd )
				)
				( attribute "RELATIVE_PROPAGATION_DELAY" ",5.00 MIL"
					( Parent
						( matchGroupRef "@baseboard_fab2_lib.baseboard_fab2(sch_1):\MG_PCIE_L1\" )
					)
					( Units "uMatchProp" "ns" 1.000000)
					( Status sCSetFlattened )
					( Origin gBackEnd )
				)
			)
			( pinPair "@baseboard_fab2_lib.baseboard_fab2(sch_1):\PP324\"
				( pinRef "@baseboard_fab2_lib.baseboard_fab2(sch_1):page109_i243:IO103" )
				( pinRef "@baseboard_fab2_lib.baseboard_fab2(sch_1):page105_i96:B" )
				( attribute "RELATIVE_PROPAGATION_DELAY_SCOPE" "L"
					( Parent
						( matchGroupRef "@baseboard_fab2_lib.baseboard_fab2(sch_1):\MG_PCIE_L0\" )
					)
					( Status sCSetFlattened )
					( Origin gBackEnd )
				)
				( attribute "RELATIVE_PROPAGATION_DELAY" ",5.00 MIL"
					( Parent
						( matchGroupRef "@baseboard_fab2_lib.baseboard_fab2(sch_1):\MG_PCIE_L0\" )
					)
					( Units "uMatchProp" "ns" 1.000000)
					( Status sCSetFlattened )
					( Origin gBackEnd )
				)
			)
			( pinPair "@baseboard_fab2_lib.baseboard_fab2(sch_1):\PP5911\"
				( pinRef "@baseboard_fab2_lib.baseboard_fab2(sch_1):page31_i106:PE2_TX_DN(0)" )
				( pinRef "@baseboard_fab2_lib.baseboard_fab2(sch_1):page109_i243:IO103" )
				( attribute "PROPAGATION_DELAY_MIN" "3000.00 MIL"
					( Units "uMaxMinProp" "ns" 1.000000)
					( Status sCSetFlattened )
					( Origin gBackEnd )
				)
				( attribute "PROPAGATION_DELAY_MAX" "16000.00 MIL"
					( Units "uMaxMinProp" "ns" 1.000000)
					( Status sCSetFlattened )
					( Origin gBackEnd )
				)
				( attribute "RELATIVE_PROPAGATION_DELAY_SCOPE" "G"
					( Parent
						( matchGroupRef "@baseboard_fab2_lib.baseboard_fab2(sch_1):\MG_P3E_CPU0_PE2_SS_TX0001\" )
					)
					( Status sCSetFlattened )
					( Origin gBackEnd )
				)
				( attribute "RELATIVE_PROPAGATION_DELAY" ",500.00 MIL"
					( Parent
						( matchGroupRef "@baseboard_fab2_lib.baseboard_fab2(sch_1):\MG_P3E_CPU0_PE2_SS_TX0001\" )
					)
					( Units "uMatchProp" "ns" 1.000000)
					( Status sCSetFlattened )
					( Origin gBackEnd )
				)
			)
			( pinPair "@baseboard_fab2_lib.baseboard_fab2(sch_1):\PP325\"
				( pinRef "@baseboard_fab2_lib.baseboard_fab2(sch_1):page109_i243:IO105" )
				( pinRef "@baseboard_fab2_lib.baseboard_fab2(sch_1):page105_i93:B" )
				( attribute "RELATIVE_PROPAGATION_DELAY_SCOPE" "L"
					( Parent
						( matchGroupRef "@baseboard_fab2_lib.baseboard_fab2(sch_1):\MG_PCIE_L0\" )
					)
					( Status sCSetFlattened )
					( Origin gBackEnd )
				)
				( attribute "RELATIVE_PROPAGATION_DELAY" ",5.00 MIL"
					( Parent
						( matchGroupRef "@baseboard_fab2_lib.baseboard_fab2(sch_1):\MG_PCIE_L0\" )
					)
					( Units "uMatchProp" "ns" 1.000000)
					( Status sCSetFlattened )
					( Origin gBackEnd )
				)
			)
			( pinPair "@baseboard_fab2_lib.baseboard_fab2(sch_1):\PP326\"
				( pinRef "@baseboard_fab2_lib.baseboard_fab2(sch_1):page31_i106:PE2_TX_DP(0)" )
				( pinRef "@baseboard_fab2_lib.baseboard_fab2(sch_1):page105_i93:A" )
				( attribute "RELATIVE_PROPAGATION_DELAY_SCOPE" "L"
					( Parent
						( matchGroupRef "@baseboard_fab2_lib.baseboard_fab2(sch_1):\MG_PCIE_L1\" )
					)
					( Status sCSetFlattened )
					( Origin gBackEnd )
				)
				( attribute "RELATIVE_PROPAGATION_DELAY" ",5.00 MIL"
					( Parent
						( matchGroupRef "@baseboard_fab2_lib.baseboard_fab2(sch_1):\MG_PCIE_L1\" )
					)
					( Units "uMatchProp" "ns" 1.000000)
					( Status sCSetFlattened )
					( Origin gBackEnd )
				)
			)
			( pinPair "@baseboard_fab2_lib.baseboard_fab2(sch_1):\PP5910\"
				( pinRef "@baseboard_fab2_lib.baseboard_fab2(sch_1):page31_i106:PE2_TX_DP(0)" )
				( pinRef "@baseboard_fab2_lib.baseboard_fab2(sch_1):page109_i243:IO105" )
				( attribute "PROPAGATION_DELAY_MIN" "3000.00 MIL"
					( Units "uMaxMinProp" "ns" 1.000000)
					( Status sCSetFlattened )
					( Origin gBackEnd )
				)
				( attribute "PROPAGATION_DELAY_MAX" "16000.00 MIL"
					( Units "uMaxMinProp" "ns" 1.000000)
					( Status sCSetFlattened )
					( Origin gBackEnd )
				)
				( attribute "RELATIVE_PROPAGATION_DELAY_SCOPE" "G"
					( Parent
						( matchGroupRef "@baseboard_fab2_lib.baseboard_fab2(sch_1):\MG_P3E_CPU0_PE2_SS_TX0001\" )
					)
					( Status sCSetFlattened )
					( Origin gBackEnd )
				)
				( attribute "RELATIVE_PROPAGATION_DELAY" ",500.00 MIL"
					( Parent
						( matchGroupRef "@baseboard_fab2_lib.baseboard_fab2(sch_1):\MG_P3E_CPU0_PE2_SS_TX0001\" )
					)
					( Units "uMatchProp" "ns" 1.000000)
					( Status sCSetFlattened )
					( Origin gBackEnd )
				)
			)
			( pinPair "@baseboard_fab2_lib.baseboard_fab2(sch_1):\PP319\"
				( pinRef "@baseboard_fab2_lib.baseboard_fab2(sch_1):page31_i106:PE2_TX_DN(1)" )
				( pinRef "@baseboard_fab2_lib.baseboard_fab2(sch_1):page105_i62:A" )
				( attribute "RELATIVE_PROPAGATION_DELAY_SCOPE" "L"
					( Parent
						( matchGroupRef "@baseboard_fab2_lib.baseboard_fab2(sch_1):\MG_PCIE_L1\" )
					)
					( Status sCSetFlattened )
					( Origin gBackEnd )
				)
				( attribute "RELATIVE_PROPAGATION_DELAY" ",5.00 MIL"
					( Parent
						( matchGroupRef "@baseboard_fab2_lib.baseboard_fab2(sch_1):\MG_PCIE_L1\" )
					)
					( Units "uMatchProp" "ns" 1.000000)
					( Status sCSetFlattened )
					( Origin gBackEnd )
				)
			)
			( pinPair "@baseboard_fab2_lib.baseboard_fab2(sch_1):\PP320\"
				( pinRef "@baseboard_fab2_lib.baseboard_fab2(sch_1):page109_i243:IO111" )
				( pinRef "@baseboard_fab2_lib.baseboard_fab2(sch_1):page105_i62:B" )
				( attribute "RELATIVE_PROPAGATION_DELAY_SCOPE" "L"
					( Parent
						( matchGroupRef "@baseboard_fab2_lib.baseboard_fab2(sch_1):\MG_PCIE_L0\" )
					)
					( Status sCSetFlattened )
					( Origin gBackEnd )
				)
				( attribute "RELATIVE_PROPAGATION_DELAY" ",5.00 MIL"
					( Parent
						( matchGroupRef "@baseboard_fab2_lib.baseboard_fab2(sch_1):\MG_PCIE_L0\" )
					)
					( Units "uMatchProp" "ns" 1.000000)
					( Status sCSetFlattened )
					( Origin gBackEnd )
				)
			)
			( pinPair "@baseboard_fab2_lib.baseboard_fab2(sch_1):\PP5819\"
				( pinRef "@baseboard_fab2_lib.baseboard_fab2(sch_1):page31_i106:PE2_TX_DN(1)" )
				( pinRef "@baseboard_fab2_lib.baseboard_fab2(sch_1):page109_i243:IO111" )
				( attribute "PROPAGATION_DELAY_MIN" "3000.00 MIL"
					( Units "uMaxMinProp" "ns" 1.000000)
					( Status sCSetFlattened )
					( Origin gBackEnd )
				)
				( attribute "PROPAGATION_DELAY_MAX" "16000.00 MIL"
					( Units "uMaxMinProp" "ns" 1.000000)
					( Status sCSetFlattened )
					( Origin gBackEnd )
				)
				( attribute "RELATIVE_PROPAGATION_DELAY_SCOPE" "G"
					( Parent
						( matchGroupRef "@baseboard_fab2_lib.baseboard_fab2(sch_1):\MG_P3E_CPU0_PE2_SS_TX0001\" )
					)
					( Status sCSetFlattened )
					( Origin gBackEnd )
				)
				( attribute "RELATIVE_PROPAGATION_DELAY" ",500.00 MIL"
					( Parent
						( matchGroupRef "@baseboard_fab2_lib.baseboard_fab2(sch_1):\MG_P3E_CPU0_PE2_SS_TX0001\" )
					)
					( Units "uMatchProp" "ns" 1.000000)
					( Status sCSetFlattened )
					( Origin gBackEnd )
				)
			)
			( pinPair "@baseboard_fab2_lib.baseboard_fab2(sch_1):\PP321\"
				( pinRef "@baseboard_fab2_lib.baseboard_fab2(sch_1):page109_i243:IO109" )
				( pinRef "@baseboard_fab2_lib.baseboard_fab2(sch_1):page105_i76:B" )
				( attribute "RELATIVE_PROPAGATION_DELAY_SCOPE" "L"
					( Parent
						( matchGroupRef "@baseboard_fab2_lib.baseboard_fab2(sch_1):\MG_PCIE_L0\" )
					)
					( Status sCSetFlattened )
					( Origin gBackEnd )
				)
				( attribute "RELATIVE_PROPAGATION_DELAY" ",5.00 MIL"
					( Parent
						( matchGroupRef "@baseboard_fab2_lib.baseboard_fab2(sch_1):\MG_PCIE_L0\" )
					)
					( Units "uMatchProp" "ns" 1.000000)
					( Status sCSetFlattened )
					( Origin gBackEnd )
				)
			)
			( pinPair "@baseboard_fab2_lib.baseboard_fab2(sch_1):\PP322\"
				( pinRef "@baseboard_fab2_lib.baseboard_fab2(sch_1):page31_i106:PE2_TX_DP(1)" )
				( pinRef "@baseboard_fab2_lib.baseboard_fab2(sch_1):page105_i76:A" )
				( attribute "RELATIVE_PROPAGATION_DELAY_SCOPE" "L"
					( Parent
						( matchGroupRef "@baseboard_fab2_lib.baseboard_fab2(sch_1):\MG_PCIE_L1\" )
					)
					( Status sCSetFlattened )
					( Origin gBackEnd )
				)
				( attribute "RELATIVE_PROPAGATION_DELAY" ",5.00 MIL"
					( Parent
						( matchGroupRef "@baseboard_fab2_lib.baseboard_fab2(sch_1):\MG_PCIE_L1\" )
					)
					( Units "uMatchProp" "ns" 1.000000)
					( Status sCSetFlattened )
					( Origin gBackEnd )
				)
			)
			( pinPair "@baseboard_fab2_lib.baseboard_fab2(sch_1):\PP5900\"
				( pinRef "@baseboard_fab2_lib.baseboard_fab2(sch_1):page31_i106:PE2_TX_DP(1)" )
				( pinRef "@baseboard_fab2_lib.baseboard_fab2(sch_1):page109_i243:IO109" )
				( attribute "PROPAGATION_DELAY_MIN" "3000.00 MIL"
					( Units "uMaxMinProp" "ns" 1.000000)
					( Status sCSetFlattened )
					( Origin gBackEnd )
				)
				( attribute "PROPAGATION_DELAY_MAX" "16000.00 MIL"
					( Units "uMaxMinProp" "ns" 1.000000)
					( Status sCSetFlattened )
					( Origin gBackEnd )
				)
				( attribute "RELATIVE_PROPAGATION_DELAY_SCOPE" "G"
					( Parent
						( matchGroupRef "@baseboard_fab2_lib.baseboard_fab2(sch_1):\MG_P3E_CPU0_PE2_SS_TX0001\" )
					)
					( Status sCSetFlattened )
					( Origin gBackEnd )
				)
				( attribute "RELATIVE_PROPAGATION_DELAY" ",500.00 MIL"
					( Parent
						( matchGroupRef "@baseboard_fab2_lib.baseboard_fab2(sch_1):\MG_P3E_CPU0_PE2_SS_TX0001\" )
					)
					( Units "uMatchProp" "ns" 1.000000)
					( Status sCSetFlattened )
					( Origin gBackEnd )
				)
			)
			( pinPair "@baseboard_fab2_lib.baseboard_fab2(sch_1):\PP315\"
				( pinRef "@baseboard_fab2_lib.baseboard_fab2(sch_1):page31_i106:PE2_TX_DN(2)" )
				( pinRef "@baseboard_fab2_lib.baseboard_fab2(sch_1):page105_i61:A" )
				( attribute "RELATIVE_PROPAGATION_DELAY_SCOPE" "L"
					( Parent
						( matchGroupRef "@baseboard_fab2_lib.baseboard_fab2(sch_1):\MG_PCIE_L1\" )
					)
					( Status sCSetFlattened )
					( Origin gBackEnd )
				)
				( attribute "RELATIVE_PROPAGATION_DELAY" ",5.00 MIL"
					( Parent
						( matchGroupRef "@baseboard_fab2_lib.baseboard_fab2(sch_1):\MG_PCIE_L1\" )
					)
					( Units "uMatchProp" "ns" 1.000000)
					( Status sCSetFlattened )
					( Origin gBackEnd )
				)
			)
			( pinPair "@baseboard_fab2_lib.baseboard_fab2(sch_1):\PP316\"
				( pinRef "@baseboard_fab2_lib.baseboard_fab2(sch_1):page109_i243:IO115" )
				( pinRef "@baseboard_fab2_lib.baseboard_fab2(sch_1):page105_i61:B" )
				( attribute "RELATIVE_PROPAGATION_DELAY_SCOPE" "L"
					( Parent
						( matchGroupRef "@baseboard_fab2_lib.baseboard_fab2(sch_1):\MG_PCIE_L0\" )
					)
					( Status sCSetFlattened )
					( Origin gBackEnd )
				)
				( attribute "RELATIVE_PROPAGATION_DELAY" ",5.00 MIL"
					( Parent
						( matchGroupRef "@baseboard_fab2_lib.baseboard_fab2(sch_1):\MG_PCIE_L0\" )
					)
					( Units "uMatchProp" "ns" 1.000000)
					( Status sCSetFlattened )
					( Origin gBackEnd )
				)
			)
			( pinPair "@baseboard_fab2_lib.baseboard_fab2(sch_1):\PP5826\"
				( pinRef "@baseboard_fab2_lib.baseboard_fab2(sch_1):page31_i106:PE2_TX_DN(2)" )
				( pinRef "@baseboard_fab2_lib.baseboard_fab2(sch_1):page109_i243:IO115" )
				( attribute "PROPAGATION_DELAY_MIN" "3000.00 MIL"
					( Units "uMaxMinProp" "ns" 1.000000)
					( Status sCSetFlattened )
					( Origin gBackEnd )
				)
				( attribute "PROPAGATION_DELAY_MAX" "16000.00 MIL"
					( Units "uMaxMinProp" "ns" 1.000000)
					( Status sCSetFlattened )
					( Origin gBackEnd )
				)
				( attribute "RELATIVE_PROPAGATION_DELAY_SCOPE" "G"
					( Parent
						( matchGroupRef "@baseboard_fab2_lib.baseboard_fab2(sch_1):\MG_P3E_CPU0_PE2_SS_TX0203\" )
					)
					( Status sCSetFlattened )
					( Origin gBackEnd )
				)
				( attribute "RELATIVE_PROPAGATION_DELAY" ",500.00 MIL"
					( Parent
						( matchGroupRef "@baseboard_fab2_lib.baseboard_fab2(sch_1):\MG_P3E_CPU0_PE2_SS_TX0203\" )
					)
					( Units "uMatchProp" "ns" 1.000000)
					( Status sCSetFlattened )
					( Origin gBackEnd )
				)
			)
			( pinPair "@baseboard_fab2_lib.baseboard_fab2(sch_1):\PP317\"
				( pinRef "@baseboard_fab2_lib.baseboard_fab2(sch_1):page109_i243:IO117" )
				( pinRef "@baseboard_fab2_lib.baseboard_fab2(sch_1):page105_i75:B" )
				( attribute "RELATIVE_PROPAGATION_DELAY_SCOPE" "L"
					( Parent
						( matchGroupRef "@baseboard_fab2_lib.baseboard_fab2(sch_1):\MG_PCIE_L0\" )
					)
					( Status sCSetFlattened )
					( Origin gBackEnd )
				)
				( attribute "RELATIVE_PROPAGATION_DELAY" ",5.00 MIL"
					( Parent
						( matchGroupRef "@baseboard_fab2_lib.baseboard_fab2(sch_1):\MG_PCIE_L0\" )
					)
					( Units "uMatchProp" "ns" 1.000000)
					( Status sCSetFlattened )
					( Origin gBackEnd )
				)
			)
			( pinPair "@baseboard_fab2_lib.baseboard_fab2(sch_1):\PP318\"
				( pinRef "@baseboard_fab2_lib.baseboard_fab2(sch_1):page31_i106:PE2_TX_DP(2)" )
				( pinRef "@baseboard_fab2_lib.baseboard_fab2(sch_1):page105_i75:A" )
				( attribute "RELATIVE_PROPAGATION_DELAY_SCOPE" "L"
					( Parent
						( matchGroupRef "@baseboard_fab2_lib.baseboard_fab2(sch_1):\MG_PCIE_L1\" )
					)
					( Status sCSetFlattened )
					( Origin gBackEnd )
				)
				( attribute "RELATIVE_PROPAGATION_DELAY" ",5.00 MIL"
					( Parent
						( matchGroupRef "@baseboard_fab2_lib.baseboard_fab2(sch_1):\MG_PCIE_L1\" )
					)
					( Units "uMatchProp" "ns" 1.000000)
					( Status sCSetFlattened )
					( Origin gBackEnd )
				)
			)
			( pinPair "@baseboard_fab2_lib.baseboard_fab2(sch_1):\PP5825\"
				( pinRef "@baseboard_fab2_lib.baseboard_fab2(sch_1):page31_i106:PE2_TX_DP(2)" )
				( pinRef "@baseboard_fab2_lib.baseboard_fab2(sch_1):page109_i243:IO117" )
				( attribute "PROPAGATION_DELAY_MIN" "3000.00 MIL"
					( Units "uMaxMinProp" "ns" 1.000000)
					( Status sCSetFlattened )
					( Origin gBackEnd )
				)
				( attribute "PROPAGATION_DELAY_MAX" "16000.00 MIL"
					( Units "uMaxMinProp" "ns" 1.000000)
					( Status sCSetFlattened )
					( Origin gBackEnd )
				)
				( attribute "RELATIVE_PROPAGATION_DELAY_SCOPE" "G"
					( Parent
						( matchGroupRef "@baseboard_fab2_lib.baseboard_fab2(sch_1):\MG_P3E_CPU0_PE2_SS_TX0203\" )
					)
					( Status sCSetFlattened )
					( Origin gBackEnd )
				)
				( attribute "RELATIVE_PROPAGATION_DELAY" ",500.00 MIL"
					( Parent
						( matchGroupRef "@baseboard_fab2_lib.baseboard_fab2(sch_1):\MG_P3E_CPU0_PE2_SS_TX0203\" )
					)
					( Units "uMatchProp" "ns" 1.000000)
					( Status sCSetFlattened )
					( Origin gBackEnd )
				)
			)
			( pinPair "@baseboard_fab2_lib.baseboard_fab2(sch_1):\PP311\"
				( pinRef "@baseboard_fab2_lib.baseboard_fab2(sch_1):page31_i106:PE2_TX_DN(3)" )
				( pinRef "@baseboard_fab2_lib.baseboard_fab2(sch_1):page105_i56:A" )
				( attribute "RELATIVE_PROPAGATION_DELAY_SCOPE" "L"
					( Parent
						( matchGroupRef "@baseboard_fab2_lib.baseboard_fab2(sch_1):\MG_PCIE_L1\" )
					)
					( Status sCSetFlattened )
					( Origin gBackEnd )
				)
				( attribute "RELATIVE_PROPAGATION_DELAY" ",5.00 MIL"
					( Parent
						( matchGroupRef "@baseboard_fab2_lib.baseboard_fab2(sch_1):\MG_PCIE_L1\" )
					)
					( Units "uMatchProp" "ns" 1.000000)
					( Status sCSetFlattened )
					( Origin gBackEnd )
				)
			)
			( pinPair "@baseboard_fab2_lib.baseboard_fab2(sch_1):\PP312\"
				( pinRef "@baseboard_fab2_lib.baseboard_fab2(sch_1):page109_i243:IO121" )
				( pinRef "@baseboard_fab2_lib.baseboard_fab2(sch_1):page105_i56:B" )
				( attribute "RELATIVE_PROPAGATION_DELAY_SCOPE" "L"
					( Parent
						( matchGroupRef "@baseboard_fab2_lib.baseboard_fab2(sch_1):\MG_PCIE_L0\" )
					)
					( Status sCSetFlattened )
					( Origin gBackEnd )
				)
				( attribute "RELATIVE_PROPAGATION_DELAY" ",5.00 MIL"
					( Parent
						( matchGroupRef "@baseboard_fab2_lib.baseboard_fab2(sch_1):\MG_PCIE_L0\" )
					)
					( Units "uMatchProp" "ns" 1.000000)
					( Status sCSetFlattened )
					( Origin gBackEnd )
				)
			)
			( pinPair "@baseboard_fab2_lib.baseboard_fab2(sch_1):\PP5857\"
				( pinRef "@baseboard_fab2_lib.baseboard_fab2(sch_1):page31_i106:PE2_TX_DN(3)" )
				( pinRef "@baseboard_fab2_lib.baseboard_fab2(sch_1):page109_i243:IO121" )
				( attribute "PROPAGATION_DELAY_MIN" "3000.00 MIL"
					( Units "uMaxMinProp" "ns" 1.000000)
					( Status sCSetFlattened )
					( Origin gBackEnd )
				)
				( attribute "PROPAGATION_DELAY_MAX" "16000.00 MIL"
					( Units "uMaxMinProp" "ns" 1.000000)
					( Status sCSetFlattened )
					( Origin gBackEnd )
				)
				( attribute "RELATIVE_PROPAGATION_DELAY_SCOPE" "G"
					( Parent
						( matchGroupRef "@baseboard_fab2_lib.baseboard_fab2(sch_1):\MG_P3E_CPU0_PE2_SS_TX0203\" )
					)
					( Status sCSetFlattened )
					( Origin gBackEnd )
				)
				( attribute "RELATIVE_PROPAGATION_DELAY" ",500.00 MIL"
					( Parent
						( matchGroupRef "@baseboard_fab2_lib.baseboard_fab2(sch_1):\MG_P3E_CPU0_PE2_SS_TX0203\" )
					)
					( Units "uMatchProp" "ns" 1.000000)
					( Status sCSetFlattened )
					( Origin gBackEnd )
				)
			)
			( pinPair "@baseboard_fab2_lib.baseboard_fab2(sch_1):\PP313\"
				( pinRef "@baseboard_fab2_lib.baseboard_fab2(sch_1):page109_i243:IO123" )
				( pinRef "@baseboard_fab2_lib.baseboard_fab2(sch_1):page105_i71:B" )
				( attribute "RELATIVE_PROPAGATION_DELAY_SCOPE" "L"
					( Parent
						( matchGroupRef "@baseboard_fab2_lib.baseboard_fab2(sch_1):\MG_PCIE_L0\" )
					)
					( Status sCSetFlattened )
					( Origin gBackEnd )
				)
				( attribute "RELATIVE_PROPAGATION_DELAY" ",5.00 MIL"
					( Parent
						( matchGroupRef "@baseboard_fab2_lib.baseboard_fab2(sch_1):\MG_PCIE_L0\" )
					)
					( Units "uMatchProp" "ns" 1.000000)
					( Status sCSetFlattened )
					( Origin gBackEnd )
				)
			)
			( pinPair "@baseboard_fab2_lib.baseboard_fab2(sch_1):\PP314\"
				( pinRef "@baseboard_fab2_lib.baseboard_fab2(sch_1):page31_i106:PE2_TX_DP(3)" )
				( pinRef "@baseboard_fab2_lib.baseboard_fab2(sch_1):page105_i71:A" )
				( attribute "RELATIVE_PROPAGATION_DELAY_SCOPE" "L"
					( Parent
						( matchGroupRef "@baseboard_fab2_lib.baseboard_fab2(sch_1):\MG_PCIE_L1\" )
					)
					( Status sCSetFlattened )
					( Origin gBackEnd )
				)
				( attribute "RELATIVE_PROPAGATION_DELAY" ",5.00 MIL"
					( Parent
						( matchGroupRef "@baseboard_fab2_lib.baseboard_fab2(sch_1):\MG_PCIE_L1\" )
					)
					( Units "uMatchProp" "ns" 1.000000)
					( Status sCSetFlattened )
					( Origin gBackEnd )
				)
			)
			( pinPair "@baseboard_fab2_lib.baseboard_fab2(sch_1):\PP5815\"
				( pinRef "@baseboard_fab2_lib.baseboard_fab2(sch_1):page31_i106:PE2_TX_DP(3)" )
				( pinRef "@baseboard_fab2_lib.baseboard_fab2(sch_1):page109_i243:IO123" )
				( attribute "PROPAGATION_DELAY_MIN" "3000.00 MIL"
					( Units "uMaxMinProp" "ns" 1.000000)
					( Status sCSetFlattened )
					( Origin gBackEnd )
				)
				( attribute "PROPAGATION_DELAY_MAX" "16000.00 MIL"
					( Units "uMaxMinProp" "ns" 1.000000)
					( Status sCSetFlattened )
					( Origin gBackEnd )
				)
				( attribute "RELATIVE_PROPAGATION_DELAY_SCOPE" "G"
					( Parent
						( matchGroupRef "@baseboard_fab2_lib.baseboard_fab2(sch_1):\MG_P3E_CPU0_PE2_SS_TX0203\" )
					)
					( Status sCSetFlattened )
					( Origin gBackEnd )
				)
				( attribute "RELATIVE_PROPAGATION_DELAY" ",500.00 MIL"
					( Parent
						( matchGroupRef "@baseboard_fab2_lib.baseboard_fab2(sch_1):\MG_P3E_CPU0_PE2_SS_TX0203\" )
					)
					( Units "uMatchProp" "ns" 1.000000)
					( Status sCSetFlattened )
					( Origin gBackEnd )
				)
			)
			( pinPair "@baseboard_fab2_lib.baseboard_fab2(sch_1):\PP307\"
				( pinRef "@baseboard_fab2_lib.baseboard_fab2(sch_1):page31_i106:PE2_TX_DN(4)" )
				( pinRef "@baseboard_fab2_lib.baseboard_fab2(sch_1):page105_i58:A" )
				( attribute "RELATIVE_PROPAGATION_DELAY_SCOPE" "L"
					( Parent
						( matchGroupRef "@baseboard_fab2_lib.baseboard_fab2(sch_1):\MG_PCIE_L1\" )
					)
					( Status sCSetFlattened )
					( Origin gBackEnd )
				)
				( attribute "RELATIVE_PROPAGATION_DELAY" ",5.00 MIL"
					( Parent
						( matchGroupRef "@baseboard_fab2_lib.baseboard_fab2(sch_1):\MG_PCIE_L1\" )
					)
					( Units "uMatchProp" "ns" 1.000000)
					( Status sCSetFlattened )
					( Origin gBackEnd )
				)
			)
			( pinPair "@baseboard_fab2_lib.baseboard_fab2(sch_1):\PP308\"
				( pinRef "@baseboard_fab2_lib.baseboard_fab2(sch_1):page109_i243:IO127" )
				( pinRef "@baseboard_fab2_lib.baseboard_fab2(sch_1):page105_i58:B" )
				( attribute "RELATIVE_PROPAGATION_DELAY_SCOPE" "L"
					( Parent
						( matchGroupRef "@baseboard_fab2_lib.baseboard_fab2(sch_1):\MG_PCIE_L0\" )
					)
					( Status sCSetFlattened )
					( Origin gBackEnd )
				)
				( attribute "RELATIVE_PROPAGATION_DELAY" ",5.00 MIL"
					( Parent
						( matchGroupRef "@baseboard_fab2_lib.baseboard_fab2(sch_1):\MG_PCIE_L0\" )
					)
					( Units "uMatchProp" "ns" 1.000000)
					( Status sCSetFlattened )
					( Origin gBackEnd )
				)
			)
			( pinPair "@baseboard_fab2_lib.baseboard_fab2(sch_1):\PP5821\"
				( pinRef "@baseboard_fab2_lib.baseboard_fab2(sch_1):page31_i106:PE2_TX_DN(4)" )
				( pinRef "@baseboard_fab2_lib.baseboard_fab2(sch_1):page109_i243:IO127" )
				( attribute "PROPAGATION_DELAY_MIN" "3000.00 MIL"
					( Units "uMaxMinProp" "ns" 1.000000)
					( Status sCSetFlattened )
					( Origin gBackEnd )
				)
				( attribute "PROPAGATION_DELAY_MAX" "16000.00 MIL"
					( Units "uMaxMinProp" "ns" 1.000000)
					( Status sCSetFlattened )
					( Origin gBackEnd )
				)
				( attribute "RELATIVE_PROPAGATION_DELAY_SCOPE" "G"
					( Parent
						( matchGroupRef "@baseboard_fab2_lib.baseboard_fab2(sch_1):\MG_P3E_CPU0_PE2_SS_TX0405\" )
					)
					( Status sCSetFlattened )
					( Origin gBackEnd )
				)
				( attribute "RELATIVE_PROPAGATION_DELAY" ",500.00 MIL"
					( Parent
						( matchGroupRef "@baseboard_fab2_lib.baseboard_fab2(sch_1):\MG_P3E_CPU0_PE2_SS_TX0405\" )
					)
					( Units "uMatchProp" "ns" 1.000000)
					( Status sCSetFlattened )
					( Origin gBackEnd )
				)
			)
			( pinPair "@baseboard_fab2_lib.baseboard_fab2(sch_1):\PP309\"
				( pinRef "@baseboard_fab2_lib.baseboard_fab2(sch_1):page109_i243:IO129" )
				( pinRef "@baseboard_fab2_lib.baseboard_fab2(sch_1):page105_i70:B" )
				( attribute "RELATIVE_PROPAGATION_DELAY_SCOPE" "L"
					( Parent
						( matchGroupRef "@baseboard_fab2_lib.baseboard_fab2(sch_1):\MG_PCIE_L0\" )
					)
					( Status sCSetFlattened )
					( Origin gBackEnd )
				)
				( attribute "RELATIVE_PROPAGATION_DELAY" ",5.00 MIL"
					( Parent
						( matchGroupRef "@baseboard_fab2_lib.baseboard_fab2(sch_1):\MG_PCIE_L0\" )
					)
					( Units "uMatchProp" "ns" 1.000000)
					( Status sCSetFlattened )
					( Origin gBackEnd )
				)
			)
			( pinPair "@baseboard_fab2_lib.baseboard_fab2(sch_1):\PP310\"
				( pinRef "@baseboard_fab2_lib.baseboard_fab2(sch_1):page31_i106:PE2_TX_DP(4)" )
				( pinRef "@baseboard_fab2_lib.baseboard_fab2(sch_1):page105_i70:A" )
				( attribute "RELATIVE_PROPAGATION_DELAY_SCOPE" "L"
					( Parent
						( matchGroupRef "@baseboard_fab2_lib.baseboard_fab2(sch_1):\MG_PCIE_L1\" )
					)
					( Status sCSetFlattened )
					( Origin gBackEnd )
				)
				( attribute "RELATIVE_PROPAGATION_DELAY" ",5.00 MIL"
					( Parent
						( matchGroupRef "@baseboard_fab2_lib.baseboard_fab2(sch_1):\MG_PCIE_L1\" )
					)
					( Units "uMatchProp" "ns" 1.000000)
					( Status sCSetFlattened )
					( Origin gBackEnd )
				)
			)
			( pinPair "@baseboard_fab2_lib.baseboard_fab2(sch_1):\PP5820\"
				( pinRef "@baseboard_fab2_lib.baseboard_fab2(sch_1):page31_i106:PE2_TX_DP(4)" )
				( pinRef "@baseboard_fab2_lib.baseboard_fab2(sch_1):page109_i243:IO129" )
				( attribute "PROPAGATION_DELAY_MIN" "3000.00 MIL"
					( Units "uMaxMinProp" "ns" 1.000000)
					( Status sCSetFlattened )
					( Origin gBackEnd )
				)
				( attribute "PROPAGATION_DELAY_MAX" "16000.00 MIL"
					( Units "uMaxMinProp" "ns" 1.000000)
					( Status sCSetFlattened )
					( Origin gBackEnd )
				)
				( attribute "RELATIVE_PROPAGATION_DELAY_SCOPE" "G"
					( Parent
						( matchGroupRef "@baseboard_fab2_lib.baseboard_fab2(sch_1):\MG_P3E_CPU0_PE2_SS_TX0405\" )
					)
					( Status sCSetFlattened )
					( Origin gBackEnd )
				)
				( attribute "RELATIVE_PROPAGATION_DELAY" ",500.00 MIL"
					( Parent
						( matchGroupRef "@baseboard_fab2_lib.baseboard_fab2(sch_1):\MG_P3E_CPU0_PE2_SS_TX0405\" )
					)
					( Units "uMatchProp" "ns" 1.000000)
					( Status sCSetFlattened )
					( Origin gBackEnd )
				)
			)
			( pinPair "@baseboard_fab2_lib.baseboard_fab2(sch_1):\PP303\"
				( pinRef "@baseboard_fab2_lib.baseboard_fab2(sch_1):page31_i106:PE2_TX_DN(5)" )
				( pinRef "@baseboard_fab2_lib.baseboard_fab2(sch_1):page105_i55:A" )
				( attribute "RELATIVE_PROPAGATION_DELAY_SCOPE" "L"
					( Parent
						( matchGroupRef "@baseboard_fab2_lib.baseboard_fab2(sch_1):\MG_PCIE_L1\" )
					)
					( Status sCSetFlattened )
					( Origin gBackEnd )
				)
				( attribute "RELATIVE_PROPAGATION_DELAY" ",5.00 MIL"
					( Parent
						( matchGroupRef "@baseboard_fab2_lib.baseboard_fab2(sch_1):\MG_PCIE_L1\" )
					)
					( Units "uMatchProp" "ns" 1.000000)
					( Status sCSetFlattened )
					( Origin gBackEnd )
				)
			)
			( pinPair "@baseboard_fab2_lib.baseboard_fab2(sch_1):\PP304\"
				( pinRef "@baseboard_fab2_lib.baseboard_fab2(sch_1):page109_i243:IO133" )
				( pinRef "@baseboard_fab2_lib.baseboard_fab2(sch_1):page105_i55:B" )
				( attribute "RELATIVE_PROPAGATION_DELAY_SCOPE" "L"
					( Parent
						( matchGroupRef "@baseboard_fab2_lib.baseboard_fab2(sch_1):\MG_PCIE_L0\" )
					)
					( Status sCSetFlattened )
					( Origin gBackEnd )
				)
				( attribute "RELATIVE_PROPAGATION_DELAY" ",5.00 MIL"
					( Parent
						( matchGroupRef "@baseboard_fab2_lib.baseboard_fab2(sch_1):\MG_PCIE_L0\" )
					)
					( Units "uMatchProp" "ns" 1.000000)
					( Status sCSetFlattened )
					( Origin gBackEnd )
				)
			)
			( pinPair "@baseboard_fab2_lib.baseboard_fab2(sch_1):\PP5912\"
				( pinRef "@baseboard_fab2_lib.baseboard_fab2(sch_1):page31_i106:PE2_TX_DN(5)" )
				( pinRef "@baseboard_fab2_lib.baseboard_fab2(sch_1):page109_i243:IO133" )
				( attribute "PROPAGATION_DELAY_MIN" "3000.00 MIL"
					( Units "uMaxMinProp" "ns" 1.000000)
					( Status sCSetFlattened )
					( Origin gBackEnd )
				)
				( attribute "PROPAGATION_DELAY_MAX" "16000.00 MIL"
					( Units "uMaxMinProp" "ns" 1.000000)
					( Status sCSetFlattened )
					( Origin gBackEnd )
				)
				( attribute "RELATIVE_PROPAGATION_DELAY_SCOPE" "G"
					( Parent
						( matchGroupRef "@baseboard_fab2_lib.baseboard_fab2(sch_1):\MG_P3E_CPU0_PE2_SS_TX0405\" )
					)
					( Status sCSetFlattened )
					( Origin gBackEnd )
				)
				( attribute "RELATIVE_PROPAGATION_DELAY" ",500.00 MIL"
					( Parent
						( matchGroupRef "@baseboard_fab2_lib.baseboard_fab2(sch_1):\MG_P3E_CPU0_PE2_SS_TX0405\" )
					)
					( Units "uMatchProp" "ns" 1.000000)
					( Status sCSetFlattened )
					( Origin gBackEnd )
				)
			)
			( pinPair "@baseboard_fab2_lib.baseboard_fab2(sch_1):\PP305\"
				( pinRef "@baseboard_fab2_lib.baseboard_fab2(sch_1):page109_i243:IO135" )
				( pinRef "@baseboard_fab2_lib.baseboard_fab2(sch_1):page105_i69:B" )
				( attribute "RELATIVE_PROPAGATION_DELAY_SCOPE" "L"
					( Parent
						( matchGroupRef "@baseboard_fab2_lib.baseboard_fab2(sch_1):\MG_PCIE_L0\" )
					)
					( Status sCSetFlattened )
					( Origin gBackEnd )
				)
				( attribute "RELATIVE_PROPAGATION_DELAY" ",5.00 MIL"
					( Parent
						( matchGroupRef "@baseboard_fab2_lib.baseboard_fab2(sch_1):\MG_PCIE_L0\" )
					)
					( Units "uMatchProp" "ns" 1.000000)
					( Status sCSetFlattened )
					( Origin gBackEnd )
				)
			)
			( pinPair "@baseboard_fab2_lib.baseboard_fab2(sch_1):\PP306\"
				( pinRef "@baseboard_fab2_lib.baseboard_fab2(sch_1):page31_i106:PE2_TX_DP(5)" )
				( pinRef "@baseboard_fab2_lib.baseboard_fab2(sch_1):page105_i69:A" )
				( attribute "RELATIVE_PROPAGATION_DELAY_SCOPE" "L"
					( Parent
						( matchGroupRef "@baseboard_fab2_lib.baseboard_fab2(sch_1):\MG_PCIE_L1\" )
					)
					( Status sCSetFlattened )
					( Origin gBackEnd )
				)
				( attribute "RELATIVE_PROPAGATION_DELAY" ",5.00 MIL"
					( Parent
						( matchGroupRef "@baseboard_fab2_lib.baseboard_fab2(sch_1):\MG_PCIE_L1\" )
					)
					( Units "uMatchProp" "ns" 1.000000)
					( Status sCSetFlattened )
					( Origin gBackEnd )
				)
			)
			( pinPair "@baseboard_fab2_lib.baseboard_fab2(sch_1):\PP5827\"
				( pinRef "@baseboard_fab2_lib.baseboard_fab2(sch_1):page31_i106:PE2_TX_DP(5)" )
				( pinRef "@baseboard_fab2_lib.baseboard_fab2(sch_1):page109_i243:IO135" )
				( attribute "PROPAGATION_DELAY_MIN" "3000.00 MIL"
					( Units "uMaxMinProp" "ns" 1.000000)
					( Status sCSetFlattened )
					( Origin gBackEnd )
				)
				( attribute "PROPAGATION_DELAY_MAX" "16000.00 MIL"
					( Units "uMaxMinProp" "ns" 1.000000)
					( Status sCSetFlattened )
					( Origin gBackEnd )
				)
				( attribute "RELATIVE_PROPAGATION_DELAY_SCOPE" "G"
					( Parent
						( matchGroupRef "@baseboard_fab2_lib.baseboard_fab2(sch_1):\MG_P3E_CPU0_PE2_SS_TX0405\" )
					)
					( Status sCSetFlattened )
					( Origin gBackEnd )
				)
				( attribute "RELATIVE_PROPAGATION_DELAY" ",500.00 MIL"
					( Parent
						( matchGroupRef "@baseboard_fab2_lib.baseboard_fab2(sch_1):\MG_P3E_CPU0_PE2_SS_TX0405\" )
					)
					( Units "uMatchProp" "ns" 1.000000)
					( Status sCSetFlattened )
					( Origin gBackEnd )
				)
			)
			( pinPair "@baseboard_fab2_lib.baseboard_fab2(sch_1):\PP299\"
				( pinRef "@baseboard_fab2_lib.baseboard_fab2(sch_1):page31_i106:PE2_TX_DN(6)" )
				( pinRef "@baseboard_fab2_lib.baseboard_fab2(sch_1):page105_i1:A" )
				( attribute "RELATIVE_PROPAGATION_DELAY_SCOPE" "L"
					( Parent
						( matchGroupRef "@baseboard_fab2_lib.baseboard_fab2(sch_1):\MG_PCIE_L1\" )
					)
					( Status sCSetFlattened )
					( Origin gBackEnd )
				)
				( attribute "RELATIVE_PROPAGATION_DELAY" ",5.00 MIL"
					( Parent
						( matchGroupRef "@baseboard_fab2_lib.baseboard_fab2(sch_1):\MG_PCIE_L1\" )
					)
					( Units "uMatchProp" "ns" 1.000000)
					( Status sCSetFlattened )
					( Origin gBackEnd )
				)
			)
			( pinPair "@baseboard_fab2_lib.baseboard_fab2(sch_1):\PP300\"
				( pinRef "@baseboard_fab2_lib.baseboard_fab2(sch_1):page109_i243:IO139" )
				( pinRef "@baseboard_fab2_lib.baseboard_fab2(sch_1):page105_i1:B" )
				( attribute "RELATIVE_PROPAGATION_DELAY_SCOPE" "L"
					( Parent
						( matchGroupRef "@baseboard_fab2_lib.baseboard_fab2(sch_1):\MG_PCIE_L0\" )
					)
					( Status sCSetFlattened )
					( Origin gBackEnd )
				)
				( attribute "RELATIVE_PROPAGATION_DELAY" ",5.00 MIL"
					( Parent
						( matchGroupRef "@baseboard_fab2_lib.baseboard_fab2(sch_1):\MG_PCIE_L0\" )
					)
					( Units "uMatchProp" "ns" 1.000000)
					( Status sCSetFlattened )
					( Origin gBackEnd )
				)
			)
			( pinPair "@baseboard_fab2_lib.baseboard_fab2(sch_1):\PP5917\"
				( pinRef "@baseboard_fab2_lib.baseboard_fab2(sch_1):page31_i106:PE2_TX_DN(6)" )
				( pinRef "@baseboard_fab2_lib.baseboard_fab2(sch_1):page109_i243:IO139" )
				( attribute "PROPAGATION_DELAY_MIN" "3000.00 MIL"
					( Units "uMaxMinProp" "ns" 1.000000)
					( Status sCSetFlattened )
					( Origin gBackEnd )
				)
				( attribute "PROPAGATION_DELAY_MAX" "16000.00 MIL"
					( Units "uMaxMinProp" "ns" 1.000000)
					( Status sCSetFlattened )
					( Origin gBackEnd )
				)
				( attribute "RELATIVE_PROPAGATION_DELAY_SCOPE" "G"
					( Parent
						( matchGroupRef "@baseboard_fab2_lib.baseboard_fab2(sch_1):\MG_P3E_CPU0_PE2_SS_TX0607\" )
					)
					( Status sCSetFlattened )
					( Origin gBackEnd )
				)
				( attribute "RELATIVE_PROPAGATION_DELAY" ",500.00 MIL"
					( Parent
						( matchGroupRef "@baseboard_fab2_lib.baseboard_fab2(sch_1):\MG_P3E_CPU0_PE2_SS_TX0607\" )
					)
					( Units "uMatchProp" "ns" 1.000000)
					( Status sCSetFlattened )
					( Origin gBackEnd )
				)
			)
			( pinPair "@baseboard_fab2_lib.baseboard_fab2(sch_1):\PP301\"
				( pinRef "@baseboard_fab2_lib.baseboard_fab2(sch_1):page109_i243:IO141" )
				( pinRef "@baseboard_fab2_lib.baseboard_fab2(sch_1):page105_i52:B" )
				( attribute "RELATIVE_PROPAGATION_DELAY_SCOPE" "L"
					( Parent
						( matchGroupRef "@baseboard_fab2_lib.baseboard_fab2(sch_1):\MG_PCIE_L0\" )
					)
					( Status sCSetFlattened )
					( Origin gBackEnd )
				)
				( attribute "RELATIVE_PROPAGATION_DELAY" ",5.00 MIL"
					( Parent
						( matchGroupRef "@baseboard_fab2_lib.baseboard_fab2(sch_1):\MG_PCIE_L0\" )
					)
					( Units "uMatchProp" "ns" 1.000000)
					( Status sCSetFlattened )
					( Origin gBackEnd )
				)
			)
			( pinPair "@baseboard_fab2_lib.baseboard_fab2(sch_1):\PP302\"
				( pinRef "@baseboard_fab2_lib.baseboard_fab2(sch_1):page31_i106:PE2_TX_DP(6)" )
				( pinRef "@baseboard_fab2_lib.baseboard_fab2(sch_1):page105_i52:A" )
				( attribute "RELATIVE_PROPAGATION_DELAY_SCOPE" "L"
					( Parent
						( matchGroupRef "@baseboard_fab2_lib.baseboard_fab2(sch_1):\MG_PCIE_L1\" )
					)
					( Status sCSetFlattened )
					( Origin gBackEnd )
				)
				( attribute "RELATIVE_PROPAGATION_DELAY" ",5.00 MIL"
					( Parent
						( matchGroupRef "@baseboard_fab2_lib.baseboard_fab2(sch_1):\MG_PCIE_L1\" )
					)
					( Units "uMatchProp" "ns" 1.000000)
					( Status sCSetFlattened )
					( Origin gBackEnd )
				)
			)
			( pinPair "@baseboard_fab2_lib.baseboard_fab2(sch_1):\PP5913\"
				( pinRef "@baseboard_fab2_lib.baseboard_fab2(sch_1):page31_i106:PE2_TX_DP(6)" )
				( pinRef "@baseboard_fab2_lib.baseboard_fab2(sch_1):page109_i243:IO141" )
				( attribute "PROPAGATION_DELAY_MIN" "3000.00 MIL"
					( Units "uMaxMinProp" "ns" 1.000000)
					( Status sCSetFlattened )
					( Origin gBackEnd )
				)
				( attribute "PROPAGATION_DELAY_MAX" "16000.00 MIL"
					( Units "uMaxMinProp" "ns" 1.000000)
					( Status sCSetFlattened )
					( Origin gBackEnd )
				)
				( attribute "RELATIVE_PROPAGATION_DELAY_SCOPE" "G"
					( Parent
						( matchGroupRef "@baseboard_fab2_lib.baseboard_fab2(sch_1):\MG_P3E_CPU0_PE2_SS_TX0607\" )
					)
					( Status sCSetFlattened )
					( Origin gBackEnd )
				)
				( attribute "RELATIVE_PROPAGATION_DELAY" ",500.00 MIL"
					( Parent
						( matchGroupRef "@baseboard_fab2_lib.baseboard_fab2(sch_1):\MG_P3E_CPU0_PE2_SS_TX0607\" )
					)
					( Units "uMatchProp" "ns" 1.000000)
					( Status sCSetFlattened )
					( Origin gBackEnd )
				)
			)
			( pinPair "@baseboard_fab2_lib.baseboard_fab2(sch_1):\PP295\"
				( pinRef "@baseboard_fab2_lib.baseboard_fab2(sch_1):page31_i106:PE2_TX_DN(7)" )
				( pinRef "@baseboard_fab2_lib.baseboard_fab2(sch_1):page105_i37:A" )
				( attribute "RELATIVE_PROPAGATION_DELAY_SCOPE" "L"
					( Parent
						( matchGroupRef "@baseboard_fab2_lib.baseboard_fab2(sch_1):\MG_PCIE_L1\" )
					)
					( Status sCSetFlattened )
					( Origin gBackEnd )
				)
				( attribute "RELATIVE_PROPAGATION_DELAY" ",5.00 MIL"
					( Parent
						( matchGroupRef "@baseboard_fab2_lib.baseboard_fab2(sch_1):\MG_PCIE_L1\" )
					)
					( Units "uMatchProp" "ns" 1.000000)
					( Status sCSetFlattened )
					( Origin gBackEnd )
				)
			)
			( pinPair "@baseboard_fab2_lib.baseboard_fab2(sch_1):\PP296\"
				( pinRef "@baseboard_fab2_lib.baseboard_fab2(sch_1):page109_i243:IO145" )
				( pinRef "@baseboard_fab2_lib.baseboard_fab2(sch_1):page105_i37:B" )
				( attribute "RELATIVE_PROPAGATION_DELAY_SCOPE" "L"
					( Parent
						( matchGroupRef "@baseboard_fab2_lib.baseboard_fab2(sch_1):\MG_PCIE_L0\" )
					)
					( Status sCSetFlattened )
					( Origin gBackEnd )
				)
				( attribute "RELATIVE_PROPAGATION_DELAY" ",5.00 MIL"
					( Parent
						( matchGroupRef "@baseboard_fab2_lib.baseboard_fab2(sch_1):\MG_PCIE_L0\" )
					)
					( Units "uMatchProp" "ns" 1.000000)
					( Status sCSetFlattened )
					( Origin gBackEnd )
				)
			)
			( pinPair "@baseboard_fab2_lib.baseboard_fab2(sch_1):\PP5919\"
				( pinRef "@baseboard_fab2_lib.baseboard_fab2(sch_1):page31_i106:PE2_TX_DN(7)" )
				( pinRef "@baseboard_fab2_lib.baseboard_fab2(sch_1):page109_i243:IO145" )
				( attribute "PROPAGATION_DELAY_MIN" "3000.00 MIL"
					( Units "uMaxMinProp" "ns" 1.000000)
					( Status sCSetFlattened )
					( Origin gBackEnd )
				)
				( attribute "PROPAGATION_DELAY_MAX" "16000.00 MIL"
					( Units "uMaxMinProp" "ns" 1.000000)
					( Status sCSetFlattened )
					( Origin gBackEnd )
				)
				( attribute "RELATIVE_PROPAGATION_DELAY_SCOPE" "G"
					( Parent
						( matchGroupRef "@baseboard_fab2_lib.baseboard_fab2(sch_1):\MG_P3E_CPU0_PE2_SS_TX0607\" )
					)
					( Status sCSetFlattened )
					( Origin gBackEnd )
				)
				( attribute "RELATIVE_PROPAGATION_DELAY" ",500.00 MIL"
					( Parent
						( matchGroupRef "@baseboard_fab2_lib.baseboard_fab2(sch_1):\MG_P3E_CPU0_PE2_SS_TX0607\" )
					)
					( Units "uMatchProp" "ns" 1.000000)
					( Status sCSetFlattened )
					( Origin gBackEnd )
				)
			)
			( pinPair "@baseboard_fab2_lib.baseboard_fab2(sch_1):\PP297\"
				( pinRef "@baseboard_fab2_lib.baseboard_fab2(sch_1):page109_i243:IO147" )
				( pinRef "@baseboard_fab2_lib.baseboard_fab2(sch_1):page105_i51:B" )
				( attribute "RELATIVE_PROPAGATION_DELAY_SCOPE" "L"
					( Parent
						( matchGroupRef "@baseboard_fab2_lib.baseboard_fab2(sch_1):\MG_PCIE_L0\" )
					)
					( Status sCSetFlattened )
					( Origin gBackEnd )
				)
				( attribute "RELATIVE_PROPAGATION_DELAY" ",5.00 MIL"
					( Parent
						( matchGroupRef "@baseboard_fab2_lib.baseboard_fab2(sch_1):\MG_PCIE_L0\" )
					)
					( Units "uMatchProp" "ns" 1.000000)
					( Status sCSetFlattened )
					( Origin gBackEnd )
				)
			)
			( pinPair "@baseboard_fab2_lib.baseboard_fab2(sch_1):\PP298\"
				( pinRef "@baseboard_fab2_lib.baseboard_fab2(sch_1):page31_i106:PE2_TX_DP(7)" )
				( pinRef "@baseboard_fab2_lib.baseboard_fab2(sch_1):page105_i51:A" )
				( attribute "RELATIVE_PROPAGATION_DELAY_SCOPE" "L"
					( Parent
						( matchGroupRef "@baseboard_fab2_lib.baseboard_fab2(sch_1):\MG_PCIE_L1\" )
					)
					( Status sCSetFlattened )
					( Origin gBackEnd )
				)
				( attribute "RELATIVE_PROPAGATION_DELAY" ",5.00 MIL"
					( Parent
						( matchGroupRef "@baseboard_fab2_lib.baseboard_fab2(sch_1):\MG_PCIE_L1\" )
					)
					( Units "uMatchProp" "ns" 1.000000)
					( Status sCSetFlattened )
					( Origin gBackEnd )
				)
			)
			( pinPair "@baseboard_fab2_lib.baseboard_fab2(sch_1):\PP5918\"
				( pinRef "@baseboard_fab2_lib.baseboard_fab2(sch_1):page31_i106:PE2_TX_DP(7)" )
				( pinRef "@baseboard_fab2_lib.baseboard_fab2(sch_1):page109_i243:IO147" )
				( attribute "PROPAGATION_DELAY_MIN" "3000.00 MIL"
					( Units "uMaxMinProp" "ns" 1.000000)
					( Status sCSetFlattened )
					( Origin gBackEnd )
				)
				( attribute "PROPAGATION_DELAY_MAX" "16000.00 MIL"
					( Units "uMaxMinProp" "ns" 1.000000)
					( Status sCSetFlattened )
					( Origin gBackEnd )
				)
				( attribute "RELATIVE_PROPAGATION_DELAY_SCOPE" "G"
					( Parent
						( matchGroupRef "@baseboard_fab2_lib.baseboard_fab2(sch_1):\MG_P3E_CPU0_PE2_SS_TX0607\" )
					)
					( Status sCSetFlattened )
					( Origin gBackEnd )
				)
				( attribute "RELATIVE_PROPAGATION_DELAY" ",500.00 MIL"
					( Parent
						( matchGroupRef "@baseboard_fab2_lib.baseboard_fab2(sch_1):\MG_P3E_CPU0_PE2_SS_TX0607\" )
					)
					( Units "uMatchProp" "ns" 1.000000)
					( Status sCSetFlattened )
					( Origin gBackEnd )
				)
			)
			( pinPair "@baseboard_fab2_lib.baseboard_fab2(sch_1):\PP291\"
				( pinRef "@baseboard_fab2_lib.baseboard_fab2(sch_1):page31_i106:PE2_TX_DN(8)" )
				( pinRef "@baseboard_fab2_lib.baseboard_fab2(sch_1):page105_i34:A" )
				( attribute "RELATIVE_PROPAGATION_DELAY_SCOPE" "L"
					( Parent
						( matchGroupRef "@baseboard_fab2_lib.baseboard_fab2(sch_1):\MG_PCIE_L1\" )
					)
					( Status sCSetFlattened )
					( Origin gBackEnd )
				)
				( attribute "RELATIVE_PROPAGATION_DELAY" ",5.00 MIL"
					( Parent
						( matchGroupRef "@baseboard_fab2_lib.baseboard_fab2(sch_1):\MG_PCIE_L1\" )
					)
					( Units "uMatchProp" "ns" 1.000000)
					( Status sCSetFlattened )
					( Origin gBackEnd )
				)
			)
			( pinPair "@baseboard_fab2_lib.baseboard_fab2(sch_1):\PP292\"
				( pinRef "@baseboard_fab2_lib.baseboard_fab2(sch_1):page109_i243:IO151" )
				( pinRef "@baseboard_fab2_lib.baseboard_fab2(sch_1):page105_i34:B" )
				( attribute "RELATIVE_PROPAGATION_DELAY_SCOPE" "L"
					( Parent
						( matchGroupRef "@baseboard_fab2_lib.baseboard_fab2(sch_1):\MG_PCIE_L0\" )
					)
					( Status sCSetFlattened )
					( Origin gBackEnd )
				)
				( attribute "RELATIVE_PROPAGATION_DELAY" ",5.00 MIL"
					( Parent
						( matchGroupRef "@baseboard_fab2_lib.baseboard_fab2(sch_1):\MG_PCIE_L0\" )
					)
					( Units "uMatchProp" "ns" 1.000000)
					( Status sCSetFlattened )
					( Origin gBackEnd )
				)
			)
			( pinPair "@baseboard_fab2_lib.baseboard_fab2(sch_1):\PP5915\"
				( pinRef "@baseboard_fab2_lib.baseboard_fab2(sch_1):page31_i106:PE2_TX_DN(8)" )
				( pinRef "@baseboard_fab2_lib.baseboard_fab2(sch_1):page109_i243:IO151" )
				( attribute "PROPAGATION_DELAY_MIN" "3000.00 MIL"
					( Units "uMaxMinProp" "ns" 1.000000)
					( Status sCSetFlattened )
					( Origin gBackEnd )
				)
				( attribute "PROPAGATION_DELAY_MAX" "16000.00 MIL"
					( Units "uMaxMinProp" "ns" 1.000000)
					( Status sCSetFlattened )
					( Origin gBackEnd )
				)
				( attribute "RELATIVE_PROPAGATION_DELAY_SCOPE" "G"
					( Parent
						( matchGroupRef "@baseboard_fab2_lib.baseboard_fab2(sch_1):\MG_P3E_CPU0_PE2_SS_TX0809\" )
					)
					( Status sCSetFlattened )
					( Origin gBackEnd )
				)
				( attribute "RELATIVE_PROPAGATION_DELAY" ",500.00 MIL"
					( Parent
						( matchGroupRef "@baseboard_fab2_lib.baseboard_fab2(sch_1):\MG_P3E_CPU0_PE2_SS_TX0809\" )
					)
					( Units "uMatchProp" "ns" 1.000000)
					( Status sCSetFlattened )
					( Origin gBackEnd )
				)
			)
			( pinPair "@baseboard_fab2_lib.baseboard_fab2(sch_1):\PP293\"
				( pinRef "@baseboard_fab2_lib.baseboard_fab2(sch_1):page109_i243:IO153" )
				( pinRef "@baseboard_fab2_lib.baseboard_fab2(sch_1):page105_i46:B" )
				( attribute "RELATIVE_PROPAGATION_DELAY_SCOPE" "L"
					( Parent
						( matchGroupRef "@baseboard_fab2_lib.baseboard_fab2(sch_1):\MG_PCIE_L0\" )
					)
					( Status sCSetFlattened )
					( Origin gBackEnd )
				)
				( attribute "RELATIVE_PROPAGATION_DELAY" ",5.00 MIL"
					( Parent
						( matchGroupRef "@baseboard_fab2_lib.baseboard_fab2(sch_1):\MG_PCIE_L0\" )
					)
					( Units "uMatchProp" "ns" 1.000000)
					( Status sCSetFlattened )
					( Origin gBackEnd )
				)
			)
			( pinPair "@baseboard_fab2_lib.baseboard_fab2(sch_1):\PP294\"
				( pinRef "@baseboard_fab2_lib.baseboard_fab2(sch_1):page31_i106:PE2_TX_DP(8)" )
				( pinRef "@baseboard_fab2_lib.baseboard_fab2(sch_1):page105_i46:A" )
				( attribute "RELATIVE_PROPAGATION_DELAY_SCOPE" "L"
					( Parent
						( matchGroupRef "@baseboard_fab2_lib.baseboard_fab2(sch_1):\MG_PCIE_L1\" )
					)
					( Status sCSetFlattened )
					( Origin gBackEnd )
				)
				( attribute "RELATIVE_PROPAGATION_DELAY" ",5.00 MIL"
					( Parent
						( matchGroupRef "@baseboard_fab2_lib.baseboard_fab2(sch_1):\MG_PCIE_L1\" )
					)
					( Units "uMatchProp" "ns" 1.000000)
					( Status sCSetFlattened )
					( Origin gBackEnd )
				)
			)
			( pinPair "@baseboard_fab2_lib.baseboard_fab2(sch_1):\PP5920\"
				( pinRef "@baseboard_fab2_lib.baseboard_fab2(sch_1):page31_i106:PE2_TX_DP(8)" )
				( pinRef "@baseboard_fab2_lib.baseboard_fab2(sch_1):page109_i243:IO153" )
				( attribute "PROPAGATION_DELAY_MIN" "3000.00 MIL"
					( Units "uMaxMinProp" "ns" 1.000000)
					( Status sCSetFlattened )
					( Origin gBackEnd )
				)
				( attribute "PROPAGATION_DELAY_MAX" "16000.00 MIL"
					( Units "uMaxMinProp" "ns" 1.000000)
					( Status sCSetFlattened )
					( Origin gBackEnd )
				)
				( attribute "RELATIVE_PROPAGATION_DELAY_SCOPE" "G"
					( Parent
						( matchGroupRef "@baseboard_fab2_lib.baseboard_fab2(sch_1):\MG_P3E_CPU0_PE2_SS_TX0809\" )
					)
					( Status sCSetFlattened )
					( Origin gBackEnd )
				)
				( attribute "RELATIVE_PROPAGATION_DELAY" ",500.00 MIL"
					( Parent
						( matchGroupRef "@baseboard_fab2_lib.baseboard_fab2(sch_1):\MG_P3E_CPU0_PE2_SS_TX0809\" )
					)
					( Units "uMatchProp" "ns" 1.000000)
					( Status sCSetFlattened )
					( Origin gBackEnd )
				)
			)
			( pinPair "@baseboard_fab2_lib.baseboard_fab2(sch_1):\PP287\"
				( pinRef "@baseboard_fab2_lib.baseboard_fab2(sch_1):page31_i106:PE2_TX_DN(9)" )
				( pinRef "@baseboard_fab2_lib.baseboard_fab2(sch_1):page105_i32:A" )
				( attribute "RELATIVE_PROPAGATION_DELAY_SCOPE" "L"
					( Parent
						( matchGroupRef "@baseboard_fab2_lib.baseboard_fab2(sch_1):\MG_PCIE_L1\" )
					)
					( Status sCSetFlattened )
					( Origin gBackEnd )
				)
				( attribute "RELATIVE_PROPAGATION_DELAY" ",5.00 MIL"
					( Parent
						( matchGroupRef "@baseboard_fab2_lib.baseboard_fab2(sch_1):\MG_PCIE_L1\" )
					)
					( Units "uMatchProp" "ns" 1.000000)
					( Status sCSetFlattened )
					( Origin gBackEnd )
				)
			)
			( pinPair "@baseboard_fab2_lib.baseboard_fab2(sch_1):\PP288\"
				( pinRef "@baseboard_fab2_lib.baseboard_fab2(sch_1):page109_i243:IO157" )
				( pinRef "@baseboard_fab2_lib.baseboard_fab2(sch_1):page105_i32:B" )
				( attribute "RELATIVE_PROPAGATION_DELAY_SCOPE" "L"
					( Parent
						( matchGroupRef "@baseboard_fab2_lib.baseboard_fab2(sch_1):\MG_PCIE_L0\" )
					)
					( Status sCSetFlattened )
					( Origin gBackEnd )
				)
				( attribute "RELATIVE_PROPAGATION_DELAY" ",5.00 MIL"
					( Parent
						( matchGroupRef "@baseboard_fab2_lib.baseboard_fab2(sch_1):\MG_PCIE_L0\" )
					)
					( Units "uMatchProp" "ns" 1.000000)
					( Status sCSetFlattened )
					( Origin gBackEnd )
				)
			)
			( pinPair "@baseboard_fab2_lib.baseboard_fab2(sch_1):\PP5925\"
				( pinRef "@baseboard_fab2_lib.baseboard_fab2(sch_1):page31_i106:PE2_TX_DN(9)" )
				( pinRef "@baseboard_fab2_lib.baseboard_fab2(sch_1):page109_i243:IO157" )
				( attribute "PROPAGATION_DELAY_MIN" "3000.00 MIL"
					( Units "uMaxMinProp" "ns" 1.000000)
					( Status sCSetFlattened )
					( Origin gBackEnd )
				)
				( attribute "PROPAGATION_DELAY_MAX" "16000.00 MIL"
					( Units "uMaxMinProp" "ns" 1.000000)
					( Status sCSetFlattened )
					( Origin gBackEnd )
				)
				( attribute "RELATIVE_PROPAGATION_DELAY_SCOPE" "G"
					( Parent
						( matchGroupRef "@baseboard_fab2_lib.baseboard_fab2(sch_1):\MG_P3E_CPU0_PE2_SS_TX0809\" )
					)
					( Status sCSetFlattened )
					( Origin gBackEnd )
				)
				( attribute "RELATIVE_PROPAGATION_DELAY" ",500.00 MIL"
					( Parent
						( matchGroupRef "@baseboard_fab2_lib.baseboard_fab2(sch_1):\MG_P3E_CPU0_PE2_SS_TX0809\" )
					)
					( Units "uMatchProp" "ns" 1.000000)
					( Status sCSetFlattened )
					( Origin gBackEnd )
				)
			)
			( pinPair "@baseboard_fab2_lib.baseboard_fab2(sch_1):\PP289\"
				( pinRef "@baseboard_fab2_lib.baseboard_fab2(sch_1):page109_i243:IO159" )
				( pinRef "@baseboard_fab2_lib.baseboard_fab2(sch_1):page105_i44:B" )
				( attribute "RELATIVE_PROPAGATION_DELAY_SCOPE" "L"
					( Parent
						( matchGroupRef "@baseboard_fab2_lib.baseboard_fab2(sch_1):\MG_PCIE_L0\" )
					)
					( Status sCSetFlattened )
					( Origin gBackEnd )
				)
				( attribute "RELATIVE_PROPAGATION_DELAY" ",5.00 MIL"
					( Parent
						( matchGroupRef "@baseboard_fab2_lib.baseboard_fab2(sch_1):\MG_PCIE_L0\" )
					)
					( Units "uMatchProp" "ns" 1.000000)
					( Status sCSetFlattened )
					( Origin gBackEnd )
				)
			)
			( pinPair "@baseboard_fab2_lib.baseboard_fab2(sch_1):\PP290\"
				( pinRef "@baseboard_fab2_lib.baseboard_fab2(sch_1):page31_i106:PE2_TX_DP(9)" )
				( pinRef "@baseboard_fab2_lib.baseboard_fab2(sch_1):page105_i44:A" )
				( attribute "RELATIVE_PROPAGATION_DELAY_SCOPE" "L"
					( Parent
						( matchGroupRef "@baseboard_fab2_lib.baseboard_fab2(sch_1):\MG_PCIE_L1\" )
					)
					( Status sCSetFlattened )
					( Origin gBackEnd )
				)
				( attribute "RELATIVE_PROPAGATION_DELAY" ",5.00 MIL"
					( Parent
						( matchGroupRef "@baseboard_fab2_lib.baseboard_fab2(sch_1):\MG_PCIE_L1\" )
					)
					( Units "uMatchProp" "ns" 1.000000)
					( Status sCSetFlattened )
					( Origin gBackEnd )
				)
			)
			( pinPair "@baseboard_fab2_lib.baseboard_fab2(sch_1):\PP5914\"
				( pinRef "@baseboard_fab2_lib.baseboard_fab2(sch_1):page31_i106:PE2_TX_DP(9)" )
				( pinRef "@baseboard_fab2_lib.baseboard_fab2(sch_1):page109_i243:IO159" )
				( attribute "PROPAGATION_DELAY_MIN" "3000.00 MIL"
					( Units "uMaxMinProp" "ns" 1.000000)
					( Status sCSetFlattened )
					( Origin gBackEnd )
				)
				( attribute "PROPAGATION_DELAY_MAX" "16000.00 MIL"
					( Units "uMaxMinProp" "ns" 1.000000)
					( Status sCSetFlattened )
					( Origin gBackEnd )
				)
				( attribute "RELATIVE_PROPAGATION_DELAY_SCOPE" "G"
					( Parent
						( matchGroupRef "@baseboard_fab2_lib.baseboard_fab2(sch_1):\MG_P3E_CPU0_PE2_SS_TX0809\" )
					)
					( Status sCSetFlattened )
					( Origin gBackEnd )
				)
				( attribute "RELATIVE_PROPAGATION_DELAY" ",500.00 MIL"
					( Parent
						( matchGroupRef "@baseboard_fab2_lib.baseboard_fab2(sch_1):\MG_P3E_CPU0_PE2_SS_TX0809\" )
					)
					( Units "uMatchProp" "ns" 1.000000)
					( Status sCSetFlattened )
					( Origin gBackEnd )
				)
			)
			( pinPair "@baseboard_fab2_lib.baseboard_fab2(sch_1):\PP283\"
				( pinRef "@baseboard_fab2_lib.baseboard_fab2(sch_1):page31_i106:PE2_TX_DN(10)" )
				( pinRef "@baseboard_fab2_lib.baseboard_fab2(sch_1):page105_i31:A" )
				( attribute "RELATIVE_PROPAGATION_DELAY_SCOPE" "L"
					( Parent
						( matchGroupRef "@baseboard_fab2_lib.baseboard_fab2(sch_1):\MG_PCIE_L1\" )
					)
					( Status sCSetFlattened )
					( Origin gBackEnd )
				)
				( attribute "RELATIVE_PROPAGATION_DELAY" ",5.00 MIL"
					( Parent
						( matchGroupRef "@baseboard_fab2_lib.baseboard_fab2(sch_1):\MG_PCIE_L1\" )
					)
					( Units "uMatchProp" "ns" 1.000000)
					( Status sCSetFlattened )
					( Origin gBackEnd )
				)
			)
			( pinPair "@baseboard_fab2_lib.baseboard_fab2(sch_1):\PP284\"
				( pinRef "@baseboard_fab2_lib.baseboard_fab2(sch_1):page109_i243:IO163" )
				( pinRef "@baseboard_fab2_lib.baseboard_fab2(sch_1):page105_i31:B" )
				( attribute "RELATIVE_PROPAGATION_DELAY_SCOPE" "L"
					( Parent
						( matchGroupRef "@baseboard_fab2_lib.baseboard_fab2(sch_1):\MG_PCIE_L0\" )
					)
					( Status sCSetFlattened )
					( Origin gBackEnd )
				)
				( attribute "RELATIVE_PROPAGATION_DELAY" ",5.00 MIL"
					( Parent
						( matchGroupRef "@baseboard_fab2_lib.baseboard_fab2(sch_1):\MG_PCIE_L0\" )
					)
					( Units "uMatchProp" "ns" 1.000000)
					( Status sCSetFlattened )
					( Origin gBackEnd )
				)
			)
			( pinPair "@baseboard_fab2_lib.baseboard_fab2(sch_1):\PP5927\"
				( pinRef "@baseboard_fab2_lib.baseboard_fab2(sch_1):page31_i106:PE2_TX_DN(10)" )
				( pinRef "@baseboard_fab2_lib.baseboard_fab2(sch_1):page109_i243:IO163" )
				( attribute "PROPAGATION_DELAY_MIN" "3000.00 MIL"
					( Units "uMaxMinProp" "ns" 1.000000)
					( Status sCSetFlattened )
					( Origin gBackEnd )
				)
				( attribute "PROPAGATION_DELAY_MAX" "16000.00 MIL"
					( Units "uMaxMinProp" "ns" 1.000000)
					( Status sCSetFlattened )
					( Origin gBackEnd )
				)
				( attribute "RELATIVE_PROPAGATION_DELAY_SCOPE" "G"
					( Parent
						( matchGroupRef "@baseboard_fab2_lib.baseboard_fab2(sch_1):\MG_P3E_CPU0_PE2_SS_TX1011\" )
					)
					( Status sCSetFlattened )
					( Origin gBackEnd )
				)
				( attribute "RELATIVE_PROPAGATION_DELAY" ",500.00 MIL"
					( Parent
						( matchGroupRef "@baseboard_fab2_lib.baseboard_fab2(sch_1):\MG_P3E_CPU0_PE2_SS_TX1011\" )
					)
					( Units "uMatchProp" "ns" 1.000000)
					( Status sCSetFlattened )
					( Origin gBackEnd )
				)
			)
			( pinPair "@baseboard_fab2_lib.baseboard_fab2(sch_1):\PP285\"
				( pinRef "@baseboard_fab2_lib.baseboard_fab2(sch_1):page109_i243:IO165" )
				( pinRef "@baseboard_fab2_lib.baseboard_fab2(sch_1):page105_i45:B" )
				( attribute "RELATIVE_PROPAGATION_DELAY_SCOPE" "L"
					( Parent
						( matchGroupRef "@baseboard_fab2_lib.baseboard_fab2(sch_1):\MG_PCIE_L0\" )
					)
					( Status sCSetFlattened )
					( Origin gBackEnd )
				)
				( attribute "RELATIVE_PROPAGATION_DELAY" ",5.00 MIL"
					( Parent
						( matchGroupRef "@baseboard_fab2_lib.baseboard_fab2(sch_1):\MG_PCIE_L0\" )
					)
					( Units "uMatchProp" "ns" 1.000000)
					( Status sCSetFlattened )
					( Origin gBackEnd )
				)
			)
			( pinPair "@baseboard_fab2_lib.baseboard_fab2(sch_1):\PP286\"
				( pinRef "@baseboard_fab2_lib.baseboard_fab2(sch_1):page31_i106:PE2_TX_DP(10)" )
				( pinRef "@baseboard_fab2_lib.baseboard_fab2(sch_1):page105_i45:A" )
				( attribute "RELATIVE_PROPAGATION_DELAY_SCOPE" "L"
					( Parent
						( matchGroupRef "@baseboard_fab2_lib.baseboard_fab2(sch_1):\MG_PCIE_L1\" )
					)
					( Status sCSetFlattened )
					( Origin gBackEnd )
				)
				( attribute "RELATIVE_PROPAGATION_DELAY" ",5.00 MIL"
					( Parent
						( matchGroupRef "@baseboard_fab2_lib.baseboard_fab2(sch_1):\MG_PCIE_L1\" )
					)
					( Units "uMatchProp" "ns" 1.000000)
					( Status sCSetFlattened )
					( Origin gBackEnd )
				)
			)
			( pinPair "@baseboard_fab2_lib.baseboard_fab2(sch_1):\PP5924\"
				( pinRef "@baseboard_fab2_lib.baseboard_fab2(sch_1):page31_i106:PE2_TX_DP(10)" )
				( pinRef "@baseboard_fab2_lib.baseboard_fab2(sch_1):page109_i243:IO165" )
				( attribute "PROPAGATION_DELAY_MIN" "3000.00 MIL"
					( Units "uMaxMinProp" "ns" 1.000000)
					( Status sCSetFlattened )
					( Origin gBackEnd )
				)
				( attribute "PROPAGATION_DELAY_MAX" "16000.00 MIL"
					( Units "uMaxMinProp" "ns" 1.000000)
					( Status sCSetFlattened )
					( Origin gBackEnd )
				)
				( attribute "RELATIVE_PROPAGATION_DELAY_SCOPE" "G"
					( Parent
						( matchGroupRef "@baseboard_fab2_lib.baseboard_fab2(sch_1):\MG_P3E_CPU0_PE2_SS_TX1011\" )
					)
					( Status sCSetFlattened )
					( Origin gBackEnd )
				)
				( attribute "RELATIVE_PROPAGATION_DELAY" ",500.00 MIL"
					( Parent
						( matchGroupRef "@baseboard_fab2_lib.baseboard_fab2(sch_1):\MG_P3E_CPU0_PE2_SS_TX1011\" )
					)
					( Units "uMatchProp" "ns" 1.000000)
					( Status sCSetFlattened )
					( Origin gBackEnd )
				)
			)
			( pinPair "@baseboard_fab2_lib.baseboard_fab2(sch_1):\PP279\"
				( pinRef "@baseboard_fab2_lib.baseboard_fab2(sch_1):page31_i106:PE2_TX_DN(11)" )
				( pinRef "@baseboard_fab2_lib.baseboard_fab2(sch_1):page105_i13:A" )
				( attribute "RELATIVE_PROPAGATION_DELAY_SCOPE" "L"
					( Parent
						( matchGroupRef "@baseboard_fab2_lib.baseboard_fab2(sch_1):\MG_PCIE_L1\" )
					)
					( Status sCSetFlattened )
					( Origin gBackEnd )
				)
				( attribute "RELATIVE_PROPAGATION_DELAY" ",5.00 MIL"
					( Parent
						( matchGroupRef "@baseboard_fab2_lib.baseboard_fab2(sch_1):\MG_PCIE_L1\" )
					)
					( Units "uMatchProp" "ns" 1.000000)
					( Status sCSetFlattened )
					( Origin gBackEnd )
				)
			)
			( pinPair "@baseboard_fab2_lib.baseboard_fab2(sch_1):\PP280\"
				( pinRef "@baseboard_fab2_lib.baseboard_fab2(sch_1):page109_i243:IO171" )
				( pinRef "@baseboard_fab2_lib.baseboard_fab2(sch_1):page105_i13:B" )
				( attribute "RELATIVE_PROPAGATION_DELAY_SCOPE" "L"
					( Parent
						( matchGroupRef "@baseboard_fab2_lib.baseboard_fab2(sch_1):\MG_PCIE_L0\" )
					)
					( Status sCSetFlattened )
					( Origin gBackEnd )
				)
				( attribute "RELATIVE_PROPAGATION_DELAY" ",5.00 MIL"
					( Parent
						( matchGroupRef "@baseboard_fab2_lib.baseboard_fab2(sch_1):\MG_PCIE_L0\" )
					)
					( Units "uMatchProp" "ns" 1.000000)
					( Status sCSetFlattened )
					( Origin gBackEnd )
				)
			)
			( pinPair "@baseboard_fab2_lib.baseboard_fab2(sch_1):\PP5929\"
				( pinRef "@baseboard_fab2_lib.baseboard_fab2(sch_1):page31_i106:PE2_TX_DN(11)" )
				( pinRef "@baseboard_fab2_lib.baseboard_fab2(sch_1):page109_i243:IO171" )
				( attribute "PROPAGATION_DELAY_MIN" "3000.00 MIL"
					( Units "uMaxMinProp" "ns" 1.000000)
					( Status sCSetFlattened )
					( Origin gBackEnd )
				)
				( attribute "PROPAGATION_DELAY_MAX" "16000.00 MIL"
					( Units "uMaxMinProp" "ns" 1.000000)
					( Status sCSetFlattened )
					( Origin gBackEnd )
				)
				( attribute "RELATIVE_PROPAGATION_DELAY_SCOPE" "G"
					( Parent
						( matchGroupRef "@baseboard_fab2_lib.baseboard_fab2(sch_1):\MG_P3E_CPU0_PE2_SS_TX1011\" )
					)
					( Status sCSetFlattened )
					( Origin gBackEnd )
				)
				( attribute "RELATIVE_PROPAGATION_DELAY" ",500.00 MIL"
					( Parent
						( matchGroupRef "@baseboard_fab2_lib.baseboard_fab2(sch_1):\MG_P3E_CPU0_PE2_SS_TX1011\" )
					)
					( Units "uMatchProp" "ns" 1.000000)
					( Status sCSetFlattened )
					( Origin gBackEnd )
				)
			)
			( pinPair "@baseboard_fab2_lib.baseboard_fab2(sch_1):\PP281\"
				( pinRef "@baseboard_fab2_lib.baseboard_fab2(sch_1):page109_i243:IO169" )
				( pinRef "@baseboard_fab2_lib.baseboard_fab2(sch_1):page105_i28:B" )
				( attribute "RELATIVE_PROPAGATION_DELAY_SCOPE" "L"
					( Parent
						( matchGroupRef "@baseboard_fab2_lib.baseboard_fab2(sch_1):\MG_PCIE_L0\" )
					)
					( Status sCSetFlattened )
					( Origin gBackEnd )
				)
				( attribute "RELATIVE_PROPAGATION_DELAY" ",5.00 MIL"
					( Parent
						( matchGroupRef "@baseboard_fab2_lib.baseboard_fab2(sch_1):\MG_PCIE_L0\" )
					)
					( Units "uMatchProp" "ns" 1.000000)
					( Status sCSetFlattened )
					( Origin gBackEnd )
				)
			)
			( pinPair "@baseboard_fab2_lib.baseboard_fab2(sch_1):\PP282\"
				( pinRef "@baseboard_fab2_lib.baseboard_fab2(sch_1):page31_i106:PE2_TX_DP(11)" )
				( pinRef "@baseboard_fab2_lib.baseboard_fab2(sch_1):page105_i28:A" )
				( attribute "RELATIVE_PROPAGATION_DELAY_SCOPE" "L"
					( Parent
						( matchGroupRef "@baseboard_fab2_lib.baseboard_fab2(sch_1):\MG_PCIE_L1\" )
					)
					( Status sCSetFlattened )
					( Origin gBackEnd )
				)
				( attribute "RELATIVE_PROPAGATION_DELAY" ",5.00 MIL"
					( Parent
						( matchGroupRef "@baseboard_fab2_lib.baseboard_fab2(sch_1):\MG_PCIE_L1\" )
					)
					( Units "uMatchProp" "ns" 1.000000)
					( Status sCSetFlattened )
					( Origin gBackEnd )
				)
			)
			( pinPair "@baseboard_fab2_lib.baseboard_fab2(sch_1):\PP5928\"
				( pinRef "@baseboard_fab2_lib.baseboard_fab2(sch_1):page31_i106:PE2_TX_DP(11)" )
				( pinRef "@baseboard_fab2_lib.baseboard_fab2(sch_1):page109_i243:IO169" )
				( attribute "PROPAGATION_DELAY_MIN" "3000.00 MIL"
					( Units "uMaxMinProp" "ns" 1.000000)
					( Status sCSetFlattened )
					( Origin gBackEnd )
				)
				( attribute "PROPAGATION_DELAY_MAX" "16000.00 MIL"
					( Units "uMaxMinProp" "ns" 1.000000)
					( Status sCSetFlattened )
					( Origin gBackEnd )
				)
				( attribute "RELATIVE_PROPAGATION_DELAY_SCOPE" "G"
					( Parent
						( matchGroupRef "@baseboard_fab2_lib.baseboard_fab2(sch_1):\MG_P3E_CPU0_PE2_SS_TX1011\" )
					)
					( Status sCSetFlattened )
					( Origin gBackEnd )
				)
				( attribute "RELATIVE_PROPAGATION_DELAY" ",500.00 MIL"
					( Parent
						( matchGroupRef "@baseboard_fab2_lib.baseboard_fab2(sch_1):\MG_P3E_CPU0_PE2_SS_TX1011\" )
					)
					( Units "uMatchProp" "ns" 1.000000)
					( Status sCSetFlattened )
					( Origin gBackEnd )
				)
			)
			( pinPair "@baseboard_fab2_lib.baseboard_fab2(sch_1):\PP275\"
				( pinRef "@baseboard_fab2_lib.baseboard_fab2(sch_1):page31_i106:PE2_TX_DN(12)" )
				( pinRef "@baseboard_fab2_lib.baseboard_fab2(sch_1):page105_i12:A" )
				( attribute "RELATIVE_PROPAGATION_DELAY_SCOPE" "L"
					( Parent
						( matchGroupRef "@baseboard_fab2_lib.baseboard_fab2(sch_1):\MG_PCIE_L1\" )
					)
					( Status sCSetFlattened )
					( Origin gBackEnd )
				)
				( attribute "RELATIVE_PROPAGATION_DELAY" ",5.00 MIL"
					( Parent
						( matchGroupRef "@baseboard_fab2_lib.baseboard_fab2(sch_1):\MG_PCIE_L1\" )
					)
					( Units "uMatchProp" "ns" 1.000000)
					( Status sCSetFlattened )
					( Origin gBackEnd )
				)
			)
			( pinPair "@baseboard_fab2_lib.baseboard_fab2(sch_1):\PP276\"
				( pinRef "@baseboard_fab2_lib.baseboard_fab2(sch_1):page109_i243:IO175" )
				( pinRef "@baseboard_fab2_lib.baseboard_fab2(sch_1):page105_i12:B" )
				( attribute "RELATIVE_PROPAGATION_DELAY_SCOPE" "L"
					( Parent
						( matchGroupRef "@baseboard_fab2_lib.baseboard_fab2(sch_1):\MG_PCIE_L0\" )
					)
					( Status sCSetFlattened )
					( Origin gBackEnd )
				)
				( attribute "RELATIVE_PROPAGATION_DELAY" ",5.00 MIL"
					( Parent
						( matchGroupRef "@baseboard_fab2_lib.baseboard_fab2(sch_1):\MG_PCIE_L0\" )
					)
					( Units "uMatchProp" "ns" 1.000000)
					( Status sCSetFlattened )
					( Origin gBackEnd )
				)
			)
			( pinPair "@baseboard_fab2_lib.baseboard_fab2(sch_1):\PP5931\"
				( pinRef "@baseboard_fab2_lib.baseboard_fab2(sch_1):page31_i106:PE2_TX_DN(12)" )
				( pinRef "@baseboard_fab2_lib.baseboard_fab2(sch_1):page109_i243:IO175" )
				( attribute "PROPAGATION_DELAY_MIN" "3000.00 MIL"
					( Units "uMaxMinProp" "ns" 1.000000)
					( Status sCSetFlattened )
					( Origin gBackEnd )
				)
				( attribute "PROPAGATION_DELAY_MAX" "16000.00 MIL"
					( Units "uMaxMinProp" "ns" 1.000000)
					( Status sCSetFlattened )
					( Origin gBackEnd )
				)
				( attribute "RELATIVE_PROPAGATION_DELAY_SCOPE" "G"
					( Parent
						( matchGroupRef "@baseboard_fab2_lib.baseboard_fab2(sch_1):\MG_P3E_CPU0_PE2_SS_TX1213\" )
					)
					( Status sCSetFlattened )
					( Origin gBackEnd )
				)
				( attribute "RELATIVE_PROPAGATION_DELAY" ",500.00 MIL"
					( Parent
						( matchGroupRef "@baseboard_fab2_lib.baseboard_fab2(sch_1):\MG_P3E_CPU0_PE2_SS_TX1213\" )
					)
					( Units "uMatchProp" "ns" 1.000000)
					( Status sCSetFlattened )
					( Origin gBackEnd )
				)
			)
			( pinPair "@baseboard_fab2_lib.baseboard_fab2(sch_1):\PP277\"
				( pinRef "@baseboard_fab2_lib.baseboard_fab2(sch_1):page109_i243:IO177" )
				( pinRef "@baseboard_fab2_lib.baseboard_fab2(sch_1):page105_i27:B" )
				( attribute "RELATIVE_PROPAGATION_DELAY_SCOPE" "L"
					( Parent
						( matchGroupRef "@baseboard_fab2_lib.baseboard_fab2(sch_1):\MG_PCIE_L0\" )
					)
					( Status sCSetFlattened )
					( Origin gBackEnd )
				)
				( attribute "RELATIVE_PROPAGATION_DELAY" ",5.00 MIL"
					( Parent
						( matchGroupRef "@baseboard_fab2_lib.baseboard_fab2(sch_1):\MG_PCIE_L0\" )
					)
					( Units "uMatchProp" "ns" 1.000000)
					( Status sCSetFlattened )
					( Origin gBackEnd )
				)
			)
			( pinPair "@baseboard_fab2_lib.baseboard_fab2(sch_1):\PP278\"
				( pinRef "@baseboard_fab2_lib.baseboard_fab2(sch_1):page31_i106:PE2_TX_DP(12)" )
				( pinRef "@baseboard_fab2_lib.baseboard_fab2(sch_1):page105_i27:A" )
				( attribute "RELATIVE_PROPAGATION_DELAY_SCOPE" "L"
					( Parent
						( matchGroupRef "@baseboard_fab2_lib.baseboard_fab2(sch_1):\MG_PCIE_L1\" )
					)
					( Status sCSetFlattened )
					( Origin gBackEnd )
				)
				( attribute "RELATIVE_PROPAGATION_DELAY" ",5.00 MIL"
					( Parent
						( matchGroupRef "@baseboard_fab2_lib.baseboard_fab2(sch_1):\MG_PCIE_L1\" )
					)
					( Units "uMatchProp" "ns" 1.000000)
					( Status sCSetFlattened )
					( Origin gBackEnd )
				)
			)
			( pinPair "@baseboard_fab2_lib.baseboard_fab2(sch_1):\PP5930\"
				( pinRef "@baseboard_fab2_lib.baseboard_fab2(sch_1):page31_i106:PE2_TX_DP(12)" )
				( pinRef "@baseboard_fab2_lib.baseboard_fab2(sch_1):page109_i243:IO177" )
				( attribute "PROPAGATION_DELAY_MIN" "3000.00 MIL"
					( Units "uMaxMinProp" "ns" 1.000000)
					( Status sCSetFlattened )
					( Origin gBackEnd )
				)
				( attribute "PROPAGATION_DELAY_MAX" "16000.00 MIL"
					( Units "uMaxMinProp" "ns" 1.000000)
					( Status sCSetFlattened )
					( Origin gBackEnd )
				)
				( attribute "RELATIVE_PROPAGATION_DELAY_SCOPE" "G"
					( Parent
						( matchGroupRef "@baseboard_fab2_lib.baseboard_fab2(sch_1):\MG_P3E_CPU0_PE2_SS_TX1213\" )
					)
					( Status sCSetFlattened )
					( Origin gBackEnd )
				)
				( attribute "RELATIVE_PROPAGATION_DELAY" ",500.00 MIL"
					( Parent
						( matchGroupRef "@baseboard_fab2_lib.baseboard_fab2(sch_1):\MG_P3E_CPU0_PE2_SS_TX1213\" )
					)
					( Units "uMatchProp" "ns" 1.000000)
					( Status sCSetFlattened )
					( Origin gBackEnd )
				)
			)
			( pinPair "@baseboard_fab2_lib.baseboard_fab2(sch_1):\PP271\"
				( pinRef "@baseboard_fab2_lib.baseboard_fab2(sch_1):page31_i106:PE2_TX_DN(13)" )
				( pinRef "@baseboard_fab2_lib.baseboard_fab2(sch_1):page105_i8:A" )
				( attribute "RELATIVE_PROPAGATION_DELAY_SCOPE" "L"
					( Parent
						( matchGroupRef "@baseboard_fab2_lib.baseboard_fab2(sch_1):\MG_PCIE_L1\" )
					)
					( Status sCSetFlattened )
					( Origin gBackEnd )
				)
				( attribute "RELATIVE_PROPAGATION_DELAY" ",5.00 MIL"
					( Parent
						( matchGroupRef "@baseboard_fab2_lib.baseboard_fab2(sch_1):\MG_PCIE_L1\" )
					)
					( Units "uMatchProp" "ns" 1.000000)
					( Status sCSetFlattened )
					( Origin gBackEnd )
				)
			)
			( pinPair "@baseboard_fab2_lib.baseboard_fab2(sch_1):\PP272\"
				( pinRef "@baseboard_fab2_lib.baseboard_fab2(sch_1):page109_i243:IO181" )
				( pinRef "@baseboard_fab2_lib.baseboard_fab2(sch_1):page105_i8:B" )
				( attribute "RELATIVE_PROPAGATION_DELAY_SCOPE" "L"
					( Parent
						( matchGroupRef "@baseboard_fab2_lib.baseboard_fab2(sch_1):\MG_PCIE_L0\" )
					)
					( Status sCSetFlattened )
					( Origin gBackEnd )
				)
				( attribute "RELATIVE_PROPAGATION_DELAY" ",5.00 MIL"
					( Parent
						( matchGroupRef "@baseboard_fab2_lib.baseboard_fab2(sch_1):\MG_PCIE_L0\" )
					)
					( Units "uMatchProp" "ns" 1.000000)
					( Status sCSetFlattened )
					( Origin gBackEnd )
				)
			)
			( pinPair "@baseboard_fab2_lib.baseboard_fab2(sch_1):\PP5933\"
				( pinRef "@baseboard_fab2_lib.baseboard_fab2(sch_1):page31_i106:PE2_TX_DN(13)" )
				( pinRef "@baseboard_fab2_lib.baseboard_fab2(sch_1):page109_i243:IO181" )
				( attribute "PROPAGATION_DELAY_MIN" "3000.00 MIL"
					( Units "uMaxMinProp" "ns" 1.000000)
					( Status sCSetFlattened )
					( Origin gBackEnd )
				)
				( attribute "PROPAGATION_DELAY_MAX" "16000.00 MIL"
					( Units "uMaxMinProp" "ns" 1.000000)
					( Status sCSetFlattened )
					( Origin gBackEnd )
				)
				( attribute "RELATIVE_PROPAGATION_DELAY_SCOPE" "G"
					( Parent
						( matchGroupRef "@baseboard_fab2_lib.baseboard_fab2(sch_1):\MG_P3E_CPU0_PE2_SS_TX1213\" )
					)
					( Status sCSetFlattened )
					( Origin gBackEnd )
				)
				( attribute "RELATIVE_PROPAGATION_DELAY" ",500.00 MIL"
					( Parent
						( matchGroupRef "@baseboard_fab2_lib.baseboard_fab2(sch_1):\MG_P3E_CPU0_PE2_SS_TX1213\" )
					)
					( Units "uMatchProp" "ns" 1.000000)
					( Status sCSetFlattened )
					( Origin gBackEnd )
				)
			)
			( pinPair "@baseboard_fab2_lib.baseboard_fab2(sch_1):\PP273\"
				( pinRef "@baseboard_fab2_lib.baseboard_fab2(sch_1):page109_i243:IO183" )
				( pinRef "@baseboard_fab2_lib.baseboard_fab2(sch_1):page105_i21:B" )
				( attribute "RELATIVE_PROPAGATION_DELAY_SCOPE" "L"
					( Parent
						( matchGroupRef "@baseboard_fab2_lib.baseboard_fab2(sch_1):\MG_PCIE_L0\" )
					)
					( Status sCSetFlattened )
					( Origin gBackEnd )
				)
				( attribute "RELATIVE_PROPAGATION_DELAY" ",5.00 MIL"
					( Parent
						( matchGroupRef "@baseboard_fab2_lib.baseboard_fab2(sch_1):\MG_PCIE_L0\" )
					)
					( Units "uMatchProp" "ns" 1.000000)
					( Status sCSetFlattened )
					( Origin gBackEnd )
				)
			)
			( pinPair "@baseboard_fab2_lib.baseboard_fab2(sch_1):\PP274\"
				( pinRef "@baseboard_fab2_lib.baseboard_fab2(sch_1):page31_i106:PE2_TX_DP(13)" )
				( pinRef "@baseboard_fab2_lib.baseboard_fab2(sch_1):page105_i21:A" )
				( attribute "RELATIVE_PROPAGATION_DELAY_SCOPE" "L"
					( Parent
						( matchGroupRef "@baseboard_fab2_lib.baseboard_fab2(sch_1):\MG_PCIE_L1\" )
					)
					( Status sCSetFlattened )
					( Origin gBackEnd )
				)
				( attribute "RELATIVE_PROPAGATION_DELAY" ",5.00 MIL"
					( Parent
						( matchGroupRef "@baseboard_fab2_lib.baseboard_fab2(sch_1):\MG_PCIE_L1\" )
					)
					( Units "uMatchProp" "ns" 1.000000)
					( Status sCSetFlattened )
					( Origin gBackEnd )
				)
			)
			( pinPair "@baseboard_fab2_lib.baseboard_fab2(sch_1):\PP5926\"
				( pinRef "@baseboard_fab2_lib.baseboard_fab2(sch_1):page31_i106:PE2_TX_DP(13)" )
				( pinRef "@baseboard_fab2_lib.baseboard_fab2(sch_1):page109_i243:IO183" )
				( attribute "PROPAGATION_DELAY_MIN" "3000.00 MIL"
					( Units "uMaxMinProp" "ns" 1.000000)
					( Status sCSetFlattened )
					( Origin gBackEnd )
				)
				( attribute "PROPAGATION_DELAY_MAX" "16000.00 MIL"
					( Units "uMaxMinProp" "ns" 1.000000)
					( Status sCSetFlattened )
					( Origin gBackEnd )
				)
				( attribute "RELATIVE_PROPAGATION_DELAY_SCOPE" "G"
					( Parent
						( matchGroupRef "@baseboard_fab2_lib.baseboard_fab2(sch_1):\MG_P3E_CPU0_PE2_SS_TX1213\" )
					)
					( Status sCSetFlattened )
					( Origin gBackEnd )
				)
				( attribute "RELATIVE_PROPAGATION_DELAY" ",500.00 MIL"
					( Parent
						( matchGroupRef "@baseboard_fab2_lib.baseboard_fab2(sch_1):\MG_P3E_CPU0_PE2_SS_TX1213\" )
					)
					( Units "uMatchProp" "ns" 1.000000)
					( Status sCSetFlattened )
					( Origin gBackEnd )
				)
			)
			( pinPair "@baseboard_fab2_lib.baseboard_fab2(sch_1):\PP267\"
				( pinRef "@baseboard_fab2_lib.baseboard_fab2(sch_1):page31_i106:PE2_TX_DN(14)" )
				( pinRef "@baseboard_fab2_lib.baseboard_fab2(sch_1):page105_i7:A" )
				( attribute "RELATIVE_PROPAGATION_DELAY_SCOPE" "L"
					( Parent
						( matchGroupRef "@baseboard_fab2_lib.baseboard_fab2(sch_1):\MG_PCIE_L1\" )
					)
					( Status sCSetFlattened )
					( Origin gBackEnd )
				)
				( attribute "RELATIVE_PROPAGATION_DELAY" ",5.00 MIL"
					( Parent
						( matchGroupRef "@baseboard_fab2_lib.baseboard_fab2(sch_1):\MG_PCIE_L1\" )
					)
					( Units "uMatchProp" "ns" 1.000000)
					( Status sCSetFlattened )
					( Origin gBackEnd )
				)
			)
			( pinPair "@baseboard_fab2_lib.baseboard_fab2(sch_1):\PP268\"
				( pinRef "@baseboard_fab2_lib.baseboard_fab2(sch_1):page109_i243:IO189" )
				( pinRef "@baseboard_fab2_lib.baseboard_fab2(sch_1):page105_i7:B" )
				( attribute "RELATIVE_PROPAGATION_DELAY_SCOPE" "L"
					( Parent
						( matchGroupRef "@baseboard_fab2_lib.baseboard_fab2(sch_1):\MG_PCIE_L0\" )
					)
					( Status sCSetFlattened )
					( Origin gBackEnd )
				)
				( attribute "RELATIVE_PROPAGATION_DELAY" ",5.00 MIL"
					( Parent
						( matchGroupRef "@baseboard_fab2_lib.baseboard_fab2(sch_1):\MG_PCIE_L0\" )
					)
					( Units "uMatchProp" "ns" 1.000000)
					( Status sCSetFlattened )
					( Origin gBackEnd )
				)
			)
			( pinPair "@baseboard_fab2_lib.baseboard_fab2(sch_1):\PP5938\"
				( pinRef "@baseboard_fab2_lib.baseboard_fab2(sch_1):page31_i106:PE2_TX_DN(14)" )
				( pinRef "@baseboard_fab2_lib.baseboard_fab2(sch_1):page109_i243:IO189" )
				( attribute "PROPAGATION_DELAY_MIN" "3000.00 MIL"
					( Units "uMaxMinProp" "ns" 1.000000)
					( Status sCSetFlattened )
					( Origin gBackEnd )
				)
				( attribute "PROPAGATION_DELAY_MAX" "16000.00 MIL"
					( Units "uMaxMinProp" "ns" 1.000000)
					( Status sCSetFlattened )
					( Origin gBackEnd )
				)
				( attribute "RELATIVE_PROPAGATION_DELAY_SCOPE" "G"
					( Parent
						( matchGroupRef "@baseboard_fab2_lib.baseboard_fab2(sch_1):\MG_P3E_CPU0_PE2_SS_TX1415\" )
					)
					( Status sCSetFlattened )
					( Origin gBackEnd )
				)
				( attribute "RELATIVE_PROPAGATION_DELAY" ",500.00 MIL"
					( Parent
						( matchGroupRef "@baseboard_fab2_lib.baseboard_fab2(sch_1):\MG_P3E_CPU0_PE2_SS_TX1415\" )
					)
					( Units "uMatchProp" "ns" 1.000000)
					( Status sCSetFlattened )
					( Origin gBackEnd )
				)
			)
			( pinPair "@baseboard_fab2_lib.baseboard_fab2(sch_1):\PP269\"
				( pinRef "@baseboard_fab2_lib.baseboard_fab2(sch_1):page109_i243:IO187" )
				( pinRef "@baseboard_fab2_lib.baseboard_fab2(sch_1):page105_i22:B" )
				( attribute "RELATIVE_PROPAGATION_DELAY_SCOPE" "L"
					( Parent
						( matchGroupRef "@baseboard_fab2_lib.baseboard_fab2(sch_1):\MG_PCIE_L0\" )
					)
					( Status sCSetFlattened )
					( Origin gBackEnd )
				)
				( attribute "RELATIVE_PROPAGATION_DELAY" ",5.00 MIL"
					( Parent
						( matchGroupRef "@baseboard_fab2_lib.baseboard_fab2(sch_1):\MG_PCIE_L0\" )
					)
					( Units "uMatchProp" "ns" 1.000000)
					( Status sCSetFlattened )
					( Origin gBackEnd )
				)
			)
			( pinPair "@baseboard_fab2_lib.baseboard_fab2(sch_1):\PP270\"
				( pinRef "@baseboard_fab2_lib.baseboard_fab2(sch_1):page31_i106:PE2_TX_DP(14)" )
				( pinRef "@baseboard_fab2_lib.baseboard_fab2(sch_1):page105_i22:A" )
				( attribute "RELATIVE_PROPAGATION_DELAY_SCOPE" "L"
					( Parent
						( matchGroupRef "@baseboard_fab2_lib.baseboard_fab2(sch_1):\MG_PCIE_L1\" )
					)
					( Status sCSetFlattened )
					( Origin gBackEnd )
				)
				( attribute "RELATIVE_PROPAGATION_DELAY" ",5.00 MIL"
					( Parent
						( matchGroupRef "@baseboard_fab2_lib.baseboard_fab2(sch_1):\MG_PCIE_L1\" )
					)
					( Units "uMatchProp" "ns" 1.000000)
					( Status sCSetFlattened )
					( Origin gBackEnd )
				)
			)
			( pinPair "@baseboard_fab2_lib.baseboard_fab2(sch_1):\PP5937\"
				( pinRef "@baseboard_fab2_lib.baseboard_fab2(sch_1):page31_i106:PE2_TX_DP(14)" )
				( pinRef "@baseboard_fab2_lib.baseboard_fab2(sch_1):page109_i243:IO187" )
				( attribute "PROPAGATION_DELAY_MIN" "3000.00 MIL"
					( Units "uMaxMinProp" "ns" 1.000000)
					( Status sCSetFlattened )
					( Origin gBackEnd )
				)
				( attribute "PROPAGATION_DELAY_MAX" "16000.00 MIL"
					( Units "uMaxMinProp" "ns" 1.000000)
					( Status sCSetFlattened )
					( Origin gBackEnd )
				)
				( attribute "RELATIVE_PROPAGATION_DELAY_SCOPE" "G"
					( Parent
						( matchGroupRef "@baseboard_fab2_lib.baseboard_fab2(sch_1):\MG_P3E_CPU0_PE2_SS_TX1415\" )
					)
					( Status sCSetFlattened )
					( Origin gBackEnd )
				)
				( attribute "RELATIVE_PROPAGATION_DELAY" ",500.00 MIL"
					( Parent
						( matchGroupRef "@baseboard_fab2_lib.baseboard_fab2(sch_1):\MG_P3E_CPU0_PE2_SS_TX1415\" )
					)
					( Units "uMatchProp" "ns" 1.000000)
					( Status sCSetFlattened )
					( Origin gBackEnd )
				)
			)
			( pinPair "@baseboard_fab2_lib.baseboard_fab2(sch_1):\PP263\"
				( pinRef "@baseboard_fab2_lib.baseboard_fab2(sch_1):page31_i106:PE2_TX_DN(15)" )
				( pinRef "@baseboard_fab2_lib.baseboard_fab2(sch_1):page105_i6:A" )
				( attribute "RELATIVE_PROPAGATION_DELAY_SCOPE" "L"
					( Parent
						( matchGroupRef "@baseboard_fab2_lib.baseboard_fab2(sch_1):\MG_PCIE_L1\" )
					)
					( Status sCSetFlattened )
					( Origin gBackEnd )
				)
				( attribute "RELATIVE_PROPAGATION_DELAY" ",5.00 MIL"
					( Parent
						( matchGroupRef "@baseboard_fab2_lib.baseboard_fab2(sch_1):\MG_PCIE_L1\" )
					)
					( Units "uMatchProp" "ns" 1.000000)
					( Status sCSetFlattened )
					( Origin gBackEnd )
				)
			)
			( pinPair "@baseboard_fab2_lib.baseboard_fab2(sch_1):\PP264\"
				( pinRef "@baseboard_fab2_lib.baseboard_fab2(sch_1):page109_i243:IO193" )
				( pinRef "@baseboard_fab2_lib.baseboard_fab2(sch_1):page105_i6:B" )
				( attribute "RELATIVE_PROPAGATION_DELAY_SCOPE" "L"
					( Parent
						( matchGroupRef "@baseboard_fab2_lib.baseboard_fab2(sch_1):\MG_PCIE_L0\" )
					)
					( Status sCSetFlattened )
					( Origin gBackEnd )
				)
				( attribute "RELATIVE_PROPAGATION_DELAY" ",5.00 MIL"
					( Parent
						( matchGroupRef "@baseboard_fab2_lib.baseboard_fab2(sch_1):\MG_PCIE_L0\" )
					)
					( Units "uMatchProp" "ns" 1.000000)
					( Status sCSetFlattened )
					( Origin gBackEnd )
				)
			)
			( pinPair "@baseboard_fab2_lib.baseboard_fab2(sch_1):\PP5941\"
				( pinRef "@baseboard_fab2_lib.baseboard_fab2(sch_1):page31_i106:PE2_TX_DN(15)" )
				( pinRef "@baseboard_fab2_lib.baseboard_fab2(sch_1):page109_i243:IO193" )
				( attribute "PROPAGATION_DELAY_MIN" "3000.00 MIL"
					( Units "uMaxMinProp" "ns" 1.000000)
					( Status sCSetFlattened )
					( Origin gBackEnd )
				)
				( attribute "PROPAGATION_DELAY_MAX" "16000.00 MIL"
					( Units "uMaxMinProp" "ns" 1.000000)
					( Status sCSetFlattened )
					( Origin gBackEnd )
				)
				( attribute "RELATIVE_PROPAGATION_DELAY_SCOPE" "G"
					( Parent
						( matchGroupRef "@baseboard_fab2_lib.baseboard_fab2(sch_1):\MG_P3E_CPU0_PE2_SS_TX1415\" )
					)
					( Status sCSetFlattened )
					( Origin gBackEnd )
				)
				( attribute "RELATIVE_PROPAGATION_DELAY" ",500.00 MIL"
					( Parent
						( matchGroupRef "@baseboard_fab2_lib.baseboard_fab2(sch_1):\MG_P3E_CPU0_PE2_SS_TX1415\" )
					)
					( Units "uMatchProp" "ns" 1.000000)
					( Status sCSetFlattened )
					( Origin gBackEnd )
				)
			)
			( pinPair "@baseboard_fab2_lib.baseboard_fab2(sch_1):\PP265\"
				( pinRef "@baseboard_fab2_lib.baseboard_fab2(sch_1):page109_i243:IO195" )
				( pinRef "@baseboard_fab2_lib.baseboard_fab2(sch_1):page105_i20:B" )
				( attribute "RELATIVE_PROPAGATION_DELAY_SCOPE" "L"
					( Parent
						( matchGroupRef "@baseboard_fab2_lib.baseboard_fab2(sch_1):\MG_PCIE_L0\" )
					)
					( Status sCSetFlattened )
					( Origin gBackEnd )
				)
				( attribute "RELATIVE_PROPAGATION_DELAY" ",5.00 MIL"
					( Parent
						( matchGroupRef "@baseboard_fab2_lib.baseboard_fab2(sch_1):\MG_PCIE_L0\" )
					)
					( Units "uMatchProp" "ns" 1.000000)
					( Status sCSetFlattened )
					( Origin gBackEnd )
				)
			)
			( pinPair "@baseboard_fab2_lib.baseboard_fab2(sch_1):\PP266\"
				( pinRef "@baseboard_fab2_lib.baseboard_fab2(sch_1):page31_i106:PE2_TX_DP(15)" )
				( pinRef "@baseboard_fab2_lib.baseboard_fab2(sch_1):page105_i20:A" )
				( attribute "RELATIVE_PROPAGATION_DELAY_SCOPE" "L"
					( Parent
						( matchGroupRef "@baseboard_fab2_lib.baseboard_fab2(sch_1):\MG_PCIE_L1\" )
					)
					( Status sCSetFlattened )
					( Origin gBackEnd )
				)
				( attribute "RELATIVE_PROPAGATION_DELAY" ",5.00 MIL"
					( Parent
						( matchGroupRef "@baseboard_fab2_lib.baseboard_fab2(sch_1):\MG_PCIE_L1\" )
					)
					( Units "uMatchProp" "ns" 1.000000)
					( Status sCSetFlattened )
					( Origin gBackEnd )
				)
			)
			( pinPair "@baseboard_fab2_lib.baseboard_fab2(sch_1):\PP5939\"
				( pinRef "@baseboard_fab2_lib.baseboard_fab2(sch_1):page31_i106:PE2_TX_DP(15)" )
				( pinRef "@baseboard_fab2_lib.baseboard_fab2(sch_1):page109_i243:IO195" )
				( attribute "PROPAGATION_DELAY_MIN" "3000.00 MIL"
					( Units "uMaxMinProp" "ns" 1.000000)
					( Status sCSetFlattened )
					( Origin gBackEnd )
				)
				( attribute "PROPAGATION_DELAY_MAX" "16000.00 MIL"
					( Units "uMaxMinProp" "ns" 1.000000)
					( Status sCSetFlattened )
					( Origin gBackEnd )
				)
				( attribute "RELATIVE_PROPAGATION_DELAY_SCOPE" "G"
					( Parent
						( matchGroupRef "@baseboard_fab2_lib.baseboard_fab2(sch_1):\MG_P3E_CPU0_PE2_SS_TX1415\" )
					)
					( Status sCSetFlattened )
					( Origin gBackEnd )
				)
				( attribute "RELATIVE_PROPAGATION_DELAY" ",500.00 MIL"
					( Parent
						( matchGroupRef "@baseboard_fab2_lib.baseboard_fab2(sch_1):\MG_P3E_CPU0_PE2_SS_TX1415\" )
					)
					( Units "uMatchProp" "ns" 1.000000)
					( Status sCSetFlattened )
					( Origin gBackEnd )
				)
			)
			( pinPair "@baseboard_fab2_lib.baseboard_fab2(sch_1):\PP259\"
				( pinRef "@baseboard_fab2_lib.baseboard_fab2(sch_1):page32_i89:PE3_TX_DN(0)" )
				( pinRef "@baseboard_fab2_lib.baseboard_fab2(sch_1):page106_i29:A" )
				( attribute "RELATIVE_PROPAGATION_DELAY_SCOPE" "L"
					( Parent
						( matchGroupRef "@baseboard_fab2_lib.baseboard_fab2(sch_1):\MG_PCIE_L1\" )
					)
					( Status sCSetFlattened )
					( Origin gBackEnd )
				)
				( attribute "RELATIVE_PROPAGATION_DELAY" ",5.00 MIL"
					( Parent
						( matchGroupRef "@baseboard_fab2_lib.baseboard_fab2(sch_1):\MG_PCIE_L1\" )
					)
					( Units "uMatchProp" "ns" 1.000000)
					( Status sCSetFlattened )
					( Origin gBackEnd )
				)
			)
			( pinPair "@baseboard_fab2_lib.baseboard_fab2(sch_1):\PP260\"
				( pinRef "@baseboard_fab2_lib.baseboard_fab2(sch_1):page187_i119:IO68" )
				( pinRef "@baseboard_fab2_lib.baseboard_fab2(sch_1):page106_i29:B" )
				( attribute "RELATIVE_PROPAGATION_DELAY_SCOPE" "L"
					( Parent
						( matchGroupRef "@baseboard_fab2_lib.baseboard_fab2(sch_1):\MG_PCIE_L0\" )
					)
					( Status sCSetFlattened )
					( Origin gBackEnd )
				)
				( attribute "RELATIVE_PROPAGATION_DELAY" ",5.00 MIL"
					( Parent
						( matchGroupRef "@baseboard_fab2_lib.baseboard_fab2(sch_1):\MG_PCIE_L0\" )
					)
					( Units "uMatchProp" "ns" 1.000000)
					( Status sCSetFlattened )
					( Origin gBackEnd )
				)
			)
			( pinPair "@baseboard_fab2_lib.baseboard_fab2(sch_1):\PP5940\"
				( pinRef "@baseboard_fab2_lib.baseboard_fab2(sch_1):page32_i89:PE3_TX_DN(0)" )
				( pinRef "@baseboard_fab2_lib.baseboard_fab2(sch_1):page187_i119:IO68" )
				( attribute "PROPAGATION_DELAY_MIN" "3000.00 MIL"
					( Units "uMaxMinProp" "ns" 1.000000)
					( Status sCSetFlattened )
					( Origin gBackEnd )
				)
				( attribute "PROPAGATION_DELAY_MAX" "16000.00 MIL"
					( Units "uMaxMinProp" "ns" 1.000000)
					( Status sCSetFlattened )
					( Origin gBackEnd )
				)
				( attribute "RELATIVE_PROPAGATION_DELAY_SCOPE" "G"
					( Parent
						( matchGroupRef "@baseboard_fab2_lib.baseboard_fab2(sch_1):\MG_P3E_CPU0_PE3_OCP_TX0001\" )
					)
					( Status sCSetFlattened )
					( Origin gBackEnd )
				)
				( attribute "RELATIVE_PROPAGATION_DELAY" ",500.00 MIL"
					( Parent
						( matchGroupRef "@baseboard_fab2_lib.baseboard_fab2(sch_1):\MG_P3E_CPU0_PE3_OCP_TX0001\" )
					)
					( Units "uMatchProp" "ns" 1.000000)
					( Status sCSetFlattened )
					( Origin gBackEnd )
				)
			)
			( pinPair "@baseboard_fab2_lib.baseboard_fab2(sch_1):\PP261\"
				( pinRef "@baseboard_fab2_lib.baseboard_fab2(sch_1):page187_i119:IO66" )
				( pinRef "@baseboard_fab2_lib.baseboard_fab2(sch_1):page106_i10:B" )
				( attribute "RELATIVE_PROPAGATION_DELAY_SCOPE" "L"
					( Parent
						( matchGroupRef "@baseboard_fab2_lib.baseboard_fab2(sch_1):\MG_PCIE_L0\" )
					)
					( Status sCSetFlattened )
					( Origin gBackEnd )
				)
				( attribute "RELATIVE_PROPAGATION_DELAY" ",5.00 MIL"
					( Parent
						( matchGroupRef "@baseboard_fab2_lib.baseboard_fab2(sch_1):\MG_PCIE_L0\" )
					)
					( Units "uMatchProp" "ns" 1.000000)
					( Status sCSetFlattened )
					( Origin gBackEnd )
				)
			)
			( pinPair "@baseboard_fab2_lib.baseboard_fab2(sch_1):\PP262\"
				( pinRef "@baseboard_fab2_lib.baseboard_fab2(sch_1):page32_i89:PE3_TX_DP(0)" )
				( pinRef "@baseboard_fab2_lib.baseboard_fab2(sch_1):page106_i10:A" )
				( attribute "RELATIVE_PROPAGATION_DELAY_SCOPE" "L"
					( Parent
						( matchGroupRef "@baseboard_fab2_lib.baseboard_fab2(sch_1):\MG_PCIE_L1\" )
					)
					( Status sCSetFlattened )
					( Origin gBackEnd )
				)
				( attribute "RELATIVE_PROPAGATION_DELAY" ",5.00 MIL"
					( Parent
						( matchGroupRef "@baseboard_fab2_lib.baseboard_fab2(sch_1):\MG_PCIE_L1\" )
					)
					( Units "uMatchProp" "ns" 1.000000)
					( Status sCSetFlattened )
					( Origin gBackEnd )
				)
			)
			( pinPair "@baseboard_fab2_lib.baseboard_fab2(sch_1):\PP5942\"
				( pinRef "@baseboard_fab2_lib.baseboard_fab2(sch_1):page32_i89:PE3_TX_DP(0)" )
				( pinRef "@baseboard_fab2_lib.baseboard_fab2(sch_1):page187_i119:IO66" )
				( attribute "PROPAGATION_DELAY_MIN" "3000.00 MIL"
					( Units "uMaxMinProp" "ns" 1.000000)
					( Status sCSetFlattened )
					( Origin gBackEnd )
				)
				( attribute "PROPAGATION_DELAY_MAX" "16000.00 MIL"
					( Units "uMaxMinProp" "ns" 1.000000)
					( Status sCSetFlattened )
					( Origin gBackEnd )
				)
				( attribute "RELATIVE_PROPAGATION_DELAY_SCOPE" "G"
					( Parent
						( matchGroupRef "@baseboard_fab2_lib.baseboard_fab2(sch_1):\MG_P3E_CPU0_PE3_OCP_TX0001\" )
					)
					( Status sCSetFlattened )
					( Origin gBackEnd )
				)
				( attribute "RELATIVE_PROPAGATION_DELAY" ",500.00 MIL"
					( Parent
						( matchGroupRef "@baseboard_fab2_lib.baseboard_fab2(sch_1):\MG_P3E_CPU0_PE3_OCP_TX0001\" )
					)
					( Units "uMatchProp" "ns" 1.000000)
					( Status sCSetFlattened )
					( Origin gBackEnd )
				)
			)
			( pinPair "@baseboard_fab2_lib.baseboard_fab2(sch_1):\PP255\"
				( pinRef "@baseboard_fab2_lib.baseboard_fab2(sch_1):page32_i89:PE3_TX_DN(1)" )
				( pinRef "@baseboard_fab2_lib.baseboard_fab2(sch_1):page106_i37:A" )
				( attribute "RELATIVE_PROPAGATION_DELAY_SCOPE" "L"
					( Parent
						( matchGroupRef "@baseboard_fab2_lib.baseboard_fab2(sch_1):\MG_PCIE_L1\" )
					)
					( Status sCSetFlattened )
					( Origin gBackEnd )
				)
				( attribute "RELATIVE_PROPAGATION_DELAY" ",5.00 MIL"
					( Parent
						( matchGroupRef "@baseboard_fab2_lib.baseboard_fab2(sch_1):\MG_PCIE_L1\" )
					)
					( Units "uMatchProp" "ns" 1.000000)
					( Status sCSetFlattened )
					( Origin gBackEnd )
				)
			)
			( pinPair "@baseboard_fab2_lib.baseboard_fab2(sch_1):\PP256\"
				( pinRef "@baseboard_fab2_lib.baseboard_fab2(sch_1):page187_i119:IO60" )
				( pinRef "@baseboard_fab2_lib.baseboard_fab2(sch_1):page106_i37:B" )
				( attribute "RELATIVE_PROPAGATION_DELAY_SCOPE" "L"
					( Parent
						( matchGroupRef "@baseboard_fab2_lib.baseboard_fab2(sch_1):\MG_PCIE_L0\" )
					)
					( Status sCSetFlattened )
					( Origin gBackEnd )
				)
				( attribute "RELATIVE_PROPAGATION_DELAY" ",5.00 MIL"
					( Parent
						( matchGroupRef "@baseboard_fab2_lib.baseboard_fab2(sch_1):\MG_PCIE_L0\" )
					)
					( Units "uMatchProp" "ns" 1.000000)
					( Status sCSetFlattened )
					( Origin gBackEnd )
				)
			)
			( pinPair "@baseboard_fab2_lib.baseboard_fab2(sch_1):\PP5944\"
				( pinRef "@baseboard_fab2_lib.baseboard_fab2(sch_1):page32_i89:PE3_TX_DN(1)" )
				( pinRef "@baseboard_fab2_lib.baseboard_fab2(sch_1):page187_i119:IO60" )
				( attribute "PROPAGATION_DELAY_MIN" "3000.00 MIL"
					( Units "uMaxMinProp" "ns" 1.000000)
					( Status sCSetFlattened )
					( Origin gBackEnd )
				)
				( attribute "PROPAGATION_DELAY_MAX" "16000.00 MIL"
					( Units "uMaxMinProp" "ns" 1.000000)
					( Status sCSetFlattened )
					( Origin gBackEnd )
				)
				( attribute "RELATIVE_PROPAGATION_DELAY_SCOPE" "G"
					( Parent
						( matchGroupRef "@baseboard_fab2_lib.baseboard_fab2(sch_1):\MG_P3E_CPU0_PE3_OCP_TX0001\" )
					)
					( Status sCSetFlattened )
					( Origin gBackEnd )
				)
				( attribute "RELATIVE_PROPAGATION_DELAY" ",500.00 MIL"
					( Parent
						( matchGroupRef "@baseboard_fab2_lib.baseboard_fab2(sch_1):\MG_P3E_CPU0_PE3_OCP_TX0001\" )
					)
					( Units "uMatchProp" "ns" 1.000000)
					( Status sCSetFlattened )
					( Origin gBackEnd )
				)
			)
			( pinPair "@baseboard_fab2_lib.baseboard_fab2(sch_1):\PP257\"
				( pinRef "@baseboard_fab2_lib.baseboard_fab2(sch_1):page187_i119:IO58" )
				( pinRef "@baseboard_fab2_lib.baseboard_fab2(sch_1):page106_i26:B" )
				( attribute "RELATIVE_PROPAGATION_DELAY_SCOPE" "L"
					( Parent
						( matchGroupRef "@baseboard_fab2_lib.baseboard_fab2(sch_1):\MG_PCIE_L0\" )
					)
					( Status sCSetFlattened )
					( Origin gBackEnd )
				)
				( attribute "RELATIVE_PROPAGATION_DELAY" ",5.00 MIL"
					( Parent
						( matchGroupRef "@baseboard_fab2_lib.baseboard_fab2(sch_1):\MG_PCIE_L0\" )
					)
					( Units "uMatchProp" "ns" 1.000000)
					( Status sCSetFlattened )
					( Origin gBackEnd )
				)
			)
			( pinPair "@baseboard_fab2_lib.baseboard_fab2(sch_1):\PP258\"
				( pinRef "@baseboard_fab2_lib.baseboard_fab2(sch_1):page32_i89:PE3_TX_DP(1)" )
				( pinRef "@baseboard_fab2_lib.baseboard_fab2(sch_1):page106_i26:A" )
				( attribute "RELATIVE_PROPAGATION_DELAY_SCOPE" "L"
					( Parent
						( matchGroupRef "@baseboard_fab2_lib.baseboard_fab2(sch_1):\MG_PCIE_L1\" )
					)
					( Status sCSetFlattened )
					( Origin gBackEnd )
				)
				( attribute "RELATIVE_PROPAGATION_DELAY" ",5.00 MIL"
					( Parent
						( matchGroupRef "@baseboard_fab2_lib.baseboard_fab2(sch_1):\MG_PCIE_L1\" )
					)
					( Units "uMatchProp" "ns" 1.000000)
					( Status sCSetFlattened )
					( Origin gBackEnd )
				)
			)
			( pinPair "@baseboard_fab2_lib.baseboard_fab2(sch_1):\PP5932\"
				( pinRef "@baseboard_fab2_lib.baseboard_fab2(sch_1):page32_i89:PE3_TX_DP(1)" )
				( pinRef "@baseboard_fab2_lib.baseboard_fab2(sch_1):page187_i119:IO58" )
				( attribute "PROPAGATION_DELAY_MIN" "3000.00 MIL"
					( Units "uMaxMinProp" "ns" 1.000000)
					( Status sCSetFlattened )
					( Origin gBackEnd )
				)
				( attribute "PROPAGATION_DELAY_MAX" "16000.00 MIL"
					( Units "uMaxMinProp" "ns" 1.000000)
					( Status sCSetFlattened )
					( Origin gBackEnd )
				)
				( attribute "RELATIVE_PROPAGATION_DELAY_SCOPE" "G"
					( Parent
						( matchGroupRef "@baseboard_fab2_lib.baseboard_fab2(sch_1):\MG_P3E_CPU0_PE3_OCP_TX0001\" )
					)
					( Status sCSetFlattened )
					( Origin gBackEnd )
				)
				( attribute "RELATIVE_PROPAGATION_DELAY" ",500.00 MIL"
					( Parent
						( matchGroupRef "@baseboard_fab2_lib.baseboard_fab2(sch_1):\MG_P3E_CPU0_PE3_OCP_TX0001\" )
					)
					( Units "uMatchProp" "ns" 1.000000)
					( Status sCSetFlattened )
					( Origin gBackEnd )
				)
			)
			( pinPair "@baseboard_fab2_lib.baseboard_fab2(sch_1):\PP251\"
				( pinRef "@baseboard_fab2_lib.baseboard_fab2(sch_1):page32_i89:PE3_TX_DN(2)" )
				( pinRef "@baseboard_fab2_lib.baseboard_fab2(sch_1):page106_i59:A" )
				( attribute "RELATIVE_PROPAGATION_DELAY_SCOPE" "L"
					( Parent
						( matchGroupRef "@baseboard_fab2_lib.baseboard_fab2(sch_1):\MG_PCIE_L1\" )
					)
					( Status sCSetFlattened )
					( Origin gBackEnd )
				)
				( attribute "RELATIVE_PROPAGATION_DELAY" ",5.00 MIL"
					( Parent
						( matchGroupRef "@baseboard_fab2_lib.baseboard_fab2(sch_1):\MG_PCIE_L1\" )
					)
					( Units "uMatchProp" "ns" 1.000000)
					( Status sCSetFlattened )
					( Origin gBackEnd )
				)
			)
			( pinPair "@baseboard_fab2_lib.baseboard_fab2(sch_1):\PP252\"
				( pinRef "@baseboard_fab2_lib.baseboard_fab2(sch_1):page187_i119:IO52" )
				( pinRef "@baseboard_fab2_lib.baseboard_fab2(sch_1):page106_i59:B" )
				( attribute "RELATIVE_PROPAGATION_DELAY_SCOPE" "L"
					( Parent
						( matchGroupRef "@baseboard_fab2_lib.baseboard_fab2(sch_1):\MG_PCIE_L0\" )
					)
					( Status sCSetFlattened )
					( Origin gBackEnd )
				)
				( attribute "RELATIVE_PROPAGATION_DELAY" ",5.00 MIL"
					( Parent
						( matchGroupRef "@baseboard_fab2_lib.baseboard_fab2(sch_1):\MG_PCIE_L0\" )
					)
					( Units "uMatchProp" "ns" 1.000000)
					( Status sCSetFlattened )
					( Origin gBackEnd )
				)
			)
			( pinPair "@baseboard_fab2_lib.baseboard_fab2(sch_1):\PP5945\"
				( pinRef "@baseboard_fab2_lib.baseboard_fab2(sch_1):page32_i89:PE3_TX_DN(2)" )
				( pinRef "@baseboard_fab2_lib.baseboard_fab2(sch_1):page187_i119:IO52" )
				( attribute "PROPAGATION_DELAY_MIN" "3000.00 MIL"
					( Units "uMaxMinProp" "ns" 1.000000)
					( Status sCSetFlattened )
					( Origin gBackEnd )
				)
				( attribute "PROPAGATION_DELAY_MAX" "16000.00 MIL"
					( Units "uMaxMinProp" "ns" 1.000000)
					( Status sCSetFlattened )
					( Origin gBackEnd )
				)
				( attribute "RELATIVE_PROPAGATION_DELAY_SCOPE" "G"
					( Parent
						( matchGroupRef "@baseboard_fab2_lib.baseboard_fab2(sch_1):\MG_P3E_CPU0_PE3_OCP_TX0203\" )
					)
					( Status sCSetFlattened )
					( Origin gBackEnd )
				)
				( attribute "RELATIVE_PROPAGATION_DELAY" ",500.00 MIL"
					( Parent
						( matchGroupRef "@baseboard_fab2_lib.baseboard_fab2(sch_1):\MG_P3E_CPU0_PE3_OCP_TX0203\" )
					)
					( Units "uMatchProp" "ns" 1.000000)
					( Status sCSetFlattened )
					( Origin gBackEnd )
				)
			)
			( pinPair "@baseboard_fab2_lib.baseboard_fab2(sch_1):\PP253\"
				( pinRef "@baseboard_fab2_lib.baseboard_fab2(sch_1):page187_i119:IO50" )
				( pinRef "@baseboard_fab2_lib.baseboard_fab2(sch_1):page106_i40:B" )
				( attribute "RELATIVE_PROPAGATION_DELAY_SCOPE" "L"
					( Parent
						( matchGroupRef "@baseboard_fab2_lib.baseboard_fab2(sch_1):\MG_PCIE_L0\" )
					)
					( Status sCSetFlattened )
					( Origin gBackEnd )
				)
				( attribute "RELATIVE_PROPAGATION_DELAY" ",5.00 MIL"
					( Parent
						( matchGroupRef "@baseboard_fab2_lib.baseboard_fab2(sch_1):\MG_PCIE_L0\" )
					)
					( Units "uMatchProp" "ns" 1.000000)
					( Status sCSetFlattened )
					( Origin gBackEnd )
				)
			)
			( pinPair "@baseboard_fab2_lib.baseboard_fab2(sch_1):\PP254\"
				( pinRef "@baseboard_fab2_lib.baseboard_fab2(sch_1):page32_i89:PE3_TX_DP(2)" )
				( pinRef "@baseboard_fab2_lib.baseboard_fab2(sch_1):page106_i40:A" )
				( attribute "RELATIVE_PROPAGATION_DELAY_SCOPE" "L"
					( Parent
						( matchGroupRef "@baseboard_fab2_lib.baseboard_fab2(sch_1):\MG_PCIE_L1\" )
					)
					( Status sCSetFlattened )
					( Origin gBackEnd )
				)
				( attribute "RELATIVE_PROPAGATION_DELAY" ",5.00 MIL"
					( Parent
						( matchGroupRef "@baseboard_fab2_lib.baseboard_fab2(sch_1):\MG_PCIE_L1\" )
					)
					( Units "uMatchProp" "ns" 1.000000)
					( Status sCSetFlattened )
					( Origin gBackEnd )
				)
			)
			( pinPair "@baseboard_fab2_lib.baseboard_fab2(sch_1):\PP5943\"
				( pinRef "@baseboard_fab2_lib.baseboard_fab2(sch_1):page32_i89:PE3_TX_DP(2)" )
				( pinRef "@baseboard_fab2_lib.baseboard_fab2(sch_1):page187_i119:IO50" )
				( attribute "PROPAGATION_DELAY_MIN" "3000.00 MIL"
					( Units "uMaxMinProp" "ns" 1.000000)
					( Status sCSetFlattened )
					( Origin gBackEnd )
				)
				( attribute "PROPAGATION_DELAY_MAX" "16000.00 MIL"
					( Units "uMaxMinProp" "ns" 1.000000)
					( Status sCSetFlattened )
					( Origin gBackEnd )
				)
				( attribute "RELATIVE_PROPAGATION_DELAY_SCOPE" "G"
					( Parent
						( matchGroupRef "@baseboard_fab2_lib.baseboard_fab2(sch_1):\MG_P3E_CPU0_PE3_OCP_TX0203\" )
					)
					( Status sCSetFlattened )
					( Origin gBackEnd )
				)
				( attribute "RELATIVE_PROPAGATION_DELAY" ",500.00 MIL"
					( Parent
						( matchGroupRef "@baseboard_fab2_lib.baseboard_fab2(sch_1):\MG_P3E_CPU0_PE3_OCP_TX0203\" )
					)
					( Units "uMatchProp" "ns" 1.000000)
					( Status sCSetFlattened )
					( Origin gBackEnd )
				)
			)
			( pinPair "@baseboard_fab2_lib.baseboard_fab2(sch_1):\PP247\"
				( pinRef "@baseboard_fab2_lib.baseboard_fab2(sch_1):page32_i89:PE3_TX_DN(3)" )
				( pinRef "@baseboard_fab2_lib.baseboard_fab2(sch_1):page106_i70:A" )
				( attribute "RELATIVE_PROPAGATION_DELAY_SCOPE" "L"
					( Parent
						( matchGroupRef "@baseboard_fab2_lib.baseboard_fab2(sch_1):\MG_PCIE_L1\" )
					)
					( Status sCSetFlattened )
					( Origin gBackEnd )
				)
				( attribute "RELATIVE_PROPAGATION_DELAY" ",5.00 MIL"
					( Parent
						( matchGroupRef "@baseboard_fab2_lib.baseboard_fab2(sch_1):\MG_PCIE_L1\" )
					)
					( Units "uMatchProp" "ns" 1.000000)
					( Status sCSetFlattened )
					( Origin gBackEnd )
				)
			)
			( pinPair "@baseboard_fab2_lib.baseboard_fab2(sch_1):\PP248\"
				( pinRef "@baseboard_fab2_lib.baseboard_fab2(sch_1):page187_i119:IO44" )
				( pinRef "@baseboard_fab2_lib.baseboard_fab2(sch_1):page106_i70:B" )
				( attribute "RELATIVE_PROPAGATION_DELAY_SCOPE" "L"
					( Parent
						( matchGroupRef "@baseboard_fab2_lib.baseboard_fab2(sch_1):\MG_PCIE_L0\" )
					)
					( Status sCSetFlattened )
					( Origin gBackEnd )
				)
				( attribute "RELATIVE_PROPAGATION_DELAY" ",5.00 MIL"
					( Parent
						( matchGroupRef "@baseboard_fab2_lib.baseboard_fab2(sch_1):\MG_PCIE_L0\" )
					)
					( Units "uMatchProp" "ns" 1.000000)
					( Status sCSetFlattened )
					( Origin gBackEnd )
				)
			)
			( pinPair "@baseboard_fab2_lib.baseboard_fab2(sch_1):\PP5948\"
				( pinRef "@baseboard_fab2_lib.baseboard_fab2(sch_1):page32_i89:PE3_TX_DN(3)" )
				( pinRef "@baseboard_fab2_lib.baseboard_fab2(sch_1):page187_i119:IO44" )
				( attribute "PROPAGATION_DELAY_MIN" "3000.00 MIL"
					( Units "uMaxMinProp" "ns" 1.000000)
					( Status sCSetFlattened )
					( Origin gBackEnd )
				)
				( attribute "PROPAGATION_DELAY_MAX" "16000.00 MIL"
					( Units "uMaxMinProp" "ns" 1.000000)
					( Status sCSetFlattened )
					( Origin gBackEnd )
				)
				( attribute "RELATIVE_PROPAGATION_DELAY_SCOPE" "G"
					( Parent
						( matchGroupRef "@baseboard_fab2_lib.baseboard_fab2(sch_1):\MG_P3E_CPU0_PE3_OCP_TX0203\" )
					)
					( Status sCSetFlattened )
					( Origin gBackEnd )
				)
				( attribute "RELATIVE_PROPAGATION_DELAY" ",500.00 MIL"
					( Parent
						( matchGroupRef "@baseboard_fab2_lib.baseboard_fab2(sch_1):\MG_P3E_CPU0_PE3_OCP_TX0203\" )
					)
					( Units "uMatchProp" "ns" 1.000000)
					( Status sCSetFlattened )
					( Origin gBackEnd )
				)
			)
			( pinPair "@baseboard_fab2_lib.baseboard_fab2(sch_1):\PP249\"
				( pinRef "@baseboard_fab2_lib.baseboard_fab2(sch_1):page187_i119:IO42" )
				( pinRef "@baseboard_fab2_lib.baseboard_fab2(sch_1):page106_i55:B" )
				( attribute "RELATIVE_PROPAGATION_DELAY_SCOPE" "L"
					( Parent
						( matchGroupRef "@baseboard_fab2_lib.baseboard_fab2(sch_1):\MG_PCIE_L0\" )
					)
					( Status sCSetFlattened )
					( Origin gBackEnd )
				)
				( attribute "RELATIVE_PROPAGATION_DELAY" ",5.00 MIL"
					( Parent
						( matchGroupRef "@baseboard_fab2_lib.baseboard_fab2(sch_1):\MG_PCIE_L0\" )
					)
					( Units "uMatchProp" "ns" 1.000000)
					( Status sCSetFlattened )
					( Origin gBackEnd )
				)
			)
			( pinPair "@baseboard_fab2_lib.baseboard_fab2(sch_1):\PP250\"
				( pinRef "@baseboard_fab2_lib.baseboard_fab2(sch_1):page32_i89:PE3_TX_DP(3)" )
				( pinRef "@baseboard_fab2_lib.baseboard_fab2(sch_1):page106_i55:A" )
				( attribute "RELATIVE_PROPAGATION_DELAY_SCOPE" "L"
					( Parent
						( matchGroupRef "@baseboard_fab2_lib.baseboard_fab2(sch_1):\MG_PCIE_L1\" )
					)
					( Status sCSetFlattened )
					( Origin gBackEnd )
				)
				( attribute "RELATIVE_PROPAGATION_DELAY" ",5.00 MIL"
					( Parent
						( matchGroupRef "@baseboard_fab2_lib.baseboard_fab2(sch_1):\MG_PCIE_L1\" )
					)
					( Units "uMatchProp" "ns" 1.000000)
					( Status sCSetFlattened )
					( Origin gBackEnd )
				)
			)
			( pinPair "@baseboard_fab2_lib.baseboard_fab2(sch_1):\PP5946\"
				( pinRef "@baseboard_fab2_lib.baseboard_fab2(sch_1):page32_i89:PE3_TX_DP(3)" )
				( pinRef "@baseboard_fab2_lib.baseboard_fab2(sch_1):page187_i119:IO42" )
				( attribute "PROPAGATION_DELAY_MIN" "3000.00 MIL"
					( Units "uMaxMinProp" "ns" 1.000000)
					( Status sCSetFlattened )
					( Origin gBackEnd )
				)
				( attribute "PROPAGATION_DELAY_MAX" "16000.00 MIL"
					( Units "uMaxMinProp" "ns" 1.000000)
					( Status sCSetFlattened )
					( Origin gBackEnd )
				)
				( attribute "RELATIVE_PROPAGATION_DELAY_SCOPE" "G"
					( Parent
						( matchGroupRef "@baseboard_fab2_lib.baseboard_fab2(sch_1):\MG_P3E_CPU0_PE3_OCP_TX0203\" )
					)
					( Status sCSetFlattened )
					( Origin gBackEnd )
				)
				( attribute "RELATIVE_PROPAGATION_DELAY" ",500.00 MIL"
					( Parent
						( matchGroupRef "@baseboard_fab2_lib.baseboard_fab2(sch_1):\MG_P3E_CPU0_PE3_OCP_TX0203\" )
					)
					( Units "uMatchProp" "ns" 1.000000)
					( Status sCSetFlattened )
					( Origin gBackEnd )
				)
			)
			( pinPair "@baseboard_fab2_lib.baseboard_fab2(sch_1):\PP243\"
				( pinRef "@baseboard_fab2_lib.baseboard_fab2(sch_1):page32_i89:PE3_TX_DN(4)" )
				( pinRef "@baseboard_fab2_lib.baseboard_fab2(sch_1):page106_i134:A" )
				( attribute "RELATIVE_PROPAGATION_DELAY_SCOPE" "L"
					( Parent
						( matchGroupRef "@baseboard_fab2_lib.baseboard_fab2(sch_1):\MG_PCIE_L1\" )
					)
					( Status sCSetFlattened )
					( Origin gBackEnd )
				)
				( attribute "RELATIVE_PROPAGATION_DELAY" ",5.00 MIL"
					( Parent
						( matchGroupRef "@baseboard_fab2_lib.baseboard_fab2(sch_1):\MG_PCIE_L1\" )
					)
					( Units "uMatchProp" "ns" 1.000000)
					( Status sCSetFlattened )
					( Origin gBackEnd )
				)
			)
			( pinPair "@baseboard_fab2_lib.baseboard_fab2(sch_1):\PP244\"
				( pinRef "@baseboard_fab2_lib.baseboard_fab2(sch_1):page187_i119:IO36" )
				( pinRef "@baseboard_fab2_lib.baseboard_fab2(sch_1):page106_i134:B" )
				( attribute "RELATIVE_PROPAGATION_DELAY_SCOPE" "L"
					( Parent
						( matchGroupRef "@baseboard_fab2_lib.baseboard_fab2(sch_1):\MG_PCIE_L0\" )
					)
					( Status sCSetFlattened )
					( Origin gBackEnd )
				)
				( attribute "RELATIVE_PROPAGATION_DELAY" ",5.00 MIL"
					( Parent
						( matchGroupRef "@baseboard_fab2_lib.baseboard_fab2(sch_1):\MG_PCIE_L0\" )
					)
					( Units "uMatchProp" "ns" 1.000000)
					( Status sCSetFlattened )
					( Origin gBackEnd )
				)
			)
			( pinPair "@baseboard_fab2_lib.baseboard_fab2(sch_1):\PP5950\"
				( pinRef "@baseboard_fab2_lib.baseboard_fab2(sch_1):page32_i89:PE3_TX_DN(4)" )
				( pinRef "@baseboard_fab2_lib.baseboard_fab2(sch_1):page187_i119:IO36" )
				( attribute "PROPAGATION_DELAY_MIN" "3000.00 MIL"
					( Units "uMaxMinProp" "ns" 1.000000)
					( Status sCSetFlattened )
					( Origin gBackEnd )
				)
				( attribute "PROPAGATION_DELAY_MAX" "16000.00 MIL"
					( Units "uMaxMinProp" "ns" 1.000000)
					( Status sCSetFlattened )
					( Origin gBackEnd )
				)
				( attribute "RELATIVE_PROPAGATION_DELAY_SCOPE" "G"
					( Parent
						( matchGroupRef "@baseboard_fab2_lib.baseboard_fab2(sch_1):\MG_P3E_CPU0_PE3_OCP_TX0405\" )
					)
					( Status sCSetFlattened )
					( Origin gBackEnd )
				)
				( attribute "RELATIVE_PROPAGATION_DELAY" ",500.00 MIL"
					( Parent
						( matchGroupRef "@baseboard_fab2_lib.baseboard_fab2(sch_1):\MG_P3E_CPU0_PE3_OCP_TX0405\" )
					)
					( Units "uMatchProp" "ns" 1.000000)
					( Status sCSetFlattened )
					( Origin gBackEnd )
				)
			)
			( pinPair "@baseboard_fab2_lib.baseboard_fab2(sch_1):\PP245\"
				( pinRef "@baseboard_fab2_lib.baseboard_fab2(sch_1):page187_i119:IO34" )
				( pinRef "@baseboard_fab2_lib.baseboard_fab2(sch_1):page106_i128:B" )
				( attribute "RELATIVE_PROPAGATION_DELAY_SCOPE" "L"
					( Parent
						( matchGroupRef "@baseboard_fab2_lib.baseboard_fab2(sch_1):\MG_PCIE_L0\" )
					)
					( Status sCSetFlattened )
					( Origin gBackEnd )
				)
				( attribute "RELATIVE_PROPAGATION_DELAY" ",5.00 MIL"
					( Parent
						( matchGroupRef "@baseboard_fab2_lib.baseboard_fab2(sch_1):\MG_PCIE_L0\" )
					)
					( Units "uMatchProp" "ns" 1.000000)
					( Status sCSetFlattened )
					( Origin gBackEnd )
				)
			)
			( pinPair "@baseboard_fab2_lib.baseboard_fab2(sch_1):\PP246\"
				( pinRef "@baseboard_fab2_lib.baseboard_fab2(sch_1):page32_i89:PE3_TX_DP(4)" )
				( pinRef "@baseboard_fab2_lib.baseboard_fab2(sch_1):page106_i128:A" )
				( attribute "RELATIVE_PROPAGATION_DELAY_SCOPE" "L"
					( Parent
						( matchGroupRef "@baseboard_fab2_lib.baseboard_fab2(sch_1):\MG_PCIE_L1\" )
					)
					( Status sCSetFlattened )
					( Origin gBackEnd )
				)
				( attribute "RELATIVE_PROPAGATION_DELAY" ",5.00 MIL"
					( Parent
						( matchGroupRef "@baseboard_fab2_lib.baseboard_fab2(sch_1):\MG_PCIE_L1\" )
					)
					( Units "uMatchProp" "ns" 1.000000)
					( Status sCSetFlattened )
					( Origin gBackEnd )
				)
			)
			( pinPair "@baseboard_fab2_lib.baseboard_fab2(sch_1):\PP5947\"
				( pinRef "@baseboard_fab2_lib.baseboard_fab2(sch_1):page32_i89:PE3_TX_DP(4)" )
				( pinRef "@baseboard_fab2_lib.baseboard_fab2(sch_1):page187_i119:IO34" )
				( attribute "PROPAGATION_DELAY_MIN" "3000.00 MIL"
					( Units "uMaxMinProp" "ns" 1.000000)
					( Status sCSetFlattened )
					( Origin gBackEnd )
				)
				( attribute "PROPAGATION_DELAY_MAX" "16000.00 MIL"
					( Units "uMaxMinProp" "ns" 1.000000)
					( Status sCSetFlattened )
					( Origin gBackEnd )
				)
				( attribute "RELATIVE_PROPAGATION_DELAY_SCOPE" "G"
					( Parent
						( matchGroupRef "@baseboard_fab2_lib.baseboard_fab2(sch_1):\MG_P3E_CPU0_PE3_OCP_TX0405\" )
					)
					( Status sCSetFlattened )
					( Origin gBackEnd )
				)
				( attribute "RELATIVE_PROPAGATION_DELAY" ",500.00 MIL"
					( Parent
						( matchGroupRef "@baseboard_fab2_lib.baseboard_fab2(sch_1):\MG_P3E_CPU0_PE3_OCP_TX0405\" )
					)
					( Units "uMatchProp" "ns" 1.000000)
					( Status sCSetFlattened )
					( Origin gBackEnd )
				)
			)
			( pinPair "@baseboard_fab2_lib.baseboard_fab2(sch_1):\PP239\"
				( pinRef "@baseboard_fab2_lib.baseboard_fab2(sch_1):page32_i89:PE3_TX_DN(5)" )
				( pinRef "@baseboard_fab2_lib.baseboard_fab2(sch_1):page106_i137:A" )
				( attribute "RELATIVE_PROPAGATION_DELAY_SCOPE" "L"
					( Parent
						( matchGroupRef "@baseboard_fab2_lib.baseboard_fab2(sch_1):\MG_PCIE_L1\" )
					)
					( Status sCSetFlattened )
					( Origin gBackEnd )
				)
				( attribute "RELATIVE_PROPAGATION_DELAY" ",5.00 MIL"
					( Parent
						( matchGroupRef "@baseboard_fab2_lib.baseboard_fab2(sch_1):\MG_PCIE_L1\" )
					)
					( Units "uMatchProp" "ns" 1.000000)
					( Status sCSetFlattened )
					( Origin gBackEnd )
				)
			)
			( pinPair "@baseboard_fab2_lib.baseboard_fab2(sch_1):\PP240\"
				( pinRef "@baseboard_fab2_lib.baseboard_fab2(sch_1):page187_i119:IO28" )
				( pinRef "@baseboard_fab2_lib.baseboard_fab2(sch_1):page106_i137:B" )
				( attribute "RELATIVE_PROPAGATION_DELAY_SCOPE" "L"
					( Parent
						( matchGroupRef "@baseboard_fab2_lib.baseboard_fab2(sch_1):\MG_PCIE_L0\" )
					)
					( Status sCSetFlattened )
					( Origin gBackEnd )
				)
				( attribute "RELATIVE_PROPAGATION_DELAY" ",5.00 MIL"
					( Parent
						( matchGroupRef "@baseboard_fab2_lib.baseboard_fab2(sch_1):\MG_PCIE_L0\" )
					)
					( Units "uMatchProp" "ns" 1.000000)
					( Status sCSetFlattened )
					( Origin gBackEnd )
				)
			)
			( pinPair "@baseboard_fab2_lib.baseboard_fab2(sch_1):\PP5955\"
				( pinRef "@baseboard_fab2_lib.baseboard_fab2(sch_1):page32_i89:PE3_TX_DN(5)" )
				( pinRef "@baseboard_fab2_lib.baseboard_fab2(sch_1):page187_i119:IO28" )
				( attribute "PROPAGATION_DELAY_MIN" "3000.00 MIL"
					( Units "uMaxMinProp" "ns" 1.000000)
					( Status sCSetFlattened )
					( Origin gBackEnd )
				)
				( attribute "PROPAGATION_DELAY_MAX" "16000.00 MIL"
					( Units "uMaxMinProp" "ns" 1.000000)
					( Status sCSetFlattened )
					( Origin gBackEnd )
				)
				( attribute "RELATIVE_PROPAGATION_DELAY_SCOPE" "G"
					( Parent
						( matchGroupRef "@baseboard_fab2_lib.baseboard_fab2(sch_1):\MG_P3E_CPU0_PE3_OCP_TX0405\" )
					)
					( Status sCSetFlattened )
					( Origin gBackEnd )
				)
				( attribute "RELATIVE_PROPAGATION_DELAY" ",500.00 MIL"
					( Parent
						( matchGroupRef "@baseboard_fab2_lib.baseboard_fab2(sch_1):\MG_P3E_CPU0_PE3_OCP_TX0405\" )
					)
					( Units "uMatchProp" "ns" 1.000000)
					( Status sCSetFlattened )
					( Origin gBackEnd )
				)
			)
			( pinPair "@baseboard_fab2_lib.baseboard_fab2(sch_1):\PP241\"
				( pinRef "@baseboard_fab2_lib.baseboard_fab2(sch_1):page187_i119:IO26" )
				( pinRef "@baseboard_fab2_lib.baseboard_fab2(sch_1):page106_i130:B" )
				( attribute "RELATIVE_PROPAGATION_DELAY_SCOPE" "L"
					( Parent
						( matchGroupRef "@baseboard_fab2_lib.baseboard_fab2(sch_1):\MG_PCIE_L0\" )
					)
					( Status sCSetFlattened )
					( Origin gBackEnd )
				)
				( attribute "RELATIVE_PROPAGATION_DELAY" ",5.00 MIL"
					( Parent
						( matchGroupRef "@baseboard_fab2_lib.baseboard_fab2(sch_1):\MG_PCIE_L0\" )
					)
					( Units "uMatchProp" "ns" 1.000000)
					( Status sCSetFlattened )
					( Origin gBackEnd )
				)
			)
			( pinPair "@baseboard_fab2_lib.baseboard_fab2(sch_1):\PP242\"
				( pinRef "@baseboard_fab2_lib.baseboard_fab2(sch_1):page32_i89:PE3_TX_DP(5)" )
				( pinRef "@baseboard_fab2_lib.baseboard_fab2(sch_1):page106_i130:A" )
				( attribute "RELATIVE_PROPAGATION_DELAY_SCOPE" "L"
					( Parent
						( matchGroupRef "@baseboard_fab2_lib.baseboard_fab2(sch_1):\MG_PCIE_L1\" )
					)
					( Status sCSetFlattened )
					( Origin gBackEnd )
				)
				( attribute "RELATIVE_PROPAGATION_DELAY" ",5.00 MIL"
					( Parent
						( matchGroupRef "@baseboard_fab2_lib.baseboard_fab2(sch_1):\MG_PCIE_L1\" )
					)
					( Units "uMatchProp" "ns" 1.000000)
					( Status sCSetFlattened )
					( Origin gBackEnd )
				)
			)
			( pinPair "@baseboard_fab2_lib.baseboard_fab2(sch_1):\PP5949\"
				( pinRef "@baseboard_fab2_lib.baseboard_fab2(sch_1):page32_i89:PE3_TX_DP(5)" )
				( pinRef "@baseboard_fab2_lib.baseboard_fab2(sch_1):page187_i119:IO26" )
				( attribute "PROPAGATION_DELAY_MIN" "3000.00 MIL"
					( Units "uMaxMinProp" "ns" 1.000000)
					( Status sCSetFlattened )
					( Origin gBackEnd )
				)
				( attribute "PROPAGATION_DELAY_MAX" "16000.00 MIL"
					( Units "uMaxMinProp" "ns" 1.000000)
					( Status sCSetFlattened )
					( Origin gBackEnd )
				)
				( attribute "RELATIVE_PROPAGATION_DELAY_SCOPE" "G"
					( Parent
						( matchGroupRef "@baseboard_fab2_lib.baseboard_fab2(sch_1):\MG_P3E_CPU0_PE3_OCP_TX0405\" )
					)
					( Status sCSetFlattened )
					( Origin gBackEnd )
				)
				( attribute "RELATIVE_PROPAGATION_DELAY" ",500.00 MIL"
					( Parent
						( matchGroupRef "@baseboard_fab2_lib.baseboard_fab2(sch_1):\MG_P3E_CPU0_PE3_OCP_TX0405\" )
					)
					( Units "uMatchProp" "ns" 1.000000)
					( Status sCSetFlattened )
					( Origin gBackEnd )
				)
			)
			( pinPair "@baseboard_fab2_lib.baseboard_fab2(sch_1):\PP235\"
				( pinRef "@baseboard_fab2_lib.baseboard_fab2(sch_1):page32_i89:PE3_TX_DN(6)" )
				( pinRef "@baseboard_fab2_lib.baseboard_fab2(sch_1):page106_i123:A" )
				( attribute "RELATIVE_PROPAGATION_DELAY_SCOPE" "L"
					( Parent
						( matchGroupRef "@baseboard_fab2_lib.baseboard_fab2(sch_1):\MG_PCIE_L1\" )
					)
					( Status sCSetFlattened )
					( Origin gBackEnd )
				)
				( attribute "RELATIVE_PROPAGATION_DELAY" ",5.00 MIL"
					( Parent
						( matchGroupRef "@baseboard_fab2_lib.baseboard_fab2(sch_1):\MG_PCIE_L1\" )
					)
					( Units "uMatchProp" "ns" 1.000000)
					( Status sCSetFlattened )
					( Origin gBackEnd )
				)
			)
			( pinPair "@baseboard_fab2_lib.baseboard_fab2(sch_1):\PP236\"
				( pinRef "@baseboard_fab2_lib.baseboard_fab2(sch_1):page187_i119:IO20" )
				( pinRef "@baseboard_fab2_lib.baseboard_fab2(sch_1):page106_i123:B" )
				( attribute "RELATIVE_PROPAGATION_DELAY_SCOPE" "L"
					( Parent
						( matchGroupRef "@baseboard_fab2_lib.baseboard_fab2(sch_1):\MG_PCIE_L0\" )
					)
					( Status sCSetFlattened )
					( Origin gBackEnd )
				)
				( attribute "RELATIVE_PROPAGATION_DELAY" ",5.00 MIL"
					( Parent
						( matchGroupRef "@baseboard_fab2_lib.baseboard_fab2(sch_1):\MG_PCIE_L0\" )
					)
					( Units "uMatchProp" "ns" 1.000000)
					( Status sCSetFlattened )
					( Origin gBackEnd )
				)
			)
			( pinPair "@baseboard_fab2_lib.baseboard_fab2(sch_1):\PP5956\"
				( pinRef "@baseboard_fab2_lib.baseboard_fab2(sch_1):page32_i89:PE3_TX_DN(6)" )
				( pinRef "@baseboard_fab2_lib.baseboard_fab2(sch_1):page187_i119:IO20" )
				( attribute "PROPAGATION_DELAY_MIN" "3000.00 MIL"
					( Units "uMaxMinProp" "ns" 1.000000)
					( Status sCSetFlattened )
					( Origin gBackEnd )
				)
				( attribute "PROPAGATION_DELAY_MAX" "16000.00 MIL"
					( Units "uMaxMinProp" "ns" 1.000000)
					( Status sCSetFlattened )
					( Origin gBackEnd )
				)
				( attribute "RELATIVE_PROPAGATION_DELAY_SCOPE" "G"
					( Parent
						( matchGroupRef "@baseboard_fab2_lib.baseboard_fab2(sch_1):\MG_P3E_CPU0_PE3_OCP_TX0607\" )
					)
					( Status sCSetFlattened )
					( Origin gBackEnd )
				)
				( attribute "RELATIVE_PROPAGATION_DELAY" ",500.00 MIL"
					( Parent
						( matchGroupRef "@baseboard_fab2_lib.baseboard_fab2(sch_1):\MG_P3E_CPU0_PE3_OCP_TX0607\" )
					)
					( Units "uMatchProp" "ns" 1.000000)
					( Status sCSetFlattened )
					( Origin gBackEnd )
				)
			)
			( pinPair "@baseboard_fab2_lib.baseboard_fab2(sch_1):\PP237\"
				( pinRef "@baseboard_fab2_lib.baseboard_fab2(sch_1):page187_i119:IO18" )
				( pinRef "@baseboard_fab2_lib.baseboard_fab2(sch_1):page106_i141:B" )
				( attribute "RELATIVE_PROPAGATION_DELAY_SCOPE" "L"
					( Parent
						( matchGroupRef "@baseboard_fab2_lib.baseboard_fab2(sch_1):\MG_PCIE_L0\" )
					)
					( Status sCSetFlattened )
					( Origin gBackEnd )
				)
				( attribute "RELATIVE_PROPAGATION_DELAY" ",5.00 MIL"
					( Parent
						( matchGroupRef "@baseboard_fab2_lib.baseboard_fab2(sch_1):\MG_PCIE_L0\" )
					)
					( Units "uMatchProp" "ns" 1.000000)
					( Status sCSetFlattened )
					( Origin gBackEnd )
				)
			)
			( pinPair "@baseboard_fab2_lib.baseboard_fab2(sch_1):\PP238\"
				( pinRef "@baseboard_fab2_lib.baseboard_fab2(sch_1):page32_i89:PE3_TX_DP(6)" )
				( pinRef "@baseboard_fab2_lib.baseboard_fab2(sch_1):page106_i141:A" )
				( attribute "RELATIVE_PROPAGATION_DELAY_SCOPE" "L"
					( Parent
						( matchGroupRef "@baseboard_fab2_lib.baseboard_fab2(sch_1):\MG_PCIE_L1\" )
					)
					( Status sCSetFlattened )
					( Origin gBackEnd )
				)
				( attribute "RELATIVE_PROPAGATION_DELAY" ",5.00 MIL"
					( Parent
						( matchGroupRef "@baseboard_fab2_lib.baseboard_fab2(sch_1):\MG_PCIE_L1\" )
					)
					( Units "uMatchProp" "ns" 1.000000)
					( Status sCSetFlattened )
					( Origin gBackEnd )
				)
			)
			( pinPair "@baseboard_fab2_lib.baseboard_fab2(sch_1):\PP5954\"
				( pinRef "@baseboard_fab2_lib.baseboard_fab2(sch_1):page32_i89:PE3_TX_DP(6)" )
				( pinRef "@baseboard_fab2_lib.baseboard_fab2(sch_1):page187_i119:IO18" )
				( attribute "PROPAGATION_DELAY_MIN" "3000.00 MIL"
					( Units "uMaxMinProp" "ns" 1.000000)
					( Status sCSetFlattened )
					( Origin gBackEnd )
				)
				( attribute "PROPAGATION_DELAY_MAX" "16000.00 MIL"
					( Units "uMaxMinProp" "ns" 1.000000)
					( Status sCSetFlattened )
					( Origin gBackEnd )
				)
				( attribute "RELATIVE_PROPAGATION_DELAY_SCOPE" "G"
					( Parent
						( matchGroupRef "@baseboard_fab2_lib.baseboard_fab2(sch_1):\MG_P3E_CPU0_PE3_OCP_TX0607\" )
					)
					( Status sCSetFlattened )
					( Origin gBackEnd )
				)
				( attribute "RELATIVE_PROPAGATION_DELAY" ",500.00 MIL"
					( Parent
						( matchGroupRef "@baseboard_fab2_lib.baseboard_fab2(sch_1):\MG_P3E_CPU0_PE3_OCP_TX0607\" )
					)
					( Units "uMatchProp" "ns" 1.000000)
					( Status sCSetFlattened )
					( Origin gBackEnd )
				)
			)
			( pinPair "@baseboard_fab2_lib.baseboard_fab2(sch_1):\PP231\"
				( pinRef "@baseboard_fab2_lib.baseboard_fab2(sch_1):page32_i89:PE3_TX_DN(7)" )
				( pinRef "@baseboard_fab2_lib.baseboard_fab2(sch_1):page106_i147:A" )
				( attribute "RELATIVE_PROPAGATION_DELAY_SCOPE" "L"
					( Parent
						( matchGroupRef "@baseboard_fab2_lib.baseboard_fab2(sch_1):\MG_PCIE_L1\" )
					)
					( Status sCSetFlattened )
					( Origin gBackEnd )
				)
				( attribute "RELATIVE_PROPAGATION_DELAY" ",5.00 MIL"
					( Parent
						( matchGroupRef "@baseboard_fab2_lib.baseboard_fab2(sch_1):\MG_PCIE_L1\" )
					)
					( Units "uMatchProp" "ns" 1.000000)
					( Status sCSetFlattened )
					( Origin gBackEnd )
				)
			)
			( pinPair "@baseboard_fab2_lib.baseboard_fab2(sch_1):\PP232\"
				( pinRef "@baseboard_fab2_lib.baseboard_fab2(sch_1):page187_i119:IO12" )
				( pinRef "@baseboard_fab2_lib.baseboard_fab2(sch_1):page106_i147:B" )
				( attribute "RELATIVE_PROPAGATION_DELAY_SCOPE" "L"
					( Parent
						( matchGroupRef "@baseboard_fab2_lib.baseboard_fab2(sch_1):\MG_PCIE_L0\" )
					)
					( Status sCSetFlattened )
					( Origin gBackEnd )
				)
				( attribute "RELATIVE_PROPAGATION_DELAY" ",5.00 MIL"
					( Parent
						( matchGroupRef "@baseboard_fab2_lib.baseboard_fab2(sch_1):\MG_PCIE_L0\" )
					)
					( Units "uMatchProp" "ns" 1.000000)
					( Status sCSetFlattened )
					( Origin gBackEnd )
				)
			)
			( pinPair "@baseboard_fab2_lib.baseboard_fab2(sch_1):\PP5958\"
				( pinRef "@baseboard_fab2_lib.baseboard_fab2(sch_1):page32_i89:PE3_TX_DN(7)" )
				( pinRef "@baseboard_fab2_lib.baseboard_fab2(sch_1):page187_i119:IO12" )
				( attribute "PROPAGATION_DELAY_MIN" "3000.00 MIL"
					( Units "uMaxMinProp" "ns" 1.000000)
					( Status sCSetFlattened )
					( Origin gBackEnd )
				)
				( attribute "PROPAGATION_DELAY_MAX" "16000.00 MIL"
					( Units "uMaxMinProp" "ns" 1.000000)
					( Status sCSetFlattened )
					( Origin gBackEnd )
				)
				( attribute "RELATIVE_PROPAGATION_DELAY_SCOPE" "G"
					( Parent
						( matchGroupRef "@baseboard_fab2_lib.baseboard_fab2(sch_1):\MG_P3E_CPU0_PE3_OCP_TX0607\" )
					)
					( Status sCSetFlattened )
					( Origin gBackEnd )
				)
				( attribute "RELATIVE_PROPAGATION_DELAY" ",500.00 MIL"
					( Parent
						( matchGroupRef "@baseboard_fab2_lib.baseboard_fab2(sch_1):\MG_P3E_CPU0_PE3_OCP_TX0607\" )
					)
					( Units "uMatchProp" "ns" 1.000000)
					( Status sCSetFlattened )
					( Origin gBackEnd )
				)
			)
			( pinPair "@baseboard_fab2_lib.baseboard_fab2(sch_1):\PP233\"
				( pinRef "@baseboard_fab2_lib.baseboard_fab2(sch_1):page187_i119:IO10" )
				( pinRef "@baseboard_fab2_lib.baseboard_fab2(sch_1):page106_i142:B" )
				( attribute "RELATIVE_PROPAGATION_DELAY_SCOPE" "L"
					( Parent
						( matchGroupRef "@baseboard_fab2_lib.baseboard_fab2(sch_1):\MG_PCIE_L0\" )
					)
					( Status sCSetFlattened )
					( Origin gBackEnd )
				)
				( attribute "RELATIVE_PROPAGATION_DELAY" ",5.00 MIL"
					( Parent
						( matchGroupRef "@baseboard_fab2_lib.baseboard_fab2(sch_1):\MG_PCIE_L0\" )
					)
					( Units "uMatchProp" "ns" 1.000000)
					( Status sCSetFlattened )
					( Origin gBackEnd )
				)
			)
			( pinPair "@baseboard_fab2_lib.baseboard_fab2(sch_1):\PP234\"
				( pinRef "@baseboard_fab2_lib.baseboard_fab2(sch_1):page32_i89:PE3_TX_DP(7)" )
				( pinRef "@baseboard_fab2_lib.baseboard_fab2(sch_1):page106_i142:A" )
				( attribute "RELATIVE_PROPAGATION_DELAY_SCOPE" "L"
					( Parent
						( matchGroupRef "@baseboard_fab2_lib.baseboard_fab2(sch_1):\MG_PCIE_L1\" )
					)
					( Status sCSetFlattened )
					( Origin gBackEnd )
				)
				( attribute "RELATIVE_PROPAGATION_DELAY" ",5.00 MIL"
					( Parent
						( matchGroupRef "@baseboard_fab2_lib.baseboard_fab2(sch_1):\MG_PCIE_L1\" )
					)
					( Units "uMatchProp" "ns" 1.000000)
					( Status sCSetFlattened )
					( Origin gBackEnd )
				)
			)
			( pinPair "@baseboard_fab2_lib.baseboard_fab2(sch_1):\PP5957\"
				( pinRef "@baseboard_fab2_lib.baseboard_fab2(sch_1):page32_i89:PE3_TX_DP(7)" )
				( pinRef "@baseboard_fab2_lib.baseboard_fab2(sch_1):page187_i119:IO10" )
				( attribute "PROPAGATION_DELAY_MIN" "3000.00 MIL"
					( Units "uMaxMinProp" "ns" 1.000000)
					( Status sCSetFlattened )
					( Origin gBackEnd )
				)
				( attribute "PROPAGATION_DELAY_MAX" "16000.00 MIL"
					( Units "uMaxMinProp" "ns" 1.000000)
					( Status sCSetFlattened )
					( Origin gBackEnd )
				)
				( attribute "RELATIVE_PROPAGATION_DELAY_SCOPE" "G"
					( Parent
						( matchGroupRef "@baseboard_fab2_lib.baseboard_fab2(sch_1):\MG_P3E_CPU0_PE3_OCP_TX0607\" )
					)
					( Status sCSetFlattened )
					( Origin gBackEnd )
				)
				( attribute "RELATIVE_PROPAGATION_DELAY" ",500.00 MIL"
					( Parent
						( matchGroupRef "@baseboard_fab2_lib.baseboard_fab2(sch_1):\MG_P3E_CPU0_PE3_OCP_TX0607\" )
					)
					( Units "uMatchProp" "ns" 1.000000)
					( Status sCSetFlattened )
					( Origin gBackEnd )
				)
			)
			( pinPair "@baseboard_fab2_lib.baseboard_fab2(sch_1):\PP127\"
				( pinRef "@baseboard_fab2_lib.baseboard_fab2(sch_1):page32_i89:PE3_TX_DN(8)" )
				( pinRef "@baseboard_fab2_lib.baseboard_fab2(sch_1):page106_i86:A" )
				( attribute "RELATIVE_PROPAGATION_DELAY_SCOPE" "L"
					( Parent
						( matchGroupRef "@baseboard_fab2_lib.baseboard_fab2(sch_1):\MG_PCIE_L1\" )
					)
					( Status sCSetFlattened )
					( Origin gBackEnd )
				)
				( attribute "RELATIVE_PROPAGATION_DELAY" ",5.00 MIL"
					( Parent
						( matchGroupRef "@baseboard_fab2_lib.baseboard_fab2(sch_1):\MG_PCIE_L1\" )
					)
					( Units "uMatchProp" "ns" 1.000000)
					( Status sCSetFlattened )
					( Origin gBackEnd )
				)
			)
			( pinPair "@baseboard_fab2_lib.baseboard_fab2(sch_1):\PP128\"
				( pinRef "@baseboard_fab2_lib.baseboard_fab2(sch_1):page186_i336:IO114" )
				( pinRef "@baseboard_fab2_lib.baseboard_fab2(sch_1):page106_i86:B" )
				( attribute "RELATIVE_PROPAGATION_DELAY_SCOPE" "L"
					( Parent
						( matchGroupRef "@baseboard_fab2_lib.baseboard_fab2(sch_1):\MG_PCIE_L0\" )
					)
					( Status sCSetFlattened )
					( Origin gBackEnd )
				)
				( attribute "RELATIVE_PROPAGATION_DELAY" ",5.00 MIL"
					( Parent
						( matchGroupRef "@baseboard_fab2_lib.baseboard_fab2(sch_1):\MG_PCIE_L0\" )
					)
					( Units "uMatchProp" "ns" 1.000000)
					( Status sCSetFlattened )
					( Origin gBackEnd )
				)
			)
			( pinPair "@baseboard_fab2_lib.baseboard_fab2(sch_1):\PP6034\"
				( pinRef "@baseboard_fab2_lib.baseboard_fab2(sch_1):page32_i89:PE3_TX_DN(8)" )
				( pinRef "@baseboard_fab2_lib.baseboard_fab2(sch_1):page186_i336:IO114" )
				( attribute "PROPAGATION_DELAY_MIN" "3000.00 MIL"
					( Units "uMaxMinProp" "ns" 1.000000)
					( Status sCSetFlattened )
					( Origin gBackEnd )
				)
				( attribute "PROPAGATION_DELAY_MAX" "16000.00 MIL"
					( Units "uMaxMinProp" "ns" 1.000000)
					( Status sCSetFlattened )
					( Origin gBackEnd )
				)
				( attribute "RELATIVE_PROPAGATION_DELAY_SCOPE" "G"
					( Parent
						( matchGroupRef "@baseboard_fab2_lib.baseboard_fab2(sch_1):\MG_P3E_CPU0_PE3_OCP_TX0809\" )
					)
					( Status sCSetFlattened )
					( Origin gBackEnd )
				)
				( attribute "RELATIVE_PROPAGATION_DELAY" ",500.00 MIL"
					( Parent
						( matchGroupRef "@baseboard_fab2_lib.baseboard_fab2(sch_1):\MG_P3E_CPU0_PE3_OCP_TX0809\" )
					)
					( Units "uMatchProp" "ns" 1.000000)
					( Status sCSetFlattened )
					( Origin gBackEnd )
				)
			)
			( pinPair "@baseboard_fab2_lib.baseboard_fab2(sch_1):\PP129\"
				( pinRef "@baseboard_fab2_lib.baseboard_fab2(sch_1):page186_i336:IO112" )
				( pinRef "@baseboard_fab2_lib.baseboard_fab2(sch_1):page106_i76:B" )
				( attribute "RELATIVE_PROPAGATION_DELAY_SCOPE" "L"
					( Parent
						( matchGroupRef "@baseboard_fab2_lib.baseboard_fab2(sch_1):\MG_PCIE_L0\" )
					)
					( Status sCSetFlattened )
					( Origin gBackEnd )
				)
				( attribute "RELATIVE_PROPAGATION_DELAY" ",5.00 MIL"
					( Parent
						( matchGroupRef "@baseboard_fab2_lib.baseboard_fab2(sch_1):\MG_PCIE_L0\" )
					)
					( Units "uMatchProp" "ns" 1.000000)
					( Status sCSetFlattened )
					( Origin gBackEnd )
				)
			)
			( pinPair "@baseboard_fab2_lib.baseboard_fab2(sch_1):\PP130\"
				( pinRef "@baseboard_fab2_lib.baseboard_fab2(sch_1):page32_i89:PE3_TX_DP(8)" )
				( pinRef "@baseboard_fab2_lib.baseboard_fab2(sch_1):page106_i76:A" )
				( attribute "RELATIVE_PROPAGATION_DELAY_SCOPE" "L"
					( Parent
						( matchGroupRef "@baseboard_fab2_lib.baseboard_fab2(sch_1):\MG_PCIE_L1\" )
					)
					( Status sCSetFlattened )
					( Origin gBackEnd )
				)
				( attribute "RELATIVE_PROPAGATION_DELAY" ",5.00 MIL"
					( Parent
						( matchGroupRef "@baseboard_fab2_lib.baseboard_fab2(sch_1):\MG_PCIE_L1\" )
					)
					( Units "uMatchProp" "ns" 1.000000)
					( Status sCSetFlattened )
					( Origin gBackEnd )
				)
			)
			( pinPair "@baseboard_fab2_lib.baseboard_fab2(sch_1):\PP5892\"
				( pinRef "@baseboard_fab2_lib.baseboard_fab2(sch_1):page32_i89:PE3_TX_DP(8)" )
				( pinRef "@baseboard_fab2_lib.baseboard_fab2(sch_1):page186_i336:IO112" )
				( attribute "PROPAGATION_DELAY_MIN" "3000.00 MIL"
					( Units "uMaxMinProp" "ns" 1.000000)
					( Status sCSetFlattened )
					( Origin gBackEnd )
				)
				( attribute "PROPAGATION_DELAY_MAX" "16000.00 MIL"
					( Units "uMaxMinProp" "ns" 1.000000)
					( Status sCSetFlattened )
					( Origin gBackEnd )
				)
				( attribute "RELATIVE_PROPAGATION_DELAY_SCOPE" "G"
					( Parent
						( matchGroupRef "@baseboard_fab2_lib.baseboard_fab2(sch_1):\MG_P3E_CPU0_PE3_OCP_TX0809\" )
					)
					( Status sCSetFlattened )
					( Origin gBackEnd )
				)
				( attribute "RELATIVE_PROPAGATION_DELAY" ",500.00 MIL"
					( Parent
						( matchGroupRef "@baseboard_fab2_lib.baseboard_fab2(sch_1):\MG_P3E_CPU0_PE3_OCP_TX0809\" )
					)
					( Units "uMatchProp" "ns" 1.000000)
					( Status sCSetFlattened )
					( Origin gBackEnd )
				)
			)
			( pinPair "@baseboard_fab2_lib.baseboard_fab2(sch_1):\PP131\"
				( pinRef "@baseboard_fab2_lib.baseboard_fab2(sch_1):page32_i89:PE3_TX_DN(9)" )
				( pinRef "@baseboard_fab2_lib.baseboard_fab2(sch_1):page106_i90:A" )
				( attribute "RELATIVE_PROPAGATION_DELAY_SCOPE" "L"
					( Parent
						( matchGroupRef "@baseboard_fab2_lib.baseboard_fab2(sch_1):\MG_PCIE_L1\" )
					)
					( Status sCSetFlattened )
					( Origin gBackEnd )
				)
				( attribute "RELATIVE_PROPAGATION_DELAY" ",5.00 MIL"
					( Parent
						( matchGroupRef "@baseboard_fab2_lib.baseboard_fab2(sch_1):\MG_PCIE_L1\" )
					)
					( Units "uMatchProp" "ns" 1.000000)
					( Status sCSetFlattened )
					( Origin gBackEnd )
				)
			)
			( pinPair "@baseboard_fab2_lib.baseboard_fab2(sch_1):\PP132\"
				( pinRef "@baseboard_fab2_lib.baseboard_fab2(sch_1):page186_i336:IO106" )
				( pinRef "@baseboard_fab2_lib.baseboard_fab2(sch_1):page106_i90:B" )
				( attribute "RELATIVE_PROPAGATION_DELAY_SCOPE" "L"
					( Parent
						( matchGroupRef "@baseboard_fab2_lib.baseboard_fab2(sch_1):\MG_PCIE_L0\" )
					)
					( Status sCSetFlattened )
					( Origin gBackEnd )
				)
				( attribute "RELATIVE_PROPAGATION_DELAY" ",5.00 MIL"
					( Parent
						( matchGroupRef "@baseboard_fab2_lib.baseboard_fab2(sch_1):\MG_PCIE_L0\" )
					)
					( Units "uMatchProp" "ns" 1.000000)
					( Status sCSetFlattened )
					( Origin gBackEnd )
				)
			)
			( pinPair "@baseboard_fab2_lib.baseboard_fab2(sch_1):\PP5951\"
				( pinRef "@baseboard_fab2_lib.baseboard_fab2(sch_1):page32_i89:PE3_TX_DN(9)" )
				( pinRef "@baseboard_fab2_lib.baseboard_fab2(sch_1):page186_i336:IO106" )
				( attribute "PROPAGATION_DELAY_MIN" "3000.00 MIL"
					( Units "uMaxMinProp" "ns" 1.000000)
					( Status sCSetFlattened )
					( Origin gBackEnd )
				)
				( attribute "PROPAGATION_DELAY_MAX" "16000.00 MIL"
					( Units "uMaxMinProp" "ns" 1.000000)
					( Status sCSetFlattened )
					( Origin gBackEnd )
				)
				( attribute "RELATIVE_PROPAGATION_DELAY_SCOPE" "G"
					( Parent
						( matchGroupRef "@baseboard_fab2_lib.baseboard_fab2(sch_1):\MG_P3E_CPU0_PE3_OCP_TX0809\" )
					)
					( Status sCSetFlattened )
					( Origin gBackEnd )
				)
				( attribute "RELATIVE_PROPAGATION_DELAY" ",500.00 MIL"
					( Parent
						( matchGroupRef "@baseboard_fab2_lib.baseboard_fab2(sch_1):\MG_P3E_CPU0_PE3_OCP_TX0809\" )
					)
					( Units "uMatchProp" "ns" 1.000000)
					( Status sCSetFlattened )
					( Origin gBackEnd )
				)
			)
			( pinPair "@baseboard_fab2_lib.baseboard_fab2(sch_1):\PP133\"
				( pinRef "@baseboard_fab2_lib.baseboard_fab2(sch_1):page186_i336:IO104" )
				( pinRef "@baseboard_fab2_lib.baseboard_fab2(sch_1):page106_i78:B" )
				( attribute "RELATIVE_PROPAGATION_DELAY_SCOPE" "L"
					( Parent
						( matchGroupRef "@baseboard_fab2_lib.baseboard_fab2(sch_1):\MG_PCIE_L0\" )
					)
					( Status sCSetFlattened )
					( Origin gBackEnd )
				)
				( attribute "RELATIVE_PROPAGATION_DELAY" ",5.00 MIL"
					( Parent
						( matchGroupRef "@baseboard_fab2_lib.baseboard_fab2(sch_1):\MG_PCIE_L0\" )
					)
					( Units "uMatchProp" "ns" 1.000000)
					( Status sCSetFlattened )
					( Origin gBackEnd )
				)
			)
			( pinPair "@baseboard_fab2_lib.baseboard_fab2(sch_1):\PP134\"
				( pinRef "@baseboard_fab2_lib.baseboard_fab2(sch_1):page32_i89:PE3_TX_DP(9)" )
				( pinRef "@baseboard_fab2_lib.baseboard_fab2(sch_1):page106_i78:A" )
				( attribute "RELATIVE_PROPAGATION_DELAY_SCOPE" "L"
					( Parent
						( matchGroupRef "@baseboard_fab2_lib.baseboard_fab2(sch_1):\MG_PCIE_L1\" )
					)
					( Status sCSetFlattened )
					( Origin gBackEnd )
				)
				( attribute "RELATIVE_PROPAGATION_DELAY" ",5.00 MIL"
					( Parent
						( matchGroupRef "@baseboard_fab2_lib.baseboard_fab2(sch_1):\MG_PCIE_L1\" )
					)
					( Units "uMatchProp" "ns" 1.000000)
					( Status sCSetFlattened )
					( Origin gBackEnd )
				)
			)
			( pinPair "@baseboard_fab2_lib.baseboard_fab2(sch_1):\PP5988\"
				( pinRef "@baseboard_fab2_lib.baseboard_fab2(sch_1):page32_i89:PE3_TX_DP(9)" )
				( pinRef "@baseboard_fab2_lib.baseboard_fab2(sch_1):page186_i336:IO104" )
				( attribute "PROPAGATION_DELAY_MIN" "3000.00 MIL"
					( Units "uMaxMinProp" "ns" 1.000000)
					( Status sCSetFlattened )
					( Origin gBackEnd )
				)
				( attribute "PROPAGATION_DELAY_MAX" "16000.00 MIL"
					( Units "uMaxMinProp" "ns" 1.000000)
					( Status sCSetFlattened )
					( Origin gBackEnd )
				)
				( attribute "RELATIVE_PROPAGATION_DELAY_SCOPE" "G"
					( Parent
						( matchGroupRef "@baseboard_fab2_lib.baseboard_fab2(sch_1):\MG_P3E_CPU0_PE3_OCP_TX0809\" )
					)
					( Status sCSetFlattened )
					( Origin gBackEnd )
				)
				( attribute "RELATIVE_PROPAGATION_DELAY" ",500.00 MIL"
					( Parent
						( matchGroupRef "@baseboard_fab2_lib.baseboard_fab2(sch_1):\MG_P3E_CPU0_PE3_OCP_TX0809\" )
					)
					( Units "uMatchProp" "ns" 1.000000)
					( Status sCSetFlattened )
					( Origin gBackEnd )
				)
			)
			( pinPair "@baseboard_fab2_lib.baseboard_fab2(sch_1):\PP103\"
				( pinRef "@baseboard_fab2_lib.baseboard_fab2(sch_1):page32_i89:PE3_TX_DN(10)" )
				( pinRef "@baseboard_fab2_lib.baseboard_fab2(sch_1):page106_i92:A" )
				( attribute "RELATIVE_PROPAGATION_DELAY_SCOPE" "L"
					( Parent
						( matchGroupRef "@baseboard_fab2_lib.baseboard_fab2(sch_1):\MG_PCIE_L1\" )
					)
					( Status sCSetFlattened )
					( Origin gBackEnd )
				)
				( attribute "RELATIVE_PROPAGATION_DELAY" ",5.00 MIL"
					( Parent
						( matchGroupRef "@baseboard_fab2_lib.baseboard_fab2(sch_1):\MG_PCIE_L1\" )
					)
					( Units "uMatchProp" "ns" 1.000000)
					( Status sCSetFlattened )
					( Origin gBackEnd )
				)
			)
			( pinPair "@baseboard_fab2_lib.baseboard_fab2(sch_1):\PP104\"
				( pinRef "@baseboard_fab2_lib.baseboard_fab2(sch_1):page186_i336:IO98" )
				( pinRef "@baseboard_fab2_lib.baseboard_fab2(sch_1):page106_i92:B" )
				( attribute "RELATIVE_PROPAGATION_DELAY_SCOPE" "L"
					( Parent
						( matchGroupRef "@baseboard_fab2_lib.baseboard_fab2(sch_1):\MG_PCIE_L0\" )
					)
					( Status sCSetFlattened )
					( Origin gBackEnd )
				)
				( attribute "RELATIVE_PROPAGATION_DELAY" ",5.00 MIL"
					( Parent
						( matchGroupRef "@baseboard_fab2_lib.baseboard_fab2(sch_1):\MG_PCIE_L0\" )
					)
					( Units "uMatchProp" "ns" 1.000000)
					( Status sCSetFlattened )
					( Origin gBackEnd )
				)
			)
			( pinPair "@baseboard_fab2_lib.baseboard_fab2(sch_1):\PP6046\"
				( pinRef "@baseboard_fab2_lib.baseboard_fab2(sch_1):page32_i89:PE3_TX_DN(10)" )
				( pinRef "@baseboard_fab2_lib.baseboard_fab2(sch_1):page186_i336:IO98" )
				( attribute "PROPAGATION_DELAY_MIN" "3000.00 MIL"
					( Units "uMaxMinProp" "ns" 1.000000)
					( Status sCSetFlattened )
					( Origin gBackEnd )
				)
				( attribute "PROPAGATION_DELAY_MAX" "16000.00 MIL"
					( Units "uMaxMinProp" "ns" 1.000000)
					( Status sCSetFlattened )
					( Origin gBackEnd )
				)
				( attribute "RELATIVE_PROPAGATION_DELAY_SCOPE" "G"
					( Parent
						( matchGroupRef "@baseboard_fab2_lib.baseboard_fab2(sch_1):\MG_P3E_CPU0_PE3_OCP_TX1011\" )
					)
					( Status sCSetFlattened )
					( Origin gBackEnd )
				)
				( attribute "RELATIVE_PROPAGATION_DELAY" ",500.00 MIL"
					( Parent
						( matchGroupRef "@baseboard_fab2_lib.baseboard_fab2(sch_1):\MG_P3E_CPU0_PE3_OCP_TX1011\" )
					)
					( Units "uMatchProp" "ns" 1.000000)
					( Status sCSetFlattened )
					( Origin gBackEnd )
				)
			)
			( pinPair "@baseboard_fab2_lib.baseboard_fab2(sch_1):\PP105\"
				( pinRef "@baseboard_fab2_lib.baseboard_fab2(sch_1):page186_i336:IO96" )
				( pinRef "@baseboard_fab2_lib.baseboard_fab2(sch_1):page106_i82:B" )
				( attribute "RELATIVE_PROPAGATION_DELAY_SCOPE" "L"
					( Parent
						( matchGroupRef "@baseboard_fab2_lib.baseboard_fab2(sch_1):\MG_PCIE_L0\" )
					)
					( Status sCSetFlattened )
					( Origin gBackEnd )
				)
				( attribute "RELATIVE_PROPAGATION_DELAY" ",5.00 MIL"
					( Parent
						( matchGroupRef "@baseboard_fab2_lib.baseboard_fab2(sch_1):\MG_PCIE_L0\" )
					)
					( Units "uMatchProp" "ns" 1.000000)
					( Status sCSetFlattened )
					( Origin gBackEnd )
				)
			)
			( pinPair "@baseboard_fab2_lib.baseboard_fab2(sch_1):\PP106\"
				( pinRef "@baseboard_fab2_lib.baseboard_fab2(sch_1):page32_i89:PE3_TX_DP(10)" )
				( pinRef "@baseboard_fab2_lib.baseboard_fab2(sch_1):page106_i82:A" )
				( attribute "RELATIVE_PROPAGATION_DELAY_SCOPE" "L"
					( Parent
						( matchGroupRef "@baseboard_fab2_lib.baseboard_fab2(sch_1):\MG_PCIE_L1\" )
					)
					( Status sCSetFlattened )
					( Origin gBackEnd )
				)
				( attribute "RELATIVE_PROPAGATION_DELAY" ",5.00 MIL"
					( Parent
						( matchGroupRef "@baseboard_fab2_lib.baseboard_fab2(sch_1):\MG_PCIE_L1\" )
					)
					( Units "uMatchProp" "ns" 1.000000)
					( Status sCSetFlattened )
					( Origin gBackEnd )
				)
			)
			( pinPair "@baseboard_fab2_lib.baseboard_fab2(sch_1):\PP6047\"
				( pinRef "@baseboard_fab2_lib.baseboard_fab2(sch_1):page32_i89:PE3_TX_DP(10)" )
				( pinRef "@baseboard_fab2_lib.baseboard_fab2(sch_1):page186_i336:IO96" )
				( attribute "PROPAGATION_DELAY_MIN" "3000.00 MIL"
					( Units "uMaxMinProp" "ns" 1.000000)
					( Status sCSetFlattened )
					( Origin gBackEnd )
				)
				( attribute "PROPAGATION_DELAY_MAX" "16000.00 MIL"
					( Units "uMaxMinProp" "ns" 1.000000)
					( Status sCSetFlattened )
					( Origin gBackEnd )
				)
				( attribute "RELATIVE_PROPAGATION_DELAY_SCOPE" "G"
					( Parent
						( matchGroupRef "@baseboard_fab2_lib.baseboard_fab2(sch_1):\MG_P3E_CPU0_PE3_OCP_TX1011\" )
					)
					( Status sCSetFlattened )
					( Origin gBackEnd )
				)
				( attribute "RELATIVE_PROPAGATION_DELAY" ",500.00 MIL"
					( Parent
						( matchGroupRef "@baseboard_fab2_lib.baseboard_fab2(sch_1):\MG_P3E_CPU0_PE3_OCP_TX1011\" )
					)
					( Units "uMatchProp" "ns" 1.000000)
					( Status sCSetFlattened )
					( Origin gBackEnd )
				)
			)
			( pinPair "@baseboard_fab2_lib.baseboard_fab2(sch_1):\PP107\"
				( pinRef "@baseboard_fab2_lib.baseboard_fab2(sch_1):page32_i89:PE3_TX_DN(11)" )
				( pinRef "@baseboard_fab2_lib.baseboard_fab2(sch_1):page106_i95:A" )
				( attribute "RELATIVE_PROPAGATION_DELAY_SCOPE" "L"
					( Parent
						( matchGroupRef "@baseboard_fab2_lib.baseboard_fab2(sch_1):\MG_PCIE_L1\" )
					)
					( Status sCSetFlattened )
					( Origin gBackEnd )
				)
				( attribute "RELATIVE_PROPAGATION_DELAY" ",5.00 MIL"
					( Parent
						( matchGroupRef "@baseboard_fab2_lib.baseboard_fab2(sch_1):\MG_PCIE_L1\" )
					)
					( Units "uMatchProp" "ns" 1.000000)
					( Status sCSetFlattened )
					( Origin gBackEnd )
				)
			)
			( pinPair "@baseboard_fab2_lib.baseboard_fab2(sch_1):\PP108\"
				( pinRef "@baseboard_fab2_lib.baseboard_fab2(sch_1):page186_i336:IO90" )
				( pinRef "@baseboard_fab2_lib.baseboard_fab2(sch_1):page106_i95:B" )
				( attribute "RELATIVE_PROPAGATION_DELAY_SCOPE" "L"
					( Parent
						( matchGroupRef "@baseboard_fab2_lib.baseboard_fab2(sch_1):\MG_PCIE_L0\" )
					)
					( Status sCSetFlattened )
					( Origin gBackEnd )
				)
				( attribute "RELATIVE_PROPAGATION_DELAY" ",5.00 MIL"
					( Parent
						( matchGroupRef "@baseboard_fab2_lib.baseboard_fab2(sch_1):\MG_PCIE_L0\" )
					)
					( Units "uMatchProp" "ns" 1.000000)
					( Status sCSetFlattened )
					( Origin gBackEnd )
				)
			)
			( pinPair "@baseboard_fab2_lib.baseboard_fab2(sch_1):\PP6043\"
				( pinRef "@baseboard_fab2_lib.baseboard_fab2(sch_1):page32_i89:PE3_TX_DN(11)" )
				( pinRef "@baseboard_fab2_lib.baseboard_fab2(sch_1):page186_i336:IO90" )
				( attribute "PROPAGATION_DELAY_MIN" "3000.00 MIL"
					( Units "uMaxMinProp" "ns" 1.000000)
					( Status sCSetFlattened )
					( Origin gBackEnd )
				)
				( attribute "PROPAGATION_DELAY_MAX" "16000.00 MIL"
					( Units "uMaxMinProp" "ns" 1.000000)
					( Status sCSetFlattened )
					( Origin gBackEnd )
				)
				( attribute "RELATIVE_PROPAGATION_DELAY_SCOPE" "G"
					( Parent
						( matchGroupRef "@baseboard_fab2_lib.baseboard_fab2(sch_1):\MG_P3E_CPU0_PE3_OCP_TX1011\" )
					)
					( Status sCSetFlattened )
					( Origin gBackEnd )
				)
				( attribute "RELATIVE_PROPAGATION_DELAY" ",500.00 MIL"
					( Parent
						( matchGroupRef "@baseboard_fab2_lib.baseboard_fab2(sch_1):\MG_P3E_CPU0_PE3_OCP_TX1011\" )
					)
					( Units "uMatchProp" "ns" 1.000000)
					( Status sCSetFlattened )
					( Origin gBackEnd )
				)
			)
			( pinPair "@baseboard_fab2_lib.baseboard_fab2(sch_1):\PP109\"
				( pinRef "@baseboard_fab2_lib.baseboard_fab2(sch_1):page186_i336:IO88" )
				( pinRef "@baseboard_fab2_lib.baseboard_fab2(sch_1):page106_i85:B" )
				( attribute "RELATIVE_PROPAGATION_DELAY_SCOPE" "L"
					( Parent
						( matchGroupRef "@baseboard_fab2_lib.baseboard_fab2(sch_1):\MG_PCIE_L0\" )
					)
					( Status sCSetFlattened )
					( Origin gBackEnd )
				)
				( attribute "RELATIVE_PROPAGATION_DELAY" ",5.00 MIL"
					( Parent
						( matchGroupRef "@baseboard_fab2_lib.baseboard_fab2(sch_1):\MG_PCIE_L0\" )
					)
					( Units "uMatchProp" "ns" 1.000000)
					( Status sCSetFlattened )
					( Origin gBackEnd )
				)
			)
			( pinPair "@baseboard_fab2_lib.baseboard_fab2(sch_1):\PP110\"
				( pinRef "@baseboard_fab2_lib.baseboard_fab2(sch_1):page32_i89:PE3_TX_DP(11)" )
				( pinRef "@baseboard_fab2_lib.baseboard_fab2(sch_1):page106_i85:A" )
				( attribute "RELATIVE_PROPAGATION_DELAY_SCOPE" "L"
					( Parent
						( matchGroupRef "@baseboard_fab2_lib.baseboard_fab2(sch_1):\MG_PCIE_L1\" )
					)
					( Status sCSetFlattened )
					( Origin gBackEnd )
				)
				( attribute "RELATIVE_PROPAGATION_DELAY" ",5.00 MIL"
					( Parent
						( matchGroupRef "@baseboard_fab2_lib.baseboard_fab2(sch_1):\MG_PCIE_L1\" )
					)
					( Units "uMatchProp" "ns" 1.000000)
					( Status sCSetFlattened )
					( Origin gBackEnd )
				)
			)
			( pinPair "@baseboard_fab2_lib.baseboard_fab2(sch_1):\PP6042\"
				( pinRef "@baseboard_fab2_lib.baseboard_fab2(sch_1):page32_i89:PE3_TX_DP(11)" )
				( pinRef "@baseboard_fab2_lib.baseboard_fab2(sch_1):page186_i336:IO88" )
				( attribute "PROPAGATION_DELAY_MIN" "3000.00 MIL"
					( Units "uMaxMinProp" "ns" 1.000000)
					( Status sCSetFlattened )
					( Origin gBackEnd )
				)
				( attribute "PROPAGATION_DELAY_MAX" "16000.00 MIL"
					( Units "uMaxMinProp" "ns" 1.000000)
					( Status sCSetFlattened )
					( Origin gBackEnd )
				)
				( attribute "RELATIVE_PROPAGATION_DELAY_SCOPE" "G"
					( Parent
						( matchGroupRef "@baseboard_fab2_lib.baseboard_fab2(sch_1):\MG_P3E_CPU0_PE3_OCP_TX1011\" )
					)
					( Status sCSetFlattened )
					( Origin gBackEnd )
				)
				( attribute "RELATIVE_PROPAGATION_DELAY" ",500.00 MIL"
					( Parent
						( matchGroupRef "@baseboard_fab2_lib.baseboard_fab2(sch_1):\MG_P3E_CPU0_PE3_OCP_TX1011\" )
					)
					( Units "uMatchProp" "ns" 1.000000)
					( Status sCSetFlattened )
					( Origin gBackEnd )
				)
			)
			( pinPair "@baseboard_fab2_lib.baseboard_fab2(sch_1):\PP111\"
				( pinRef "@baseboard_fab2_lib.baseboard_fab2(sch_1):page32_i89:PE3_TX_DN(12)" )
				( pinRef "@baseboard_fab2_lib.baseboard_fab2(sch_1):page106_i111:A" )
				( attribute "RELATIVE_PROPAGATION_DELAY_SCOPE" "L"
					( Parent
						( matchGroupRef "@baseboard_fab2_lib.baseboard_fab2(sch_1):\MG_PCIE_L1\" )
					)
					( Status sCSetFlattened )
					( Origin gBackEnd )
				)
				( attribute "RELATIVE_PROPAGATION_DELAY" ",5.00 MIL"
					( Parent
						( matchGroupRef "@baseboard_fab2_lib.baseboard_fab2(sch_1):\MG_PCIE_L1\" )
					)
					( Units "uMatchProp" "ns" 1.000000)
					( Status sCSetFlattened )
					( Origin gBackEnd )
				)
			)
			( pinPair "@baseboard_fab2_lib.baseboard_fab2(sch_1):\PP112\"
				( pinRef "@baseboard_fab2_lib.baseboard_fab2(sch_1):page186_i336:IO82" )
				( pinRef "@baseboard_fab2_lib.baseboard_fab2(sch_1):page106_i111:B" )
				( attribute "RELATIVE_PROPAGATION_DELAY_SCOPE" "L"
					( Parent
						( matchGroupRef "@baseboard_fab2_lib.baseboard_fab2(sch_1):\MG_PCIE_L0\" )
					)
					( Status sCSetFlattened )
					( Origin gBackEnd )
				)
				( attribute "RELATIVE_PROPAGATION_DELAY" ",5.00 MIL"
					( Parent
						( matchGroupRef "@baseboard_fab2_lib.baseboard_fab2(sch_1):\MG_PCIE_L0\" )
					)
					( Units "uMatchProp" "ns" 1.000000)
					( Status sCSetFlattened )
					( Origin gBackEnd )
				)
			)
			( pinPair "@baseboard_fab2_lib.baseboard_fab2(sch_1):\PP6040\"
				( pinRef "@baseboard_fab2_lib.baseboard_fab2(sch_1):page32_i89:PE3_TX_DN(12)" )
				( pinRef "@baseboard_fab2_lib.baseboard_fab2(sch_1):page186_i336:IO82" )
				( attribute "PROPAGATION_DELAY_MIN" "3000.00 MIL"
					( Units "uMaxMinProp" "ns" 1.000000)
					( Status sCSetFlattened )
					( Origin gBackEnd )
				)
				( attribute "PROPAGATION_DELAY_MAX" "16000.00 MIL"
					( Units "uMaxMinProp" "ns" 1.000000)
					( Status sCSetFlattened )
					( Origin gBackEnd )
				)
				( attribute "RELATIVE_PROPAGATION_DELAY_SCOPE" "G"
					( Parent
						( matchGroupRef "@baseboard_fab2_lib.baseboard_fab2(sch_1):\MG_P3E_CPU0_PE3_OCP_TX1213\" )
					)
					( Status sCSetFlattened )
					( Origin gBackEnd )
				)
				( attribute "RELATIVE_PROPAGATION_DELAY" ",500.00 MIL"
					( Parent
						( matchGroupRef "@baseboard_fab2_lib.baseboard_fab2(sch_1):\MG_P3E_CPU0_PE3_OCP_TX1213\" )
					)
					( Units "uMatchProp" "ns" 1.000000)
					( Status sCSetFlattened )
					( Origin gBackEnd )
				)
			)
			( pinPair "@baseboard_fab2_lib.baseboard_fab2(sch_1):\PP113\"
				( pinRef "@baseboard_fab2_lib.baseboard_fab2(sch_1):page186_i336:IO80" )
				( pinRef "@baseboard_fab2_lib.baseboard_fab2(sch_1):page106_i100:B" )
				( attribute "RELATIVE_PROPAGATION_DELAY_SCOPE" "L"
					( Parent
						( matchGroupRef "@baseboard_fab2_lib.baseboard_fab2(sch_1):\MG_PCIE_L0\" )
					)
					( Status sCSetFlattened )
					( Origin gBackEnd )
				)
				( attribute "RELATIVE_PROPAGATION_DELAY" ",5.00 MIL"
					( Parent
						( matchGroupRef "@baseboard_fab2_lib.baseboard_fab2(sch_1):\MG_PCIE_L0\" )
					)
					( Units "uMatchProp" "ns" 1.000000)
					( Status sCSetFlattened )
					( Origin gBackEnd )
				)
			)
			( pinPair "@baseboard_fab2_lib.baseboard_fab2(sch_1):\PP114\"
				( pinRef "@baseboard_fab2_lib.baseboard_fab2(sch_1):page32_i89:PE3_TX_DP(12)" )
				( pinRef "@baseboard_fab2_lib.baseboard_fab2(sch_1):page106_i100:A" )
				( attribute "RELATIVE_PROPAGATION_DELAY_SCOPE" "L"
					( Parent
						( matchGroupRef "@baseboard_fab2_lib.baseboard_fab2(sch_1):\MG_PCIE_L1\" )
					)
					( Status sCSetFlattened )
					( Origin gBackEnd )
				)
				( attribute "RELATIVE_PROPAGATION_DELAY" ",5.00 MIL"
					( Parent
						( matchGroupRef "@baseboard_fab2_lib.baseboard_fab2(sch_1):\MG_PCIE_L1\" )
					)
					( Units "uMatchProp" "ns" 1.000000)
					( Status sCSetFlattened )
					( Origin gBackEnd )
				)
			)
			( pinPair "@baseboard_fab2_lib.baseboard_fab2(sch_1):\PP6041\"
				( pinRef "@baseboard_fab2_lib.baseboard_fab2(sch_1):page32_i89:PE3_TX_DP(12)" )
				( pinRef "@baseboard_fab2_lib.baseboard_fab2(sch_1):page186_i336:IO80" )
				( attribute "PROPAGATION_DELAY_MIN" "3000.00 MIL"
					( Units "uMaxMinProp" "ns" 1.000000)
					( Status sCSetFlattened )
					( Origin gBackEnd )
				)
				( attribute "PROPAGATION_DELAY_MAX" "16000.00 MIL"
					( Units "uMaxMinProp" "ns" 1.000000)
					( Status sCSetFlattened )
					( Origin gBackEnd )
				)
				( attribute "RELATIVE_PROPAGATION_DELAY_SCOPE" "G"
					( Parent
						( matchGroupRef "@baseboard_fab2_lib.baseboard_fab2(sch_1):\MG_P3E_CPU0_PE3_OCP_TX1213\" )
					)
					( Status sCSetFlattened )
					( Origin gBackEnd )
				)
				( attribute "RELATIVE_PROPAGATION_DELAY" ",500.00 MIL"
					( Parent
						( matchGroupRef "@baseboard_fab2_lib.baseboard_fab2(sch_1):\MG_P3E_CPU0_PE3_OCP_TX1213\" )
					)
					( Units "uMatchProp" "ns" 1.000000)
					( Status sCSetFlattened )
					( Origin gBackEnd )
				)
			)
			( pinPair "@baseboard_fab2_lib.baseboard_fab2(sch_1):\PP115\"
				( pinRef "@baseboard_fab2_lib.baseboard_fab2(sch_1):page32_i89:PE3_TX_DN(13)" )
				( pinRef "@baseboard_fab2_lib.baseboard_fab2(sch_1):page106_i117:A" )
				( attribute "RELATIVE_PROPAGATION_DELAY_SCOPE" "L"
					( Parent
						( matchGroupRef "@baseboard_fab2_lib.baseboard_fab2(sch_1):\MG_PCIE_L1\" )
					)
					( Status sCSetFlattened )
					( Origin gBackEnd )
				)
				( attribute "RELATIVE_PROPAGATION_DELAY" ",5.00 MIL"
					( Parent
						( matchGroupRef "@baseboard_fab2_lib.baseboard_fab2(sch_1):\MG_PCIE_L1\" )
					)
					( Units "uMatchProp" "ns" 1.000000)
					( Status sCSetFlattened )
					( Origin gBackEnd )
				)
			)
			( pinPair "@baseboard_fab2_lib.baseboard_fab2(sch_1):\PP116\"
				( pinRef "@baseboard_fab2_lib.baseboard_fab2(sch_1):page186_i336:IO74" )
				( pinRef "@baseboard_fab2_lib.baseboard_fab2(sch_1):page106_i117:B" )
				( attribute "RELATIVE_PROPAGATION_DELAY_SCOPE" "L"
					( Parent
						( matchGroupRef "@baseboard_fab2_lib.baseboard_fab2(sch_1):\MG_PCIE_L0\" )
					)
					( Status sCSetFlattened )
					( Origin gBackEnd )
				)
				( attribute "RELATIVE_PROPAGATION_DELAY" ",5.00 MIL"
					( Parent
						( matchGroupRef "@baseboard_fab2_lib.baseboard_fab2(sch_1):\MG_PCIE_L0\" )
					)
					( Units "uMatchProp" "ns" 1.000000)
					( Status sCSetFlattened )
					( Origin gBackEnd )
				)
			)
			( pinPair "@baseboard_fab2_lib.baseboard_fab2(sch_1):\PP6032\"
				( pinRef "@baseboard_fab2_lib.baseboard_fab2(sch_1):page32_i89:PE3_TX_DN(13)" )
				( pinRef "@baseboard_fab2_lib.baseboard_fab2(sch_1):page186_i336:IO74" )
				( attribute "PROPAGATION_DELAY_MIN" "3000.00 MIL"
					( Units "uMaxMinProp" "ns" 1.000000)
					( Status sCSetFlattened )
					( Origin gBackEnd )
				)
				( attribute "PROPAGATION_DELAY_MAX" "16000.00 MIL"
					( Units "uMaxMinProp" "ns" 1.000000)
					( Status sCSetFlattened )
					( Origin gBackEnd )
				)
				( attribute "RELATIVE_PROPAGATION_DELAY_SCOPE" "G"
					( Parent
						( matchGroupRef "@baseboard_fab2_lib.baseboard_fab2(sch_1):\MG_P3E_CPU0_PE3_OCP_TX1213\" )
					)
					( Status sCSetFlattened )
					( Origin gBackEnd )
				)
				( attribute "RELATIVE_PROPAGATION_DELAY" ",500.00 MIL"
					( Parent
						( matchGroupRef "@baseboard_fab2_lib.baseboard_fab2(sch_1):\MG_P3E_CPU0_PE3_OCP_TX1213\" )
					)
					( Units "uMatchProp" "ns" 1.000000)
					( Status sCSetFlattened )
					( Origin gBackEnd )
				)
			)
			( pinPair "@baseboard_fab2_lib.baseboard_fab2(sch_1):\PP117\"
				( pinRef "@baseboard_fab2_lib.baseboard_fab2(sch_1):page186_i336:IO72" )
				( pinRef "@baseboard_fab2_lib.baseboard_fab2(sch_1):page106_i102:B" )
				( attribute "RELATIVE_PROPAGATION_DELAY_SCOPE" "L"
					( Parent
						( matchGroupRef "@baseboard_fab2_lib.baseboard_fab2(sch_1):\MG_PCIE_L0\" )
					)
					( Status sCSetFlattened )
					( Origin gBackEnd )
				)
				( attribute "RELATIVE_PROPAGATION_DELAY" ",5.00 MIL"
					( Parent
						( matchGroupRef "@baseboard_fab2_lib.baseboard_fab2(sch_1):\MG_PCIE_L0\" )
					)
					( Units "uMatchProp" "ns" 1.000000)
					( Status sCSetFlattened )
					( Origin gBackEnd )
				)
			)
			( pinPair "@baseboard_fab2_lib.baseboard_fab2(sch_1):\PP118\"
				( pinRef "@baseboard_fab2_lib.baseboard_fab2(sch_1):page32_i89:PE3_TX_DP(13)" )
				( pinRef "@baseboard_fab2_lib.baseboard_fab2(sch_1):page106_i102:A" )
				( attribute "RELATIVE_PROPAGATION_DELAY_SCOPE" "L"
					( Parent
						( matchGroupRef "@baseboard_fab2_lib.baseboard_fab2(sch_1):\MG_PCIE_L1\" )
					)
					( Status sCSetFlattened )
					( Origin gBackEnd )
				)
				( attribute "RELATIVE_PROPAGATION_DELAY" ",5.00 MIL"
					( Parent
						( matchGroupRef "@baseboard_fab2_lib.baseboard_fab2(sch_1):\MG_PCIE_L1\" )
					)
					( Units "uMatchProp" "ns" 1.000000)
					( Status sCSetFlattened )
					( Origin gBackEnd )
				)
			)
			( pinPair "@baseboard_fab2_lib.baseboard_fab2(sch_1):\PP6037\"
				( pinRef "@baseboard_fab2_lib.baseboard_fab2(sch_1):page32_i89:PE3_TX_DP(13)" )
				( pinRef "@baseboard_fab2_lib.baseboard_fab2(sch_1):page186_i336:IO72" )
				( attribute "PROPAGATION_DELAY_MIN" "3000.00 MIL"
					( Units "uMaxMinProp" "ns" 1.000000)
					( Status sCSetFlattened )
					( Origin gBackEnd )
				)
				( attribute "PROPAGATION_DELAY_MAX" "16000.00 MIL"
					( Units "uMaxMinProp" "ns" 1.000000)
					( Status sCSetFlattened )
					( Origin gBackEnd )
				)
				( attribute "RELATIVE_PROPAGATION_DELAY_SCOPE" "G"
					( Parent
						( matchGroupRef "@baseboard_fab2_lib.baseboard_fab2(sch_1):\MG_P3E_CPU0_PE3_OCP_TX1213\" )
					)
					( Status sCSetFlattened )
					( Origin gBackEnd )
				)
				( attribute "RELATIVE_PROPAGATION_DELAY" ",500.00 MIL"
					( Parent
						( matchGroupRef "@baseboard_fab2_lib.baseboard_fab2(sch_1):\MG_P3E_CPU0_PE3_OCP_TX1213\" )
					)
					( Units "uMatchProp" "ns" 1.000000)
					( Status sCSetFlattened )
					( Origin gBackEnd )
				)
			)
			( pinPair "@baseboard_fab2_lib.baseboard_fab2(sch_1):\PP119\"
				( pinRef "@baseboard_fab2_lib.baseboard_fab2(sch_1):page32_i89:PE3_TX_DN(14)" )
				( pinRef "@baseboard_fab2_lib.baseboard_fab2(sch_1):page106_i114:A" )
				( attribute "RELATIVE_PROPAGATION_DELAY_SCOPE" "L"
					( Parent
						( matchGroupRef "@baseboard_fab2_lib.baseboard_fab2(sch_1):\MG_PCIE_L1\" )
					)
					( Status sCSetFlattened )
					( Origin gBackEnd )
				)
				( attribute "RELATIVE_PROPAGATION_DELAY" ",5.00 MIL"
					( Parent
						( matchGroupRef "@baseboard_fab2_lib.baseboard_fab2(sch_1):\MG_PCIE_L1\" )
					)
					( Units "uMatchProp" "ns" 1.000000)
					( Status sCSetFlattened )
					( Origin gBackEnd )
				)
			)
			( pinPair "@baseboard_fab2_lib.baseboard_fab2(sch_1):\PP120\"
				( pinRef "@baseboard_fab2_lib.baseboard_fab2(sch_1):page186_i336:IO66" )
				( pinRef "@baseboard_fab2_lib.baseboard_fab2(sch_1):page106_i114:B" )
				( attribute "RELATIVE_PROPAGATION_DELAY_SCOPE" "L"
					( Parent
						( matchGroupRef "@baseboard_fab2_lib.baseboard_fab2(sch_1):\MG_PCIE_L0\" )
					)
					( Status sCSetFlattened )
					( Origin gBackEnd )
				)
				( attribute "RELATIVE_PROPAGATION_DELAY" ",5.00 MIL"
					( Parent
						( matchGroupRef "@baseboard_fab2_lib.baseboard_fab2(sch_1):\MG_PCIE_L0\" )
					)
					( Units "uMatchProp" "ns" 1.000000)
					( Status sCSetFlattened )
					( Origin gBackEnd )
				)
			)
			( pinPair "@baseboard_fab2_lib.baseboard_fab2(sch_1):\PP6039\"
				( pinRef "@baseboard_fab2_lib.baseboard_fab2(sch_1):page32_i89:PE3_TX_DN(14)" )
				( pinRef "@baseboard_fab2_lib.baseboard_fab2(sch_1):page186_i336:IO66" )
				( attribute "PROPAGATION_DELAY_MIN" "3000.00 MIL"
					( Units "uMaxMinProp" "ns" 1.000000)
					( Status sCSetFlattened )
					( Origin gBackEnd )
				)
				( attribute "PROPAGATION_DELAY_MAX" "16000.00 MIL"
					( Units "uMaxMinProp" "ns" 1.000000)
					( Status sCSetFlattened )
					( Origin gBackEnd )
				)
				( attribute "RELATIVE_PROPAGATION_DELAY_SCOPE" "G"
					( Parent
						( matchGroupRef "@baseboard_fab2_lib.baseboard_fab2(sch_1):\MG_P3E_CPU0_PE3_OCP_TX1415\" )
					)
					( Status sCSetFlattened )
					( Origin gBackEnd )
				)
				( attribute "RELATIVE_PROPAGATION_DELAY" ",500.00 MIL"
					( Parent
						( matchGroupRef "@baseboard_fab2_lib.baseboard_fab2(sch_1):\MG_P3E_CPU0_PE3_OCP_TX1415\" )
					)
					( Units "uMatchProp" "ns" 1.000000)
					( Status sCSetFlattened )
					( Origin gBackEnd )
				)
			)
			( pinPair "@baseboard_fab2_lib.baseboard_fab2(sch_1):\PP121\"
				( pinRef "@baseboard_fab2_lib.baseboard_fab2(sch_1):page186_i336:IO64" )
				( pinRef "@baseboard_fab2_lib.baseboard_fab2(sch_1):page106_i105:B" )
				( attribute "RELATIVE_PROPAGATION_DELAY_SCOPE" "L"
					( Parent
						( matchGroupRef "@baseboard_fab2_lib.baseboard_fab2(sch_1):\MG_PCIE_L0\" )
					)
					( Status sCSetFlattened )
					( Origin gBackEnd )
				)
				( attribute "RELATIVE_PROPAGATION_DELAY" ",5.00 MIL"
					( Parent
						( matchGroupRef "@baseboard_fab2_lib.baseboard_fab2(sch_1):\MG_PCIE_L0\" )
					)
					( Units "uMatchProp" "ns" 1.000000)
					( Status sCSetFlattened )
					( Origin gBackEnd )
				)
			)
			( pinPair "@baseboard_fab2_lib.baseboard_fab2(sch_1):\PP122\"
				( pinRef "@baseboard_fab2_lib.baseboard_fab2(sch_1):page32_i89:PE3_TX_DP(14)" )
				( pinRef "@baseboard_fab2_lib.baseboard_fab2(sch_1):page106_i105:A" )
				( attribute "RELATIVE_PROPAGATION_DELAY_SCOPE" "L"
					( Parent
						( matchGroupRef "@baseboard_fab2_lib.baseboard_fab2(sch_1):\MG_PCIE_L1\" )
					)
					( Status sCSetFlattened )
					( Origin gBackEnd )
				)
				( attribute "RELATIVE_PROPAGATION_DELAY" ",5.00 MIL"
					( Parent
						( matchGroupRef "@baseboard_fab2_lib.baseboard_fab2(sch_1):\MG_PCIE_L1\" )
					)
					( Units "uMatchProp" "ns" 1.000000)
					( Status sCSetFlattened )
					( Origin gBackEnd )
				)
			)
			( pinPair "@baseboard_fab2_lib.baseboard_fab2(sch_1):\PP6038\"
				( pinRef "@baseboard_fab2_lib.baseboard_fab2(sch_1):page32_i89:PE3_TX_DP(14)" )
				( pinRef "@baseboard_fab2_lib.baseboard_fab2(sch_1):page186_i336:IO64" )
				( attribute "PROPAGATION_DELAY_MIN" "3000.00 MIL"
					( Units "uMaxMinProp" "ns" 1.000000)
					( Status sCSetFlattened )
					( Origin gBackEnd )
				)
				( attribute "PROPAGATION_DELAY_MAX" "16000.00 MIL"
					( Units "uMaxMinProp" "ns" 1.000000)
					( Status sCSetFlattened )
					( Origin gBackEnd )
				)
				( attribute "RELATIVE_PROPAGATION_DELAY_SCOPE" "G"
					( Parent
						( matchGroupRef "@baseboard_fab2_lib.baseboard_fab2(sch_1):\MG_P3E_CPU0_PE3_OCP_TX1415\" )
					)
					( Status sCSetFlattened )
					( Origin gBackEnd )
				)
				( attribute "RELATIVE_PROPAGATION_DELAY" ",500.00 MIL"
					( Parent
						( matchGroupRef "@baseboard_fab2_lib.baseboard_fab2(sch_1):\MG_P3E_CPU0_PE3_OCP_TX1415\" )
					)
					( Units "uMatchProp" "ns" 1.000000)
					( Status sCSetFlattened )
					( Origin gBackEnd )
				)
			)
			( pinPair "@baseboard_fab2_lib.baseboard_fab2(sch_1):\PP123\"
				( pinRef "@baseboard_fab2_lib.baseboard_fab2(sch_1):page32_i89:PE3_TX_DN(15)" )
				( pinRef "@baseboard_fab2_lib.baseboard_fab2(sch_1):page106_i122:A" )
				( attribute "RELATIVE_PROPAGATION_DELAY_SCOPE" "L"
					( Parent
						( matchGroupRef "@baseboard_fab2_lib.baseboard_fab2(sch_1):\MG_PCIE_L1\" )
					)
					( Status sCSetFlattened )
					( Origin gBackEnd )
				)
				( attribute "RELATIVE_PROPAGATION_DELAY" ",5.00 MIL"
					( Parent
						( matchGroupRef "@baseboard_fab2_lib.baseboard_fab2(sch_1):\MG_PCIE_L1\" )
					)
					( Units "uMatchProp" "ns" 1.000000)
					( Status sCSetFlattened )
					( Origin gBackEnd )
				)
			)
			( pinPair "@baseboard_fab2_lib.baseboard_fab2(sch_1):\PP124\"
				( pinRef "@baseboard_fab2_lib.baseboard_fab2(sch_1):page186_i336:IO58" )
				( pinRef "@baseboard_fab2_lib.baseboard_fab2(sch_1):page106_i122:B" )
				( attribute "RELATIVE_PROPAGATION_DELAY_SCOPE" "L"
					( Parent
						( matchGroupRef "@baseboard_fab2_lib.baseboard_fab2(sch_1):\MG_PCIE_L0\" )
					)
					( Status sCSetFlattened )
					( Origin gBackEnd )
				)
				( attribute "RELATIVE_PROPAGATION_DELAY" ",5.00 MIL"
					( Parent
						( matchGroupRef "@baseboard_fab2_lib.baseboard_fab2(sch_1):\MG_PCIE_L0\" )
					)
					( Units "uMatchProp" "ns" 1.000000)
					( Status sCSetFlattened )
					( Origin gBackEnd )
				)
			)
			( pinPair "@baseboard_fab2_lib.baseboard_fab2(sch_1):\PP6036\"
				( pinRef "@baseboard_fab2_lib.baseboard_fab2(sch_1):page32_i89:PE3_TX_DN(15)" )
				( pinRef "@baseboard_fab2_lib.baseboard_fab2(sch_1):page186_i336:IO58" )
				( attribute "PROPAGATION_DELAY_MIN" "3000.00 MIL"
					( Units "uMaxMinProp" "ns" 1.000000)
					( Status sCSetFlattened )
					( Origin gBackEnd )
				)
				( attribute "PROPAGATION_DELAY_MAX" "16000.00 MIL"
					( Units "uMaxMinProp" "ns" 1.000000)
					( Status sCSetFlattened )
					( Origin gBackEnd )
				)
				( attribute "RELATIVE_PROPAGATION_DELAY_SCOPE" "G"
					( Parent
						( matchGroupRef "@baseboard_fab2_lib.baseboard_fab2(sch_1):\MG_P3E_CPU0_PE3_OCP_TX1415\" )
					)
					( Status sCSetFlattened )
					( Origin gBackEnd )
				)
				( attribute "RELATIVE_PROPAGATION_DELAY" ",500.00 MIL"
					( Parent
						( matchGroupRef "@baseboard_fab2_lib.baseboard_fab2(sch_1):\MG_P3E_CPU0_PE3_OCP_TX1415\" )
					)
					( Units "uMatchProp" "ns" 1.000000)
					( Status sCSetFlattened )
					( Origin gBackEnd )
				)
			)
			( pinPair "@baseboard_fab2_lib.baseboard_fab2(sch_1):\PP125\"
				( pinRef "@baseboard_fab2_lib.baseboard_fab2(sch_1):page186_i336:IO56" )
				( pinRef "@baseboard_fab2_lib.baseboard_fab2(sch_1):page106_i109:B" )
				( attribute "RELATIVE_PROPAGATION_DELAY_SCOPE" "L"
					( Parent
						( matchGroupRef "@baseboard_fab2_lib.baseboard_fab2(sch_1):\MG_PCIE_L0\" )
					)
					( Status sCSetFlattened )
					( Origin gBackEnd )
				)
				( attribute "RELATIVE_PROPAGATION_DELAY" ",5.00 MIL"
					( Parent
						( matchGroupRef "@baseboard_fab2_lib.baseboard_fab2(sch_1):\MG_PCIE_L0\" )
					)
					( Units "uMatchProp" "ns" 1.000000)
					( Status sCSetFlattened )
					( Origin gBackEnd )
				)
			)
			( pinPair "@baseboard_fab2_lib.baseboard_fab2(sch_1):\PP126\"
				( pinRef "@baseboard_fab2_lib.baseboard_fab2(sch_1):page32_i89:PE3_TX_DP(15)" )
				( pinRef "@baseboard_fab2_lib.baseboard_fab2(sch_1):page106_i109:A" )
				( attribute "RELATIVE_PROPAGATION_DELAY_SCOPE" "L"
					( Parent
						( matchGroupRef "@baseboard_fab2_lib.baseboard_fab2(sch_1):\MG_PCIE_L1\" )
					)
					( Status sCSetFlattened )
					( Origin gBackEnd )
				)
				( attribute "RELATIVE_PROPAGATION_DELAY" ",5.00 MIL"
					( Parent
						( matchGroupRef "@baseboard_fab2_lib.baseboard_fab2(sch_1):\MG_PCIE_L1\" )
					)
					( Units "uMatchProp" "ns" 1.000000)
					( Status sCSetFlattened )
					( Origin gBackEnd )
				)
			)
			( pinPair "@baseboard_fab2_lib.baseboard_fab2(sch_1):\PP6035\"
				( pinRef "@baseboard_fab2_lib.baseboard_fab2(sch_1):page32_i89:PE3_TX_DP(15)" )
				( pinRef "@baseboard_fab2_lib.baseboard_fab2(sch_1):page186_i336:IO56" )
				( attribute "PROPAGATION_DELAY_MIN" "3000.00 MIL"
					( Units "uMaxMinProp" "ns" 1.000000)
					( Status sCSetFlattened )
					( Origin gBackEnd )
				)
				( attribute "PROPAGATION_DELAY_MAX" "16000.00 MIL"
					( Units "uMaxMinProp" "ns" 1.000000)
					( Status sCSetFlattened )
					( Origin gBackEnd )
				)
				( attribute "RELATIVE_PROPAGATION_DELAY_SCOPE" "G"
					( Parent
						( matchGroupRef "@baseboard_fab2_lib.baseboard_fab2(sch_1):\MG_P3E_CPU0_PE3_OCP_TX1415\" )
					)
					( Status sCSetFlattened )
					( Origin gBackEnd )
				)
				( attribute "RELATIVE_PROPAGATION_DELAY" ",500.00 MIL"
					( Parent
						( matchGroupRef "@baseboard_fab2_lib.baseboard_fab2(sch_1):\MG_P3E_CPU0_PE3_OCP_TX1415\" )
					)
					( Units "uMatchProp" "ns" 1.000000)
					( Status sCSetFlattened )
					( Origin gBackEnd )
				)
			)
			( pinPair "@baseboard_fab2_lib.baseboard_fab2(sch_1):\PP227\"
				( pinRef "@baseboard_fab2_lib.baseboard_fab2(sch_1):page66_i84:PE3_TX_DN(0)" )
				( pinRef "@baseboard_fab2_lib.baseboard_fab2(sch_1):page181_i166:B" )
				( attribute "RELATIVE_PROPAGATION_DELAY_SCOPE" "L"
					( Parent
						( matchGroupRef "@baseboard_fab2_lib.baseboard_fab2(sch_1):\MG_PCIE_L1\" )
					)
					( Status sCSetFlattened )
					( Origin gBackEnd )
				)
				( attribute "RELATIVE_PROPAGATION_DELAY" ",5.00 MIL"
					( Parent
						( matchGroupRef "@baseboard_fab2_lib.baseboard_fab2(sch_1):\MG_PCIE_L1\" )
					)
					( Units "uMatchProp" "ns" 1.000000)
					( Status sCSetFlattened )
					( Origin gBackEnd )
				)
			)
			( pinPair "@baseboard_fab2_lib.baseboard_fab2(sch_1):\PP228\"
				( pinRef "@baseboard_fab2_lib.baseboard_fab2(sch_1):page181_i111:IOB8" )
				( pinRef "@baseboard_fab2_lib.baseboard_fab2(sch_1):page181_i166:A" )
				( attribute "RELATIVE_PROPAGATION_DELAY_SCOPE" "L"
					( Parent
						( matchGroupRef "@baseboard_fab2_lib.baseboard_fab2(sch_1):\MG_PCIE_L0\" )
					)
					( Status sCSetFlattened )
					( Origin gBackEnd )
				)
				( attribute "RELATIVE_PROPAGATION_DELAY" ",5.00 MIL"
					( Parent
						( matchGroupRef "@baseboard_fab2_lib.baseboard_fab2(sch_1):\MG_PCIE_L0\" )
					)
					( Units "uMatchProp" "ns" 1.000000)
					( Status sCSetFlattened )
					( Origin gBackEnd )
				)
			)
			( pinPair "@baseboard_fab2_lib.baseboard_fab2(sch_1):\PP5952\"
				( pinRef "@baseboard_fab2_lib.baseboard_fab2(sch_1):page66_i84:PE3_TX_DN(0)" )
				( pinRef "@baseboard_fab2_lib.baseboard_fab2(sch_1):page181_i111:IOB8" )
				( attribute "PROPAGATION_DELAY_MIN" "3000.00 MIL"
					( Units "uMaxMinProp" "ns" 1.000000)
					( Status sCSetFlattened )
					( Origin gBackEnd )
				)
				( attribute "PROPAGATION_DELAY_MAX" "16000.00 MIL"
					( Units "uMaxMinProp" "ns" 1.000000)
					( Status sCSetFlattened )
					( Origin gBackEnd )
				)
				( attribute "RELATIVE_PROPAGATION_DELAY_SCOPE" "G"
					( Parent
						( matchGroupRef "@baseboard_fab2_lib.baseboard_fab2(sch_1):\MG_P3E_CPU1_PE3_MP_TX0001\" )
					)
					( Status sCSetFlattened )
					( Origin gBackEnd )
				)
				( attribute "RELATIVE_PROPAGATION_DELAY" ",500.00 MIL"
					( Parent
						( matchGroupRef "@baseboard_fab2_lib.baseboard_fab2(sch_1):\MG_P3E_CPU1_PE3_MP_TX0001\" )
					)
					( Units "uMatchProp" "ns" 1.000000)
					( Status sCSetFlattened )
					( Origin gBackEnd )
				)
			)
			( pinPair "@baseboard_fab2_lib.baseboard_fab2(sch_1):\PP229\"
				( pinRef "@baseboard_fab2_lib.baseboard_fab2(sch_1):page66_i84:PE3_TX_DP(0)" )
				( pinRef "@baseboard_fab2_lib.baseboard_fab2(sch_1):page181_i171:B" )
				( attribute "RELATIVE_PROPAGATION_DELAY_SCOPE" "L"
					( Parent
						( matchGroupRef "@baseboard_fab2_lib.baseboard_fab2(sch_1):\MG_PCIE_L1\" )
					)
					( Status sCSetFlattened )
					( Origin gBackEnd )
				)
				( attribute "RELATIVE_PROPAGATION_DELAY" ",5.00 MIL"
					( Parent
						( matchGroupRef "@baseboard_fab2_lib.baseboard_fab2(sch_1):\MG_PCIE_L1\" )
					)
					( Units "uMatchProp" "ns" 1.000000)
					( Status sCSetFlattened )
					( Origin gBackEnd )
				)
			)
			( pinPair "@baseboard_fab2_lib.baseboard_fab2(sch_1):\PP230\"
				( pinRef "@baseboard_fab2_lib.baseboard_fab2(sch_1):page181_i111:IOC8" )
				( pinRef "@baseboard_fab2_lib.baseboard_fab2(sch_1):page181_i171:A" )
				( attribute "RELATIVE_PROPAGATION_DELAY_SCOPE" "L"
					( Parent
						( matchGroupRef "@baseboard_fab2_lib.baseboard_fab2(sch_1):\MG_PCIE_L0\" )
					)
					( Status sCSetFlattened )
					( Origin gBackEnd )
				)
				( attribute "RELATIVE_PROPAGATION_DELAY" ",5.00 MIL"
					( Parent
						( matchGroupRef "@baseboard_fab2_lib.baseboard_fab2(sch_1):\MG_PCIE_L0\" )
					)
					( Units "uMatchProp" "ns" 1.000000)
					( Status sCSetFlattened )
					( Origin gBackEnd )
				)
			)
			( pinPair "@baseboard_fab2_lib.baseboard_fab2(sch_1):\PP5959\"
				( pinRef "@baseboard_fab2_lib.baseboard_fab2(sch_1):page66_i84:PE3_TX_DP(0)" )
				( pinRef "@baseboard_fab2_lib.baseboard_fab2(sch_1):page181_i111:IOC8" )
				( attribute "PROPAGATION_DELAY_MIN" "3000.00 MIL"
					( Units "uMaxMinProp" "ns" 1.000000)
					( Status sCSetFlattened )
					( Origin gBackEnd )
				)
				( attribute "PROPAGATION_DELAY_MAX" "16000.00 MIL"
					( Units "uMaxMinProp" "ns" 1.000000)
					( Status sCSetFlattened )
					( Origin gBackEnd )
				)
				( attribute "RELATIVE_PROPAGATION_DELAY_SCOPE" "G"
					( Parent
						( matchGroupRef "@baseboard_fab2_lib.baseboard_fab2(sch_1):\MG_P3E_CPU1_PE3_MP_TX0001\" )
					)
					( Status sCSetFlattened )
					( Origin gBackEnd )
				)
				( attribute "RELATIVE_PROPAGATION_DELAY" ",500.00 MIL"
					( Parent
						( matchGroupRef "@baseboard_fab2_lib.baseboard_fab2(sch_1):\MG_P3E_CPU1_PE3_MP_TX0001\" )
					)
					( Units "uMatchProp" "ns" 1.000000)
					( Status sCSetFlattened )
					( Origin gBackEnd )
				)
			)
			( pinPair "@baseboard_fab2_lib.baseboard_fab2(sch_1):\PP223\"
				( pinRef "@baseboard_fab2_lib.baseboard_fab2(sch_1):page66_i84:PE3_TX_DN(1)" )
				( pinRef "@baseboard_fab2_lib.baseboard_fab2(sch_1):page181_i172:B" )
				( attribute "RELATIVE_PROPAGATION_DELAY_SCOPE" "L"
					( Parent
						( matchGroupRef "@baseboard_fab2_lib.baseboard_fab2(sch_1):\MG_PCIE_L1\" )
					)
					( Status sCSetFlattened )
					( Origin gBackEnd )
				)
				( attribute "RELATIVE_PROPAGATION_DELAY" ",5.00 MIL"
					( Parent
						( matchGroupRef "@baseboard_fab2_lib.baseboard_fab2(sch_1):\MG_PCIE_L1\" )
					)
					( Units "uMatchProp" "ns" 1.000000)
					( Status sCSetFlattened )
					( Origin gBackEnd )
				)
			)
			( pinPair "@baseboard_fab2_lib.baseboard_fab2(sch_1):\PP224\"
				( pinRef "@baseboard_fab2_lib.baseboard_fab2(sch_1):page181_i111:IOE8" )
				( pinRef "@baseboard_fab2_lib.baseboard_fab2(sch_1):page181_i172:A" )
				( attribute "RELATIVE_PROPAGATION_DELAY_SCOPE" "L"
					( Parent
						( matchGroupRef "@baseboard_fab2_lib.baseboard_fab2(sch_1):\MG_PCIE_L0\" )
					)
					( Status sCSetFlattened )
					( Origin gBackEnd )
				)
				( attribute "RELATIVE_PROPAGATION_DELAY" ",5.00 MIL"
					( Parent
						( matchGroupRef "@baseboard_fab2_lib.baseboard_fab2(sch_1):\MG_PCIE_L0\" )
					)
					( Units "uMatchProp" "ns" 1.000000)
					( Status sCSetFlattened )
					( Origin gBackEnd )
				)
			)
			( pinPair "@baseboard_fab2_lib.baseboard_fab2(sch_1):\PP5961\"
				( pinRef "@baseboard_fab2_lib.baseboard_fab2(sch_1):page66_i84:PE3_TX_DN(1)" )
				( pinRef "@baseboard_fab2_lib.baseboard_fab2(sch_1):page181_i111:IOE8" )
				( attribute "PROPAGATION_DELAY_MIN" "3000.00 MIL"
					( Units "uMaxMinProp" "ns" 1.000000)
					( Status sCSetFlattened )
					( Origin gBackEnd )
				)
				( attribute "PROPAGATION_DELAY_MAX" "16000.00 MIL"
					( Units "uMaxMinProp" "ns" 1.000000)
					( Status sCSetFlattened )
					( Origin gBackEnd )
				)
				( attribute "RELATIVE_PROPAGATION_DELAY_SCOPE" "G"
					( Parent
						( matchGroupRef "@baseboard_fab2_lib.baseboard_fab2(sch_1):\MG_P3E_CPU1_PE3_MP_TX0001\" )
					)
					( Status sCSetFlattened )
					( Origin gBackEnd )
				)
				( attribute "RELATIVE_PROPAGATION_DELAY" ",500.00 MIL"
					( Parent
						( matchGroupRef "@baseboard_fab2_lib.baseboard_fab2(sch_1):\MG_P3E_CPU1_PE3_MP_TX0001\" )
					)
					( Units "uMatchProp" "ns" 1.000000)
					( Status sCSetFlattened )
					( Origin gBackEnd )
				)
			)
			( pinPair "@baseboard_fab2_lib.baseboard_fab2(sch_1):\PP225\"
				( pinRef "@baseboard_fab2_lib.baseboard_fab2(sch_1):page66_i84:PE3_TX_DP(1)" )
				( pinRef "@baseboard_fab2_lib.baseboard_fab2(sch_1):page181_i173:B" )
				( attribute "RELATIVE_PROPAGATION_DELAY_SCOPE" "L"
					( Parent
						( matchGroupRef "@baseboard_fab2_lib.baseboard_fab2(sch_1):\MG_PCIE_L1\" )
					)
					( Status sCSetFlattened )
					( Origin gBackEnd )
				)
				( attribute "RELATIVE_PROPAGATION_DELAY" ",5.00 MIL"
					( Parent
						( matchGroupRef "@baseboard_fab2_lib.baseboard_fab2(sch_1):\MG_PCIE_L1\" )
					)
					( Units "uMatchProp" "ns" 1.000000)
					( Status sCSetFlattened )
					( Origin gBackEnd )
				)
			)
			( pinPair "@baseboard_fab2_lib.baseboard_fab2(sch_1):\PP226\"
				( pinRef "@baseboard_fab2_lib.baseboard_fab2(sch_1):page181_i111:IOF8" )
				( pinRef "@baseboard_fab2_lib.baseboard_fab2(sch_1):page181_i173:A" )
				( attribute "RELATIVE_PROPAGATION_DELAY_SCOPE" "L"
					( Parent
						( matchGroupRef "@baseboard_fab2_lib.baseboard_fab2(sch_1):\MG_PCIE_L0\" )
					)
					( Status sCSetFlattened )
					( Origin gBackEnd )
				)
				( attribute "RELATIVE_PROPAGATION_DELAY" ",5.00 MIL"
					( Parent
						( matchGroupRef "@baseboard_fab2_lib.baseboard_fab2(sch_1):\MG_PCIE_L0\" )
					)
					( Units "uMatchProp" "ns" 1.000000)
					( Status sCSetFlattened )
					( Origin gBackEnd )
				)
			)
			( pinPair "@baseboard_fab2_lib.baseboard_fab2(sch_1):\PP5953\"
				( pinRef "@baseboard_fab2_lib.baseboard_fab2(sch_1):page66_i84:PE3_TX_DP(1)" )
				( pinRef "@baseboard_fab2_lib.baseboard_fab2(sch_1):page181_i111:IOF8" )
				( attribute "PROPAGATION_DELAY_MIN" "3000.00 MIL"
					( Units "uMaxMinProp" "ns" 1.000000)
					( Status sCSetFlattened )
					( Origin gBackEnd )
				)
				( attribute "PROPAGATION_DELAY_MAX" "16000.00 MIL"
					( Units "uMaxMinProp" "ns" 1.000000)
					( Status sCSetFlattened )
					( Origin gBackEnd )
				)
				( attribute "RELATIVE_PROPAGATION_DELAY_SCOPE" "G"
					( Parent
						( matchGroupRef "@baseboard_fab2_lib.baseboard_fab2(sch_1):\MG_P3E_CPU1_PE3_MP_TX0001\" )
					)
					( Status sCSetFlattened )
					( Origin gBackEnd )
				)
				( attribute "RELATIVE_PROPAGATION_DELAY" ",500.00 MIL"
					( Parent
						( matchGroupRef "@baseboard_fab2_lib.baseboard_fab2(sch_1):\MG_P3E_CPU1_PE3_MP_TX0001\" )
					)
					( Units "uMatchProp" "ns" 1.000000)
					( Status sCSetFlattened )
					( Origin gBackEnd )
				)
			)
			( pinPair "@baseboard_fab2_lib.baseboard_fab2(sch_1):\PP135\"
				( pinRef "@baseboard_fab2_lib.baseboard_fab2(sch_1):page108_i258:IO56" )
				( pinRef "@baseboard_fab2_lib.baseboard_fab2(sch_1):page107_i465:A" )
				( attribute "RELATIVE_PROPAGATION_DELAY_SCOPE" "L"
					( Parent
						( matchGroupRef "@baseboard_fab2_lib.baseboard_fab2(sch_1):\MG_PCIE_L0\" )
					)
					( Status sCSetFlattened )
					( Origin gBackEnd )
				)
				( attribute "RELATIVE_PROPAGATION_DELAY" ",5.00 MIL"
					( Parent
						( matchGroupRef "@baseboard_fab2_lib.baseboard_fab2(sch_1):\MG_PCIE_L0\" )
					)
					( Units "uMatchProp" "ns" 1.000000)
					( Status sCSetFlattened )
					( Origin gBackEnd )
				)
			)
			( pinPair "@baseboard_fab2_lib.baseboard_fab2(sch_1):\PP136\"
				( pinRef "@baseboard_fab2_lib.baseboard_fab2(sch_1):page117_i9:PCIEUP_0_TXN" )
				( pinRef "@baseboard_fab2_lib.baseboard_fab2(sch_1):page107_i257:A" )
				( attribute "RELATIVE_PROPAGATION_DELAY_SCOPE" "L"
					( Parent
						( matchGroupRef "@baseboard_fab2_lib.baseboard_fab2(sch_1):\MG_PCIE_L1\" )
					)
					( Status sCSetFlattened )
					( Origin gBackEnd )
				)
				( attribute "RELATIVE_PROPAGATION_DELAY" ",5.00 MIL"
					( Parent
						( matchGroupRef "@baseboard_fab2_lib.baseboard_fab2(sch_1):\MG_PCIE_L1\" )
					)
					( Units "uMatchProp" "ns" 1.000000)
					( Status sCSetFlattened )
					( Origin gBackEnd )
				)
			)
			( pinPair "@baseboard_fab2_lib.baseboard_fab2(sch_1):\PP6023\"
				( pinRef "@baseboard_fab2_lib.baseboard_fab2(sch_1):page30_i84:PE1_RX_DN(0)" )
				( pinRef "@baseboard_fab2_lib.baseboard_fab2(sch_1):page107_i465:A" )
				( attribute "RELATIVE_PROPAGATION_DELAY_SCOPE" "L"
					( Parent
						( matchGroupRef "@baseboard_fab2_lib.baseboard_fab2(sch_1):\MG_PCIE_L2\" )
					)
					( Status sCSetFlattened )
					( Origin gBackEnd )
				)
				( attribute "RELATIVE_PROPAGATION_DELAY" ",5.00 MIL"
					( Parent
						( matchGroupRef "@baseboard_fab2_lib.baseboard_fab2(sch_1):\MG_PCIE_L2\" )
					)
					( Units "uMatchProp" "ns" 1.000000)
					( Status sCSetFlattened )
					( Origin gBackEnd )
				)
			)
			( pinPair "@baseboard_fab2_lib.baseboard_fab2(sch_1):\PP6024\"
				( pinRef "@baseboard_fab2_lib.baseboard_fab2(sch_1):page30_i84:PE1_RX_DN(0)" )
				( pinRef "@baseboard_fab2_lib.baseboard_fab2(sch_1):page117_i9:PCIEUP_0_TXN" )
				( attribute "PROPAGATION_DELAY_MIN" "3000.00 MIL"
					( Units "uMaxMinProp" "ns" 1.000000)
					( Status sCSetFlattened )
					( Origin gBackEnd )
				)
				( attribute "PROPAGATION_DELAY_MAX" "17000.00 MIL"
					( Units "uMaxMinProp" "ns" 1.000000)
					( Status sCSetFlattened )
					( Origin gBackEnd )
				)
				( attribute "RELATIVE_PROPAGATION_DELAY_SCOPE" "L"
					( Parent
						( matchGroupRef "@baseboard_fab2_lib.baseboard_fab2(sch_1):\MG_PCIE_ALL1\" )
					)
					( Status sCSetFlattened )
					( Origin gBackEnd )
				)
				( attribute "RELATIVE_PROPAGATION_DELAY" ",5.00 MIL"
					( Parent
						( matchGroupRef "@baseboard_fab2_lib.baseboard_fab2(sch_1):\MG_PCIE_ALL1\" )
					)
					( Units "uMatchProp" "ns" 1.000000)
					( Status sCSetFlattened )
					( Origin gBackEnd )
				)
			)
			( pinPair "@baseboard_fab2_lib.baseboard_fab2(sch_1):\PP6025\"
				( pinRef "@baseboard_fab2_lib.baseboard_fab2(sch_1):page30_i84:PE1_RX_DN(0)" )
				( pinRef "@baseboard_fab2_lib.baseboard_fab2(sch_1):page108_i258:IO56" )
				( attribute "PROPAGATION_DELAY_MIN" "3000.00 MIL"
					( Units "uMaxMinProp" "ns" 1.000000)
					( Status sCSetFlattened )
					( Origin gBackEnd )
				)
				( attribute "PROPAGATION_DELAY_MAX" "16000.00 MIL"
					( Units "uMaxMinProp" "ns" 1.000000)
					( Status sCSetFlattened )
					( Origin gBackEnd )
				)
				( attribute "RELATIVE_PROPAGATION_DELAY_SCOPE" "L"
					( Parent
						( matchGroupRef "@baseboard_fab2_lib.baseboard_fab2(sch_1):\MG_PCIE_ALL0\" )
					)
					( Status sCSetFlattened )
					( Origin gBackEnd )
				)
				( attribute "RELATIVE_PROPAGATION_DELAY" ",5.00 MIL"
					( Parent
						( matchGroupRef "@baseboard_fab2_lib.baseboard_fab2(sch_1):\MG_PCIE_ALL0\" )
					)
					( Units "uMatchProp" "ns" 1.000000)
					( Status sCSetFlattened )
					( Origin gBackEnd )
				)
			)
			( pinPair "@baseboard_fab2_lib.baseboard_fab2(sch_1):\PP137\"
				( pinRef "@baseboard_fab2_lib.baseboard_fab2(sch_1):page108_i258:IO54" )
				( pinRef "@baseboard_fab2_lib.baseboard_fab2(sch_1):page107_i466:A" )
				( attribute "RELATIVE_PROPAGATION_DELAY_SCOPE" "L"
					( Parent
						( matchGroupRef "@baseboard_fab2_lib.baseboard_fab2(sch_1):\MG_PCIE_L0\" )
					)
					( Status sCSetFlattened )
					( Origin gBackEnd )
				)
				( attribute "RELATIVE_PROPAGATION_DELAY" ",5.00 MIL"
					( Parent
						( matchGroupRef "@baseboard_fab2_lib.baseboard_fab2(sch_1):\MG_PCIE_L0\" )
					)
					( Units "uMatchProp" "ns" 1.000000)
					( Status sCSetFlattened )
					( Origin gBackEnd )
				)
			)
			( pinPair "@baseboard_fab2_lib.baseboard_fab2(sch_1):\PP138\"
				( pinRef "@baseboard_fab2_lib.baseboard_fab2(sch_1):page117_i9:PCIEUP_0_TXP" )
				( pinRef "@baseboard_fab2_lib.baseboard_fab2(sch_1):page107_i272:A" )
				( attribute "RELATIVE_PROPAGATION_DELAY_SCOPE" "L"
					( Parent
						( matchGroupRef "@baseboard_fab2_lib.baseboard_fab2(sch_1):\MG_PCIE_L1\" )
					)
					( Status sCSetFlattened )
					( Origin gBackEnd )
				)
				( attribute "RELATIVE_PROPAGATION_DELAY" ",5.00 MIL"
					( Parent
						( matchGroupRef "@baseboard_fab2_lib.baseboard_fab2(sch_1):\MG_PCIE_L1\" )
					)
					( Units "uMatchProp" "ns" 1.000000)
					( Status sCSetFlattened )
					( Origin gBackEnd )
				)
			)
			( pinPair "@baseboard_fab2_lib.baseboard_fab2(sch_1):\PP6029\"
				( pinRef "@baseboard_fab2_lib.baseboard_fab2(sch_1):page30_i84:PE1_RX_DP(0)" )
				( pinRef "@baseboard_fab2_lib.baseboard_fab2(sch_1):page107_i466:A" )
				( attribute "RELATIVE_PROPAGATION_DELAY_SCOPE" "L"
					( Parent
						( matchGroupRef "@baseboard_fab2_lib.baseboard_fab2(sch_1):\MG_PCIE_L2\" )
					)
					( Status sCSetFlattened )
					( Origin gBackEnd )
				)
				( attribute "RELATIVE_PROPAGATION_DELAY" ",5.00 MIL"
					( Parent
						( matchGroupRef "@baseboard_fab2_lib.baseboard_fab2(sch_1):\MG_PCIE_L2\" )
					)
					( Units "uMatchProp" "ns" 1.000000)
					( Status sCSetFlattened )
					( Origin gBackEnd )
				)
			)
			( pinPair "@baseboard_fab2_lib.baseboard_fab2(sch_1):\PP6030\"
				( pinRef "@baseboard_fab2_lib.baseboard_fab2(sch_1):page30_i84:PE1_RX_DP(0)" )
				( pinRef "@baseboard_fab2_lib.baseboard_fab2(sch_1):page117_i9:PCIEUP_0_TXP" )
				( attribute "PROPAGATION_DELAY_MIN" "3000.00 MIL"
					( Units "uMaxMinProp" "ns" 1.000000)
					( Status sCSetFlattened )
					( Origin gBackEnd )
				)
				( attribute "PROPAGATION_DELAY_MAX" "17000.00 MIL"
					( Units "uMaxMinProp" "ns" 1.000000)
					( Status sCSetFlattened )
					( Origin gBackEnd )
				)
				( attribute "RELATIVE_PROPAGATION_DELAY_SCOPE" "L"
					( Parent
						( matchGroupRef "@baseboard_fab2_lib.baseboard_fab2(sch_1):\MG_PCIE_ALL1\" )
					)
					( Status sCSetFlattened )
					( Origin gBackEnd )
				)
				( attribute "RELATIVE_PROPAGATION_DELAY" ",5.00 MIL"
					( Parent
						( matchGroupRef "@baseboard_fab2_lib.baseboard_fab2(sch_1):\MG_PCIE_ALL1\" )
					)
					( Units "uMatchProp" "ns" 1.000000)
					( Status sCSetFlattened )
					( Origin gBackEnd )
				)
			)
			( pinPair "@baseboard_fab2_lib.baseboard_fab2(sch_1):\PP6031\"
				( pinRef "@baseboard_fab2_lib.baseboard_fab2(sch_1):page30_i84:PE1_RX_DP(0)" )
				( pinRef "@baseboard_fab2_lib.baseboard_fab2(sch_1):page108_i258:IO54" )
				( attribute "PROPAGATION_DELAY_MIN" "3000.00 MIL"
					( Units "uMaxMinProp" "ns" 1.000000)
					( Status sCSetFlattened )
					( Origin gBackEnd )
				)
				( attribute "PROPAGATION_DELAY_MAX" "16000.00 MIL"
					( Units "uMaxMinProp" "ns" 1.000000)
					( Status sCSetFlattened )
					( Origin gBackEnd )
				)
				( attribute "RELATIVE_PROPAGATION_DELAY_SCOPE" "L"
					( Parent
						( matchGroupRef "@baseboard_fab2_lib.baseboard_fab2(sch_1):\MG_PCIE_ALL0\" )
					)
					( Status sCSetFlattened )
					( Origin gBackEnd )
				)
				( attribute "RELATIVE_PROPAGATION_DELAY" ",5.00 MIL"
					( Parent
						( matchGroupRef "@baseboard_fab2_lib.baseboard_fab2(sch_1):\MG_PCIE_ALL0\" )
					)
					( Units "uMatchProp" "ns" 1.000000)
					( Status sCSetFlattened )
					( Origin gBackEnd )
				)
			)
			( pinPair "@baseboard_fab2_lib.baseboard_fab2(sch_1):\PP139\"
				( pinRef "@baseboard_fab2_lib.baseboard_fab2(sch_1):page108_i258:IO62" )
				( pinRef "@baseboard_fab2_lib.baseboard_fab2(sch_1):page107_i464:A" )
				( attribute "RELATIVE_PROPAGATION_DELAY_SCOPE" "L"
					( Parent
						( matchGroupRef "@baseboard_fab2_lib.baseboard_fab2(sch_1):\MG_PCIE_L0\" )
					)
					( Status sCSetFlattened )
					( Origin gBackEnd )
				)
				( attribute "RELATIVE_PROPAGATION_DELAY" ",5.00 MIL"
					( Parent
						( matchGroupRef "@baseboard_fab2_lib.baseboard_fab2(sch_1):\MG_PCIE_L0\" )
					)
					( Units "uMatchProp" "ns" 1.000000)
					( Status sCSetFlattened )
					( Origin gBackEnd )
				)
			)
			( pinPair "@baseboard_fab2_lib.baseboard_fab2(sch_1):\PP140\"
				( pinRef "@baseboard_fab2_lib.baseboard_fab2(sch_1):page117_i9:PCIEUP_1_TXN" )
				( pinRef "@baseboard_fab2_lib.baseboard_fab2(sch_1):page107_i260:A" )
				( attribute "RELATIVE_PROPAGATION_DELAY_SCOPE" "L"
					( Parent
						( matchGroupRef "@baseboard_fab2_lib.baseboard_fab2(sch_1):\MG_PCIE_L1\" )
					)
					( Status sCSetFlattened )
					( Origin gBackEnd )
				)
				( attribute "RELATIVE_PROPAGATION_DELAY" ",5.00 MIL"
					( Parent
						( matchGroupRef "@baseboard_fab2_lib.baseboard_fab2(sch_1):\MG_PCIE_L1\" )
					)
					( Units "uMatchProp" "ns" 1.000000)
					( Status sCSetFlattened )
					( Origin gBackEnd )
				)
			)
			( pinPair "@baseboard_fab2_lib.baseboard_fab2(sch_1):\PP6026\"
				( pinRef "@baseboard_fab2_lib.baseboard_fab2(sch_1):page30_i84:PE1_RX_DN(1)" )
				( pinRef "@baseboard_fab2_lib.baseboard_fab2(sch_1):page107_i464:A" )
				( attribute "RELATIVE_PROPAGATION_DELAY_SCOPE" "L"
					( Parent
						( matchGroupRef "@baseboard_fab2_lib.baseboard_fab2(sch_1):\MG_PCIE_L2\" )
					)
					( Status sCSetFlattened )
					( Origin gBackEnd )
				)
				( attribute "RELATIVE_PROPAGATION_DELAY" ",5.00 MIL"
					( Parent
						( matchGroupRef "@baseboard_fab2_lib.baseboard_fab2(sch_1):\MG_PCIE_L2\" )
					)
					( Units "uMatchProp" "ns" 1.000000)
					( Status sCSetFlattened )
					( Origin gBackEnd )
				)
			)
			( pinPair "@baseboard_fab2_lib.baseboard_fab2(sch_1):\PP6027\"
				( pinRef "@baseboard_fab2_lib.baseboard_fab2(sch_1):page30_i84:PE1_RX_DN(1)" )
				( pinRef "@baseboard_fab2_lib.baseboard_fab2(sch_1):page117_i9:PCIEUP_1_TXN" )
				( attribute "PROPAGATION_DELAY_MIN" "3000.00 MIL"
					( Units "uMaxMinProp" "ns" 1.000000)
					( Status sCSetFlattened )
					( Origin gBackEnd )
				)
				( attribute "PROPAGATION_DELAY_MAX" "17000.00 MIL"
					( Units "uMaxMinProp" "ns" 1.000000)
					( Status sCSetFlattened )
					( Origin gBackEnd )
				)
				( attribute "RELATIVE_PROPAGATION_DELAY_SCOPE" "L"
					( Parent
						( matchGroupRef "@baseboard_fab2_lib.baseboard_fab2(sch_1):\MG_PCIE_ALL1\" )
					)
					( Status sCSetFlattened )
					( Origin gBackEnd )
				)
				( attribute "RELATIVE_PROPAGATION_DELAY" ",5.00 MIL"
					( Parent
						( matchGroupRef "@baseboard_fab2_lib.baseboard_fab2(sch_1):\MG_PCIE_ALL1\" )
					)
					( Units "uMatchProp" "ns" 1.000000)
					( Status sCSetFlattened )
					( Origin gBackEnd )
				)
			)
			( pinPair "@baseboard_fab2_lib.baseboard_fab2(sch_1):\PP6028\"
				( pinRef "@baseboard_fab2_lib.baseboard_fab2(sch_1):page30_i84:PE1_RX_DN(1)" )
				( pinRef "@baseboard_fab2_lib.baseboard_fab2(sch_1):page108_i258:IO62" )
				( attribute "PROPAGATION_DELAY_MIN" "3000.00 MIL"
					( Units "uMaxMinProp" "ns" 1.000000)
					( Status sCSetFlattened )
					( Origin gBackEnd )
				)
				( attribute "PROPAGATION_DELAY_MAX" "16000.00 MIL"
					( Units "uMaxMinProp" "ns" 1.000000)
					( Status sCSetFlattened )
					( Origin gBackEnd )
				)
				( attribute "RELATIVE_PROPAGATION_DELAY_SCOPE" "L"
					( Parent
						( matchGroupRef "@baseboard_fab2_lib.baseboard_fab2(sch_1):\MG_PCIE_ALL0\" )
					)
					( Status sCSetFlattened )
					( Origin gBackEnd )
				)
				( attribute "RELATIVE_PROPAGATION_DELAY" ",5.00 MIL"
					( Parent
						( matchGroupRef "@baseboard_fab2_lib.baseboard_fab2(sch_1):\MG_PCIE_ALL0\" )
					)
					( Units "uMatchProp" "ns" 1.000000)
					( Status sCSetFlattened )
					( Origin gBackEnd )
				)
			)
			( pinPair "@baseboard_fab2_lib.baseboard_fab2(sch_1):\PP141\"
				( pinRef "@baseboard_fab2_lib.baseboard_fab2(sch_1):page108_i258:IO60" )
				( pinRef "@baseboard_fab2_lib.baseboard_fab2(sch_1):page107_i467:A" )
				( attribute "RELATIVE_PROPAGATION_DELAY_SCOPE" "L"
					( Parent
						( matchGroupRef "@baseboard_fab2_lib.baseboard_fab2(sch_1):\MG_PCIE_L0\" )
					)
					( Status sCSetFlattened )
					( Origin gBackEnd )
				)
				( attribute "RELATIVE_PROPAGATION_DELAY" ",5.00 MIL"
					( Parent
						( matchGroupRef "@baseboard_fab2_lib.baseboard_fab2(sch_1):\MG_PCIE_L0\" )
					)
					( Units "uMatchProp" "ns" 1.000000)
					( Status sCSetFlattened )
					( Origin gBackEnd )
				)
			)
			( pinPair "@baseboard_fab2_lib.baseboard_fab2(sch_1):\PP142\"
				( pinRef "@baseboard_fab2_lib.baseboard_fab2(sch_1):page117_i9:PCIEUP_1_TXP" )
				( pinRef "@baseboard_fab2_lib.baseboard_fab2(sch_1):page107_i274:A" )
				( attribute "RELATIVE_PROPAGATION_DELAY_SCOPE" "L"
					( Parent
						( matchGroupRef "@baseboard_fab2_lib.baseboard_fab2(sch_1):\MG_PCIE_L1\" )
					)
					( Status sCSetFlattened )
					( Origin gBackEnd )
				)
				( attribute "RELATIVE_PROPAGATION_DELAY" ",5.00 MIL"
					( Parent
						( matchGroupRef "@baseboard_fab2_lib.baseboard_fab2(sch_1):\MG_PCIE_L1\" )
					)
					( Units "uMatchProp" "ns" 1.000000)
					( Status sCSetFlattened )
					( Origin gBackEnd )
				)
			)
			( pinPair "@baseboard_fab2_lib.baseboard_fab2(sch_1):\PP6020\"
				( pinRef "@baseboard_fab2_lib.baseboard_fab2(sch_1):page30_i84:PE1_RX_DP(1)" )
				( pinRef "@baseboard_fab2_lib.baseboard_fab2(sch_1):page107_i467:A" )
				( attribute "RELATIVE_PROPAGATION_DELAY_SCOPE" "L"
					( Parent
						( matchGroupRef "@baseboard_fab2_lib.baseboard_fab2(sch_1):\MG_PCIE_L2\" )
					)
					( Status sCSetFlattened )
					( Origin gBackEnd )
				)
				( attribute "RELATIVE_PROPAGATION_DELAY" ",5.00 MIL"
					( Parent
						( matchGroupRef "@baseboard_fab2_lib.baseboard_fab2(sch_1):\MG_PCIE_L2\" )
					)
					( Units "uMatchProp" "ns" 1.000000)
					( Status sCSetFlattened )
					( Origin gBackEnd )
				)
			)
			( pinPair "@baseboard_fab2_lib.baseboard_fab2(sch_1):\PP6021\"
				( pinRef "@baseboard_fab2_lib.baseboard_fab2(sch_1):page30_i84:PE1_RX_DP(1)" )
				( pinRef "@baseboard_fab2_lib.baseboard_fab2(sch_1):page117_i9:PCIEUP_1_TXP" )
				( attribute "PROPAGATION_DELAY_MIN" "3000.00 MIL"
					( Units "uMaxMinProp" "ns" 1.000000)
					( Status sCSetFlattened )
					( Origin gBackEnd )
				)
				( attribute "PROPAGATION_DELAY_MAX" "17000.00 MIL"
					( Units "uMaxMinProp" "ns" 1.000000)
					( Status sCSetFlattened )
					( Origin gBackEnd )
				)
				( attribute "RELATIVE_PROPAGATION_DELAY_SCOPE" "L"
					( Parent
						( matchGroupRef "@baseboard_fab2_lib.baseboard_fab2(sch_1):\MG_PCIE_ALL1\" )
					)
					( Status sCSetFlattened )
					( Origin gBackEnd )
				)
				( attribute "RELATIVE_PROPAGATION_DELAY" ",5.00 MIL"
					( Parent
						( matchGroupRef "@baseboard_fab2_lib.baseboard_fab2(sch_1):\MG_PCIE_ALL1\" )
					)
					( Units "uMatchProp" "ns" 1.000000)
					( Status sCSetFlattened )
					( Origin gBackEnd )
				)
			)
			( pinPair "@baseboard_fab2_lib.baseboard_fab2(sch_1):\PP6022\"
				( pinRef "@baseboard_fab2_lib.baseboard_fab2(sch_1):page30_i84:PE1_RX_DP(1)" )
				( pinRef "@baseboard_fab2_lib.baseboard_fab2(sch_1):page108_i258:IO60" )
				( attribute "PROPAGATION_DELAY_MIN" "3000.00 MIL"
					( Units "uMaxMinProp" "ns" 1.000000)
					( Status sCSetFlattened )
					( Origin gBackEnd )
				)
				( attribute "PROPAGATION_DELAY_MAX" "16000.00 MIL"
					( Units "uMaxMinProp" "ns" 1.000000)
					( Status sCSetFlattened )
					( Origin gBackEnd )
				)
				( attribute "RELATIVE_PROPAGATION_DELAY_SCOPE" "L"
					( Parent
						( matchGroupRef "@baseboard_fab2_lib.baseboard_fab2(sch_1):\MG_PCIE_ALL0\" )
					)
					( Status sCSetFlattened )
					( Origin gBackEnd )
				)
				( attribute "RELATIVE_PROPAGATION_DELAY" ",5.00 MIL"
					( Parent
						( matchGroupRef "@baseboard_fab2_lib.baseboard_fab2(sch_1):\MG_PCIE_ALL0\" )
					)
					( Units "uMatchProp" "ns" 1.000000)
					( Status sCSetFlattened )
					( Origin gBackEnd )
				)
			)
			( pinPair "@baseboard_fab2_lib.baseboard_fab2(sch_1):\PP143\"
				( pinRef "@baseboard_fab2_lib.baseboard_fab2(sch_1):page108_i258:IO72" )
				( pinRef "@baseboard_fab2_lib.baseboard_fab2(sch_1):page107_i463:A" )
				( attribute "RELATIVE_PROPAGATION_DELAY_SCOPE" "L"
					( Parent
						( matchGroupRef "@baseboard_fab2_lib.baseboard_fab2(sch_1):\MG_PCIE_L0\" )
					)
					( Status sCSetFlattened )
					( Origin gBackEnd )
				)
				( attribute "RELATIVE_PROPAGATION_DELAY" ",5.00 MIL"
					( Parent
						( matchGroupRef "@baseboard_fab2_lib.baseboard_fab2(sch_1):\MG_PCIE_L0\" )
					)
					( Units "uMatchProp" "ns" 1.000000)
					( Status sCSetFlattened )
					( Origin gBackEnd )
				)
			)
			( pinPair "@baseboard_fab2_lib.baseboard_fab2(sch_1):\PP144\"
				( pinRef "@baseboard_fab2_lib.baseboard_fab2(sch_1):page117_i9:PCIEUP_2_TXN" )
				( pinRef "@baseboard_fab2_lib.baseboard_fab2(sch_1):page107_i264:A" )
				( attribute "RELATIVE_PROPAGATION_DELAY_SCOPE" "L"
					( Parent
						( matchGroupRef "@baseboard_fab2_lib.baseboard_fab2(sch_1):\MG_PCIE_L1\" )
					)
					( Status sCSetFlattened )
					( Origin gBackEnd )
				)
				( attribute "RELATIVE_PROPAGATION_DELAY" ",5.00 MIL"
					( Parent
						( matchGroupRef "@baseboard_fab2_lib.baseboard_fab2(sch_1):\MG_PCIE_L1\" )
					)
					( Units "uMatchProp" "ns" 1.000000)
					( Status sCSetFlattened )
					( Origin gBackEnd )
				)
			)
			( pinPair "@baseboard_fab2_lib.baseboard_fab2(sch_1):\PP6017\"
				( pinRef "@baseboard_fab2_lib.baseboard_fab2(sch_1):page30_i84:PE1_RX_DN(2)" )
				( pinRef "@baseboard_fab2_lib.baseboard_fab2(sch_1):page107_i463:A" )
				( attribute "RELATIVE_PROPAGATION_DELAY_SCOPE" "L"
					( Parent
						( matchGroupRef "@baseboard_fab2_lib.baseboard_fab2(sch_1):\MG_PCIE_L2\" )
					)
					( Status sCSetFlattened )
					( Origin gBackEnd )
				)
				( attribute "RELATIVE_PROPAGATION_DELAY" ",5.00 MIL"
					( Parent
						( matchGroupRef "@baseboard_fab2_lib.baseboard_fab2(sch_1):\MG_PCIE_L2\" )
					)
					( Units "uMatchProp" "ns" 1.000000)
					( Status sCSetFlattened )
					( Origin gBackEnd )
				)
			)
			( pinPair "@baseboard_fab2_lib.baseboard_fab2(sch_1):\PP6018\"
				( pinRef "@baseboard_fab2_lib.baseboard_fab2(sch_1):page30_i84:PE1_RX_DN(2)" )
				( pinRef "@baseboard_fab2_lib.baseboard_fab2(sch_1):page117_i9:PCIEUP_2_TXN" )
				( attribute "PROPAGATION_DELAY_MIN" "3000.00 MIL"
					( Units "uMaxMinProp" "ns" 1.000000)
					( Status sCSetFlattened )
					( Origin gBackEnd )
				)
				( attribute "PROPAGATION_DELAY_MAX" "17000.00 MIL"
					( Units "uMaxMinProp" "ns" 1.000000)
					( Status sCSetFlattened )
					( Origin gBackEnd )
				)
				( attribute "RELATIVE_PROPAGATION_DELAY_SCOPE" "L"
					( Parent
						( matchGroupRef "@baseboard_fab2_lib.baseboard_fab2(sch_1):\MG_PCIE_ALL1\" )
					)
					( Status sCSetFlattened )
					( Origin gBackEnd )
				)
				( attribute "RELATIVE_PROPAGATION_DELAY" ",5.00 MIL"
					( Parent
						( matchGroupRef "@baseboard_fab2_lib.baseboard_fab2(sch_1):\MG_PCIE_ALL1\" )
					)
					( Units "uMatchProp" "ns" 1.000000)
					( Status sCSetFlattened )
					( Origin gBackEnd )
				)
			)
			( pinPair "@baseboard_fab2_lib.baseboard_fab2(sch_1):\PP6019\"
				( pinRef "@baseboard_fab2_lib.baseboard_fab2(sch_1):page30_i84:PE1_RX_DN(2)" )
				( pinRef "@baseboard_fab2_lib.baseboard_fab2(sch_1):page108_i258:IO72" )
				( attribute "PROPAGATION_DELAY_MIN" "3000.00 MIL"
					( Units "uMaxMinProp" "ns" 1.000000)
					( Status sCSetFlattened )
					( Origin gBackEnd )
				)
				( attribute "PROPAGATION_DELAY_MAX" "16000.00 MIL"
					( Units "uMaxMinProp" "ns" 1.000000)
					( Status sCSetFlattened )
					( Origin gBackEnd )
				)
				( attribute "RELATIVE_PROPAGATION_DELAY_SCOPE" "L"
					( Parent
						( matchGroupRef "@baseboard_fab2_lib.baseboard_fab2(sch_1):\MG_PCIE_ALL0\" )
					)
					( Status sCSetFlattened )
					( Origin gBackEnd )
				)
				( attribute "RELATIVE_PROPAGATION_DELAY" ",5.00 MIL"
					( Parent
						( matchGroupRef "@baseboard_fab2_lib.baseboard_fab2(sch_1):\MG_PCIE_ALL0\" )
					)
					( Units "uMatchProp" "ns" 1.000000)
					( Status sCSetFlattened )
					( Origin gBackEnd )
				)
			)
			( pinPair "@baseboard_fab2_lib.baseboard_fab2(sch_1):\PP145\"
				( pinRef "@baseboard_fab2_lib.baseboard_fab2(sch_1):page108_i258:IO70" )
				( pinRef "@baseboard_fab2_lib.baseboard_fab2(sch_1):page107_i468:A" )
				( attribute "RELATIVE_PROPAGATION_DELAY_SCOPE" "L"
					( Parent
						( matchGroupRef "@baseboard_fab2_lib.baseboard_fab2(sch_1):\MG_PCIE_L0\" )
					)
					( Status sCSetFlattened )
					( Origin gBackEnd )
				)
				( attribute "RELATIVE_PROPAGATION_DELAY" ",5.00 MIL"
					( Parent
						( matchGroupRef "@baseboard_fab2_lib.baseboard_fab2(sch_1):\MG_PCIE_L0\" )
					)
					( Units "uMatchProp" "ns" 1.000000)
					( Status sCSetFlattened )
					( Origin gBackEnd )
				)
			)
			( pinPair "@baseboard_fab2_lib.baseboard_fab2(sch_1):\PP146\"
				( pinRef "@baseboard_fab2_lib.baseboard_fab2(sch_1):page117_i9:PCIEUP_2_TXP" )
				( pinRef "@baseboard_fab2_lib.baseboard_fab2(sch_1):page107_i277:A" )
				( attribute "RELATIVE_PROPAGATION_DELAY_SCOPE" "L"
					( Parent
						( matchGroupRef "@baseboard_fab2_lib.baseboard_fab2(sch_1):\MG_PCIE_L1\" )
					)
					( Status sCSetFlattened )
					( Origin gBackEnd )
				)
				( attribute "RELATIVE_PROPAGATION_DELAY" ",5.00 MIL"
					( Parent
						( matchGroupRef "@baseboard_fab2_lib.baseboard_fab2(sch_1):\MG_PCIE_L1\" )
					)
					( Units "uMatchProp" "ns" 1.000000)
					( Status sCSetFlattened )
					( Origin gBackEnd )
				)
			)
			( pinPair "@baseboard_fab2_lib.baseboard_fab2(sch_1):\PP6014\"
				( pinRef "@baseboard_fab2_lib.baseboard_fab2(sch_1):page30_i84:PE1_RX_DP(2)" )
				( pinRef "@baseboard_fab2_lib.baseboard_fab2(sch_1):page107_i468:A" )
				( attribute "RELATIVE_PROPAGATION_DELAY_SCOPE" "L"
					( Parent
						( matchGroupRef "@baseboard_fab2_lib.baseboard_fab2(sch_1):\MG_PCIE_L2\" )
					)
					( Status sCSetFlattened )
					( Origin gBackEnd )
				)
				( attribute "RELATIVE_PROPAGATION_DELAY" ",5.00 MIL"
					( Parent
						( matchGroupRef "@baseboard_fab2_lib.baseboard_fab2(sch_1):\MG_PCIE_L2\" )
					)
					( Units "uMatchProp" "ns" 1.000000)
					( Status sCSetFlattened )
					( Origin gBackEnd )
				)
			)
			( pinPair "@baseboard_fab2_lib.baseboard_fab2(sch_1):\PP6015\"
				( pinRef "@baseboard_fab2_lib.baseboard_fab2(sch_1):page30_i84:PE1_RX_DP(2)" )
				( pinRef "@baseboard_fab2_lib.baseboard_fab2(sch_1):page117_i9:PCIEUP_2_TXP" )
				( attribute "PROPAGATION_DELAY_MIN" "3000.00 MIL"
					( Units "uMaxMinProp" "ns" 1.000000)
					( Status sCSetFlattened )
					( Origin gBackEnd )
				)
				( attribute "PROPAGATION_DELAY_MAX" "17000.00 MIL"
					( Units "uMaxMinProp" "ns" 1.000000)
					( Status sCSetFlattened )
					( Origin gBackEnd )
				)
				( attribute "RELATIVE_PROPAGATION_DELAY_SCOPE" "L"
					( Parent
						( matchGroupRef "@baseboard_fab2_lib.baseboard_fab2(sch_1):\MG_PCIE_ALL1\" )
					)
					( Status sCSetFlattened )
					( Origin gBackEnd )
				)
				( attribute "RELATIVE_PROPAGATION_DELAY" ",5.00 MIL"
					( Parent
						( matchGroupRef "@baseboard_fab2_lib.baseboard_fab2(sch_1):\MG_PCIE_ALL1\" )
					)
					( Units "uMatchProp" "ns" 1.000000)
					( Status sCSetFlattened )
					( Origin gBackEnd )
				)
			)
			( pinPair "@baseboard_fab2_lib.baseboard_fab2(sch_1):\PP6016\"
				( pinRef "@baseboard_fab2_lib.baseboard_fab2(sch_1):page30_i84:PE1_RX_DP(2)" )
				( pinRef "@baseboard_fab2_lib.baseboard_fab2(sch_1):page108_i258:IO70" )
				( attribute "PROPAGATION_DELAY_MIN" "3000.00 MIL"
					( Units "uMaxMinProp" "ns" 1.000000)
					( Status sCSetFlattened )
					( Origin gBackEnd )
				)
				( attribute "PROPAGATION_DELAY_MAX" "16000.00 MIL"
					( Units "uMaxMinProp" "ns" 1.000000)
					( Status sCSetFlattened )
					( Origin gBackEnd )
				)
				( attribute "RELATIVE_PROPAGATION_DELAY_SCOPE" "L"
					( Parent
						( matchGroupRef "@baseboard_fab2_lib.baseboard_fab2(sch_1):\MG_PCIE_ALL0\" )
					)
					( Status sCSetFlattened )
					( Origin gBackEnd )
				)
				( attribute "RELATIVE_PROPAGATION_DELAY" ",5.00 MIL"
					( Parent
						( matchGroupRef "@baseboard_fab2_lib.baseboard_fab2(sch_1):\MG_PCIE_ALL0\" )
					)
					( Units "uMatchProp" "ns" 1.000000)
					( Status sCSetFlattened )
					( Origin gBackEnd )
				)
			)
			( pinPair "@baseboard_fab2_lib.baseboard_fab2(sch_1):\PP147\"
				( pinRef "@baseboard_fab2_lib.baseboard_fab2(sch_1):page108_i258:IO78" )
				( pinRef "@baseboard_fab2_lib.baseboard_fab2(sch_1):page107_i462:A" )
				( attribute "RELATIVE_PROPAGATION_DELAY_SCOPE" "L"
					( Parent
						( matchGroupRef "@baseboard_fab2_lib.baseboard_fab2(sch_1):\MG_PCIE_L0\" )
					)
					( Status sCSetFlattened )
					( Origin gBackEnd )
				)
				( attribute "RELATIVE_PROPAGATION_DELAY" ",5.00 MIL"
					( Parent
						( matchGroupRef "@baseboard_fab2_lib.baseboard_fab2(sch_1):\MG_PCIE_L0\" )
					)
					( Units "uMatchProp" "ns" 1.000000)
					( Status sCSetFlattened )
					( Origin gBackEnd )
				)
			)
			( pinPair "@baseboard_fab2_lib.baseboard_fab2(sch_1):\PP148\"
				( pinRef "@baseboard_fab2_lib.baseboard_fab2(sch_1):page117_i9:PCIEUP_3_TXN" )
				( pinRef "@baseboard_fab2_lib.baseboard_fab2(sch_1):page107_i267:A" )
				( attribute "RELATIVE_PROPAGATION_DELAY_SCOPE" "L"
					( Parent
						( matchGroupRef "@baseboard_fab2_lib.baseboard_fab2(sch_1):\MG_PCIE_L1\" )
					)
					( Status sCSetFlattened )
					( Origin gBackEnd )
				)
				( attribute "RELATIVE_PROPAGATION_DELAY" ",5.00 MIL"
					( Parent
						( matchGroupRef "@baseboard_fab2_lib.baseboard_fab2(sch_1):\MG_PCIE_L1\" )
					)
					( Units "uMatchProp" "ns" 1.000000)
					( Status sCSetFlattened )
					( Origin gBackEnd )
				)
			)
			( pinPair "@baseboard_fab2_lib.baseboard_fab2(sch_1):\PP6011\"
				( pinRef "@baseboard_fab2_lib.baseboard_fab2(sch_1):page30_i84:PE1_RX_DN(3)" )
				( pinRef "@baseboard_fab2_lib.baseboard_fab2(sch_1):page107_i462:A" )
				( attribute "RELATIVE_PROPAGATION_DELAY_SCOPE" "L"
					( Parent
						( matchGroupRef "@baseboard_fab2_lib.baseboard_fab2(sch_1):\MG_PCIE_L2\" )
					)
					( Status sCSetFlattened )
					( Origin gBackEnd )
				)
				( attribute "RELATIVE_PROPAGATION_DELAY" ",5.00 MIL"
					( Parent
						( matchGroupRef "@baseboard_fab2_lib.baseboard_fab2(sch_1):\MG_PCIE_L2\" )
					)
					( Units "uMatchProp" "ns" 1.000000)
					( Status sCSetFlattened )
					( Origin gBackEnd )
				)
			)
			( pinPair "@baseboard_fab2_lib.baseboard_fab2(sch_1):\PP6012\"
				( pinRef "@baseboard_fab2_lib.baseboard_fab2(sch_1):page30_i84:PE1_RX_DN(3)" )
				( pinRef "@baseboard_fab2_lib.baseboard_fab2(sch_1):page117_i9:PCIEUP_3_TXN" )
				( attribute "PROPAGATION_DELAY_MIN" "3000.00 MIL"
					( Units "uMaxMinProp" "ns" 1.000000)
					( Status sCSetFlattened )
					( Origin gBackEnd )
				)
				( attribute "PROPAGATION_DELAY_MAX" "17000.00 MIL"
					( Units "uMaxMinProp" "ns" 1.000000)
					( Status sCSetFlattened )
					( Origin gBackEnd )
				)
				( attribute "RELATIVE_PROPAGATION_DELAY_SCOPE" "L"
					( Parent
						( matchGroupRef "@baseboard_fab2_lib.baseboard_fab2(sch_1):\MG_PCIE_ALL1\" )
					)
					( Status sCSetFlattened )
					( Origin gBackEnd )
				)
				( attribute "RELATIVE_PROPAGATION_DELAY" ",5.00 MIL"
					( Parent
						( matchGroupRef "@baseboard_fab2_lib.baseboard_fab2(sch_1):\MG_PCIE_ALL1\" )
					)
					( Units "uMatchProp" "ns" 1.000000)
					( Status sCSetFlattened )
					( Origin gBackEnd )
				)
			)
			( pinPair "@baseboard_fab2_lib.baseboard_fab2(sch_1):\PP6013\"
				( pinRef "@baseboard_fab2_lib.baseboard_fab2(sch_1):page30_i84:PE1_RX_DN(3)" )
				( pinRef "@baseboard_fab2_lib.baseboard_fab2(sch_1):page108_i258:IO78" )
				( attribute "PROPAGATION_DELAY_MIN" "3000.00 MIL"
					( Units "uMaxMinProp" "ns" 1.000000)
					( Status sCSetFlattened )
					( Origin gBackEnd )
				)
				( attribute "PROPAGATION_DELAY_MAX" "16000.00 MIL"
					( Units "uMaxMinProp" "ns" 1.000000)
					( Status sCSetFlattened )
					( Origin gBackEnd )
				)
				( attribute "RELATIVE_PROPAGATION_DELAY_SCOPE" "L"
					( Parent
						( matchGroupRef "@baseboard_fab2_lib.baseboard_fab2(sch_1):\MG_PCIE_ALL0\" )
					)
					( Status sCSetFlattened )
					( Origin gBackEnd )
				)
				( attribute "RELATIVE_PROPAGATION_DELAY" ",5.00 MIL"
					( Parent
						( matchGroupRef "@baseboard_fab2_lib.baseboard_fab2(sch_1):\MG_PCIE_ALL0\" )
					)
					( Units "uMatchProp" "ns" 1.000000)
					( Status sCSetFlattened )
					( Origin gBackEnd )
				)
			)
			( pinPair "@baseboard_fab2_lib.baseboard_fab2(sch_1):\PP149\"
				( pinRef "@baseboard_fab2_lib.baseboard_fab2(sch_1):page108_i258:IO76" )
				( pinRef "@baseboard_fab2_lib.baseboard_fab2(sch_1):page107_i469:A" )
				( attribute "RELATIVE_PROPAGATION_DELAY_SCOPE" "L"
					( Parent
						( matchGroupRef "@baseboard_fab2_lib.baseboard_fab2(sch_1):\MG_PCIE_L0\" )
					)
					( Status sCSetFlattened )
					( Origin gBackEnd )
				)
				( attribute "RELATIVE_PROPAGATION_DELAY" ",5.00 MIL"
					( Parent
						( matchGroupRef "@baseboard_fab2_lib.baseboard_fab2(sch_1):\MG_PCIE_L0\" )
					)
					( Units "uMatchProp" "ns" 1.000000)
					( Status sCSetFlattened )
					( Origin gBackEnd )
				)
			)
			( pinPair "@baseboard_fab2_lib.baseboard_fab2(sch_1):\PP150\"
				( pinRef "@baseboard_fab2_lib.baseboard_fab2(sch_1):page117_i9:PCIEUP_3_TXP" )
				( pinRef "@baseboard_fab2_lib.baseboard_fab2(sch_1):page107_i279:A" )
				( attribute "RELATIVE_PROPAGATION_DELAY_SCOPE" "L"
					( Parent
						( matchGroupRef "@baseboard_fab2_lib.baseboard_fab2(sch_1):\MG_PCIE_L1\" )
					)
					( Status sCSetFlattened )
					( Origin gBackEnd )
				)
				( attribute "RELATIVE_PROPAGATION_DELAY" ",5.00 MIL"
					( Parent
						( matchGroupRef "@baseboard_fab2_lib.baseboard_fab2(sch_1):\MG_PCIE_L1\" )
					)
					( Units "uMatchProp" "ns" 1.000000)
					( Status sCSetFlattened )
					( Origin gBackEnd )
				)
			)
			( pinPair "@baseboard_fab2_lib.baseboard_fab2(sch_1):\PP5934\"
				( pinRef "@baseboard_fab2_lib.baseboard_fab2(sch_1):page30_i84:PE1_RX_DP(3)" )
				( pinRef "@baseboard_fab2_lib.baseboard_fab2(sch_1):page107_i469:A" )
				( attribute "RELATIVE_PROPAGATION_DELAY_SCOPE" "L"
					( Parent
						( matchGroupRef "@baseboard_fab2_lib.baseboard_fab2(sch_1):\MG_PCIE_L2\" )
					)
					( Status sCSetFlattened )
					( Origin gBackEnd )
				)
				( attribute "RELATIVE_PROPAGATION_DELAY" ",5.00 MIL"
					( Parent
						( matchGroupRef "@baseboard_fab2_lib.baseboard_fab2(sch_1):\MG_PCIE_L2\" )
					)
					( Units "uMatchProp" "ns" 1.000000)
					( Status sCSetFlattened )
					( Origin gBackEnd )
				)
			)
			( pinPair "@baseboard_fab2_lib.baseboard_fab2(sch_1):\PP5935\"
				( pinRef "@baseboard_fab2_lib.baseboard_fab2(sch_1):page30_i84:PE1_RX_DP(3)" )
				( pinRef "@baseboard_fab2_lib.baseboard_fab2(sch_1):page117_i9:PCIEUP_3_TXP" )
				( attribute "PROPAGATION_DELAY_MIN" "3000.00 MIL"
					( Units "uMaxMinProp" "ns" 1.000000)
					( Status sCSetFlattened )
					( Origin gBackEnd )
				)
				( attribute "PROPAGATION_DELAY_MAX" "17000.00 MIL"
					( Units "uMaxMinProp" "ns" 1.000000)
					( Status sCSetFlattened )
					( Origin gBackEnd )
				)
				( attribute "RELATIVE_PROPAGATION_DELAY_SCOPE" "L"
					( Parent
						( matchGroupRef "@baseboard_fab2_lib.baseboard_fab2(sch_1):\MG_PCIE_ALL1\" )
					)
					( Status sCSetFlattened )
					( Origin gBackEnd )
				)
				( attribute "RELATIVE_PROPAGATION_DELAY" ",5.00 MIL"
					( Parent
						( matchGroupRef "@baseboard_fab2_lib.baseboard_fab2(sch_1):\MG_PCIE_ALL1\" )
					)
					( Units "uMatchProp" "ns" 1.000000)
					( Status sCSetFlattened )
					( Origin gBackEnd )
				)
			)
			( pinPair "@baseboard_fab2_lib.baseboard_fab2(sch_1):\PP5936\"
				( pinRef "@baseboard_fab2_lib.baseboard_fab2(sch_1):page30_i84:PE1_RX_DP(3)" )
				( pinRef "@baseboard_fab2_lib.baseboard_fab2(sch_1):page108_i258:IO76" )
				( attribute "PROPAGATION_DELAY_MIN" "3000.00 MIL"
					( Units "uMaxMinProp" "ns" 1.000000)
					( Status sCSetFlattened )
					( Origin gBackEnd )
				)
				( attribute "PROPAGATION_DELAY_MAX" "16000.00 MIL"
					( Units "uMaxMinProp" "ns" 1.000000)
					( Status sCSetFlattened )
					( Origin gBackEnd )
				)
				( attribute "RELATIVE_PROPAGATION_DELAY_SCOPE" "L"
					( Parent
						( matchGroupRef "@baseboard_fab2_lib.baseboard_fab2(sch_1):\MG_PCIE_ALL0\" )
					)
					( Status sCSetFlattened )
					( Origin gBackEnd )
				)
				( attribute "RELATIVE_PROPAGATION_DELAY" ",5.00 MIL"
					( Parent
						( matchGroupRef "@baseboard_fab2_lib.baseboard_fab2(sch_1):\MG_PCIE_ALL0\" )
					)
					( Units "uMatchProp" "ns" 1.000000)
					( Status sCSetFlattened )
					( Origin gBackEnd )
				)
			)
			( pinPair "@baseboard_fab2_lib.baseboard_fab2(sch_1):\PP151\"
				( pinRef "@baseboard_fab2_lib.baseboard_fab2(sch_1):page108_i258:IO84" )
				( pinRef "@baseboard_fab2_lib.baseboard_fab2(sch_1):page107_i461:A" )
				( attribute "RELATIVE_PROPAGATION_DELAY_SCOPE" "L"
					( Parent
						( matchGroupRef "@baseboard_fab2_lib.baseboard_fab2(sch_1):\MG_PCIE_L0\" )
					)
					( Status sCSetFlattened )
					( Origin gBackEnd )
				)
				( attribute "RELATIVE_PROPAGATION_DELAY" ",5.00 MIL"
					( Parent
						( matchGroupRef "@baseboard_fab2_lib.baseboard_fab2(sch_1):\MG_PCIE_L0\" )
					)
					( Units "uMatchProp" "ns" 1.000000)
					( Status sCSetFlattened )
					( Origin gBackEnd )
				)
			)
			( pinPair "@baseboard_fab2_lib.baseboard_fab2(sch_1):\PP152\"
				( pinRef "@baseboard_fab2_lib.baseboard_fab2(sch_1):page117_i9:PCIEUP_4_TXN" )
				( pinRef "@baseboard_fab2_lib.baseboard_fab2(sch_1):page107_i265:A" )
				( attribute "RELATIVE_PROPAGATION_DELAY_SCOPE" "L"
					( Parent
						( matchGroupRef "@baseboard_fab2_lib.baseboard_fab2(sch_1):\MG_PCIE_L1\" )
					)
					( Status sCSetFlattened )
					( Origin gBackEnd )
				)
				( attribute "RELATIVE_PROPAGATION_DELAY" ",5.00 MIL"
					( Parent
						( matchGroupRef "@baseboard_fab2_lib.baseboard_fab2(sch_1):\MG_PCIE_L1\" )
					)
					( Units "uMatchProp" "ns" 1.000000)
					( Status sCSetFlattened )
					( Origin gBackEnd )
				)
			)
			( pinPair "@baseboard_fab2_lib.baseboard_fab2(sch_1):\PP5921\"
				( pinRef "@baseboard_fab2_lib.baseboard_fab2(sch_1):page30_i84:PE1_RX_DN(4)" )
				( pinRef "@baseboard_fab2_lib.baseboard_fab2(sch_1):page107_i461:A" )
				( attribute "RELATIVE_PROPAGATION_DELAY_SCOPE" "L"
					( Parent
						( matchGroupRef "@baseboard_fab2_lib.baseboard_fab2(sch_1):\MG_PCIE_L2\" )
					)
					( Status sCSetFlattened )
					( Origin gBackEnd )
				)
				( attribute "RELATIVE_PROPAGATION_DELAY" ",5.00 MIL"
					( Parent
						( matchGroupRef "@baseboard_fab2_lib.baseboard_fab2(sch_1):\MG_PCIE_L2\" )
					)
					( Units "uMatchProp" "ns" 1.000000)
					( Status sCSetFlattened )
					( Origin gBackEnd )
				)
			)
			( pinPair "@baseboard_fab2_lib.baseboard_fab2(sch_1):\PP5922\"
				( pinRef "@baseboard_fab2_lib.baseboard_fab2(sch_1):page30_i84:PE1_RX_DN(4)" )
				( pinRef "@baseboard_fab2_lib.baseboard_fab2(sch_1):page117_i9:PCIEUP_4_TXN" )
				( attribute "PROPAGATION_DELAY_MIN" "3000.00 MIL"
					( Units "uMaxMinProp" "ns" 1.000000)
					( Status sCSetFlattened )
					( Origin gBackEnd )
				)
				( attribute "PROPAGATION_DELAY_MAX" "17000.00 MIL"
					( Units "uMaxMinProp" "ns" 1.000000)
					( Status sCSetFlattened )
					( Origin gBackEnd )
				)
				( attribute "RELATIVE_PROPAGATION_DELAY_SCOPE" "L"
					( Parent
						( matchGroupRef "@baseboard_fab2_lib.baseboard_fab2(sch_1):\MG_PCIE_ALL1\" )
					)
					( Status sCSetFlattened )
					( Origin gBackEnd )
				)
				( attribute "RELATIVE_PROPAGATION_DELAY" ",5.00 MIL"
					( Parent
						( matchGroupRef "@baseboard_fab2_lib.baseboard_fab2(sch_1):\MG_PCIE_ALL1\" )
					)
					( Units "uMatchProp" "ns" 1.000000)
					( Status sCSetFlattened )
					( Origin gBackEnd )
				)
			)
			( pinPair "@baseboard_fab2_lib.baseboard_fab2(sch_1):\PP5923\"
				( pinRef "@baseboard_fab2_lib.baseboard_fab2(sch_1):page30_i84:PE1_RX_DN(4)" )
				( pinRef "@baseboard_fab2_lib.baseboard_fab2(sch_1):page108_i258:IO84" )
				( attribute "PROPAGATION_DELAY_MIN" "3000.00 MIL"
					( Units "uMaxMinProp" "ns" 1.000000)
					( Status sCSetFlattened )
					( Origin gBackEnd )
				)
				( attribute "PROPAGATION_DELAY_MAX" "16000.00 MIL"
					( Units "uMaxMinProp" "ns" 1.000000)
					( Status sCSetFlattened )
					( Origin gBackEnd )
				)
				( attribute "RELATIVE_PROPAGATION_DELAY_SCOPE" "L"
					( Parent
						( matchGroupRef "@baseboard_fab2_lib.baseboard_fab2(sch_1):\MG_PCIE_ALL0\" )
					)
					( Status sCSetFlattened )
					( Origin gBackEnd )
				)
				( attribute "RELATIVE_PROPAGATION_DELAY" ",5.00 MIL"
					( Parent
						( matchGroupRef "@baseboard_fab2_lib.baseboard_fab2(sch_1):\MG_PCIE_ALL0\" )
					)
					( Units "uMatchProp" "ns" 1.000000)
					( Status sCSetFlattened )
					( Origin gBackEnd )
				)
			)
			( pinPair "@baseboard_fab2_lib.baseboard_fab2(sch_1):\PP153\"
				( pinRef "@baseboard_fab2_lib.baseboard_fab2(sch_1):page108_i258:IO82" )
				( pinRef "@baseboard_fab2_lib.baseboard_fab2(sch_1):page107_i470:A" )
				( attribute "RELATIVE_PROPAGATION_DELAY_SCOPE" "L"
					( Parent
						( matchGroupRef "@baseboard_fab2_lib.baseboard_fab2(sch_1):\MG_PCIE_L0\" )
					)
					( Status sCSetFlattened )
					( Origin gBackEnd )
				)
				( attribute "RELATIVE_PROPAGATION_DELAY" ",5.00 MIL"
					( Parent
						( matchGroupRef "@baseboard_fab2_lib.baseboard_fab2(sch_1):\MG_PCIE_L0\" )
					)
					( Units "uMatchProp" "ns" 1.000000)
					( Status sCSetFlattened )
					( Origin gBackEnd )
				)
			)
			( pinPair "@baseboard_fab2_lib.baseboard_fab2(sch_1):\PP154\"
				( pinRef "@baseboard_fab2_lib.baseboard_fab2(sch_1):page117_i9:PCIEUP_4_TXP" )
				( pinRef "@baseboard_fab2_lib.baseboard_fab2(sch_1):page107_i278:A" )
				( attribute "RELATIVE_PROPAGATION_DELAY_SCOPE" "L"
					( Parent
						( matchGroupRef "@baseboard_fab2_lib.baseboard_fab2(sch_1):\MG_PCIE_L1\" )
					)
					( Status sCSetFlattened )
					( Origin gBackEnd )
				)
				( attribute "RELATIVE_PROPAGATION_DELAY" ",5.00 MIL"
					( Parent
						( matchGroupRef "@baseboard_fab2_lib.baseboard_fab2(sch_1):\MG_PCIE_L1\" )
					)
					( Units "uMatchProp" "ns" 1.000000)
					( Status sCSetFlattened )
					( Origin gBackEnd )
				)
			)
			( pinPair "@baseboard_fab2_lib.baseboard_fab2(sch_1):\PP5984\"
				( pinRef "@baseboard_fab2_lib.baseboard_fab2(sch_1):page30_i84:PE1_RX_DP(4)" )
				( pinRef "@baseboard_fab2_lib.baseboard_fab2(sch_1):page107_i470:A" )
				( attribute "RELATIVE_PROPAGATION_DELAY_SCOPE" "L"
					( Parent
						( matchGroupRef "@baseboard_fab2_lib.baseboard_fab2(sch_1):\MG_PCIE_L2\" )
					)
					( Status sCSetFlattened )
					( Origin gBackEnd )
				)
				( attribute "RELATIVE_PROPAGATION_DELAY" ",5.00 MIL"
					( Parent
						( matchGroupRef "@baseboard_fab2_lib.baseboard_fab2(sch_1):\MG_PCIE_L2\" )
					)
					( Units "uMatchProp" "ns" 1.000000)
					( Status sCSetFlattened )
					( Origin gBackEnd )
				)
			)
			( pinPair "@baseboard_fab2_lib.baseboard_fab2(sch_1):\PP5985\"
				( pinRef "@baseboard_fab2_lib.baseboard_fab2(sch_1):page30_i84:PE1_RX_DP(4)" )
				( pinRef "@baseboard_fab2_lib.baseboard_fab2(sch_1):page117_i9:PCIEUP_4_TXP" )
				( attribute "PROPAGATION_DELAY_MIN" "3000.00 MIL"
					( Units "uMaxMinProp" "ns" 1.000000)
					( Status sCSetFlattened )
					( Origin gBackEnd )
				)
				( attribute "PROPAGATION_DELAY_MAX" "17000.00 MIL"
					( Units "uMaxMinProp" "ns" 1.000000)
					( Status sCSetFlattened )
					( Origin gBackEnd )
				)
				( attribute "RELATIVE_PROPAGATION_DELAY_SCOPE" "L"
					( Parent
						( matchGroupRef "@baseboard_fab2_lib.baseboard_fab2(sch_1):\MG_PCIE_ALL1\" )
					)
					( Status sCSetFlattened )
					( Origin gBackEnd )
				)
				( attribute "RELATIVE_PROPAGATION_DELAY" ",5.00 MIL"
					( Parent
						( matchGroupRef "@baseboard_fab2_lib.baseboard_fab2(sch_1):\MG_PCIE_ALL1\" )
					)
					( Units "uMatchProp" "ns" 1.000000)
					( Status sCSetFlattened )
					( Origin gBackEnd )
				)
			)
			( pinPair "@baseboard_fab2_lib.baseboard_fab2(sch_1):\PP5986\"
				( pinRef "@baseboard_fab2_lib.baseboard_fab2(sch_1):page30_i84:PE1_RX_DP(4)" )
				( pinRef "@baseboard_fab2_lib.baseboard_fab2(sch_1):page108_i258:IO82" )
				( attribute "PROPAGATION_DELAY_MIN" "3000.00 MIL"
					( Units "uMaxMinProp" "ns" 1.000000)
					( Status sCSetFlattened )
					( Origin gBackEnd )
				)
				( attribute "PROPAGATION_DELAY_MAX" "16000.00 MIL"
					( Units "uMaxMinProp" "ns" 1.000000)
					( Status sCSetFlattened )
					( Origin gBackEnd )
				)
				( attribute "RELATIVE_PROPAGATION_DELAY_SCOPE" "L"
					( Parent
						( matchGroupRef "@baseboard_fab2_lib.baseboard_fab2(sch_1):\MG_PCIE_ALL0\" )
					)
					( Status sCSetFlattened )
					( Origin gBackEnd )
				)
				( attribute "RELATIVE_PROPAGATION_DELAY" ",5.00 MIL"
					( Parent
						( matchGroupRef "@baseboard_fab2_lib.baseboard_fab2(sch_1):\MG_PCIE_ALL0\" )
					)
					( Units "uMatchProp" "ns" 1.000000)
					( Status sCSetFlattened )
					( Origin gBackEnd )
				)
			)
			( pinPair "@baseboard_fab2_lib.baseboard_fab2(sch_1):\PP155\"
				( pinRef "@baseboard_fab2_lib.baseboard_fab2(sch_1):page108_i258:IO90" )
				( pinRef "@baseboard_fab2_lib.baseboard_fab2(sch_1):page107_i460:A" )
				( attribute "RELATIVE_PROPAGATION_DELAY_SCOPE" "L"
					( Parent
						( matchGroupRef "@baseboard_fab2_lib.baseboard_fab2(sch_1):\MG_PCIE_L0\" )
					)
					( Status sCSetFlattened )
					( Origin gBackEnd )
				)
				( attribute "RELATIVE_PROPAGATION_DELAY" ",5.00 MIL"
					( Parent
						( matchGroupRef "@baseboard_fab2_lib.baseboard_fab2(sch_1):\MG_PCIE_L0\" )
					)
					( Units "uMatchProp" "ns" 1.000000)
					( Status sCSetFlattened )
					( Origin gBackEnd )
				)
			)
			( pinPair "@baseboard_fab2_lib.baseboard_fab2(sch_1):\PP156\"
				( pinRef "@baseboard_fab2_lib.baseboard_fab2(sch_1):page117_i9:PCIEUP_5_TXN" )
				( pinRef "@baseboard_fab2_lib.baseboard_fab2(sch_1):page107_i287:A" )
				( attribute "RELATIVE_PROPAGATION_DELAY_SCOPE" "L"
					( Parent
						( matchGroupRef "@baseboard_fab2_lib.baseboard_fab2(sch_1):\MG_PCIE_L1\" )
					)
					( Status sCSetFlattened )
					( Origin gBackEnd )
				)
				( attribute "RELATIVE_PROPAGATION_DELAY" ",5.00 MIL"
					( Parent
						( matchGroupRef "@baseboard_fab2_lib.baseboard_fab2(sch_1):\MG_PCIE_L1\" )
					)
					( Units "uMatchProp" "ns" 1.000000)
					( Status sCSetFlattened )
					( Origin gBackEnd )
				)
			)
			( pinPair "@baseboard_fab2_lib.baseboard_fab2(sch_1):\PP6000\"
				( pinRef "@baseboard_fab2_lib.baseboard_fab2(sch_1):page30_i84:PE1_RX_DN(5)" )
				( pinRef "@baseboard_fab2_lib.baseboard_fab2(sch_1):page107_i460:A" )
				( attribute "RELATIVE_PROPAGATION_DELAY_SCOPE" "L"
					( Parent
						( matchGroupRef "@baseboard_fab2_lib.baseboard_fab2(sch_1):\MG_PCIE_L2\" )
					)
					( Status sCSetFlattened )
					( Origin gBackEnd )
				)
				( attribute "RELATIVE_PROPAGATION_DELAY" ",5.00 MIL"
					( Parent
						( matchGroupRef "@baseboard_fab2_lib.baseboard_fab2(sch_1):\MG_PCIE_L2\" )
					)
					( Units "uMatchProp" "ns" 1.000000)
					( Status sCSetFlattened )
					( Origin gBackEnd )
				)
			)
			( pinPair "@baseboard_fab2_lib.baseboard_fab2(sch_1):\PP6001\"
				( pinRef "@baseboard_fab2_lib.baseboard_fab2(sch_1):page30_i84:PE1_RX_DN(5)" )
				( pinRef "@baseboard_fab2_lib.baseboard_fab2(sch_1):page117_i9:PCIEUP_5_TXN" )
				( attribute "PROPAGATION_DELAY_MIN" "3000.00 MIL"
					( Units "uMaxMinProp" "ns" 1.000000)
					( Status sCSetFlattened )
					( Origin gBackEnd )
				)
				( attribute "PROPAGATION_DELAY_MAX" "17000.00 MIL"
					( Units "uMaxMinProp" "ns" 1.000000)
					( Status sCSetFlattened )
					( Origin gBackEnd )
				)
				( attribute "RELATIVE_PROPAGATION_DELAY_SCOPE" "L"
					( Parent
						( matchGroupRef "@baseboard_fab2_lib.baseboard_fab2(sch_1):\MG_PCIE_ALL1\" )
					)
					( Status sCSetFlattened )
					( Origin gBackEnd )
				)
				( attribute "RELATIVE_PROPAGATION_DELAY" ",5.00 MIL"
					( Parent
						( matchGroupRef "@baseboard_fab2_lib.baseboard_fab2(sch_1):\MG_PCIE_ALL1\" )
					)
					( Units "uMatchProp" "ns" 1.000000)
					( Status sCSetFlattened )
					( Origin gBackEnd )
				)
			)
			( pinPair "@baseboard_fab2_lib.baseboard_fab2(sch_1):\PP6002\"
				( pinRef "@baseboard_fab2_lib.baseboard_fab2(sch_1):page30_i84:PE1_RX_DN(5)" )
				( pinRef "@baseboard_fab2_lib.baseboard_fab2(sch_1):page108_i258:IO90" )
				( attribute "PROPAGATION_DELAY_MIN" "3000.00 MIL"
					( Units "uMaxMinProp" "ns" 1.000000)
					( Status sCSetFlattened )
					( Origin gBackEnd )
				)
				( attribute "PROPAGATION_DELAY_MAX" "16000.00 MIL"
					( Units "uMaxMinProp" "ns" 1.000000)
					( Status sCSetFlattened )
					( Origin gBackEnd )
				)
				( attribute "RELATIVE_PROPAGATION_DELAY_SCOPE" "L"
					( Parent
						( matchGroupRef "@baseboard_fab2_lib.baseboard_fab2(sch_1):\MG_PCIE_ALL0\" )
					)
					( Status sCSetFlattened )
					( Origin gBackEnd )
				)
				( attribute "RELATIVE_PROPAGATION_DELAY" ",5.00 MIL"
					( Parent
						( matchGroupRef "@baseboard_fab2_lib.baseboard_fab2(sch_1):\MG_PCIE_ALL0\" )
					)
					( Units "uMatchProp" "ns" 1.000000)
					( Status sCSetFlattened )
					( Origin gBackEnd )
				)
			)
			( pinPair "@baseboard_fab2_lib.baseboard_fab2(sch_1):\PP157\"
				( pinRef "@baseboard_fab2_lib.baseboard_fab2(sch_1):page108_i258:IO88" )
				( pinRef "@baseboard_fab2_lib.baseboard_fab2(sch_1):page107_i471:A" )
				( attribute "RELATIVE_PROPAGATION_DELAY_SCOPE" "L"
					( Parent
						( matchGroupRef "@baseboard_fab2_lib.baseboard_fab2(sch_1):\MG_PCIE_L0\" )
					)
					( Status sCSetFlattened )
					( Origin gBackEnd )
				)
				( attribute "RELATIVE_PROPAGATION_DELAY" ",5.00 MIL"
					( Parent
						( matchGroupRef "@baseboard_fab2_lib.baseboard_fab2(sch_1):\MG_PCIE_L0\" )
					)
					( Units "uMatchProp" "ns" 1.000000)
					( Status sCSetFlattened )
					( Origin gBackEnd )
				)
			)
			( pinPair "@baseboard_fab2_lib.baseboard_fab2(sch_1):\PP158\"
				( pinRef "@baseboard_fab2_lib.baseboard_fab2(sch_1):page117_i9:PCIEUP_5_TXP" )
				( pinRef "@baseboard_fab2_lib.baseboard_fab2(sch_1):page107_i297:A" )
				( attribute "RELATIVE_PROPAGATION_DELAY_SCOPE" "L"
					( Parent
						( matchGroupRef "@baseboard_fab2_lib.baseboard_fab2(sch_1):\MG_PCIE_L1\" )
					)
					( Status sCSetFlattened )
					( Origin gBackEnd )
				)
				( attribute "RELATIVE_PROPAGATION_DELAY" ",5.00 MIL"
					( Parent
						( matchGroupRef "@baseboard_fab2_lib.baseboard_fab2(sch_1):\MG_PCIE_L1\" )
					)
					( Units "uMatchProp" "ns" 1.000000)
					( Status sCSetFlattened )
					( Origin gBackEnd )
				)
			)
			( pinPair "@baseboard_fab2_lib.baseboard_fab2(sch_1):\PP6006\"
				( pinRef "@baseboard_fab2_lib.baseboard_fab2(sch_1):page30_i84:PE1_RX_DP(5)" )
				( pinRef "@baseboard_fab2_lib.baseboard_fab2(sch_1):page107_i471:A" )
				( attribute "RELATIVE_PROPAGATION_DELAY_SCOPE" "L"
					( Parent
						( matchGroupRef "@baseboard_fab2_lib.baseboard_fab2(sch_1):\MG_PCIE_L2\" )
					)
					( Status sCSetFlattened )
					( Origin gBackEnd )
				)
				( attribute "RELATIVE_PROPAGATION_DELAY" ",5.00 MIL"
					( Parent
						( matchGroupRef "@baseboard_fab2_lib.baseboard_fab2(sch_1):\MG_PCIE_L2\" )
					)
					( Units "uMatchProp" "ns" 1.000000)
					( Status sCSetFlattened )
					( Origin gBackEnd )
				)
			)
			( pinPair "@baseboard_fab2_lib.baseboard_fab2(sch_1):\PP6007\"
				( pinRef "@baseboard_fab2_lib.baseboard_fab2(sch_1):page30_i84:PE1_RX_DP(5)" )
				( pinRef "@baseboard_fab2_lib.baseboard_fab2(sch_1):page117_i9:PCIEUP_5_TXP" )
				( attribute "PROPAGATION_DELAY_MIN" "3000.00 MIL"
					( Units "uMaxMinProp" "ns" 1.000000)
					( Status sCSetFlattened )
					( Origin gBackEnd )
				)
				( attribute "PROPAGATION_DELAY_MAX" "17000.00 MIL"
					( Units "uMaxMinProp" "ns" 1.000000)
					( Status sCSetFlattened )
					( Origin gBackEnd )
				)
				( attribute "RELATIVE_PROPAGATION_DELAY_SCOPE" "L"
					( Parent
						( matchGroupRef "@baseboard_fab2_lib.baseboard_fab2(sch_1):\MG_PCIE_ALL1\" )
					)
					( Status sCSetFlattened )
					( Origin gBackEnd )
				)
				( attribute "RELATIVE_PROPAGATION_DELAY" ",5.00 MIL"
					( Parent
						( matchGroupRef "@baseboard_fab2_lib.baseboard_fab2(sch_1):\MG_PCIE_ALL1\" )
					)
					( Units "uMatchProp" "ns" 1.000000)
					( Status sCSetFlattened )
					( Origin gBackEnd )
				)
			)
			( pinPair "@baseboard_fab2_lib.baseboard_fab2(sch_1):\PP6008\"
				( pinRef "@baseboard_fab2_lib.baseboard_fab2(sch_1):page30_i84:PE1_RX_DP(5)" )
				( pinRef "@baseboard_fab2_lib.baseboard_fab2(sch_1):page108_i258:IO88" )
				( attribute "PROPAGATION_DELAY_MIN" "3000.00 MIL"
					( Units "uMaxMinProp" "ns" 1.000000)
					( Status sCSetFlattened )
					( Origin gBackEnd )
				)
				( attribute "PROPAGATION_DELAY_MAX" "16000.00 MIL"
					( Units "uMaxMinProp" "ns" 1.000000)
					( Status sCSetFlattened )
					( Origin gBackEnd )
				)
				( attribute "RELATIVE_PROPAGATION_DELAY_SCOPE" "L"
					( Parent
						( matchGroupRef "@baseboard_fab2_lib.baseboard_fab2(sch_1):\MG_PCIE_ALL0\" )
					)
					( Status sCSetFlattened )
					( Origin gBackEnd )
				)
				( attribute "RELATIVE_PROPAGATION_DELAY" ",5.00 MIL"
					( Parent
						( matchGroupRef "@baseboard_fab2_lib.baseboard_fab2(sch_1):\MG_PCIE_ALL0\" )
					)
					( Units "uMatchProp" "ns" 1.000000)
					( Status sCSetFlattened )
					( Origin gBackEnd )
				)
			)
			( pinPair "@baseboard_fab2_lib.baseboard_fab2(sch_1):\PP159\"
				( pinRef "@baseboard_fab2_lib.baseboard_fab2(sch_1):page108_i258:IO96" )
				( pinRef "@baseboard_fab2_lib.baseboard_fab2(sch_1):page107_i459:A" )
				( attribute "RELATIVE_PROPAGATION_DELAY_SCOPE" "L"
					( Parent
						( matchGroupRef "@baseboard_fab2_lib.baseboard_fab2(sch_1):\MG_PCIE_L0\" )
					)
					( Status sCSetFlattened )
					( Origin gBackEnd )
				)
				( attribute "RELATIVE_PROPAGATION_DELAY" ",5.00 MIL"
					( Parent
						( matchGroupRef "@baseboard_fab2_lib.baseboard_fab2(sch_1):\MG_PCIE_L0\" )
					)
					( Units "uMatchProp" "ns" 1.000000)
					( Status sCSetFlattened )
					( Origin gBackEnd )
				)
			)
			( pinPair "@baseboard_fab2_lib.baseboard_fab2(sch_1):\PP160\"
				( pinRef "@baseboard_fab2_lib.baseboard_fab2(sch_1):page117_i9:PCIEUP_6_TXN" )
				( pinRef "@baseboard_fab2_lib.baseboard_fab2(sch_1):page107_i286:A" )
				( attribute "RELATIVE_PROPAGATION_DELAY_SCOPE" "L"
					( Parent
						( matchGroupRef "@baseboard_fab2_lib.baseboard_fab2(sch_1):\MG_PCIE_L1\" )
					)
					( Status sCSetFlattened )
					( Origin gBackEnd )
				)
				( attribute "RELATIVE_PROPAGATION_DELAY" ",5.00 MIL"
					( Parent
						( matchGroupRef "@baseboard_fab2_lib.baseboard_fab2(sch_1):\MG_PCIE_L1\" )
					)
					( Units "uMatchProp" "ns" 1.000000)
					( Status sCSetFlattened )
					( Origin gBackEnd )
				)
			)
			( pinPair "@baseboard_fab2_lib.baseboard_fab2(sch_1):\PP6003\"
				( pinRef "@baseboard_fab2_lib.baseboard_fab2(sch_1):page30_i84:PE1_RX_DN(6)" )
				( pinRef "@baseboard_fab2_lib.baseboard_fab2(sch_1):page107_i459:A" )
				( attribute "RELATIVE_PROPAGATION_DELAY_SCOPE" "L"
					( Parent
						( matchGroupRef "@baseboard_fab2_lib.baseboard_fab2(sch_1):\MG_PCIE_L2\" )
					)
					( Status sCSetFlattened )
					( Origin gBackEnd )
				)
				( attribute "RELATIVE_PROPAGATION_DELAY" ",5.00 MIL"
					( Parent
						( matchGroupRef "@baseboard_fab2_lib.baseboard_fab2(sch_1):\MG_PCIE_L2\" )
					)
					( Units "uMatchProp" "ns" 1.000000)
					( Status sCSetFlattened )
					( Origin gBackEnd )
				)
			)
			( pinPair "@baseboard_fab2_lib.baseboard_fab2(sch_1):\PP6004\"
				( pinRef "@baseboard_fab2_lib.baseboard_fab2(sch_1):page30_i84:PE1_RX_DN(6)" )
				( pinRef "@baseboard_fab2_lib.baseboard_fab2(sch_1):page117_i9:PCIEUP_6_TXN" )
				( attribute "PROPAGATION_DELAY_MIN" "3000.00 MIL"
					( Units "uMaxMinProp" "ns" 1.000000)
					( Status sCSetFlattened )
					( Origin gBackEnd )
				)
				( attribute "PROPAGATION_DELAY_MAX" "17000.00 MIL"
					( Units "uMaxMinProp" "ns" 1.000000)
					( Status sCSetFlattened )
					( Origin gBackEnd )
				)
				( attribute "RELATIVE_PROPAGATION_DELAY_SCOPE" "L"
					( Parent
						( matchGroupRef "@baseboard_fab2_lib.baseboard_fab2(sch_1):\MG_PCIE_ALL1\" )
					)
					( Status sCSetFlattened )
					( Origin gBackEnd )
				)
				( attribute "RELATIVE_PROPAGATION_DELAY" ",5.00 MIL"
					( Parent
						( matchGroupRef "@baseboard_fab2_lib.baseboard_fab2(sch_1):\MG_PCIE_ALL1\" )
					)
					( Units "uMatchProp" "ns" 1.000000)
					( Status sCSetFlattened )
					( Origin gBackEnd )
				)
			)
			( pinPair "@baseboard_fab2_lib.baseboard_fab2(sch_1):\PP6005\"
				( pinRef "@baseboard_fab2_lib.baseboard_fab2(sch_1):page30_i84:PE1_RX_DN(6)" )
				( pinRef "@baseboard_fab2_lib.baseboard_fab2(sch_1):page108_i258:IO96" )
				( attribute "PROPAGATION_DELAY_MIN" "3000.00 MIL"
					( Units "uMaxMinProp" "ns" 1.000000)
					( Status sCSetFlattened )
					( Origin gBackEnd )
				)
				( attribute "PROPAGATION_DELAY_MAX" "16000.00 MIL"
					( Units "uMaxMinProp" "ns" 1.000000)
					( Status sCSetFlattened )
					( Origin gBackEnd )
				)
				( attribute "RELATIVE_PROPAGATION_DELAY_SCOPE" "L"
					( Parent
						( matchGroupRef "@baseboard_fab2_lib.baseboard_fab2(sch_1):\MG_PCIE_ALL0\" )
					)
					( Status sCSetFlattened )
					( Origin gBackEnd )
				)
				( attribute "RELATIVE_PROPAGATION_DELAY" ",5.00 MIL"
					( Parent
						( matchGroupRef "@baseboard_fab2_lib.baseboard_fab2(sch_1):\MG_PCIE_ALL0\" )
					)
					( Units "uMatchProp" "ns" 1.000000)
					( Status sCSetFlattened )
					( Origin gBackEnd )
				)
			)
			( pinPair "@baseboard_fab2_lib.baseboard_fab2(sch_1):\PP161\"
				( pinRef "@baseboard_fab2_lib.baseboard_fab2(sch_1):page108_i258:IO94" )
				( pinRef "@baseboard_fab2_lib.baseboard_fab2(sch_1):page107_i472:A" )
				( attribute "RELATIVE_PROPAGATION_DELAY_SCOPE" "L"
					( Parent
						( matchGroupRef "@baseboard_fab2_lib.baseboard_fab2(sch_1):\MG_PCIE_L0\" )
					)
					( Status sCSetFlattened )
					( Origin gBackEnd )
				)
				( attribute "RELATIVE_PROPAGATION_DELAY" ",5.00 MIL"
					( Parent
						( matchGroupRef "@baseboard_fab2_lib.baseboard_fab2(sch_1):\MG_PCIE_L0\" )
					)
					( Units "uMatchProp" "ns" 1.000000)
					( Status sCSetFlattened )
					( Origin gBackEnd )
				)
			)
			( pinPair "@baseboard_fab2_lib.baseboard_fab2(sch_1):\PP162\"
				( pinRef "@baseboard_fab2_lib.baseboard_fab2(sch_1):page117_i9:PCIEUP_6_TXP" )
				( pinRef "@baseboard_fab2_lib.baseboard_fab2(sch_1):page107_i296:A" )
				( attribute "RELATIVE_PROPAGATION_DELAY_SCOPE" "L"
					( Parent
						( matchGroupRef "@baseboard_fab2_lib.baseboard_fab2(sch_1):\MG_PCIE_L1\" )
					)
					( Status sCSetFlattened )
					( Origin gBackEnd )
				)
				( attribute "RELATIVE_PROPAGATION_DELAY" ",5.00 MIL"
					( Parent
						( matchGroupRef "@baseboard_fab2_lib.baseboard_fab2(sch_1):\MG_PCIE_L1\" )
					)
					( Units "uMatchProp" "ns" 1.000000)
					( Status sCSetFlattened )
					( Origin gBackEnd )
				)
			)
			( pinPair "@baseboard_fab2_lib.baseboard_fab2(sch_1):\PP5997\"
				( pinRef "@baseboard_fab2_lib.baseboard_fab2(sch_1):page30_i84:PE1_RX_DP(6)" )
				( pinRef "@baseboard_fab2_lib.baseboard_fab2(sch_1):page107_i472:A" )
				( attribute "RELATIVE_PROPAGATION_DELAY_SCOPE" "L"
					( Parent
						( matchGroupRef "@baseboard_fab2_lib.baseboard_fab2(sch_1):\MG_PCIE_L2\" )
					)
					( Status sCSetFlattened )
					( Origin gBackEnd )
				)
				( attribute "RELATIVE_PROPAGATION_DELAY" ",5.00 MIL"
					( Parent
						( matchGroupRef "@baseboard_fab2_lib.baseboard_fab2(sch_1):\MG_PCIE_L2\" )
					)
					( Units "uMatchProp" "ns" 1.000000)
					( Status sCSetFlattened )
					( Origin gBackEnd )
				)
			)
			( pinPair "@baseboard_fab2_lib.baseboard_fab2(sch_1):\PP5998\"
				( pinRef "@baseboard_fab2_lib.baseboard_fab2(sch_1):page30_i84:PE1_RX_DP(6)" )
				( pinRef "@baseboard_fab2_lib.baseboard_fab2(sch_1):page117_i9:PCIEUP_6_TXP" )
				( attribute "PROPAGATION_DELAY_MIN" "3000.00 MIL"
					( Units "uMaxMinProp" "ns" 1.000000)
					( Status sCSetFlattened )
					( Origin gBackEnd )
				)
				( attribute "PROPAGATION_DELAY_MAX" "17000.00 MIL"
					( Units "uMaxMinProp" "ns" 1.000000)
					( Status sCSetFlattened )
					( Origin gBackEnd )
				)
				( attribute "RELATIVE_PROPAGATION_DELAY_SCOPE" "L"
					( Parent
						( matchGroupRef "@baseboard_fab2_lib.baseboard_fab2(sch_1):\MG_PCIE_ALL1\" )
					)
					( Status sCSetFlattened )
					( Origin gBackEnd )
				)
				( attribute "RELATIVE_PROPAGATION_DELAY" ",5.00 MIL"
					( Parent
						( matchGroupRef "@baseboard_fab2_lib.baseboard_fab2(sch_1):\MG_PCIE_ALL1\" )
					)
					( Units "uMatchProp" "ns" 1.000000)
					( Status sCSetFlattened )
					( Origin gBackEnd )
				)
			)
			( pinPair "@baseboard_fab2_lib.baseboard_fab2(sch_1):\PP5999\"
				( pinRef "@baseboard_fab2_lib.baseboard_fab2(sch_1):page30_i84:PE1_RX_DP(6)" )
				( pinRef "@baseboard_fab2_lib.baseboard_fab2(sch_1):page108_i258:IO94" )
				( attribute "PROPAGATION_DELAY_MIN" "3000.00 MIL"
					( Units "uMaxMinProp" "ns" 1.000000)
					( Status sCSetFlattened )
					( Origin gBackEnd )
				)
				( attribute "PROPAGATION_DELAY_MAX" "16000.00 MIL"
					( Units "uMaxMinProp" "ns" 1.000000)
					( Status sCSetFlattened )
					( Origin gBackEnd )
				)
				( attribute "RELATIVE_PROPAGATION_DELAY_SCOPE" "L"
					( Parent
						( matchGroupRef "@baseboard_fab2_lib.baseboard_fab2(sch_1):\MG_PCIE_ALL0\" )
					)
					( Status sCSetFlattened )
					( Origin gBackEnd )
				)
				( attribute "RELATIVE_PROPAGATION_DELAY" ",5.00 MIL"
					( Parent
						( matchGroupRef "@baseboard_fab2_lib.baseboard_fab2(sch_1):\MG_PCIE_ALL0\" )
					)
					( Units "uMatchProp" "ns" 1.000000)
					( Status sCSetFlattened )
					( Origin gBackEnd )
				)
			)
			( pinPair "@baseboard_fab2_lib.baseboard_fab2(sch_1):\PP3001\"
				( pinRef "@baseboard_fab2_lib.baseboard_fab2(sch_1):page117_i9:PCIEUP_8_TXN" )
				( pinRef "@baseboard_fab2_lib.baseboard_fab2(sch_1):page105_i217:A" )
				( attribute "RELATIVE_PROPAGATION_DELAY_SCOPE" "L"
					( Parent
						( matchGroupRef "@baseboard_fab2_lib.baseboard_fab2(sch_1):\MG_PCIE_L1\" )
					)
					( Status sCSetFlattened )
					( Origin gBackEnd )
				)
				( attribute "RELATIVE_PROPAGATION_DELAY" ",5.00 MIL"
					( Parent
						( matchGroupRef "@baseboard_fab2_lib.baseboard_fab2(sch_1):\MG_PCIE_L1\" )
					)
					( Units "uMatchProp" "ns" 1.000000)
					( Status sCSetFlattened )
					( Origin gBackEnd )
				)
			)
			( pinPair "@baseboard_fab2_lib.baseboard_fab2(sch_1):\PP3002\"
				( pinRef "@baseboard_fab2_lib.baseboard_fab2(sch_1):page105_i217:B" )
				( pinRef "@baseboard_fab2_lib.baseboard_fab2(sch_1):page30_i84:PE1_RX_DN(8)" )
				( attribute "RELATIVE_PROPAGATION_DELAY_SCOPE" "L"
					( Parent
						( matchGroupRef "@baseboard_fab2_lib.baseboard_fab2(sch_1):\MG_PCIE_L0\" )
					)
					( Status sCSetFlattened )
					( Origin gBackEnd )
				)
				( attribute "RELATIVE_PROPAGATION_DELAY" ",5.00 MIL"
					( Parent
						( matchGroupRef "@baseboard_fab2_lib.baseboard_fab2(sch_1):\MG_PCIE_L0\" )
					)
					( Units "uMatchProp" "ns" 1.000000)
					( Status sCSetFlattened )
					( Origin gBackEnd )
				)
			)
			( pinPair "@baseboard_fab2_lib.baseboard_fab2(sch_1):\PP5829\"
				( pinRef "@baseboard_fab2_lib.baseboard_fab2(sch_1):page117_i9:PCIEUP_8_TXN" )
				( pinRef "@baseboard_fab2_lib.baseboard_fab2(sch_1):page30_i84:PE1_RX_DN(8)" )
				( attribute "PROPAGATION_DELAY_MIN" "3000.00 MIL"
					( Units "uMaxMinProp" "ns" 1.000000)
					( Status sCSetFlattened )
					( Origin gBackEnd )
				)
				( attribute "PROPAGATION_DELAY_MAX" "17000.00 MIL"
					( Units "uMaxMinProp" "ns" 1.000000)
					( Status sCSetFlattened )
					( Origin gBackEnd )
				)
				( attribute "RELATIVE_PROPAGATION_DELAY_SCOPE" "G"
					( Parent
						( matchGroupRef "@baseboard_fab2_lib.baseboard_fab2(sch_1):\MG_P3E_CPU0_PE1_PCH_PCIEUP_RX0809\" )
					)
					( Status sCSetFlattened )
					( Origin gBackEnd )
				)
				( attribute "RELATIVE_PROPAGATION_DELAY" ",500.00 MIL"
					( Parent
						( matchGroupRef "@baseboard_fab2_lib.baseboard_fab2(sch_1):\MG_P3E_CPU0_PE1_PCH_PCIEUP_RX0809\" )
					)
					( Units "uMatchProp" "ns" 1.000000)
					( Status sCSetFlattened )
					( Origin gBackEnd )
				)
			)
			( pinPair "@baseboard_fab2_lib.baseboard_fab2(sch_1):\PP2999\"
				( pinRef "@baseboard_fab2_lib.baseboard_fab2(sch_1):page117_i9:PCIEUP_8_TXP" )
				( pinRef "@baseboard_fab2_lib.baseboard_fab2(sch_1):page105_i206:A" )
				( attribute "RELATIVE_PROPAGATION_DELAY_SCOPE" "L"
					( Parent
						( matchGroupRef "@baseboard_fab2_lib.baseboard_fab2(sch_1):\MG_PCIE_L1\" )
					)
					( Status sCSetFlattened )
					( Origin gBackEnd )
				)
				( attribute "RELATIVE_PROPAGATION_DELAY" ",5.00 MIL"
					( Parent
						( matchGroupRef "@baseboard_fab2_lib.baseboard_fab2(sch_1):\MG_PCIE_L1\" )
					)
					( Units "uMatchProp" "ns" 1.000000)
					( Status sCSetFlattened )
					( Origin gBackEnd )
				)
			)
			( pinPair "@baseboard_fab2_lib.baseboard_fab2(sch_1):\PP3000\"
				( pinRef "@baseboard_fab2_lib.baseboard_fab2(sch_1):page105_i206:B" )
				( pinRef "@baseboard_fab2_lib.baseboard_fab2(sch_1):page30_i84:PE1_RX_DP(8)" )
				( attribute "RELATIVE_PROPAGATION_DELAY_SCOPE" "L"
					( Parent
						( matchGroupRef "@baseboard_fab2_lib.baseboard_fab2(sch_1):\MG_PCIE_L0\" )
					)
					( Status sCSetFlattened )
					( Origin gBackEnd )
				)
				( attribute "RELATIVE_PROPAGATION_DELAY" ",5.00 MIL"
					( Parent
						( matchGroupRef "@baseboard_fab2_lib.baseboard_fab2(sch_1):\MG_PCIE_L0\" )
					)
					( Units "uMatchProp" "ns" 1.000000)
					( Status sCSetFlattened )
					( Origin gBackEnd )
				)
			)
			( pinPair "@baseboard_fab2_lib.baseboard_fab2(sch_1):\PP5836\"
				( pinRef "@baseboard_fab2_lib.baseboard_fab2(sch_1):page117_i9:PCIEUP_8_TXP" )
				( pinRef "@baseboard_fab2_lib.baseboard_fab2(sch_1):page30_i84:PE1_RX_DP(8)" )
				( attribute "PROPAGATION_DELAY_MIN" "3000.00 MIL"
					( Units "uMaxMinProp" "ns" 1.000000)
					( Status sCSetFlattened )
					( Origin gBackEnd )
				)
				( attribute "PROPAGATION_DELAY_MAX" "17000.00 MIL"
					( Units "uMaxMinProp" "ns" 1.000000)
					( Status sCSetFlattened )
					( Origin gBackEnd )
				)
				( attribute "RELATIVE_PROPAGATION_DELAY_SCOPE" "G"
					( Parent
						( matchGroupRef "@baseboard_fab2_lib.baseboard_fab2(sch_1):\MG_P3E_CPU0_PE1_PCH_PCIEUP_RX0809\" )
					)
					( Status sCSetFlattened )
					( Origin gBackEnd )
				)
				( attribute "RELATIVE_PROPAGATION_DELAY" ",500.00 MIL"
					( Parent
						( matchGroupRef "@baseboard_fab2_lib.baseboard_fab2(sch_1):\MG_P3E_CPU0_PE1_PCH_PCIEUP_RX0809\" )
					)
					( Units "uMatchProp" "ns" 1.000000)
					( Status sCSetFlattened )
					( Origin gBackEnd )
				)
			)
			( pinPair "@baseboard_fab2_lib.baseboard_fab2(sch_1):\PP2997\"
				( pinRef "@baseboard_fab2_lib.baseboard_fab2(sch_1):page117_i9:PCIEUP_9_TXN" )
				( pinRef "@baseboard_fab2_lib.baseboard_fab2(sch_1):page105_i225:A" )
				( attribute "RELATIVE_PROPAGATION_DELAY_SCOPE" "L"
					( Parent
						( matchGroupRef "@baseboard_fab2_lib.baseboard_fab2(sch_1):\MG_PCIE_L1\" )
					)
					( Status sCSetFlattened )
					( Origin gBackEnd )
				)
				( attribute "RELATIVE_PROPAGATION_DELAY" ",5.00 MIL"
					( Parent
						( matchGroupRef "@baseboard_fab2_lib.baseboard_fab2(sch_1):\MG_PCIE_L1\" )
					)
					( Units "uMatchProp" "ns" 1.000000)
					( Status sCSetFlattened )
					( Origin gBackEnd )
				)
			)
			( pinPair "@baseboard_fab2_lib.baseboard_fab2(sch_1):\PP2998\"
				( pinRef "@baseboard_fab2_lib.baseboard_fab2(sch_1):page105_i225:B" )
				( pinRef "@baseboard_fab2_lib.baseboard_fab2(sch_1):page30_i84:PE1_RX_DN(9)" )
				( attribute "RELATIVE_PROPAGATION_DELAY_SCOPE" "L"
					( Parent
						( matchGroupRef "@baseboard_fab2_lib.baseboard_fab2(sch_1):\MG_PCIE_L0\" )
					)
					( Status sCSetFlattened )
					( Origin gBackEnd )
				)
				( attribute "RELATIVE_PROPAGATION_DELAY" ",5.00 MIL"
					( Parent
						( matchGroupRef "@baseboard_fab2_lib.baseboard_fab2(sch_1):\MG_PCIE_L0\" )
					)
					( Units "uMatchProp" "ns" 1.000000)
					( Status sCSetFlattened )
					( Origin gBackEnd )
				)
			)
			( pinPair "@baseboard_fab2_lib.baseboard_fab2(sch_1):\PP5835\"
				( pinRef "@baseboard_fab2_lib.baseboard_fab2(sch_1):page117_i9:PCIEUP_9_TXN" )
				( pinRef "@baseboard_fab2_lib.baseboard_fab2(sch_1):page30_i84:PE1_RX_DN(9)" )
				( attribute "PROPAGATION_DELAY_MIN" "3000.00 MIL"
					( Units "uMaxMinProp" "ns" 1.000000)
					( Status sCSetFlattened )
					( Origin gBackEnd )
				)
				( attribute "PROPAGATION_DELAY_MAX" "17000.00 MIL"
					( Units "uMaxMinProp" "ns" 1.000000)
					( Status sCSetFlattened )
					( Origin gBackEnd )
				)
				( attribute "RELATIVE_PROPAGATION_DELAY_SCOPE" "G"
					( Parent
						( matchGroupRef "@baseboard_fab2_lib.baseboard_fab2(sch_1):\MG_P3E_CPU0_PE1_PCH_PCIEUP_RX0809\" )
					)
					( Status sCSetFlattened )
					( Origin gBackEnd )
				)
				( attribute "RELATIVE_PROPAGATION_DELAY" ",500.00 MIL"
					( Parent
						( matchGroupRef "@baseboard_fab2_lib.baseboard_fab2(sch_1):\MG_P3E_CPU0_PE1_PCH_PCIEUP_RX0809\" )
					)
					( Units "uMatchProp" "ns" 1.000000)
					( Status sCSetFlattened )
					( Origin gBackEnd )
				)
			)
			( pinPair "@baseboard_fab2_lib.baseboard_fab2(sch_1):\PP2995\"
				( pinRef "@baseboard_fab2_lib.baseboard_fab2(sch_1):page117_i9:PCIEUP_9_TXP" )
				( pinRef "@baseboard_fab2_lib.baseboard_fab2(sch_1):page105_i218:A" )
				( attribute "RELATIVE_PROPAGATION_DELAY_SCOPE" "L"
					( Parent
						( matchGroupRef "@baseboard_fab2_lib.baseboard_fab2(sch_1):\MG_PCIE_L1\" )
					)
					( Status sCSetFlattened )
					( Origin gBackEnd )
				)
				( attribute "RELATIVE_PROPAGATION_DELAY" ",5.00 MIL"
					( Parent
						( matchGroupRef "@baseboard_fab2_lib.baseboard_fab2(sch_1):\MG_PCIE_L1\" )
					)
					( Units "uMatchProp" "ns" 1.000000)
					( Status sCSetFlattened )
					( Origin gBackEnd )
				)
			)
			( pinPair "@baseboard_fab2_lib.baseboard_fab2(sch_1):\PP2996\"
				( pinRef "@baseboard_fab2_lib.baseboard_fab2(sch_1):page105_i218:B" )
				( pinRef "@baseboard_fab2_lib.baseboard_fab2(sch_1):page30_i84:PE1_RX_DP(9)" )
				( attribute "RELATIVE_PROPAGATION_DELAY_SCOPE" "L"
					( Parent
						( matchGroupRef "@baseboard_fab2_lib.baseboard_fab2(sch_1):\MG_PCIE_L0\" )
					)
					( Status sCSetFlattened )
					( Origin gBackEnd )
				)
				( attribute "RELATIVE_PROPAGATION_DELAY" ",5.00 MIL"
					( Parent
						( matchGroupRef "@baseboard_fab2_lib.baseboard_fab2(sch_1):\MG_PCIE_L0\" )
					)
					( Units "uMatchProp" "ns" 1.000000)
					( Status sCSetFlattened )
					( Origin gBackEnd )
				)
			)
			( pinPair "@baseboard_fab2_lib.baseboard_fab2(sch_1):\PP5837\"
				( pinRef "@baseboard_fab2_lib.baseboard_fab2(sch_1):page117_i9:PCIEUP_9_TXP" )
				( pinRef "@baseboard_fab2_lib.baseboard_fab2(sch_1):page30_i84:PE1_RX_DP(9)" )
				( attribute "PROPAGATION_DELAY_MIN" "3000.00 MIL"
					( Units "uMaxMinProp" "ns" 1.000000)
					( Status sCSetFlattened )
					( Origin gBackEnd )
				)
				( attribute "PROPAGATION_DELAY_MAX" "17000.00 MIL"
					( Units "uMaxMinProp" "ns" 1.000000)
					( Status sCSetFlattened )
					( Origin gBackEnd )
				)
				( attribute "RELATIVE_PROPAGATION_DELAY_SCOPE" "G"
					( Parent
						( matchGroupRef "@baseboard_fab2_lib.baseboard_fab2(sch_1):\MG_P3E_CPU0_PE1_PCH_PCIEUP_RX0809\" )
					)
					( Status sCSetFlattened )
					( Origin gBackEnd )
				)
				( attribute "RELATIVE_PROPAGATION_DELAY" ",500.00 MIL"
					( Parent
						( matchGroupRef "@baseboard_fab2_lib.baseboard_fab2(sch_1):\MG_P3E_CPU0_PE1_PCH_PCIEUP_RX0809\" )
					)
					( Units "uMatchProp" "ns" 1.000000)
					( Status sCSetFlattened )
					( Origin gBackEnd )
				)
			)
			( pinPair "@baseboard_fab2_lib.baseboard_fab2(sch_1):\PP219\"
				( pinRef "@baseboard_fab2_lib.baseboard_fab2(sch_1):page66_i84:PE3_TX_DN(2)" )
				( pinRef "@baseboard_fab2_lib.baseboard_fab2(sch_1):page181_i174:B" )
				( attribute "RELATIVE_PROPAGATION_DELAY_SCOPE" "L"
					( Parent
						( matchGroupRef "@baseboard_fab2_lib.baseboard_fab2(sch_1):\MG_PCIE_L1\" )
					)
					( Status sCSetFlattened )
					( Origin gBackEnd )
				)
				( attribute "RELATIVE_PROPAGATION_DELAY" ",5.00 MIL"
					( Parent
						( matchGroupRef "@baseboard_fab2_lib.baseboard_fab2(sch_1):\MG_PCIE_L1\" )
					)
					( Units "uMatchProp" "ns" 1.000000)
					( Status sCSetFlattened )
					( Origin gBackEnd )
				)
			)
			( pinPair "@baseboard_fab2_lib.baseboard_fab2(sch_1):\PP220\"
				( pinRef "@baseboard_fab2_lib.baseboard_fab2(sch_1):page181_i111:IOH8" )
				( pinRef "@baseboard_fab2_lib.baseboard_fab2(sch_1):page181_i174:A" )
				( attribute "RELATIVE_PROPAGATION_DELAY_SCOPE" "L"
					( Parent
						( matchGroupRef "@baseboard_fab2_lib.baseboard_fab2(sch_1):\MG_PCIE_L0\" )
					)
					( Status sCSetFlattened )
					( Origin gBackEnd )
				)
				( attribute "RELATIVE_PROPAGATION_DELAY" ",5.00 MIL"
					( Parent
						( matchGroupRef "@baseboard_fab2_lib.baseboard_fab2(sch_1):\MG_PCIE_L0\" )
					)
					( Units "uMatchProp" "ns" 1.000000)
					( Status sCSetFlattened )
					( Origin gBackEnd )
				)
			)
			( pinPair "@baseboard_fab2_lib.baseboard_fab2(sch_1):\PP5963\"
				( pinRef "@baseboard_fab2_lib.baseboard_fab2(sch_1):page66_i84:PE3_TX_DN(2)" )
				( pinRef "@baseboard_fab2_lib.baseboard_fab2(sch_1):page181_i111:IOH8" )
				( attribute "PROPAGATION_DELAY_MIN" "3000.00 MIL"
					( Units "uMaxMinProp" "ns" 1.000000)
					( Status sCSetFlattened )
					( Origin gBackEnd )
				)
				( attribute "PROPAGATION_DELAY_MAX" "16000.00 MIL"
					( Units "uMaxMinProp" "ns" 1.000000)
					( Status sCSetFlattened )
					( Origin gBackEnd )
				)
				( attribute "RELATIVE_PROPAGATION_DELAY_SCOPE" "G"
					( Parent
						( matchGroupRef "@baseboard_fab2_lib.baseboard_fab2(sch_1):\MG_P3E_CPU1_PE3_MP_TX0203\" )
					)
					( Status sCSetFlattened )
					( Origin gBackEnd )
				)
				( attribute "RELATIVE_PROPAGATION_DELAY" ",500.00 MIL"
					( Parent
						( matchGroupRef "@baseboard_fab2_lib.baseboard_fab2(sch_1):\MG_P3E_CPU1_PE3_MP_TX0203\" )
					)
					( Units "uMatchProp" "ns" 1.000000)
					( Status sCSetFlattened )
					( Origin gBackEnd )
				)
			)
			( pinPair "@baseboard_fab2_lib.baseboard_fab2(sch_1):\PP221\"
				( pinRef "@baseboard_fab2_lib.baseboard_fab2(sch_1):page66_i84:PE3_TX_DP(2)" )
				( pinRef "@baseboard_fab2_lib.baseboard_fab2(sch_1):page181_i175:B" )
				( attribute "RELATIVE_PROPAGATION_DELAY_SCOPE" "L"
					( Parent
						( matchGroupRef "@baseboard_fab2_lib.baseboard_fab2(sch_1):\MG_PCIE_L1\" )
					)
					( Status sCSetFlattened )
					( Origin gBackEnd )
				)
				( attribute "RELATIVE_PROPAGATION_DELAY" ",5.00 MIL"
					( Parent
						( matchGroupRef "@baseboard_fab2_lib.baseboard_fab2(sch_1):\MG_PCIE_L1\" )
					)
					( Units "uMatchProp" "ns" 1.000000)
					( Status sCSetFlattened )
					( Origin gBackEnd )
				)
			)
			( pinPair "@baseboard_fab2_lib.baseboard_fab2(sch_1):\PP222\"
				( pinRef "@baseboard_fab2_lib.baseboard_fab2(sch_1):page181_i111:IOI8" )
				( pinRef "@baseboard_fab2_lib.baseboard_fab2(sch_1):page181_i175:A" )
				( attribute "RELATIVE_PROPAGATION_DELAY_SCOPE" "L"
					( Parent
						( matchGroupRef "@baseboard_fab2_lib.baseboard_fab2(sch_1):\MG_PCIE_L0\" )
					)
					( Status sCSetFlattened )
					( Origin gBackEnd )
				)
				( attribute "RELATIVE_PROPAGATION_DELAY" ",5.00 MIL"
					( Parent
						( matchGroupRef "@baseboard_fab2_lib.baseboard_fab2(sch_1):\MG_PCIE_L0\" )
					)
					( Units "uMatchProp" "ns" 1.000000)
					( Status sCSetFlattened )
					( Origin gBackEnd )
				)
			)
			( pinPair "@baseboard_fab2_lib.baseboard_fab2(sch_1):\PP5960\"
				( pinRef "@baseboard_fab2_lib.baseboard_fab2(sch_1):page66_i84:PE3_TX_DP(2)" )
				( pinRef "@baseboard_fab2_lib.baseboard_fab2(sch_1):page181_i111:IOI8" )
				( attribute "PROPAGATION_DELAY_MIN" "3000.00 MIL"
					( Units "uMaxMinProp" "ns" 1.000000)
					( Status sCSetFlattened )
					( Origin gBackEnd )
				)
				( attribute "PROPAGATION_DELAY_MAX" "16000.00 MIL"
					( Units "uMaxMinProp" "ns" 1.000000)
					( Status sCSetFlattened )
					( Origin gBackEnd )
				)
				( attribute "RELATIVE_PROPAGATION_DELAY_SCOPE" "G"
					( Parent
						( matchGroupRef "@baseboard_fab2_lib.baseboard_fab2(sch_1):\MG_P3E_CPU1_PE3_MP_TX0203\" )
					)
					( Status sCSetFlattened )
					( Origin gBackEnd )
				)
				( attribute "RELATIVE_PROPAGATION_DELAY" ",500.00 MIL"
					( Parent
						( matchGroupRef "@baseboard_fab2_lib.baseboard_fab2(sch_1):\MG_P3E_CPU1_PE3_MP_TX0203\" )
					)
					( Units "uMatchProp" "ns" 1.000000)
					( Status sCSetFlattened )
					( Origin gBackEnd )
				)
			)
			( pinPair "@baseboard_fab2_lib.baseboard_fab2(sch_1):\PP215\"
				( pinRef "@baseboard_fab2_lib.baseboard_fab2(sch_1):page66_i84:PE3_TX_DN(3)" )
				( pinRef "@baseboard_fab2_lib.baseboard_fab2(sch_1):page181_i163:B" )
				( attribute "RELATIVE_PROPAGATION_DELAY_SCOPE" "L"
					( Parent
						( matchGroupRef "@baseboard_fab2_lib.baseboard_fab2(sch_1):\MG_PCIE_L1\" )
					)
					( Status sCSetFlattened )
					( Origin gBackEnd )
				)
				( attribute "RELATIVE_PROPAGATION_DELAY" ",5.00 MIL"
					( Parent
						( matchGroupRef "@baseboard_fab2_lib.baseboard_fab2(sch_1):\MG_PCIE_L1\" )
					)
					( Units "uMatchProp" "ns" 1.000000)
					( Status sCSetFlattened )
					( Origin gBackEnd )
				)
			)
			( pinPair "@baseboard_fab2_lib.baseboard_fab2(sch_1):\PP216\"
				( pinRef "@baseboard_fab2_lib.baseboard_fab2(sch_1):page181_i111:IOA7" )
				( pinRef "@baseboard_fab2_lib.baseboard_fab2(sch_1):page181_i163:A" )
				( attribute "RELATIVE_PROPAGATION_DELAY_SCOPE" "L"
					( Parent
						( matchGroupRef "@baseboard_fab2_lib.baseboard_fab2(sch_1):\MG_PCIE_L0\" )
					)
					( Status sCSetFlattened )
					( Origin gBackEnd )
				)
				( attribute "RELATIVE_PROPAGATION_DELAY" ",5.00 MIL"
					( Parent
						( matchGroupRef "@baseboard_fab2_lib.baseboard_fab2(sch_1):\MG_PCIE_L0\" )
					)
					( Units "uMatchProp" "ns" 1.000000)
					( Status sCSetFlattened )
					( Origin gBackEnd )
				)
			)
			( pinPair "@baseboard_fab2_lib.baseboard_fab2(sch_1):\PP5965\"
				( pinRef "@baseboard_fab2_lib.baseboard_fab2(sch_1):page66_i84:PE3_TX_DN(3)" )
				( pinRef "@baseboard_fab2_lib.baseboard_fab2(sch_1):page181_i111:IOA7" )
				( attribute "PROPAGATION_DELAY_MIN" "3000.00 MIL"
					( Units "uMaxMinProp" "ns" 1.000000)
					( Status sCSetFlattened )
					( Origin gBackEnd )
				)
				( attribute "PROPAGATION_DELAY_MAX" "16000.00 MIL"
					( Units "uMaxMinProp" "ns" 1.000000)
					( Status sCSetFlattened )
					( Origin gBackEnd )
				)
				( attribute "RELATIVE_PROPAGATION_DELAY_SCOPE" "G"
					( Parent
						( matchGroupRef "@baseboard_fab2_lib.baseboard_fab2(sch_1):\MG_P3E_CPU1_PE3_MP_TX0203\" )
					)
					( Status sCSetFlattened )
					( Origin gBackEnd )
				)
				( attribute "RELATIVE_PROPAGATION_DELAY" ",500.00 MIL"
					( Parent
						( matchGroupRef "@baseboard_fab2_lib.baseboard_fab2(sch_1):\MG_P3E_CPU1_PE3_MP_TX0203\" )
					)
					( Units "uMatchProp" "ns" 1.000000)
					( Status sCSetFlattened )
					( Origin gBackEnd )
				)
			)
			( pinPair "@baseboard_fab2_lib.baseboard_fab2(sch_1):\PP217\"
				( pinRef "@baseboard_fab2_lib.baseboard_fab2(sch_1):page66_i84:PE3_TX_DP(3)" )
				( pinRef "@baseboard_fab2_lib.baseboard_fab2(sch_1):page181_i168:B" )
				( attribute "RELATIVE_PROPAGATION_DELAY_SCOPE" "L"
					( Parent
						( matchGroupRef "@baseboard_fab2_lib.baseboard_fab2(sch_1):\MG_PCIE_L1\" )
					)
					( Status sCSetFlattened )
					( Origin gBackEnd )
				)
				( attribute "RELATIVE_PROPAGATION_DELAY" ",5.00 MIL"
					( Parent
						( matchGroupRef "@baseboard_fab2_lib.baseboard_fab2(sch_1):\MG_PCIE_L1\" )
					)
					( Units "uMatchProp" "ns" 1.000000)
					( Status sCSetFlattened )
					( Origin gBackEnd )
				)
			)
			( pinPair "@baseboard_fab2_lib.baseboard_fab2(sch_1):\PP218\"
				( pinRef "@baseboard_fab2_lib.baseboard_fab2(sch_1):page181_i111:IOB7" )
				( pinRef "@baseboard_fab2_lib.baseboard_fab2(sch_1):page181_i168:A" )
				( attribute "RELATIVE_PROPAGATION_DELAY_SCOPE" "L"
					( Parent
						( matchGroupRef "@baseboard_fab2_lib.baseboard_fab2(sch_1):\MG_PCIE_L0\" )
					)
					( Status sCSetFlattened )
					( Origin gBackEnd )
				)
				( attribute "RELATIVE_PROPAGATION_DELAY" ",5.00 MIL"
					( Parent
						( matchGroupRef "@baseboard_fab2_lib.baseboard_fab2(sch_1):\MG_PCIE_L0\" )
					)
					( Units "uMatchProp" "ns" 1.000000)
					( Status sCSetFlattened )
					( Origin gBackEnd )
				)
			)
			( pinPair "@baseboard_fab2_lib.baseboard_fab2(sch_1):\PP5964\"
				( pinRef "@baseboard_fab2_lib.baseboard_fab2(sch_1):page66_i84:PE3_TX_DP(3)" )
				( pinRef "@baseboard_fab2_lib.baseboard_fab2(sch_1):page181_i111:IOB7" )
				( attribute "PROPAGATION_DELAY_MIN" "3000.00 MIL"
					( Units "uMaxMinProp" "ns" 1.000000)
					( Status sCSetFlattened )
					( Origin gBackEnd )
				)
				( attribute "PROPAGATION_DELAY_MAX" "16000.00 MIL"
					( Units "uMaxMinProp" "ns" 1.000000)
					( Status sCSetFlattened )
					( Origin gBackEnd )
				)
				( attribute "RELATIVE_PROPAGATION_DELAY_SCOPE" "G"
					( Parent
						( matchGroupRef "@baseboard_fab2_lib.baseboard_fab2(sch_1):\MG_P3E_CPU1_PE3_MP_TX0203\" )
					)
					( Status sCSetFlattened )
					( Origin gBackEnd )
				)
				( attribute "RELATIVE_PROPAGATION_DELAY" ",500.00 MIL"
					( Parent
						( matchGroupRef "@baseboard_fab2_lib.baseboard_fab2(sch_1):\MG_P3E_CPU1_PE3_MP_TX0203\" )
					)
					( Units "uMatchProp" "ns" 1.000000)
					( Status sCSetFlattened )
					( Origin gBackEnd )
				)
			)
			( pinPair "@baseboard_fab2_lib.baseboard_fab2(sch_1):\PP211\"
				( pinRef "@baseboard_fab2_lib.baseboard_fab2(sch_1):page66_i84:PE3_TX_DN(4)" )
				( pinRef "@baseboard_fab2_lib.baseboard_fab2(sch_1):page181_i164:B" )
				( attribute "RELATIVE_PROPAGATION_DELAY_SCOPE" "L"
					( Parent
						( matchGroupRef "@baseboard_fab2_lib.baseboard_fab2(sch_1):\MG_PCIE_L1\" )
					)
					( Status sCSetFlattened )
					( Origin gBackEnd )
				)
				( attribute "RELATIVE_PROPAGATION_DELAY" ",5.00 MIL"
					( Parent
						( matchGroupRef "@baseboard_fab2_lib.baseboard_fab2(sch_1):\MG_PCIE_L1\" )
					)
					( Units "uMatchProp" "ns" 1.000000)
					( Status sCSetFlattened )
					( Origin gBackEnd )
				)
			)
			( pinPair "@baseboard_fab2_lib.baseboard_fab2(sch_1):\PP212\"
				( pinRef "@baseboard_fab2_lib.baseboard_fab2(sch_1):page181_i111:IOD7" )
				( pinRef "@baseboard_fab2_lib.baseboard_fab2(sch_1):page181_i164:A" )
				( attribute "RELATIVE_PROPAGATION_DELAY_SCOPE" "L"
					( Parent
						( matchGroupRef "@baseboard_fab2_lib.baseboard_fab2(sch_1):\MG_PCIE_L0\" )
					)
					( Status sCSetFlattened )
					( Origin gBackEnd )
				)
				( attribute "RELATIVE_PROPAGATION_DELAY" ",5.00 MIL"
					( Parent
						( matchGroupRef "@baseboard_fab2_lib.baseboard_fab2(sch_1):\MG_PCIE_L0\" )
					)
					( Units "uMatchProp" "ns" 1.000000)
					( Status sCSetFlattened )
					( Origin gBackEnd )
				)
			)
			( pinPair "@baseboard_fab2_lib.baseboard_fab2(sch_1):\PP5967\"
				( pinRef "@baseboard_fab2_lib.baseboard_fab2(sch_1):page66_i84:PE3_TX_DN(4)" )
				( pinRef "@baseboard_fab2_lib.baseboard_fab2(sch_1):page181_i111:IOD7" )
				( attribute "PROPAGATION_DELAY_MIN" "3000.00 MIL"
					( Units "uMaxMinProp" "ns" 1.000000)
					( Status sCSetFlattened )
					( Origin gBackEnd )
				)
				( attribute "PROPAGATION_DELAY_MAX" "16000.00 MIL"
					( Units "uMaxMinProp" "ns" 1.000000)
					( Status sCSetFlattened )
					( Origin gBackEnd )
				)
				( attribute "RELATIVE_PROPAGATION_DELAY_SCOPE" "G"
					( Parent
						( matchGroupRef "@baseboard_fab2_lib.baseboard_fab2(sch_1):\MG_P3E_CPU1_PE3_MP_TX0405\" )
					)
					( Status sCSetFlattened )
					( Origin gBackEnd )
				)
				( attribute "RELATIVE_PROPAGATION_DELAY" ",500.00 MIL"
					( Parent
						( matchGroupRef "@baseboard_fab2_lib.baseboard_fab2(sch_1):\MG_P3E_CPU1_PE3_MP_TX0405\" )
					)
					( Units "uMatchProp" "ns" 1.000000)
					( Status sCSetFlattened )
					( Origin gBackEnd )
				)
			)
			( pinPair "@baseboard_fab2_lib.baseboard_fab2(sch_1):\PP213\"
				( pinRef "@baseboard_fab2_lib.baseboard_fab2(sch_1):page66_i84:PE3_TX_DP(4)" )
				( pinRef "@baseboard_fab2_lib.baseboard_fab2(sch_1):page181_i169:B" )
				( attribute "RELATIVE_PROPAGATION_DELAY_SCOPE" "L"
					( Parent
						( matchGroupRef "@baseboard_fab2_lib.baseboard_fab2(sch_1):\MG_PCIE_L1\" )
					)
					( Status sCSetFlattened )
					( Origin gBackEnd )
				)
				( attribute "RELATIVE_PROPAGATION_DELAY" ",5.00 MIL"
					( Parent
						( matchGroupRef "@baseboard_fab2_lib.baseboard_fab2(sch_1):\MG_PCIE_L1\" )
					)
					( Units "uMatchProp" "ns" 1.000000)
					( Status sCSetFlattened )
					( Origin gBackEnd )
				)
			)
			( pinPair "@baseboard_fab2_lib.baseboard_fab2(sch_1):\PP214\"
				( pinRef "@baseboard_fab2_lib.baseboard_fab2(sch_1):page181_i111:IOE7" )
				( pinRef "@baseboard_fab2_lib.baseboard_fab2(sch_1):page181_i169:A" )
				( attribute "RELATIVE_PROPAGATION_DELAY_SCOPE" "L"
					( Parent
						( matchGroupRef "@baseboard_fab2_lib.baseboard_fab2(sch_1):\MG_PCIE_L0\" )
					)
					( Status sCSetFlattened )
					( Origin gBackEnd )
				)
				( attribute "RELATIVE_PROPAGATION_DELAY" ",5.00 MIL"
					( Parent
						( matchGroupRef "@baseboard_fab2_lib.baseboard_fab2(sch_1):\MG_PCIE_L0\" )
					)
					( Units "uMatchProp" "ns" 1.000000)
					( Status sCSetFlattened )
					( Origin gBackEnd )
				)
			)
			( pinPair "@baseboard_fab2_lib.baseboard_fab2(sch_1):\PP5966\"
				( pinRef "@baseboard_fab2_lib.baseboard_fab2(sch_1):page66_i84:PE3_TX_DP(4)" )
				( pinRef "@baseboard_fab2_lib.baseboard_fab2(sch_1):page181_i111:IOE7" )
				( attribute "PROPAGATION_DELAY_MIN" "3000.00 MIL"
					( Units "uMaxMinProp" "ns" 1.000000)
					( Status sCSetFlattened )
					( Origin gBackEnd )
				)
				( attribute "PROPAGATION_DELAY_MAX" "16000.00 MIL"
					( Units "uMaxMinProp" "ns" 1.000000)
					( Status sCSetFlattened )
					( Origin gBackEnd )
				)
				( attribute "RELATIVE_PROPAGATION_DELAY_SCOPE" "G"
					( Parent
						( matchGroupRef "@baseboard_fab2_lib.baseboard_fab2(sch_1):\MG_P3E_CPU1_PE3_MP_TX0405\" )
					)
					( Status sCSetFlattened )
					( Origin gBackEnd )
				)
				( attribute "RELATIVE_PROPAGATION_DELAY" ",500.00 MIL"
					( Parent
						( matchGroupRef "@baseboard_fab2_lib.baseboard_fab2(sch_1):\MG_P3E_CPU1_PE3_MP_TX0405\" )
					)
					( Units "uMatchProp" "ns" 1.000000)
					( Status sCSetFlattened )
					( Origin gBackEnd )
				)
			)
			( pinPair "@baseboard_fab2_lib.baseboard_fab2(sch_1):\PP207\"
				( pinRef "@baseboard_fab2_lib.baseboard_fab2(sch_1):page66_i84:PE3_TX_DN(5)" )
				( pinRef "@baseboard_fab2_lib.baseboard_fab2(sch_1):page181_i170:B" )
				( attribute "RELATIVE_PROPAGATION_DELAY_SCOPE" "L"
					( Parent
						( matchGroupRef "@baseboard_fab2_lib.baseboard_fab2(sch_1):\MG_PCIE_L1\" )
					)
					( Status sCSetFlattened )
					( Origin gBackEnd )
				)
				( attribute "RELATIVE_PROPAGATION_DELAY" ",5.00 MIL"
					( Parent
						( matchGroupRef "@baseboard_fab2_lib.baseboard_fab2(sch_1):\MG_PCIE_L1\" )
					)
					( Units "uMatchProp" "ns" 1.000000)
					( Status sCSetFlattened )
					( Origin gBackEnd )
				)
			)
			( pinPair "@baseboard_fab2_lib.baseboard_fab2(sch_1):\PP208\"
				( pinRef "@baseboard_fab2_lib.baseboard_fab2(sch_1):page181_i111:IOH7" )
				( pinRef "@baseboard_fab2_lib.baseboard_fab2(sch_1):page181_i170:A" )
				( attribute "RELATIVE_PROPAGATION_DELAY_SCOPE" "L"
					( Parent
						( matchGroupRef "@baseboard_fab2_lib.baseboard_fab2(sch_1):\MG_PCIE_L0\" )
					)
					( Status sCSetFlattened )
					( Origin gBackEnd )
				)
				( attribute "RELATIVE_PROPAGATION_DELAY" ",5.00 MIL"
					( Parent
						( matchGroupRef "@baseboard_fab2_lib.baseboard_fab2(sch_1):\MG_PCIE_L0\" )
					)
					( Units "uMatchProp" "ns" 1.000000)
					( Status sCSetFlattened )
					( Origin gBackEnd )
				)
			)
			( pinPair "@baseboard_fab2_lib.baseboard_fab2(sch_1):\PP5968\"
				( pinRef "@baseboard_fab2_lib.baseboard_fab2(sch_1):page66_i84:PE3_TX_DN(5)" )
				( pinRef "@baseboard_fab2_lib.baseboard_fab2(sch_1):page181_i111:IOH7" )
				( attribute "PROPAGATION_DELAY_MIN" "3000.00 MIL"
					( Units "uMaxMinProp" "ns" 1.000000)
					( Status sCSetFlattened )
					( Origin gBackEnd )
				)
				( attribute "PROPAGATION_DELAY_MAX" "16000.00 MIL"
					( Units "uMaxMinProp" "ns" 1.000000)
					( Status sCSetFlattened )
					( Origin gBackEnd )
				)
				( attribute "RELATIVE_PROPAGATION_DELAY_SCOPE" "G"
					( Parent
						( matchGroupRef "@baseboard_fab2_lib.baseboard_fab2(sch_1):\MG_P3E_CPU1_PE3_MP_TX0405\" )
					)
					( Status sCSetFlattened )
					( Origin gBackEnd )
				)
				( attribute "RELATIVE_PROPAGATION_DELAY" ",500.00 MIL"
					( Parent
						( matchGroupRef "@baseboard_fab2_lib.baseboard_fab2(sch_1):\MG_P3E_CPU1_PE3_MP_TX0405\" )
					)
					( Units "uMatchProp" "ns" 1.000000)
					( Status sCSetFlattened )
					( Origin gBackEnd )
				)
			)
			( pinPair "@baseboard_fab2_lib.baseboard_fab2(sch_1):\PP209\"
				( pinRef "@baseboard_fab2_lib.baseboard_fab2(sch_1):page66_i84:PE3_TX_DP(5)" )
				( pinRef "@baseboard_fab2_lib.baseboard_fab2(sch_1):page181_i165:B" )
				( attribute "RELATIVE_PROPAGATION_DELAY_SCOPE" "L"
					( Parent
						( matchGroupRef "@baseboard_fab2_lib.baseboard_fab2(sch_1):\MG_PCIE_L1\" )
					)
					( Status sCSetFlattened )
					( Origin gBackEnd )
				)
				( attribute "RELATIVE_PROPAGATION_DELAY" ",5.00 MIL"
					( Parent
						( matchGroupRef "@baseboard_fab2_lib.baseboard_fab2(sch_1):\MG_PCIE_L1\" )
					)
					( Units "uMatchProp" "ns" 1.000000)
					( Status sCSetFlattened )
					( Origin gBackEnd )
				)
			)
			( pinPair "@baseboard_fab2_lib.baseboard_fab2(sch_1):\PP210\"
				( pinRef "@baseboard_fab2_lib.baseboard_fab2(sch_1):page181_i111:IOG7" )
				( pinRef "@baseboard_fab2_lib.baseboard_fab2(sch_1):page181_i165:A" )
				( attribute "RELATIVE_PROPAGATION_DELAY_SCOPE" "L"
					( Parent
						( matchGroupRef "@baseboard_fab2_lib.baseboard_fab2(sch_1):\MG_PCIE_L0\" )
					)
					( Status sCSetFlattened )
					( Origin gBackEnd )
				)
				( attribute "RELATIVE_PROPAGATION_DELAY" ",5.00 MIL"
					( Parent
						( matchGroupRef "@baseboard_fab2_lib.baseboard_fab2(sch_1):\MG_PCIE_L0\" )
					)
					( Units "uMatchProp" "ns" 1.000000)
					( Status sCSetFlattened )
					( Origin gBackEnd )
				)
			)
			( pinPair "@baseboard_fab2_lib.baseboard_fab2(sch_1):\PP5962\"
				( pinRef "@baseboard_fab2_lib.baseboard_fab2(sch_1):page66_i84:PE3_TX_DP(5)" )
				( pinRef "@baseboard_fab2_lib.baseboard_fab2(sch_1):page181_i111:IOG7" )
				( attribute "PROPAGATION_DELAY_MIN" "3000.00 MIL"
					( Units "uMaxMinProp" "ns" 1.000000)
					( Status sCSetFlattened )
					( Origin gBackEnd )
				)
				( attribute "PROPAGATION_DELAY_MAX" "16000.00 MIL"
					( Units "uMaxMinProp" "ns" 1.000000)
					( Status sCSetFlattened )
					( Origin gBackEnd )
				)
				( attribute "RELATIVE_PROPAGATION_DELAY_SCOPE" "G"
					( Parent
						( matchGroupRef "@baseboard_fab2_lib.baseboard_fab2(sch_1):\MG_P3E_CPU1_PE3_MP_TX0405\" )
					)
					( Status sCSetFlattened )
					( Origin gBackEnd )
				)
				( attribute "RELATIVE_PROPAGATION_DELAY" ",500.00 MIL"
					( Parent
						( matchGroupRef "@baseboard_fab2_lib.baseboard_fab2(sch_1):\MG_P3E_CPU1_PE3_MP_TX0405\" )
					)
					( Units "uMatchProp" "ns" 1.000000)
					( Status sCSetFlattened )
					( Origin gBackEnd )
				)
			)
			( pinPair "@baseboard_fab2_lib.baseboard_fab2(sch_1):\PP203\"
				( pinRef "@baseboard_fab2_lib.baseboard_fab2(sch_1):page66_i84:PE3_TX_DN(6)" )
				( pinRef "@baseboard_fab2_lib.baseboard_fab2(sch_1):page181_i160:B" )
				( attribute "RELATIVE_PROPAGATION_DELAY_SCOPE" "L"
					( Parent
						( matchGroupRef "@baseboard_fab2_lib.baseboard_fab2(sch_1):\MG_PCIE_L1\" )
					)
					( Status sCSetFlattened )
					( Origin gBackEnd )
				)
				( attribute "RELATIVE_PROPAGATION_DELAY" ",5.00 MIL"
					( Parent
						( matchGroupRef "@baseboard_fab2_lib.baseboard_fab2(sch_1):\MG_PCIE_L1\" )
					)
					( Units "uMatchProp" "ns" 1.000000)
					( Status sCSetFlattened )
					( Origin gBackEnd )
				)
			)
			( pinPair "@baseboard_fab2_lib.baseboard_fab2(sch_1):\PP204\"
				( pinRef "@baseboard_fab2_lib.baseboard_fab2(sch_1):page181_i111:IOE6" )
				( pinRef "@baseboard_fab2_lib.baseboard_fab2(sch_1):page181_i160:A" )
				( attribute "RELATIVE_PROPAGATION_DELAY_SCOPE" "L"
					( Parent
						( matchGroupRef "@baseboard_fab2_lib.baseboard_fab2(sch_1):\MG_PCIE_L0\" )
					)
					( Status sCSetFlattened )
					( Origin gBackEnd )
				)
				( attribute "RELATIVE_PROPAGATION_DELAY" ",5.00 MIL"
					( Parent
						( matchGroupRef "@baseboard_fab2_lib.baseboard_fab2(sch_1):\MG_PCIE_L0\" )
					)
					( Units "uMatchProp" "ns" 1.000000)
					( Status sCSetFlattened )
					( Origin gBackEnd )
				)
			)
			( pinPair "@baseboard_fab2_lib.baseboard_fab2(sch_1):\PP5971\"
				( pinRef "@baseboard_fab2_lib.baseboard_fab2(sch_1):page66_i84:PE3_TX_DN(6)" )
				( pinRef "@baseboard_fab2_lib.baseboard_fab2(sch_1):page181_i111:IOE6" )
				( attribute "PROPAGATION_DELAY_MIN" "3000.00 MIL"
					( Units "uMaxMinProp" "ns" 1.000000)
					( Status sCSetFlattened )
					( Origin gBackEnd )
				)
				( attribute "PROPAGATION_DELAY_MAX" "16000.00 MIL"
					( Units "uMaxMinProp" "ns" 1.000000)
					( Status sCSetFlattened )
					( Origin gBackEnd )
				)
				( attribute "RELATIVE_PROPAGATION_DELAY_SCOPE" "G"
					( Parent
						( matchGroupRef "@baseboard_fab2_lib.baseboard_fab2(sch_1):\MG_P3E_CPU1_PE3_MP_TX0607\" )
					)
					( Status sCSetFlattened )
					( Origin gBackEnd )
				)
				( attribute "RELATIVE_PROPAGATION_DELAY" ",500.00 MIL"
					( Parent
						( matchGroupRef "@baseboard_fab2_lib.baseboard_fab2(sch_1):\MG_P3E_CPU1_PE3_MP_TX0607\" )
					)
					( Units "uMatchProp" "ns" 1.000000)
					( Status sCSetFlattened )
					( Origin gBackEnd )
				)
			)
			( pinPair "@baseboard_fab2_lib.baseboard_fab2(sch_1):\PP205\"
				( pinRef "@baseboard_fab2_lib.baseboard_fab2(sch_1):page66_i84:PE3_TX_DP(6)" )
				( pinRef "@baseboard_fab2_lib.baseboard_fab2(sch_1):page181_i161:B" )
				( attribute "RELATIVE_PROPAGATION_DELAY_SCOPE" "L"
					( Parent
						( matchGroupRef "@baseboard_fab2_lib.baseboard_fab2(sch_1):\MG_PCIE_L1\" )
					)
					( Status sCSetFlattened )
					( Origin gBackEnd )
				)
				( attribute "RELATIVE_PROPAGATION_DELAY" ",5.00 MIL"
					( Parent
						( matchGroupRef "@baseboard_fab2_lib.baseboard_fab2(sch_1):\MG_PCIE_L1\" )
					)
					( Units "uMatchProp" "ns" 1.000000)
					( Status sCSetFlattened )
					( Origin gBackEnd )
				)
			)
			( pinPair "@baseboard_fab2_lib.baseboard_fab2(sch_1):\PP206\"
				( pinRef "@baseboard_fab2_lib.baseboard_fab2(sch_1):page181_i111:IOF6" )
				( pinRef "@baseboard_fab2_lib.baseboard_fab2(sch_1):page181_i161:A" )
				( attribute "RELATIVE_PROPAGATION_DELAY_SCOPE" "L"
					( Parent
						( matchGroupRef "@baseboard_fab2_lib.baseboard_fab2(sch_1):\MG_PCIE_L0\" )
					)
					( Status sCSetFlattened )
					( Origin gBackEnd )
				)
				( attribute "RELATIVE_PROPAGATION_DELAY" ",5.00 MIL"
					( Parent
						( matchGroupRef "@baseboard_fab2_lib.baseboard_fab2(sch_1):\MG_PCIE_L0\" )
					)
					( Units "uMatchProp" "ns" 1.000000)
					( Status sCSetFlattened )
					( Origin gBackEnd )
				)
			)
			( pinPair "@baseboard_fab2_lib.baseboard_fab2(sch_1):\PP5970\"
				( pinRef "@baseboard_fab2_lib.baseboard_fab2(sch_1):page66_i84:PE3_TX_DP(6)" )
				( pinRef "@baseboard_fab2_lib.baseboard_fab2(sch_1):page181_i111:IOF6" )
				( attribute "PROPAGATION_DELAY_MIN" "3000.00 MIL"
					( Units "uMaxMinProp" "ns" 1.000000)
					( Status sCSetFlattened )
					( Origin gBackEnd )
				)
				( attribute "PROPAGATION_DELAY_MAX" "16000.00 MIL"
					( Units "uMaxMinProp" "ns" 1.000000)
					( Status sCSetFlattened )
					( Origin gBackEnd )
				)
				( attribute "RELATIVE_PROPAGATION_DELAY_SCOPE" "G"
					( Parent
						( matchGroupRef "@baseboard_fab2_lib.baseboard_fab2(sch_1):\MG_P3E_CPU1_PE3_MP_TX0607\" )
					)
					( Status sCSetFlattened )
					( Origin gBackEnd )
				)
				( attribute "RELATIVE_PROPAGATION_DELAY" ",500.00 MIL"
					( Parent
						( matchGroupRef "@baseboard_fab2_lib.baseboard_fab2(sch_1):\MG_P3E_CPU1_PE3_MP_TX0607\" )
					)
					( Units "uMatchProp" "ns" 1.000000)
					( Status sCSetFlattened )
					( Origin gBackEnd )
				)
			)
			( pinPair "@baseboard_fab2_lib.baseboard_fab2(sch_1):\PP199\"
				( pinRef "@baseboard_fab2_lib.baseboard_fab2(sch_1):page66_i84:PE3_TX_DN(11)" )
				( pinRef "@baseboard_fab2_lib.baseboard_fab2(sch_1):page182_i51:B" )
				( attribute "RELATIVE_PROPAGATION_DELAY_SCOPE" "L"
					( Parent
						( matchGroupRef "@baseboard_fab2_lib.baseboard_fab2(sch_1):\MG_PCIE_L1\" )
					)
					( Status sCSetFlattened )
					( Origin gBackEnd )
				)
				( attribute "RELATIVE_PROPAGATION_DELAY" ",5.00 MIL"
					( Parent
						( matchGroupRef "@baseboard_fab2_lib.baseboard_fab2(sch_1):\MG_PCIE_L1\" )
					)
					( Units "uMatchProp" "ns" 1.000000)
					( Status sCSetFlattened )
					( Origin gBackEnd )
				)
			)
			( pinPair "@baseboard_fab2_lib.baseboard_fab2(sch_1):\PP200\"
				( pinRef "@baseboard_fab2_lib.baseboard_fab2(sch_1):page182_i18:IOA7" )
				( pinRef "@baseboard_fab2_lib.baseboard_fab2(sch_1):page182_i51:A" )
				( attribute "RELATIVE_PROPAGATION_DELAY_SCOPE" "L"
					( Parent
						( matchGroupRef "@baseboard_fab2_lib.baseboard_fab2(sch_1):\MG_PCIE_L0\" )
					)
					( Status sCSetFlattened )
					( Origin gBackEnd )
				)
				( attribute "RELATIVE_PROPAGATION_DELAY" ",5.00 MIL"
					( Parent
						( matchGroupRef "@baseboard_fab2_lib.baseboard_fab2(sch_1):\MG_PCIE_L0\" )
					)
					( Units "uMatchProp" "ns" 1.000000)
					( Status sCSetFlattened )
					( Origin gBackEnd )
				)
			)
			( pinPair "@baseboard_fab2_lib.baseboard_fab2(sch_1):\PP5974\"
				( pinRef "@baseboard_fab2_lib.baseboard_fab2(sch_1):page66_i84:PE3_TX_DN(11)" )
				( pinRef "@baseboard_fab2_lib.baseboard_fab2(sch_1):page182_i18:IOA7" )
				( attribute "PROPAGATION_DELAY_MIN" "3000.00 MIL"
					( Units "uMaxMinProp" "ns" 1.000000)
					( Status sCSetFlattened )
					( Origin gBackEnd )
				)
				( attribute "PROPAGATION_DELAY_MAX" "16000.00 MIL"
					( Units "uMaxMinProp" "ns" 1.000000)
					( Status sCSetFlattened )
					( Origin gBackEnd )
				)
				( attribute "RELATIVE_PROPAGATION_DELAY_SCOPE" "G"
					( Parent
						( matchGroupRef "@baseboard_fab2_lib.baseboard_fab2(sch_1):\MG_P3E_CPU1_PE3_MP_TX1011\" )
					)
					( Status sCSetFlattened )
					( Origin gBackEnd )
				)
				( attribute "RELATIVE_PROPAGATION_DELAY" ",500.00 MIL"
					( Parent
						( matchGroupRef "@baseboard_fab2_lib.baseboard_fab2(sch_1):\MG_P3E_CPU1_PE3_MP_TX1011\" )
					)
					( Units "uMatchProp" "ns" 1.000000)
					( Status sCSetFlattened )
					( Origin gBackEnd )
				)
			)
			( pinPair "@baseboard_fab2_lib.baseboard_fab2(sch_1):\PP201\"
				( pinRef "@baseboard_fab2_lib.baseboard_fab2(sch_1):page182_i18:IOB7" )
				( pinRef "@baseboard_fab2_lib.baseboard_fab2(sch_1):page182_i55:A" )
				( attribute "RELATIVE_PROPAGATION_DELAY_SCOPE" "L"
					( Parent
						( matchGroupRef "@baseboard_fab2_lib.baseboard_fab2(sch_1):\MG_PCIE_L0\" )
					)
					( Status sCSetFlattened )
					( Origin gBackEnd )
				)
				( attribute "RELATIVE_PROPAGATION_DELAY" ",5.00 MIL"
					( Parent
						( matchGroupRef "@baseboard_fab2_lib.baseboard_fab2(sch_1):\MG_PCIE_L0\" )
					)
					( Units "uMatchProp" "ns" 1.000000)
					( Status sCSetFlattened )
					( Origin gBackEnd )
				)
			)
			( pinPair "@baseboard_fab2_lib.baseboard_fab2(sch_1):\PP202\"
				( pinRef "@baseboard_fab2_lib.baseboard_fab2(sch_1):page66_i84:PE3_TX_DP(11)" )
				( pinRef "@baseboard_fab2_lib.baseboard_fab2(sch_1):page182_i55:B" )
				( attribute "RELATIVE_PROPAGATION_DELAY_SCOPE" "L"
					( Parent
						( matchGroupRef "@baseboard_fab2_lib.baseboard_fab2(sch_1):\MG_PCIE_L1\" )
					)
					( Status sCSetFlattened )
					( Origin gBackEnd )
				)
				( attribute "RELATIVE_PROPAGATION_DELAY" ",5.00 MIL"
					( Parent
						( matchGroupRef "@baseboard_fab2_lib.baseboard_fab2(sch_1):\MG_PCIE_L1\" )
					)
					( Units "uMatchProp" "ns" 1.000000)
					( Status sCSetFlattened )
					( Origin gBackEnd )
				)
			)
			( pinPair "@baseboard_fab2_lib.baseboard_fab2(sch_1):\PP5972\"
				( pinRef "@baseboard_fab2_lib.baseboard_fab2(sch_1):page66_i84:PE3_TX_DP(11)" )
				( pinRef "@baseboard_fab2_lib.baseboard_fab2(sch_1):page182_i18:IOB7" )
				( attribute "PROPAGATION_DELAY_MIN" "3000.00 MIL"
					( Units "uMaxMinProp" "ns" 1.000000)
					( Status sCSetFlattened )
					( Origin gBackEnd )
				)
				( attribute "PROPAGATION_DELAY_MAX" "16000.00 MIL"
					( Units "uMaxMinProp" "ns" 1.000000)
					( Status sCSetFlattened )
					( Origin gBackEnd )
				)
				( attribute "RELATIVE_PROPAGATION_DELAY_SCOPE" "G"
					( Parent
						( matchGroupRef "@baseboard_fab2_lib.baseboard_fab2(sch_1):\MG_P3E_CPU1_PE3_MP_TX1011\" )
					)
					( Status sCSetFlattened )
					( Origin gBackEnd )
				)
				( attribute "RELATIVE_PROPAGATION_DELAY" ",500.00 MIL"
					( Parent
						( matchGroupRef "@baseboard_fab2_lib.baseboard_fab2(sch_1):\MG_P3E_CPU1_PE3_MP_TX1011\" )
					)
					( Units "uMatchProp" "ns" 1.000000)
					( Status sCSetFlattened )
					( Origin gBackEnd )
				)
			)
			( pinPair "@baseboard_fab2_lib.baseboard_fab2(sch_1):\PP195\"
				( pinRef "@baseboard_fab2_lib.baseboard_fab2(sch_1):page66_i84:PE3_TX_DN(12)" )
				( pinRef "@baseboard_fab2_lib.baseboard_fab2(sch_1):page182_i52:B" )
				( attribute "RELATIVE_PROPAGATION_DELAY_SCOPE" "L"
					( Parent
						( matchGroupRef "@baseboard_fab2_lib.baseboard_fab2(sch_1):\MG_PCIE_L1\" )
					)
					( Status sCSetFlattened )
					( Origin gBackEnd )
				)
				( attribute "RELATIVE_PROPAGATION_DELAY" ",5.00 MIL"
					( Parent
						( matchGroupRef "@baseboard_fab2_lib.baseboard_fab2(sch_1):\MG_PCIE_L1\" )
					)
					( Units "uMatchProp" "ns" 1.000000)
					( Status sCSetFlattened )
					( Origin gBackEnd )
				)
			)
			( pinPair "@baseboard_fab2_lib.baseboard_fab2(sch_1):\PP196\"
				( pinRef "@baseboard_fab2_lib.baseboard_fab2(sch_1):page182_i18:IOD7" )
				( pinRef "@baseboard_fab2_lib.baseboard_fab2(sch_1):page182_i52:A" )
				( attribute "RELATIVE_PROPAGATION_DELAY_SCOPE" "L"
					( Parent
						( matchGroupRef "@baseboard_fab2_lib.baseboard_fab2(sch_1):\MG_PCIE_L0\" )
					)
					( Status sCSetFlattened )
					( Origin gBackEnd )
				)
				( attribute "RELATIVE_PROPAGATION_DELAY" ",5.00 MIL"
					( Parent
						( matchGroupRef "@baseboard_fab2_lib.baseboard_fab2(sch_1):\MG_PCIE_L0\" )
					)
					( Units "uMatchProp" "ns" 1.000000)
					( Status sCSetFlattened )
					( Origin gBackEnd )
				)
			)
			( pinPair "@baseboard_fab2_lib.baseboard_fab2(sch_1):\PP5973\"
				( pinRef "@baseboard_fab2_lib.baseboard_fab2(sch_1):page66_i84:PE3_TX_DN(12)" )
				( pinRef "@baseboard_fab2_lib.baseboard_fab2(sch_1):page182_i18:IOD7" )
				( attribute "PROPAGATION_DELAY_MIN" "3000.00 MIL"
					( Units "uMaxMinProp" "ns" 1.000000)
					( Status sCSetFlattened )
					( Origin gBackEnd )
				)
				( attribute "PROPAGATION_DELAY_MAX" "16000.00 MIL"
					( Units "uMaxMinProp" "ns" 1.000000)
					( Status sCSetFlattened )
					( Origin gBackEnd )
				)
				( attribute "RELATIVE_PROPAGATION_DELAY_SCOPE" "G"
					( Parent
						( matchGroupRef "@baseboard_fab2_lib.baseboard_fab2(sch_1):\MG_P3E_CPU1_PE3_MP_TX1213\" )
					)
					( Status sCSetFlattened )
					( Origin gBackEnd )
				)
				( attribute "RELATIVE_PROPAGATION_DELAY" ",500.00 MIL"
					( Parent
						( matchGroupRef "@baseboard_fab2_lib.baseboard_fab2(sch_1):\MG_P3E_CPU1_PE3_MP_TX1213\" )
					)
					( Units "uMatchProp" "ns" 1.000000)
					( Status sCSetFlattened )
					( Origin gBackEnd )
				)
			)
			( pinPair "@baseboard_fab2_lib.baseboard_fab2(sch_1):\PP197\"
				( pinRef "@baseboard_fab2_lib.baseboard_fab2(sch_1):page182_i18:IOE7" )
				( pinRef "@baseboard_fab2_lib.baseboard_fab2(sch_1):page182_i56:A" )
				( attribute "RELATIVE_PROPAGATION_DELAY_SCOPE" "L"
					( Parent
						( matchGroupRef "@baseboard_fab2_lib.baseboard_fab2(sch_1):\MG_PCIE_L0\" )
					)
					( Status sCSetFlattened )
					( Origin gBackEnd )
				)
				( attribute "RELATIVE_PROPAGATION_DELAY" ",5.00 MIL"
					( Parent
						( matchGroupRef "@baseboard_fab2_lib.baseboard_fab2(sch_1):\MG_PCIE_L0\" )
					)
					( Units "uMatchProp" "ns" 1.000000)
					( Status sCSetFlattened )
					( Origin gBackEnd )
				)
			)
			( pinPair "@baseboard_fab2_lib.baseboard_fab2(sch_1):\PP198\"
				( pinRef "@baseboard_fab2_lib.baseboard_fab2(sch_1):page66_i84:PE3_TX_DP(12)" )
				( pinRef "@baseboard_fab2_lib.baseboard_fab2(sch_1):page182_i56:B" )
				( attribute "RELATIVE_PROPAGATION_DELAY_SCOPE" "L"
					( Parent
						( matchGroupRef "@baseboard_fab2_lib.baseboard_fab2(sch_1):\MG_PCIE_L1\" )
					)
					( Status sCSetFlattened )
					( Origin gBackEnd )
				)
				( attribute "RELATIVE_PROPAGATION_DELAY" ",5.00 MIL"
					( Parent
						( matchGroupRef "@baseboard_fab2_lib.baseboard_fab2(sch_1):\MG_PCIE_L1\" )
					)
					( Units "uMatchProp" "ns" 1.000000)
					( Status sCSetFlattened )
					( Origin gBackEnd )
				)
			)
			( pinPair "@baseboard_fab2_lib.baseboard_fab2(sch_1):\PP5975\"
				( pinRef "@baseboard_fab2_lib.baseboard_fab2(sch_1):page66_i84:PE3_TX_DP(12)" )
				( pinRef "@baseboard_fab2_lib.baseboard_fab2(sch_1):page182_i18:IOE7" )
				( attribute "PROPAGATION_DELAY_MIN" "3000.00 MIL"
					( Units "uMaxMinProp" "ns" 1.000000)
					( Status sCSetFlattened )
					( Origin gBackEnd )
				)
				( attribute "PROPAGATION_DELAY_MAX" "16000.00 MIL"
					( Units "uMaxMinProp" "ns" 1.000000)
					( Status sCSetFlattened )
					( Origin gBackEnd )
				)
				( attribute "RELATIVE_PROPAGATION_DELAY_SCOPE" "G"
					( Parent
						( matchGroupRef "@baseboard_fab2_lib.baseboard_fab2(sch_1):\MG_P3E_CPU1_PE3_MP_TX1213\" )
					)
					( Status sCSetFlattened )
					( Origin gBackEnd )
				)
				( attribute "RELATIVE_PROPAGATION_DELAY" ",500.00 MIL"
					( Parent
						( matchGroupRef "@baseboard_fab2_lib.baseboard_fab2(sch_1):\MG_P3E_CPU1_PE3_MP_TX1213\" )
					)
					( Units "uMatchProp" "ns" 1.000000)
					( Status sCSetFlattened )
					( Origin gBackEnd )
				)
			)
			( pinPair "@baseboard_fab2_lib.baseboard_fab2(sch_1):\PP191\"
				( pinRef "@baseboard_fab2_lib.baseboard_fab2(sch_1):page66_i84:PE3_TX_DN(13)" )
				( pinRef "@baseboard_fab2_lib.baseboard_fab2(sch_1):page182_i81:B" )
				( attribute "RELATIVE_PROPAGATION_DELAY_SCOPE" "L"
					( Parent
						( matchGroupRef "@baseboard_fab2_lib.baseboard_fab2(sch_1):\MG_PCIE_L1\" )
					)
					( Status sCSetFlattened )
					( Origin gBackEnd )
				)
				( attribute "RELATIVE_PROPAGATION_DELAY" ",5.00 MIL"
					( Parent
						( matchGroupRef "@baseboard_fab2_lib.baseboard_fab2(sch_1):\MG_PCIE_L1\" )
					)
					( Units "uMatchProp" "ns" 1.000000)
					( Status sCSetFlattened )
					( Origin gBackEnd )
				)
			)
			( pinPair "@baseboard_fab2_lib.baseboard_fab2(sch_1):\PP192\"
				( pinRef "@baseboard_fab2_lib.baseboard_fab2(sch_1):page182_i18:IOG7" )
				( pinRef "@baseboard_fab2_lib.baseboard_fab2(sch_1):page182_i81:A" )
				( attribute "RELATIVE_PROPAGATION_DELAY_SCOPE" "L"
					( Parent
						( matchGroupRef "@baseboard_fab2_lib.baseboard_fab2(sch_1):\MG_PCIE_L0\" )
					)
					( Status sCSetFlattened )
					( Origin gBackEnd )
				)
				( attribute "RELATIVE_PROPAGATION_DELAY" ",5.00 MIL"
					( Parent
						( matchGroupRef "@baseboard_fab2_lib.baseboard_fab2(sch_1):\MG_PCIE_L0\" )
					)
					( Units "uMatchProp" "ns" 1.000000)
					( Status sCSetFlattened )
					( Origin gBackEnd )
				)
			)
			( pinPair "@baseboard_fab2_lib.baseboard_fab2(sch_1):\PP5976\"
				( pinRef "@baseboard_fab2_lib.baseboard_fab2(sch_1):page66_i84:PE3_TX_DN(13)" )
				( pinRef "@baseboard_fab2_lib.baseboard_fab2(sch_1):page182_i18:IOG7" )
				( attribute "PROPAGATION_DELAY_MIN" "3000.00 MIL"
					( Units "uMaxMinProp" "ns" 1.000000)
					( Status sCSetFlattened )
					( Origin gBackEnd )
				)
				( attribute "PROPAGATION_DELAY_MAX" "16000.00 MIL"
					( Units "uMaxMinProp" "ns" 1.000000)
					( Status sCSetFlattened )
					( Origin gBackEnd )
				)
				( attribute "RELATIVE_PROPAGATION_DELAY_SCOPE" "G"
					( Parent
						( matchGroupRef "@baseboard_fab2_lib.baseboard_fab2(sch_1):\MG_P3E_CPU1_PE3_MP_TX1213\" )
					)
					( Status sCSetFlattened )
					( Origin gBackEnd )
				)
				( attribute "RELATIVE_PROPAGATION_DELAY" ",500.00 MIL"
					( Parent
						( matchGroupRef "@baseboard_fab2_lib.baseboard_fab2(sch_1):\MG_P3E_CPU1_PE3_MP_TX1213\" )
					)
					( Units "uMatchProp" "ns" 1.000000)
					( Status sCSetFlattened )
					( Origin gBackEnd )
				)
			)
			( pinPair "@baseboard_fab2_lib.baseboard_fab2(sch_1):\PP193\"
				( pinRef "@baseboard_fab2_lib.baseboard_fab2(sch_1):page182_i18:IOH7" )
				( pinRef "@baseboard_fab2_lib.baseboard_fab2(sch_1):page182_i83:A" )
				( attribute "RELATIVE_PROPAGATION_DELAY_SCOPE" "L"
					( Parent
						( matchGroupRef "@baseboard_fab2_lib.baseboard_fab2(sch_1):\MG_PCIE_L0\" )
					)
					( Status sCSetFlattened )
					( Origin gBackEnd )
				)
				( attribute "RELATIVE_PROPAGATION_DELAY" ",5.00 MIL"
					( Parent
						( matchGroupRef "@baseboard_fab2_lib.baseboard_fab2(sch_1):\MG_PCIE_L0\" )
					)
					( Units "uMatchProp" "ns" 1.000000)
					( Status sCSetFlattened )
					( Origin gBackEnd )
				)
			)
			( pinPair "@baseboard_fab2_lib.baseboard_fab2(sch_1):\PP194\"
				( pinRef "@baseboard_fab2_lib.baseboard_fab2(sch_1):page66_i84:PE3_TX_DP(13)" )
				( pinRef "@baseboard_fab2_lib.baseboard_fab2(sch_1):page182_i83:B" )
				( attribute "RELATIVE_PROPAGATION_DELAY_SCOPE" "L"
					( Parent
						( matchGroupRef "@baseboard_fab2_lib.baseboard_fab2(sch_1):\MG_PCIE_L1\" )
					)
					( Status sCSetFlattened )
					( Origin gBackEnd )
				)
				( attribute "RELATIVE_PROPAGATION_DELAY" ",5.00 MIL"
					( Parent
						( matchGroupRef "@baseboard_fab2_lib.baseboard_fab2(sch_1):\MG_PCIE_L1\" )
					)
					( Units "uMatchProp" "ns" 1.000000)
					( Status sCSetFlattened )
					( Origin gBackEnd )
				)
			)
			( pinPair "@baseboard_fab2_lib.baseboard_fab2(sch_1):\PP5969\"
				( pinRef "@baseboard_fab2_lib.baseboard_fab2(sch_1):page66_i84:PE3_TX_DP(13)" )
				( pinRef "@baseboard_fab2_lib.baseboard_fab2(sch_1):page182_i18:IOH7" )
				( attribute "PROPAGATION_DELAY_MIN" "3000.00 MIL"
					( Units "uMaxMinProp" "ns" 1.000000)
					( Status sCSetFlattened )
					( Origin gBackEnd )
				)
				( attribute "PROPAGATION_DELAY_MAX" "16000.00 MIL"
					( Units "uMaxMinProp" "ns" 1.000000)
					( Status sCSetFlattened )
					( Origin gBackEnd )
				)
				( attribute "RELATIVE_PROPAGATION_DELAY_SCOPE" "G"
					( Parent
						( matchGroupRef "@baseboard_fab2_lib.baseboard_fab2(sch_1):\MG_P3E_CPU1_PE3_MP_TX1213\" )
					)
					( Status sCSetFlattened )
					( Origin gBackEnd )
				)
				( attribute "RELATIVE_PROPAGATION_DELAY" ",500.00 MIL"
					( Parent
						( matchGroupRef "@baseboard_fab2_lib.baseboard_fab2(sch_1):\MG_P3E_CPU1_PE3_MP_TX1213\" )
					)
					( Units "uMatchProp" "ns" 1.000000)
					( Status sCSetFlattened )
					( Origin gBackEnd )
				)
			)
			( pinPair "@baseboard_fab2_lib.baseboard_fab2(sch_1):\PP187\"
				( pinRef "@baseboard_fab2_lib.baseboard_fab2(sch_1):page66_i84:PE3_TX_DN(14)" )
				( pinRef "@baseboard_fab2_lib.baseboard_fab2(sch_1):page182_i50:B" )
				( attribute "RELATIVE_PROPAGATION_DELAY_SCOPE" "L"
					( Parent
						( matchGroupRef "@baseboard_fab2_lib.baseboard_fab2(sch_1):\MG_PCIE_L1\" )
					)
					( Status sCSetFlattened )
					( Origin gBackEnd )
				)
				( attribute "RELATIVE_PROPAGATION_DELAY" ",5.00 MIL"
					( Parent
						( matchGroupRef "@baseboard_fab2_lib.baseboard_fab2(sch_1):\MG_PCIE_L1\" )
					)
					( Units "uMatchProp" "ns" 1.000000)
					( Status sCSetFlattened )
					( Origin gBackEnd )
				)
			)
			( pinPair "@baseboard_fab2_lib.baseboard_fab2(sch_1):\PP188\"
				( pinRef "@baseboard_fab2_lib.baseboard_fab2(sch_1):page182_i18:IOE6" )
				( pinRef "@baseboard_fab2_lib.baseboard_fab2(sch_1):page182_i50:A" )
				( attribute "RELATIVE_PROPAGATION_DELAY_SCOPE" "L"
					( Parent
						( matchGroupRef "@baseboard_fab2_lib.baseboard_fab2(sch_1):\MG_PCIE_L0\" )
					)
					( Status sCSetFlattened )
					( Origin gBackEnd )
				)
				( attribute "RELATIVE_PROPAGATION_DELAY" ",5.00 MIL"
					( Parent
						( matchGroupRef "@baseboard_fab2_lib.baseboard_fab2(sch_1):\MG_PCIE_L0\" )
					)
					( Units "uMatchProp" "ns" 1.000000)
					( Status sCSetFlattened )
					( Origin gBackEnd )
				)
			)
			( pinPair "@baseboard_fab2_lib.baseboard_fab2(sch_1):\PP5979\"
				( pinRef "@baseboard_fab2_lib.baseboard_fab2(sch_1):page66_i84:PE3_TX_DN(14)" )
				( pinRef "@baseboard_fab2_lib.baseboard_fab2(sch_1):page182_i18:IOE6" )
				( attribute "PROPAGATION_DELAY_MIN" "3000.00 MIL"
					( Units "uMaxMinProp" "ns" 1.000000)
					( Status sCSetFlattened )
					( Origin gBackEnd )
				)
				( attribute "PROPAGATION_DELAY_MAX" "16000.00 MIL"
					( Units "uMaxMinProp" "ns" 1.000000)
					( Status sCSetFlattened )
					( Origin gBackEnd )
				)
				( attribute "RELATIVE_PROPAGATION_DELAY_SCOPE" "G"
					( Parent
						( matchGroupRef "@baseboard_fab2_lib.baseboard_fab2(sch_1):\MG_P3E_CPU1_PE3_MP_TX1415\" )
					)
					( Status sCSetFlattened )
					( Origin gBackEnd )
				)
				( attribute "RELATIVE_PROPAGATION_DELAY" ",500.00 MIL"
					( Parent
						( matchGroupRef "@baseboard_fab2_lib.baseboard_fab2(sch_1):\MG_P3E_CPU1_PE3_MP_TX1415\" )
					)
					( Units "uMatchProp" "ns" 1.000000)
					( Status sCSetFlattened )
					( Origin gBackEnd )
				)
			)
			( pinPair "@baseboard_fab2_lib.baseboard_fab2(sch_1):\PP189\"
				( pinRef "@baseboard_fab2_lib.baseboard_fab2(sch_1):page182_i18:IOF6" )
				( pinRef "@baseboard_fab2_lib.baseboard_fab2(sch_1):page182_i53:A" )
				( attribute "RELATIVE_PROPAGATION_DELAY_SCOPE" "L"
					( Parent
						( matchGroupRef "@baseboard_fab2_lib.baseboard_fab2(sch_1):\MG_PCIE_L0\" )
					)
					( Status sCSetFlattened )
					( Origin gBackEnd )
				)
				( attribute "RELATIVE_PROPAGATION_DELAY" ",5.00 MIL"
					( Parent
						( matchGroupRef "@baseboard_fab2_lib.baseboard_fab2(sch_1):\MG_PCIE_L0\" )
					)
					( Units "uMatchProp" "ns" 1.000000)
					( Status sCSetFlattened )
					( Origin gBackEnd )
				)
			)
			( pinPair "@baseboard_fab2_lib.baseboard_fab2(sch_1):\PP190\"
				( pinRef "@baseboard_fab2_lib.baseboard_fab2(sch_1):page66_i84:PE3_TX_DP(14)" )
				( pinRef "@baseboard_fab2_lib.baseboard_fab2(sch_1):page182_i53:B" )
				( attribute "RELATIVE_PROPAGATION_DELAY_SCOPE" "L"
					( Parent
						( matchGroupRef "@baseboard_fab2_lib.baseboard_fab2(sch_1):\MG_PCIE_L1\" )
					)
					( Status sCSetFlattened )
					( Origin gBackEnd )
				)
				( attribute "RELATIVE_PROPAGATION_DELAY" ",5.00 MIL"
					( Parent
						( matchGroupRef "@baseboard_fab2_lib.baseboard_fab2(sch_1):\MG_PCIE_L1\" )
					)
					( Units "uMatchProp" "ns" 1.000000)
					( Status sCSetFlattened )
					( Origin gBackEnd )
				)
			)
			( pinPair "@baseboard_fab2_lib.baseboard_fab2(sch_1):\PP5977\"
				( pinRef "@baseboard_fab2_lib.baseboard_fab2(sch_1):page66_i84:PE3_TX_DP(14)" )
				( pinRef "@baseboard_fab2_lib.baseboard_fab2(sch_1):page182_i18:IOF6" )
				( attribute "PROPAGATION_DELAY_MIN" "3000.00 MIL"
					( Units "uMaxMinProp" "ns" 1.000000)
					( Status sCSetFlattened )
					( Origin gBackEnd )
				)
				( attribute "PROPAGATION_DELAY_MAX" "16000.00 MIL"
					( Units "uMaxMinProp" "ns" 1.000000)
					( Status sCSetFlattened )
					( Origin gBackEnd )
				)
				( attribute "RELATIVE_PROPAGATION_DELAY_SCOPE" "G"
					( Parent
						( matchGroupRef "@baseboard_fab2_lib.baseboard_fab2(sch_1):\MG_P3E_CPU1_PE3_MP_TX1415\" )
					)
					( Status sCSetFlattened )
					( Origin gBackEnd )
				)
				( attribute "RELATIVE_PROPAGATION_DELAY" ",500.00 MIL"
					( Parent
						( matchGroupRef "@baseboard_fab2_lib.baseboard_fab2(sch_1):\MG_P3E_CPU1_PE3_MP_TX1415\" )
					)
					( Units "uMatchProp" "ns" 1.000000)
					( Status sCSetFlattened )
					( Origin gBackEnd )
				)
			)
			( pinPair "@baseboard_fab2_lib.baseboard_fab2(sch_1):\PP175\"
				( pinRef "@baseboard_fab2_lib.baseboard_fab2(sch_1):page182_i49:B" )
				( pinRef "@baseboard_fab2_lib.baseboard_fab2(sch_1):page66_i84:PE3_TX_DN(15)" )
				( attribute "RELATIVE_PROPAGATION_DELAY_SCOPE" "L"
					( Parent
						( matchGroupRef "@baseboard_fab2_lib.baseboard_fab2(sch_1):\MG_PCIE_L1\" )
					)
					( Status sCSetFlattened )
					( Origin gBackEnd )
				)
				( attribute "RELATIVE_PROPAGATION_DELAY" ",5.00 MIL"
					( Parent
						( matchGroupRef "@baseboard_fab2_lib.baseboard_fab2(sch_1):\MG_PCIE_L1\" )
					)
					( Units "uMatchProp" "ns" 1.000000)
					( Status sCSetFlattened )
					( Origin gBackEnd )
				)
			)
			( pinPair "@baseboard_fab2_lib.baseboard_fab2(sch_1):\PP176\"
				( pinRef "@baseboard_fab2_lib.baseboard_fab2(sch_1):page182_i18:IOH6" )
				( pinRef "@baseboard_fab2_lib.baseboard_fab2(sch_1):page182_i49:A" )
				( attribute "RELATIVE_PROPAGATION_DELAY_SCOPE" "L"
					( Parent
						( matchGroupRef "@baseboard_fab2_lib.baseboard_fab2(sch_1):\MG_PCIE_L0\" )
					)
					( Status sCSetFlattened )
					( Origin gBackEnd )
				)
				( attribute "RELATIVE_PROPAGATION_DELAY" ",5.00 MIL"
					( Parent
						( matchGroupRef "@baseboard_fab2_lib.baseboard_fab2(sch_1):\MG_PCIE_L0\" )
					)
					( Units "uMatchProp" "ns" 1.000000)
					( Status sCSetFlattened )
					( Origin gBackEnd )
				)
			)
			( pinPair "@baseboard_fab2_lib.baseboard_fab2(sch_1):\PP5987\"
				( pinRef "@baseboard_fab2_lib.baseboard_fab2(sch_1):page66_i84:PE3_TX_DN(15)" )
				( pinRef "@baseboard_fab2_lib.baseboard_fab2(sch_1):page182_i18:IOH6" )
				( attribute "PROPAGATION_DELAY_MIN" "3000.00 MIL"
					( Units "uMaxMinProp" "ns" 1.000000)
					( Status sCSetFlattened )
					( Origin gBackEnd )
				)
				( attribute "PROPAGATION_DELAY_MAX" "16000.00 MIL"
					( Units "uMaxMinProp" "ns" 1.000000)
					( Status sCSetFlattened )
					( Origin gBackEnd )
				)
				( attribute "RELATIVE_PROPAGATION_DELAY_SCOPE" "G"
					( Parent
						( matchGroupRef "@baseboard_fab2_lib.baseboard_fab2(sch_1):\MG_P3E_CPU1_PE3_MP_TX1415\" )
					)
					( Status sCSetFlattened )
					( Origin gBackEnd )
				)
				( attribute "RELATIVE_PROPAGATION_DELAY" ",500.00 MIL"
					( Parent
						( matchGroupRef "@baseboard_fab2_lib.baseboard_fab2(sch_1):\MG_P3E_CPU1_PE3_MP_TX1415\" )
					)
					( Units "uMatchProp" "ns" 1.000000)
					( Status sCSetFlattened )
					( Origin gBackEnd )
				)
			)
			( pinPair "@baseboard_fab2_lib.baseboard_fab2(sch_1):\PP177\"
				( pinRef "@baseboard_fab2_lib.baseboard_fab2(sch_1):page182_i18:IOI6" )
				( pinRef "@baseboard_fab2_lib.baseboard_fab2(sch_1):page182_i54:A" )
				( attribute "RELATIVE_PROPAGATION_DELAY_SCOPE" "L"
					( Parent
						( matchGroupRef "@baseboard_fab2_lib.baseboard_fab2(sch_1):\MG_PCIE_L0\" )
					)
					( Status sCSetFlattened )
					( Origin gBackEnd )
				)
				( attribute "RELATIVE_PROPAGATION_DELAY" ",5.00 MIL"
					( Parent
						( matchGroupRef "@baseboard_fab2_lib.baseboard_fab2(sch_1):\MG_PCIE_L0\" )
					)
					( Units "uMatchProp" "ns" 1.000000)
					( Status sCSetFlattened )
					( Origin gBackEnd )
				)
			)
			( pinPair "@baseboard_fab2_lib.baseboard_fab2(sch_1):\PP178\"
				( pinRef "@baseboard_fab2_lib.baseboard_fab2(sch_1):page182_i54:B" )
				( pinRef "@baseboard_fab2_lib.baseboard_fab2(sch_1):page66_i84:PE3_TX_DP(15)" )
				( attribute "RELATIVE_PROPAGATION_DELAY_SCOPE" "L"
					( Parent
						( matchGroupRef "@baseboard_fab2_lib.baseboard_fab2(sch_1):\MG_PCIE_L1\" )
					)
					( Status sCSetFlattened )
					( Origin gBackEnd )
				)
				( attribute "RELATIVE_PROPAGATION_DELAY" ",5.00 MIL"
					( Parent
						( matchGroupRef "@baseboard_fab2_lib.baseboard_fab2(sch_1):\MG_PCIE_L1\" )
					)
					( Units "uMatchProp" "ns" 1.000000)
					( Status sCSetFlattened )
					( Origin gBackEnd )
				)
			)
			( pinPair "@baseboard_fab2_lib.baseboard_fab2(sch_1):\PP5978\"
				( pinRef "@baseboard_fab2_lib.baseboard_fab2(sch_1):page66_i84:PE3_TX_DP(15)" )
				( pinRef "@baseboard_fab2_lib.baseboard_fab2(sch_1):page182_i18:IOI6" )
				( attribute "PROPAGATION_DELAY_MIN" "3000.00 MIL"
					( Units "uMaxMinProp" "ns" 1.000000)
					( Status sCSetFlattened )
					( Origin gBackEnd )
				)
				( attribute "PROPAGATION_DELAY_MAX" "16000.00 MIL"
					( Units "uMaxMinProp" "ns" 1.000000)
					( Status sCSetFlattened )
					( Origin gBackEnd )
				)
				( attribute "RELATIVE_PROPAGATION_DELAY_SCOPE" "G"
					( Parent
						( matchGroupRef "@baseboard_fab2_lib.baseboard_fab2(sch_1):\MG_P3E_CPU1_PE3_MP_TX1415\" )
					)
					( Status sCSetFlattened )
					( Origin gBackEnd )
				)
				( attribute "RELATIVE_PROPAGATION_DELAY" ",500.00 MIL"
					( Parent
						( matchGroupRef "@baseboard_fab2_lib.baseboard_fab2(sch_1):\MG_P3E_CPU1_PE3_MP_TX1415\" )
					)
					( Units "uMatchProp" "ns" 1.000000)
					( Status sCSetFlattened )
					( Origin gBackEnd )
				)
			)
			( pinPair "@baseboard_fab2_lib.baseboard_fab2(sch_1):\PP183\"
				( pinRef "@baseboard_fab2_lib.baseboard_fab2(sch_1):page66_i84:PE3_TX_DN(7)" )
				( pinRef "@baseboard_fab2_lib.baseboard_fab2(sch_1):page181_i167:B" )
				( attribute "RELATIVE_PROPAGATION_DELAY_SCOPE" "L"
					( Parent
						( matchGroupRef "@baseboard_fab2_lib.baseboard_fab2(sch_1):\MG_PCIE_L1\" )
					)
					( Status sCSetFlattened )
					( Origin gBackEnd )
				)
				( attribute "RELATIVE_PROPAGATION_DELAY" ",5.00 MIL"
					( Parent
						( matchGroupRef "@baseboard_fab2_lib.baseboard_fab2(sch_1):\MG_PCIE_L1\" )
					)
					( Units "uMatchProp" "ns" 1.000000)
					( Status sCSetFlattened )
					( Origin gBackEnd )
				)
			)
			( pinPair "@baseboard_fab2_lib.baseboard_fab2(sch_1):\PP184\"
				( pinRef "@baseboard_fab2_lib.baseboard_fab2(sch_1):page181_i111:IOI6" )
				( pinRef "@baseboard_fab2_lib.baseboard_fab2(sch_1):page181_i167:A" )
				( attribute "RELATIVE_PROPAGATION_DELAY_SCOPE" "L"
					( Parent
						( matchGroupRef "@baseboard_fab2_lib.baseboard_fab2(sch_1):\MG_PCIE_L0\" )
					)
					( Status sCSetFlattened )
					( Origin gBackEnd )
				)
				( attribute "RELATIVE_PROPAGATION_DELAY" ",5.00 MIL"
					( Parent
						( matchGroupRef "@baseboard_fab2_lib.baseboard_fab2(sch_1):\MG_PCIE_L0\" )
					)
					( Units "uMatchProp" "ns" 1.000000)
					( Status sCSetFlattened )
					( Origin gBackEnd )
				)
			)
			( pinPair "@baseboard_fab2_lib.baseboard_fab2(sch_1):\PP5981\"
				( pinRef "@baseboard_fab2_lib.baseboard_fab2(sch_1):page66_i84:PE3_TX_DN(7)" )
				( pinRef "@baseboard_fab2_lib.baseboard_fab2(sch_1):page181_i111:IOI6" )
				( attribute "PROPAGATION_DELAY_MIN" "3000.00 MIL"
					( Units "uMaxMinProp" "ns" 1.000000)
					( Status sCSetFlattened )
					( Origin gBackEnd )
				)
				( attribute "PROPAGATION_DELAY_MAX" "16000.00 MIL"
					( Units "uMaxMinProp" "ns" 1.000000)
					( Status sCSetFlattened )
					( Origin gBackEnd )
				)
				( attribute "RELATIVE_PROPAGATION_DELAY_SCOPE" "G"
					( Parent
						( matchGroupRef "@baseboard_fab2_lib.baseboard_fab2(sch_1):\MG_P3E_CPU1_PE3_MP_TX0607\" )
					)
					( Status sCSetFlattened )
					( Origin gBackEnd )
				)
				( attribute "RELATIVE_PROPAGATION_DELAY" ",500.00 MIL"
					( Parent
						( matchGroupRef "@baseboard_fab2_lib.baseboard_fab2(sch_1):\MG_P3E_CPU1_PE3_MP_TX0607\" )
					)
					( Units "uMatchProp" "ns" 1.000000)
					( Status sCSetFlattened )
					( Origin gBackEnd )
				)
			)
			( pinPair "@baseboard_fab2_lib.baseboard_fab2(sch_1):\PP185\"
				( pinRef "@baseboard_fab2_lib.baseboard_fab2(sch_1):page66_i84:PE3_TX_DP(7)" )
				( pinRef "@baseboard_fab2_lib.baseboard_fab2(sch_1):page181_i162:B" )
				( attribute "RELATIVE_PROPAGATION_DELAY_SCOPE" "L"
					( Parent
						( matchGroupRef "@baseboard_fab2_lib.baseboard_fab2(sch_1):\MG_PCIE_L1\" )
					)
					( Status sCSetFlattened )
					( Origin gBackEnd )
				)
				( attribute "RELATIVE_PROPAGATION_DELAY" ",5.00 MIL"
					( Parent
						( matchGroupRef "@baseboard_fab2_lib.baseboard_fab2(sch_1):\MG_PCIE_L1\" )
					)
					( Units "uMatchProp" "ns" 1.000000)
					( Status sCSetFlattened )
					( Origin gBackEnd )
				)
			)
			( pinPair "@baseboard_fab2_lib.baseboard_fab2(sch_1):\PP186\"
				( pinRef "@baseboard_fab2_lib.baseboard_fab2(sch_1):page181_i111:IOH6" )
				( pinRef "@baseboard_fab2_lib.baseboard_fab2(sch_1):page181_i162:A" )
				( attribute "RELATIVE_PROPAGATION_DELAY_SCOPE" "L"
					( Parent
						( matchGroupRef "@baseboard_fab2_lib.baseboard_fab2(sch_1):\MG_PCIE_L0\" )
					)
					( Status sCSetFlattened )
					( Origin gBackEnd )
				)
				( attribute "RELATIVE_PROPAGATION_DELAY" ",5.00 MIL"
					( Parent
						( matchGroupRef "@baseboard_fab2_lib.baseboard_fab2(sch_1):\MG_PCIE_L0\" )
					)
					( Units "uMatchProp" "ns" 1.000000)
					( Status sCSetFlattened )
					( Origin gBackEnd )
				)
			)
			( pinPair "@baseboard_fab2_lib.baseboard_fab2(sch_1):\PP5980\"
				( pinRef "@baseboard_fab2_lib.baseboard_fab2(sch_1):page66_i84:PE3_TX_DP(7)" )
				( pinRef "@baseboard_fab2_lib.baseboard_fab2(sch_1):page181_i111:IOH6" )
				( attribute "PROPAGATION_DELAY_MIN" "3000.00 MIL"
					( Units "uMaxMinProp" "ns" 1.000000)
					( Status sCSetFlattened )
					( Origin gBackEnd )
				)
				( attribute "PROPAGATION_DELAY_MAX" "16000.00 MIL"
					( Units "uMaxMinProp" "ns" 1.000000)
					( Status sCSetFlattened )
					( Origin gBackEnd )
				)
				( attribute "RELATIVE_PROPAGATION_DELAY_SCOPE" "G"
					( Parent
						( matchGroupRef "@baseboard_fab2_lib.baseboard_fab2(sch_1):\MG_P3E_CPU1_PE3_MP_TX0607\" )
					)
					( Status sCSetFlattened )
					( Origin gBackEnd )
				)
				( attribute "RELATIVE_PROPAGATION_DELAY" ",500.00 MIL"
					( Parent
						( matchGroupRef "@baseboard_fab2_lib.baseboard_fab2(sch_1):\MG_P3E_CPU1_PE3_MP_TX0607\" )
					)
					( Units "uMatchProp" "ns" 1.000000)
					( Status sCSetFlattened )
					( Origin gBackEnd )
				)
			)
			( pinPair "@baseboard_fab2_lib.baseboard_fab2(sch_1):\PP179\"
				( pinRef "@baseboard_fab2_lib.baseboard_fab2(sch_1):page182_i13:B" )
				( pinRef "@baseboard_fab2_lib.baseboard_fab2(sch_1):page66_i84:PE3_TX_DN(9)" )
				( attribute "RELATIVE_PROPAGATION_DELAY_SCOPE" "L"
					( Parent
						( matchGroupRef "@baseboard_fab2_lib.baseboard_fab2(sch_1):\MG_PCIE_L1\" )
					)
					( Status sCSetFlattened )
					( Origin gBackEnd )
				)
				( attribute "RELATIVE_PROPAGATION_DELAY" ",5.00 MIL"
					( Parent
						( matchGroupRef "@baseboard_fab2_lib.baseboard_fab2(sch_1):\MG_PCIE_L1\" )
					)
					( Units "uMatchProp" "ns" 1.000000)
					( Status sCSetFlattened )
					( Origin gBackEnd )
				)
			)
			( pinPair "@baseboard_fab2_lib.baseboard_fab2(sch_1):\PP180\"
				( pinRef "@baseboard_fab2_lib.baseboard_fab2(sch_1):page182_i18:IOE8" )
				( pinRef "@baseboard_fab2_lib.baseboard_fab2(sch_1):page182_i13:A" )
				( attribute "RELATIVE_PROPAGATION_DELAY_SCOPE" "L"
					( Parent
						( matchGroupRef "@baseboard_fab2_lib.baseboard_fab2(sch_1):\MG_PCIE_L0\" )
					)
					( Status sCSetFlattened )
					( Origin gBackEnd )
				)
				( attribute "RELATIVE_PROPAGATION_DELAY" ",5.00 MIL"
					( Parent
						( matchGroupRef "@baseboard_fab2_lib.baseboard_fab2(sch_1):\MG_PCIE_L0\" )
					)
					( Units "uMatchProp" "ns" 1.000000)
					( Status sCSetFlattened )
					( Origin gBackEnd )
				)
			)
			( pinPair "@baseboard_fab2_lib.baseboard_fab2(sch_1):\PP5983\"
				( pinRef "@baseboard_fab2_lib.baseboard_fab2(sch_1):page66_i84:PE3_TX_DN(9)" )
				( pinRef "@baseboard_fab2_lib.baseboard_fab2(sch_1):page182_i18:IOE8" )
				( attribute "PROPAGATION_DELAY_MIN" "3000.00 MIL"
					( Units "uMaxMinProp" "ns" 1.000000)
					( Status sCSetFlattened )
					( Origin gBackEnd )
				)
				( attribute "PROPAGATION_DELAY_MAX" "16000.00 MIL"
					( Units "uMaxMinProp" "ns" 1.000000)
					( Status sCSetFlattened )
					( Origin gBackEnd )
				)
				( attribute "RELATIVE_PROPAGATION_DELAY_SCOPE" "G"
					( Parent
						( matchGroupRef "@baseboard_fab2_lib.baseboard_fab2(sch_1):\MG_P3E_CPU1_PE3_MP_TX0809\" )
					)
					( Status sCSetFlattened )
					( Origin gBackEnd )
				)
				( attribute "RELATIVE_PROPAGATION_DELAY" ",500.00 MIL"
					( Parent
						( matchGroupRef "@baseboard_fab2_lib.baseboard_fab2(sch_1):\MG_P3E_CPU1_PE3_MP_TX0809\" )
					)
					( Units "uMatchProp" "ns" 1.000000)
					( Status sCSetFlattened )
					( Origin gBackEnd )
				)
			)
			( pinPair "@baseboard_fab2_lib.baseboard_fab2(sch_1):\PP181\"
				( pinRef "@baseboard_fab2_lib.baseboard_fab2(sch_1):page182_i18:IOF8" )
				( pinRef "@baseboard_fab2_lib.baseboard_fab2(sch_1):page182_i16:A" )
				( attribute "RELATIVE_PROPAGATION_DELAY_SCOPE" "L"
					( Parent
						( matchGroupRef "@baseboard_fab2_lib.baseboard_fab2(sch_1):\MG_PCIE_L0\" )
					)
					( Status sCSetFlattened )
					( Origin gBackEnd )
				)
				( attribute "RELATIVE_PROPAGATION_DELAY" ",5.00 MIL"
					( Parent
						( matchGroupRef "@baseboard_fab2_lib.baseboard_fab2(sch_1):\MG_PCIE_L0\" )
					)
					( Units "uMatchProp" "ns" 1.000000)
					( Status sCSetFlattened )
					( Origin gBackEnd )
				)
			)
			( pinPair "@baseboard_fab2_lib.baseboard_fab2(sch_1):\PP182\"
				( pinRef "@baseboard_fab2_lib.baseboard_fab2(sch_1):page182_i16:B" )
				( pinRef "@baseboard_fab2_lib.baseboard_fab2(sch_1):page66_i84:PE3_TX_DP(9)" )
				( attribute "RELATIVE_PROPAGATION_DELAY_SCOPE" "L"
					( Parent
						( matchGroupRef "@baseboard_fab2_lib.baseboard_fab2(sch_1):\MG_PCIE_L1\" )
					)
					( Status sCSetFlattened )
					( Origin gBackEnd )
				)
				( attribute "RELATIVE_PROPAGATION_DELAY" ",5.00 MIL"
					( Parent
						( matchGroupRef "@baseboard_fab2_lib.baseboard_fab2(sch_1):\MG_PCIE_L1\" )
					)
					( Units "uMatchProp" "ns" 1.000000)
					( Status sCSetFlattened )
					( Origin gBackEnd )
				)
			)
			( pinPair "@baseboard_fab2_lib.baseboard_fab2(sch_1):\PP5982\"
				( pinRef "@baseboard_fab2_lib.baseboard_fab2(sch_1):page66_i84:PE3_TX_DP(9)" )
				( pinRef "@baseboard_fab2_lib.baseboard_fab2(sch_1):page182_i18:IOF8" )
				( attribute "PROPAGATION_DELAY_MIN" "3000.00 MIL"
					( Units "uMaxMinProp" "ns" 1.000000)
					( Status sCSetFlattened )
					( Origin gBackEnd )
				)
				( attribute "PROPAGATION_DELAY_MAX" "16000.00 MIL"
					( Units "uMaxMinProp" "ns" 1.000000)
					( Status sCSetFlattened )
					( Origin gBackEnd )
				)
				( attribute "RELATIVE_PROPAGATION_DELAY_SCOPE" "G"
					( Parent
						( matchGroupRef "@baseboard_fab2_lib.baseboard_fab2(sch_1):\MG_P3E_CPU1_PE3_MP_TX0809\" )
					)
					( Status sCSetFlattened )
					( Origin gBackEnd )
				)
				( attribute "RELATIVE_PROPAGATION_DELAY" ",500.00 MIL"
					( Parent
						( matchGroupRef "@baseboard_fab2_lib.baseboard_fab2(sch_1):\MG_P3E_CPU1_PE3_MP_TX0809\" )
					)
					( Units "uMatchProp" "ns" 1.000000)
					( Status sCSetFlattened )
					( Origin gBackEnd )
				)
			)
			( pinPair "@baseboard_fab2_lib.baseboard_fab2(sch_1):\PP3033\"
				( pinRef "@baseboard_fab2_lib.baseboard_fab2(sch_1):page66_i84:PE3_RX_DP(0)" )
				( pinRef "@baseboard_fab2_lib.baseboard_fab2(sch_1):page181_i111:IOB1" )
				( attribute "PROPAGATION_DELAY_MIN" "3000.00 MIL"
					( Units "uMaxMinProp" "ns" 1.000000)
					( Status sCSetFlattened )
					( Origin gBackEnd )
				)
				( attribute "PROPAGATION_DELAY_MAX" "16000.00 MIL"
					( Units "uMaxMinProp" "ns" 1.000000)
					( Status sCSetFlattened )
					( Origin gBackEnd )
				)
				( attribute "RELATIVE_PROPAGATION_DELAY_SCOPE" "G"
					( Parent
						( matchGroupRef "@baseboard_fab2_lib.baseboard_fab2(sch_1):\MG_P3E_CPU1_PE3_MP_RX0001\" )
					)
					( Status sCSetFlattened )
					( Origin gBackEnd )
				)
				( attribute "RELATIVE_PROPAGATION_DELAY" ",500.00 MIL"
					( Parent
						( matchGroupRef "@baseboard_fab2_lib.baseboard_fab2(sch_1):\MG_P3E_CPU1_PE3_MP_RX0001\" )
					)
					( Units "uMatchProp" "ns" 1.000000)
					( Status sCSetFlattened )
					( Origin gBackEnd )
				)
			)
			( pinPair "@baseboard_fab2_lib.baseboard_fab2(sch_1):\PP3031\"
				( pinRef "@baseboard_fab2_lib.baseboard_fab2(sch_1):page66_i84:PE3_RX_DN(0)" )
				( pinRef "@baseboard_fab2_lib.baseboard_fab2(sch_1):page181_i111:IOA1" )
				( attribute "PROPAGATION_DELAY_MIN" "3000.00 MIL"
					( Units "uMaxMinProp" "ns" 1.000000)
					( Status sCSetFlattened )
					( Origin gBackEnd )
				)
				( attribute "PROPAGATION_DELAY_MAX" "16000.00 MIL"
					( Units "uMaxMinProp" "ns" 1.000000)
					( Status sCSetFlattened )
					( Origin gBackEnd )
				)
				( attribute "RELATIVE_PROPAGATION_DELAY_SCOPE" "G"
					( Parent
						( matchGroupRef "@baseboard_fab2_lib.baseboard_fab2(sch_1):\MG_P3E_CPU1_PE3_MP_RX0001\" )
					)
					( Status sCSetFlattened )
					( Origin gBackEnd )
				)
				( attribute "RELATIVE_PROPAGATION_DELAY" ",500.00 MIL"
					( Parent
						( matchGroupRef "@baseboard_fab2_lib.baseboard_fab2(sch_1):\MG_P3E_CPU1_PE3_MP_RX0001\" )
					)
					( Units "uMatchProp" "ns" 1.000000)
					( Status sCSetFlattened )
					( Origin gBackEnd )
				)
			)
			( pinPair "@baseboard_fab2_lib.baseboard_fab2(sch_1):\PP3034\"
				( pinRef "@baseboard_fab2_lib.baseboard_fab2(sch_1):page66_i84:PE3_RX_DP(1)" )
				( pinRef "@baseboard_fab2_lib.baseboard_fab2(sch_1):page181_i111:IOE1" )
				( attribute "PROPAGATION_DELAY_MIN" "3000.00 MIL"
					( Units "uMaxMinProp" "ns" 1.000000)
					( Status sCSetFlattened )
					( Origin gBackEnd )
				)
				( attribute "PROPAGATION_DELAY_MAX" "16000.00 MIL"
					( Units "uMaxMinProp" "ns" 1.000000)
					( Status sCSetFlattened )
					( Origin gBackEnd )
				)
				( attribute "RELATIVE_PROPAGATION_DELAY_SCOPE" "G"
					( Parent
						( matchGroupRef "@baseboard_fab2_lib.baseboard_fab2(sch_1):\MG_P3E_CPU1_PE3_MP_RX0001\" )
					)
					( Status sCSetFlattened )
					( Origin gBackEnd )
				)
				( attribute "RELATIVE_PROPAGATION_DELAY" ",500.00 MIL"
					( Parent
						( matchGroupRef "@baseboard_fab2_lib.baseboard_fab2(sch_1):\MG_P3E_CPU1_PE3_MP_RX0001\" )
					)
					( Units "uMatchProp" "ns" 1.000000)
					( Status sCSetFlattened )
					( Origin gBackEnd )
				)
			)
			( pinPair "@baseboard_fab2_lib.baseboard_fab2(sch_1):\PP3032\"
				( pinRef "@baseboard_fab2_lib.baseboard_fab2(sch_1):page66_i84:PE3_RX_DN(1)" )
				( pinRef "@baseboard_fab2_lib.baseboard_fab2(sch_1):page181_i111:IOD1" )
				( attribute "PROPAGATION_DELAY_MIN" "3000.00 MIL"
					( Units "uMaxMinProp" "ns" 1.000000)
					( Status sCSetFlattened )
					( Origin gBackEnd )
				)
				( attribute "PROPAGATION_DELAY_MAX" "16000.00 MIL"
					( Units "uMaxMinProp" "ns" 1.000000)
					( Status sCSetFlattened )
					( Origin gBackEnd )
				)
				( attribute "RELATIVE_PROPAGATION_DELAY_SCOPE" "G"
					( Parent
						( matchGroupRef "@baseboard_fab2_lib.baseboard_fab2(sch_1):\MG_P3E_CPU1_PE3_MP_RX0001\" )
					)
					( Status sCSetFlattened )
					( Origin gBackEnd )
				)
				( attribute "RELATIVE_PROPAGATION_DELAY" ",500.00 MIL"
					( Parent
						( matchGroupRef "@baseboard_fab2_lib.baseboard_fab2(sch_1):\MG_P3E_CPU1_PE3_MP_RX0001\" )
					)
					( Units "uMatchProp" "ns" 1.000000)
					( Status sCSetFlattened )
					( Origin gBackEnd )
				)
			)
			( pinPair "@baseboard_fab2_lib.baseboard_fab2(sch_1):\PP3029\"
				( pinRef "@baseboard_fab2_lib.baseboard_fab2(sch_1):page66_i84:PE3_RX_DP(2)" )
				( pinRef "@baseboard_fab2_lib.baseboard_fab2(sch_1):page181_i111:IOG1" )
				( attribute "PROPAGATION_DELAY_MIN" "3000.00 MIL"
					( Units "uMaxMinProp" "ns" 1.000000)
					( Status sCSetFlattened )
					( Origin gBackEnd )
				)
				( attribute "PROPAGATION_DELAY_MAX" "16000.00 MIL"
					( Units "uMaxMinProp" "ns" 1.000000)
					( Status sCSetFlattened )
					( Origin gBackEnd )
				)
				( attribute "RELATIVE_PROPAGATION_DELAY_SCOPE" "G"
					( Parent
						( matchGroupRef "@baseboard_fab2_lib.baseboard_fab2(sch_1):\MG_P3E_CPU1_PE3_MP_RX0203\" )
					)
					( Status sCSetFlattened )
					( Origin gBackEnd )
				)
				( attribute "RELATIVE_PROPAGATION_DELAY" ",500.00 MIL"
					( Parent
						( matchGroupRef "@baseboard_fab2_lib.baseboard_fab2(sch_1):\MG_P3E_CPU1_PE3_MP_RX0203\" )
					)
					( Units "uMatchProp" "ns" 1.000000)
					( Status sCSetFlattened )
					( Origin gBackEnd )
				)
			)
			( pinPair "@baseboard_fab2_lib.baseboard_fab2(sch_1):\PP3027\"
				( pinRef "@baseboard_fab2_lib.baseboard_fab2(sch_1):page66_i84:PE3_RX_DN(2)" )
				( pinRef "@baseboard_fab2_lib.baseboard_fab2(sch_1):page181_i111:IOH1" )
				( attribute "PROPAGATION_DELAY_MIN" "3000.00 MIL"
					( Units "uMaxMinProp" "ns" 1.000000)
					( Status sCSetFlattened )
					( Origin gBackEnd )
				)
				( attribute "PROPAGATION_DELAY_MAX" "16000.00 MIL"
					( Units "uMaxMinProp" "ns" 1.000000)
					( Status sCSetFlattened )
					( Origin gBackEnd )
				)
				( attribute "RELATIVE_PROPAGATION_DELAY_SCOPE" "G"
					( Parent
						( matchGroupRef "@baseboard_fab2_lib.baseboard_fab2(sch_1):\MG_P3E_CPU1_PE3_MP_RX0203\" )
					)
					( Status sCSetFlattened )
					( Origin gBackEnd )
				)
				( attribute "RELATIVE_PROPAGATION_DELAY" ",500.00 MIL"
					( Parent
						( matchGroupRef "@baseboard_fab2_lib.baseboard_fab2(sch_1):\MG_P3E_CPU1_PE3_MP_RX0203\" )
					)
					( Units "uMatchProp" "ns" 1.000000)
					( Status sCSetFlattened )
					( Origin gBackEnd )
				)
			)
			( pinPair "@baseboard_fab2_lib.baseboard_fab2(sch_1):\PP3030\"
				( pinRef "@baseboard_fab2_lib.baseboard_fab2(sch_1):page66_i84:PE3_RX_DP(3)" )
				( pinRef "@baseboard_fab2_lib.baseboard_fab2(sch_1):page181_i111:IOC2" )
				( attribute "PROPAGATION_DELAY_MIN" "3000.00 MIL"
					( Units "uMaxMinProp" "ns" 1.000000)
					( Status sCSetFlattened )
					( Origin gBackEnd )
				)
				( attribute "PROPAGATION_DELAY_MAX" "16000.00 MIL"
					( Units "uMaxMinProp" "ns" 1.000000)
					( Status sCSetFlattened )
					( Origin gBackEnd )
				)
				( attribute "RELATIVE_PROPAGATION_DELAY_SCOPE" "G"
					( Parent
						( matchGroupRef "@baseboard_fab2_lib.baseboard_fab2(sch_1):\MG_P3E_CPU1_PE3_MP_RX0203\" )
					)
					( Status sCSetFlattened )
					( Origin gBackEnd )
				)
				( attribute "RELATIVE_PROPAGATION_DELAY" ",500.00 MIL"
					( Parent
						( matchGroupRef "@baseboard_fab2_lib.baseboard_fab2(sch_1):\MG_P3E_CPU1_PE3_MP_RX0203\" )
					)
					( Units "uMatchProp" "ns" 1.000000)
					( Status sCSetFlattened )
					( Origin gBackEnd )
				)
			)
			( pinPair "@baseboard_fab2_lib.baseboard_fab2(sch_1):\PP3028\"
				( pinRef "@baseboard_fab2_lib.baseboard_fab2(sch_1):page66_i84:PE3_RX_DN(3)" )
				( pinRef "@baseboard_fab2_lib.baseboard_fab2(sch_1):page181_i111:IOB2" )
				( attribute "PROPAGATION_DELAY_MIN" "3000.00 MIL"
					( Units "uMaxMinProp" "ns" 1.000000)
					( Status sCSetFlattened )
					( Origin gBackEnd )
				)
				( attribute "PROPAGATION_DELAY_MAX" "16000.00 MIL"
					( Units "uMaxMinProp" "ns" 1.000000)
					( Status sCSetFlattened )
					( Origin gBackEnd )
				)
				( attribute "RELATIVE_PROPAGATION_DELAY_SCOPE" "G"
					( Parent
						( matchGroupRef "@baseboard_fab2_lib.baseboard_fab2(sch_1):\MG_P3E_CPU1_PE3_MP_RX0203\" )
					)
					( Status sCSetFlattened )
					( Origin gBackEnd )
				)
				( attribute "RELATIVE_PROPAGATION_DELAY" ",500.00 MIL"
					( Parent
						( matchGroupRef "@baseboard_fab2_lib.baseboard_fab2(sch_1):\MG_P3E_CPU1_PE3_MP_RX0203\" )
					)
					( Units "uMatchProp" "ns" 1.000000)
					( Status sCSetFlattened )
					( Origin gBackEnd )
				)
			)
			( pinPair "@baseboard_fab2_lib.baseboard_fab2(sch_1):\PP3025\"
				( pinRef "@baseboard_fab2_lib.baseboard_fab2(sch_1):page66_i84:PE3_RX_DP(4)" )
				( pinRef "@baseboard_fab2_lib.baseboard_fab2(sch_1):page181_i111:IOF2" )
				( attribute "PROPAGATION_DELAY_MIN" "3000.00 MIL"
					( Units "uMaxMinProp" "ns" 1.000000)
					( Status sCSetFlattened )
					( Origin gBackEnd )
				)
				( attribute "PROPAGATION_DELAY_MAX" "16000.00 MIL"
					( Units "uMaxMinProp" "ns" 1.000000)
					( Status sCSetFlattened )
					( Origin gBackEnd )
				)
				( attribute "RELATIVE_PROPAGATION_DELAY_SCOPE" "G"
					( Parent
						( matchGroupRef "@baseboard_fab2_lib.baseboard_fab2(sch_1):\MG_P3E_CPU1_PE3_MP_RX0405\" )
					)
					( Status sCSetFlattened )
					( Origin gBackEnd )
				)
				( attribute "RELATIVE_PROPAGATION_DELAY" ",500.00 MIL"
					( Parent
						( matchGroupRef "@baseboard_fab2_lib.baseboard_fab2(sch_1):\MG_P3E_CPU1_PE3_MP_RX0405\" )
					)
					( Units "uMatchProp" "ns" 1.000000)
					( Status sCSetFlattened )
					( Origin gBackEnd )
				)
			)
			( pinPair "@baseboard_fab2_lib.baseboard_fab2(sch_1):\PP3023\"
				( pinRef "@baseboard_fab2_lib.baseboard_fab2(sch_1):page66_i84:PE3_RX_DN(4)" )
				( pinRef "@baseboard_fab2_lib.baseboard_fab2(sch_1):page181_i111:IOE2" )
				( attribute "PROPAGATION_DELAY_MIN" "3000.00 MIL"
					( Units "uMaxMinProp" "ns" 1.000000)
					( Status sCSetFlattened )
					( Origin gBackEnd )
				)
				( attribute "PROPAGATION_DELAY_MAX" "16000.00 MIL"
					( Units "uMaxMinProp" "ns" 1.000000)
					( Status sCSetFlattened )
					( Origin gBackEnd )
				)
				( attribute "RELATIVE_PROPAGATION_DELAY_SCOPE" "G"
					( Parent
						( matchGroupRef "@baseboard_fab2_lib.baseboard_fab2(sch_1):\MG_P3E_CPU1_PE3_MP_RX0405\" )
					)
					( Status sCSetFlattened )
					( Origin gBackEnd )
				)
				( attribute "RELATIVE_PROPAGATION_DELAY" ",500.00 MIL"
					( Parent
						( matchGroupRef "@baseboard_fab2_lib.baseboard_fab2(sch_1):\MG_P3E_CPU1_PE3_MP_RX0405\" )
					)
					( Units "uMatchProp" "ns" 1.000000)
					( Status sCSetFlattened )
					( Origin gBackEnd )
				)
			)
			( pinPair "@baseboard_fab2_lib.baseboard_fab2(sch_1):\PP3026\"
				( pinRef "@baseboard_fab2_lib.baseboard_fab2(sch_1):page66_i84:PE3_RX_DP(5)" )
				( pinRef "@baseboard_fab2_lib.baseboard_fab2(sch_1):page181_i111:IOH2" )
				( attribute "PROPAGATION_DELAY_MIN" "3000.00 MIL"
					( Units "uMaxMinProp" "ns" 1.000000)
					( Status sCSetFlattened )
					( Origin gBackEnd )
				)
				( attribute "PROPAGATION_DELAY_MAX" "16000.00 MIL"
					( Units "uMaxMinProp" "ns" 1.000000)
					( Status sCSetFlattened )
					( Origin gBackEnd )
				)
				( attribute "RELATIVE_PROPAGATION_DELAY_SCOPE" "G"
					( Parent
						( matchGroupRef "@baseboard_fab2_lib.baseboard_fab2(sch_1):\MG_P3E_CPU1_PE3_MP_RX0405\" )
					)
					( Status sCSetFlattened )
					( Origin gBackEnd )
				)
				( attribute "RELATIVE_PROPAGATION_DELAY" ",500.00 MIL"
					( Parent
						( matchGroupRef "@baseboard_fab2_lib.baseboard_fab2(sch_1):\MG_P3E_CPU1_PE3_MP_RX0405\" )
					)
					( Units "uMatchProp" "ns" 1.000000)
					( Status sCSetFlattened )
					( Origin gBackEnd )
				)
			)
			( pinPair "@baseboard_fab2_lib.baseboard_fab2(sch_1):\PP3024\"
				( pinRef "@baseboard_fab2_lib.baseboard_fab2(sch_1):page66_i84:PE3_RX_DN(5)" )
				( pinRef "@baseboard_fab2_lib.baseboard_fab2(sch_1):page181_i111:IOI2" )
				( attribute "PROPAGATION_DELAY_MIN" "3000.00 MIL"
					( Units "uMaxMinProp" "ns" 1.000000)
					( Status sCSetFlattened )
					( Origin gBackEnd )
				)
				( attribute "PROPAGATION_DELAY_MAX" "16000.00 MIL"
					( Units "uMaxMinProp" "ns" 1.000000)
					( Status sCSetFlattened )
					( Origin gBackEnd )
				)
				( attribute "RELATIVE_PROPAGATION_DELAY_SCOPE" "G"
					( Parent
						( matchGroupRef "@baseboard_fab2_lib.baseboard_fab2(sch_1):\MG_P3E_CPU1_PE3_MP_RX0405\" )
					)
					( Status sCSetFlattened )
					( Origin gBackEnd )
				)
				( attribute "RELATIVE_PROPAGATION_DELAY" ",500.00 MIL"
					( Parent
						( matchGroupRef "@baseboard_fab2_lib.baseboard_fab2(sch_1):\MG_P3E_CPU1_PE3_MP_RX0405\" )
					)
					( Units "uMatchProp" "ns" 1.000000)
					( Status sCSetFlattened )
					( Origin gBackEnd )
				)
			)
			( pinPair "@baseboard_fab2_lib.baseboard_fab2(sch_1):\PP3021\"
				( pinRef "@baseboard_fab2_lib.baseboard_fab2(sch_1):page66_i84:PE3_RX_DP(6)" )
				( pinRef "@baseboard_fab2_lib.baseboard_fab2(sch_1):page181_i111:IOA3" )
				( attribute "PROPAGATION_DELAY_MIN" "3000.00 MIL"
					( Units "uMaxMinProp" "ns" 1.000000)
					( Status sCSetFlattened )
					( Origin gBackEnd )
				)
				( attribute "PROPAGATION_DELAY_MAX" "16000.00 MIL"
					( Units "uMaxMinProp" "ns" 1.000000)
					( Status sCSetFlattened )
					( Origin gBackEnd )
				)
				( attribute "RELATIVE_PROPAGATION_DELAY_SCOPE" "G"
					( Parent
						( matchGroupRef "@baseboard_fab2_lib.baseboard_fab2(sch_1):\MG_P3E_CPU1_PE3_MP_RX0607\" )
					)
					( Status sCSetFlattened )
					( Origin gBackEnd )
				)
				( attribute "RELATIVE_PROPAGATION_DELAY" ",500.00 MIL"
					( Parent
						( matchGroupRef "@baseboard_fab2_lib.baseboard_fab2(sch_1):\MG_P3E_CPU1_PE3_MP_RX0607\" )
					)
					( Units "uMatchProp" "ns" 1.000000)
					( Status sCSetFlattened )
					( Origin gBackEnd )
				)
			)
			( pinPair "@baseboard_fab2_lib.baseboard_fab2(sch_1):\PP3019\"
				( pinRef "@baseboard_fab2_lib.baseboard_fab2(sch_1):page66_i84:PE3_RX_DN(6)" )
				( pinRef "@baseboard_fab2_lib.baseboard_fab2(sch_1):page181_i111:IOB3" )
				( attribute "PROPAGATION_DELAY_MIN" "3000.00 MIL"
					( Units "uMaxMinProp" "ns" 1.000000)
					( Status sCSetFlattened )
					( Origin gBackEnd )
				)
				( attribute "PROPAGATION_DELAY_MAX" "16000.00 MIL"
					( Units "uMaxMinProp" "ns" 1.000000)
					( Status sCSetFlattened )
					( Origin gBackEnd )
				)
				( attribute "RELATIVE_PROPAGATION_DELAY_SCOPE" "G"
					( Parent
						( matchGroupRef "@baseboard_fab2_lib.baseboard_fab2(sch_1):\MG_P3E_CPU1_PE3_MP_RX0607\" )
					)
					( Status sCSetFlattened )
					( Origin gBackEnd )
				)
				( attribute "RELATIVE_PROPAGATION_DELAY" ",500.00 MIL"
					( Parent
						( matchGroupRef "@baseboard_fab2_lib.baseboard_fab2(sch_1):\MG_P3E_CPU1_PE3_MP_RX0607\" )
					)
					( Units "uMatchProp" "ns" 1.000000)
					( Status sCSetFlattened )
					( Origin gBackEnd )
				)
			)
			( pinPair "@baseboard_fab2_lib.baseboard_fab2(sch_1):\PP3022\"
				( pinRef "@baseboard_fab2_lib.baseboard_fab2(sch_1):page66_i84:PE3_RX_DP(7)" )
				( pinRef "@baseboard_fab2_lib.baseboard_fab2(sch_1):page181_i111:IOE3" )
				( attribute "PROPAGATION_DELAY_MIN" "3000.00 MIL"
					( Units "uMaxMinProp" "ns" 1.000000)
					( Status sCSetFlattened )
					( Origin gBackEnd )
				)
				( attribute "PROPAGATION_DELAY_MAX" "16000.00 MIL"
					( Units "uMaxMinProp" "ns" 1.000000)
					( Status sCSetFlattened )
					( Origin gBackEnd )
				)
				( attribute "RELATIVE_PROPAGATION_DELAY_SCOPE" "G"
					( Parent
						( matchGroupRef "@baseboard_fab2_lib.baseboard_fab2(sch_1):\MG_P3E_CPU1_PE3_MP_RX0607\" )
					)
					( Status sCSetFlattened )
					( Origin gBackEnd )
				)
				( attribute "RELATIVE_PROPAGATION_DELAY" ",500.00 MIL"
					( Parent
						( matchGroupRef "@baseboard_fab2_lib.baseboard_fab2(sch_1):\MG_P3E_CPU1_PE3_MP_RX0607\" )
					)
					( Units "uMatchProp" "ns" 1.000000)
					( Status sCSetFlattened )
					( Origin gBackEnd )
				)
			)
			( pinPair "@baseboard_fab2_lib.baseboard_fab2(sch_1):\PP3020\"
				( pinRef "@baseboard_fab2_lib.baseboard_fab2(sch_1):page66_i84:PE3_RX_DN(7)" )
				( pinRef "@baseboard_fab2_lib.baseboard_fab2(sch_1):page181_i111:IOD3" )
				( attribute "PROPAGATION_DELAY_MIN" "3000.00 MIL"
					( Units "uMaxMinProp" "ns" 1.000000)
					( Status sCSetFlattened )
					( Origin gBackEnd )
				)
				( attribute "PROPAGATION_DELAY_MAX" "16000.00 MIL"
					( Units "uMaxMinProp" "ns" 1.000000)
					( Status sCSetFlattened )
					( Origin gBackEnd )
				)
				( attribute "RELATIVE_PROPAGATION_DELAY_SCOPE" "G"
					( Parent
						( matchGroupRef "@baseboard_fab2_lib.baseboard_fab2(sch_1):\MG_P3E_CPU1_PE3_MP_RX0607\" )
					)
					( Status sCSetFlattened )
					( Origin gBackEnd )
				)
				( attribute "RELATIVE_PROPAGATION_DELAY" ",500.00 MIL"
					( Parent
						( matchGroupRef "@baseboard_fab2_lib.baseboard_fab2(sch_1):\MG_P3E_CPU1_PE3_MP_RX0607\" )
					)
					( Units "uMatchProp" "ns" 1.000000)
					( Status sCSetFlattened )
					( Origin gBackEnd )
				)
			)
			( pinPair "@baseboard_fab2_lib.baseboard_fab2(sch_1):\PP3105\"
				( pinRef "@baseboard_fab2_lib.baseboard_fab2(sch_1):page31_i106:PE2_RX_DP(0)" )
				( pinRef "@baseboard_fab2_lib.baseboard_fab2(sch_1):page109_i243:IO108" )
				( attribute "PROPAGATION_DELAY_MIN" "3000.00 MIL"
					( Units "uMaxMinProp" "ns" 1.000000)
					( Status sCSetFlattened )
					( Origin gBackEnd )
				)
				( attribute "PROPAGATION_DELAY_MAX" "16000.00 MIL"
					( Units "uMaxMinProp" "ns" 1.000000)
					( Status sCSetFlattened )
					( Origin gBackEnd )
				)
				( attribute "RELATIVE_PROPAGATION_DELAY_SCOPE" "G"
					( Parent
						( matchGroupRef "@baseboard_fab2_lib.baseboard_fab2(sch_1):\MG_P3E_CPU0_PE2_SS_RX0001\" )
					)
					( Status sCSetFlattened )
					( Origin gBackEnd )
				)
				( attribute "RELATIVE_PROPAGATION_DELAY" ",500.00 MIL"
					( Parent
						( matchGroupRef "@baseboard_fab2_lib.baseboard_fab2(sch_1):\MG_P3E_CPU0_PE2_SS_RX0001\" )
					)
					( Units "uMatchProp" "ns" 1.000000)
					( Status sCSetFlattened )
					( Origin gBackEnd )
				)
			)
			( pinPair "@baseboard_fab2_lib.baseboard_fab2(sch_1):\PP3103\"
				( pinRef "@baseboard_fab2_lib.baseboard_fab2(sch_1):page31_i106:PE2_RX_DN(0)" )
				( pinRef "@baseboard_fab2_lib.baseboard_fab2(sch_1):page109_i243:IO106" )
				( attribute "PROPAGATION_DELAY_MIN" "3000.00 MIL"
					( Units "uMaxMinProp" "ns" 1.000000)
					( Status sCSetFlattened )
					( Origin gBackEnd )
				)
				( attribute "PROPAGATION_DELAY_MAX" "16000.00 MIL"
					( Units "uMaxMinProp" "ns" 1.000000)
					( Status sCSetFlattened )
					( Origin gBackEnd )
				)
				( attribute "RELATIVE_PROPAGATION_DELAY_SCOPE" "G"
					( Parent
						( matchGroupRef "@baseboard_fab2_lib.baseboard_fab2(sch_1):\MG_P3E_CPU0_PE2_SS_RX0001\" )
					)
					( Status sCSetFlattened )
					( Origin gBackEnd )
				)
				( attribute "RELATIVE_PROPAGATION_DELAY" ",500.00 MIL"
					( Parent
						( matchGroupRef "@baseboard_fab2_lib.baseboard_fab2(sch_1):\MG_P3E_CPU0_PE2_SS_RX0001\" )
					)
					( Units "uMatchProp" "ns" 1.000000)
					( Status sCSetFlattened )
					( Origin gBackEnd )
				)
			)
			( pinPair "@baseboard_fab2_lib.baseboard_fab2(sch_1):\PP3106\"
				( pinRef "@baseboard_fab2_lib.baseboard_fab2(sch_1):page31_i106:PE2_RX_DP(1)" )
				( pinRef "@baseboard_fab2_lib.baseboard_fab2(sch_1):page109_i243:IO114" )
				( attribute "PROPAGATION_DELAY_MIN" "3000.00 MIL"
					( Units "uMaxMinProp" "ns" 1.000000)
					( Status sCSetFlattened )
					( Origin gBackEnd )
				)
				( attribute "PROPAGATION_DELAY_MAX" "16000.00 MIL"
					( Units "uMaxMinProp" "ns" 1.000000)
					( Status sCSetFlattened )
					( Origin gBackEnd )
				)
				( attribute "RELATIVE_PROPAGATION_DELAY_SCOPE" "G"
					( Parent
						( matchGroupRef "@baseboard_fab2_lib.baseboard_fab2(sch_1):\MG_P3E_CPU0_PE2_SS_RX0001\" )
					)
					( Status sCSetFlattened )
					( Origin gBackEnd )
				)
				( attribute "RELATIVE_PROPAGATION_DELAY" ",500.00 MIL"
					( Parent
						( matchGroupRef "@baseboard_fab2_lib.baseboard_fab2(sch_1):\MG_P3E_CPU0_PE2_SS_RX0001\" )
					)
					( Units "uMatchProp" "ns" 1.000000)
					( Status sCSetFlattened )
					( Origin gBackEnd )
				)
			)
			( pinPair "@baseboard_fab2_lib.baseboard_fab2(sch_1):\PP3104\"
				( pinRef "@baseboard_fab2_lib.baseboard_fab2(sch_1):page31_i106:PE2_RX_DN(1)" )
				( pinRef "@baseboard_fab2_lib.baseboard_fab2(sch_1):page109_i243:IO112" )
				( attribute "PROPAGATION_DELAY_MIN" "3000.00 MIL"
					( Units "uMaxMinProp" "ns" 1.000000)
					( Status sCSetFlattened )
					( Origin gBackEnd )
				)
				( attribute "PROPAGATION_DELAY_MAX" "16000.00 MIL"
					( Units "uMaxMinProp" "ns" 1.000000)
					( Status sCSetFlattened )
					( Origin gBackEnd )
				)
				( attribute "RELATIVE_PROPAGATION_DELAY_SCOPE" "G"
					( Parent
						( matchGroupRef "@baseboard_fab2_lib.baseboard_fab2(sch_1):\MG_P3E_CPU0_PE2_SS_RX0001\" )
					)
					( Status sCSetFlattened )
					( Origin gBackEnd )
				)
				( attribute "RELATIVE_PROPAGATION_DELAY" ",500.00 MIL"
					( Parent
						( matchGroupRef "@baseboard_fab2_lib.baseboard_fab2(sch_1):\MG_P3E_CPU0_PE2_SS_RX0001\" )
					)
					( Units "uMatchProp" "ns" 1.000000)
					( Status sCSetFlattened )
					( Origin gBackEnd )
				)
			)
			( pinPair "@baseboard_fab2_lib.baseboard_fab2(sch_1):\PP3101\"
				( pinRef "@baseboard_fab2_lib.baseboard_fab2(sch_1):page31_i106:PE2_RX_DP(2)" )
				( pinRef "@baseboard_fab2_lib.baseboard_fab2(sch_1):page109_i243:IO120" )
				( attribute "PROPAGATION_DELAY_MIN" "3000.00 MIL"
					( Units "uMaxMinProp" "ns" 1.000000)
					( Status sCSetFlattened )
					( Origin gBackEnd )
				)
				( attribute "PROPAGATION_DELAY_MAX" "16000.00 MIL"
					( Units "uMaxMinProp" "ns" 1.000000)
					( Status sCSetFlattened )
					( Origin gBackEnd )
				)
				( attribute "RELATIVE_PROPAGATION_DELAY_SCOPE" "G"
					( Parent
						( matchGroupRef "@baseboard_fab2_lib.baseboard_fab2(sch_1):\MG_P3E_CPU0_PE2_SS_RX0203\" )
					)
					( Status sCSetFlattened )
					( Origin gBackEnd )
				)
				( attribute "RELATIVE_PROPAGATION_DELAY" ",500.00 MIL"
					( Parent
						( matchGroupRef "@baseboard_fab2_lib.baseboard_fab2(sch_1):\MG_P3E_CPU0_PE2_SS_RX0203\" )
					)
					( Units "uMatchProp" "ns" 1.000000)
					( Status sCSetFlattened )
					( Origin gBackEnd )
				)
			)
			( pinPair "@baseboard_fab2_lib.baseboard_fab2(sch_1):\PP3099\"
				( pinRef "@baseboard_fab2_lib.baseboard_fab2(sch_1):page31_i106:PE2_RX_DN(2)" )
				( pinRef "@baseboard_fab2_lib.baseboard_fab2(sch_1):page109_i243:IO118" )
				( attribute "PROPAGATION_DELAY_MIN" "3000.00 MIL"
					( Units "uMaxMinProp" "ns" 1.000000)
					( Status sCSetFlattened )
					( Origin gBackEnd )
				)
				( attribute "PROPAGATION_DELAY_MAX" "16000.00 MIL"
					( Units "uMaxMinProp" "ns" 1.000000)
					( Status sCSetFlattened )
					( Origin gBackEnd )
				)
				( attribute "RELATIVE_PROPAGATION_DELAY_SCOPE" "G"
					( Parent
						( matchGroupRef "@baseboard_fab2_lib.baseboard_fab2(sch_1):\MG_P3E_CPU0_PE2_SS_RX0203\" )
					)
					( Status sCSetFlattened )
					( Origin gBackEnd )
				)
				( attribute "RELATIVE_PROPAGATION_DELAY" ",500.00 MIL"
					( Parent
						( matchGroupRef "@baseboard_fab2_lib.baseboard_fab2(sch_1):\MG_P3E_CPU0_PE2_SS_RX0203\" )
					)
					( Units "uMatchProp" "ns" 1.000000)
					( Status sCSetFlattened )
					( Origin gBackEnd )
				)
			)
			( pinPair "@baseboard_fab2_lib.baseboard_fab2(sch_1):\PP3102\"
				( pinRef "@baseboard_fab2_lib.baseboard_fab2(sch_1):page31_i106:PE2_RX_DP(3)" )
				( pinRef "@baseboard_fab2_lib.baseboard_fab2(sch_1):page109_i243:IO126" )
				( attribute "PROPAGATION_DELAY_MIN" "3000.00 MIL"
					( Units "uMaxMinProp" "ns" 1.000000)
					( Status sCSetFlattened )
					( Origin gBackEnd )
				)
				( attribute "PROPAGATION_DELAY_MAX" "16000.00 MIL"
					( Units "uMaxMinProp" "ns" 1.000000)
					( Status sCSetFlattened )
					( Origin gBackEnd )
				)
				( attribute "RELATIVE_PROPAGATION_DELAY_SCOPE" "G"
					( Parent
						( matchGroupRef "@baseboard_fab2_lib.baseboard_fab2(sch_1):\MG_P3E_CPU0_PE2_SS_RX0203\" )
					)
					( Status sCSetFlattened )
					( Origin gBackEnd )
				)
				( attribute "RELATIVE_PROPAGATION_DELAY" ",500.00 MIL"
					( Parent
						( matchGroupRef "@baseboard_fab2_lib.baseboard_fab2(sch_1):\MG_P3E_CPU0_PE2_SS_RX0203\" )
					)
					( Units "uMatchProp" "ns" 1.000000)
					( Status sCSetFlattened )
					( Origin gBackEnd )
				)
			)
			( pinPair "@baseboard_fab2_lib.baseboard_fab2(sch_1):\PP3100\"
				( pinRef "@baseboard_fab2_lib.baseboard_fab2(sch_1):page31_i106:PE2_RX_DN(3)" )
				( pinRef "@baseboard_fab2_lib.baseboard_fab2(sch_1):page109_i243:IO124" )
				( attribute "PROPAGATION_DELAY_MIN" "3000.00 MIL"
					( Units "uMaxMinProp" "ns" 1.000000)
					( Status sCSetFlattened )
					( Origin gBackEnd )
				)
				( attribute "PROPAGATION_DELAY_MAX" "16000.00 MIL"
					( Units "uMaxMinProp" "ns" 1.000000)
					( Status sCSetFlattened )
					( Origin gBackEnd )
				)
				( attribute "RELATIVE_PROPAGATION_DELAY_SCOPE" "G"
					( Parent
						( matchGroupRef "@baseboard_fab2_lib.baseboard_fab2(sch_1):\MG_P3E_CPU0_PE2_SS_RX0203\" )
					)
					( Status sCSetFlattened )
					( Origin gBackEnd )
				)
				( attribute "RELATIVE_PROPAGATION_DELAY" ",500.00 MIL"
					( Parent
						( matchGroupRef "@baseboard_fab2_lib.baseboard_fab2(sch_1):\MG_P3E_CPU0_PE2_SS_RX0203\" )
					)
					( Units "uMatchProp" "ns" 1.000000)
					( Status sCSetFlattened )
					( Origin gBackEnd )
				)
			)
			( pinPair "@baseboard_fab2_lib.baseboard_fab2(sch_1):\PP3097\"
				( pinRef "@baseboard_fab2_lib.baseboard_fab2(sch_1):page31_i106:PE2_RX_DP(4)" )
				( pinRef "@baseboard_fab2_lib.baseboard_fab2(sch_1):page109_i243:IO132" )
				( attribute "PROPAGATION_DELAY_MIN" "3000.00 MIL"
					( Units "uMaxMinProp" "ns" 1.000000)
					( Status sCSetFlattened )
					( Origin gBackEnd )
				)
				( attribute "PROPAGATION_DELAY_MAX" "16000.00 MIL"
					( Units "uMaxMinProp" "ns" 1.000000)
					( Status sCSetFlattened )
					( Origin gBackEnd )
				)
				( attribute "RELATIVE_PROPAGATION_DELAY_SCOPE" "G"
					( Parent
						( matchGroupRef "@baseboard_fab2_lib.baseboard_fab2(sch_1):\MG_P3E_CPU0_PE2_SS_RX0405\" )
					)
					( Status sCSetFlattened )
					( Origin gBackEnd )
				)
				( attribute "RELATIVE_PROPAGATION_DELAY" ",500.00 MIL"
					( Parent
						( matchGroupRef "@baseboard_fab2_lib.baseboard_fab2(sch_1):\MG_P3E_CPU0_PE2_SS_RX0405\" )
					)
					( Units "uMatchProp" "ns" 1.000000)
					( Status sCSetFlattened )
					( Origin gBackEnd )
				)
			)
			( pinPair "@baseboard_fab2_lib.baseboard_fab2(sch_1):\PP3095\"
				( pinRef "@baseboard_fab2_lib.baseboard_fab2(sch_1):page31_i106:PE2_RX_DN(4)" )
				( pinRef "@baseboard_fab2_lib.baseboard_fab2(sch_1):page109_i243:IO130" )
				( attribute "PROPAGATION_DELAY_MIN" "3000.00 MIL"
					( Units "uMaxMinProp" "ns" 1.000000)
					( Status sCSetFlattened )
					( Origin gBackEnd )
				)
				( attribute "PROPAGATION_DELAY_MAX" "16000.00 MIL"
					( Units "uMaxMinProp" "ns" 1.000000)
					( Status sCSetFlattened )
					( Origin gBackEnd )
				)
				( attribute "RELATIVE_PROPAGATION_DELAY_SCOPE" "G"
					( Parent
						( matchGroupRef "@baseboard_fab2_lib.baseboard_fab2(sch_1):\MG_P3E_CPU0_PE2_SS_RX0405\" )
					)
					( Status sCSetFlattened )
					( Origin gBackEnd )
				)
				( attribute "RELATIVE_PROPAGATION_DELAY" ",500.00 MIL"
					( Parent
						( matchGroupRef "@baseboard_fab2_lib.baseboard_fab2(sch_1):\MG_P3E_CPU0_PE2_SS_RX0405\" )
					)
					( Units "uMatchProp" "ns" 1.000000)
					( Status sCSetFlattened )
					( Origin gBackEnd )
				)
			)
			( pinPair "@baseboard_fab2_lib.baseboard_fab2(sch_1):\PP3098\"
				( pinRef "@baseboard_fab2_lib.baseboard_fab2(sch_1):page31_i106:PE2_RX_DP(5)" )
				( pinRef "@baseboard_fab2_lib.baseboard_fab2(sch_1):page109_i243:IO138" )
				( attribute "PROPAGATION_DELAY_MIN" "3000.00 MIL"
					( Units "uMaxMinProp" "ns" 1.000000)
					( Status sCSetFlattened )
					( Origin gBackEnd )
				)
				( attribute "PROPAGATION_DELAY_MAX" "16000.00 MIL"
					( Units "uMaxMinProp" "ns" 1.000000)
					( Status sCSetFlattened )
					( Origin gBackEnd )
				)
				( attribute "RELATIVE_PROPAGATION_DELAY_SCOPE" "G"
					( Parent
						( matchGroupRef "@baseboard_fab2_lib.baseboard_fab2(sch_1):\MG_P3E_CPU0_PE2_SS_RX0405\" )
					)
					( Status sCSetFlattened )
					( Origin gBackEnd )
				)
				( attribute "RELATIVE_PROPAGATION_DELAY" ",500.00 MIL"
					( Parent
						( matchGroupRef "@baseboard_fab2_lib.baseboard_fab2(sch_1):\MG_P3E_CPU0_PE2_SS_RX0405\" )
					)
					( Units "uMatchProp" "ns" 1.000000)
					( Status sCSetFlattened )
					( Origin gBackEnd )
				)
			)
			( pinPair "@baseboard_fab2_lib.baseboard_fab2(sch_1):\PP3096\"
				( pinRef "@baseboard_fab2_lib.baseboard_fab2(sch_1):page31_i106:PE2_RX_DN(5)" )
				( pinRef "@baseboard_fab2_lib.baseboard_fab2(sch_1):page109_i243:IO136" )
				( attribute "PROPAGATION_DELAY_MIN" "3000.00 MIL"
					( Units "uMaxMinProp" "ns" 1.000000)
					( Status sCSetFlattened )
					( Origin gBackEnd )
				)
				( attribute "PROPAGATION_DELAY_MAX" "16000.00 MIL"
					( Units "uMaxMinProp" "ns" 1.000000)
					( Status sCSetFlattened )
					( Origin gBackEnd )
				)
				( attribute "RELATIVE_PROPAGATION_DELAY_SCOPE" "G"
					( Parent
						( matchGroupRef "@baseboard_fab2_lib.baseboard_fab2(sch_1):\MG_P3E_CPU0_PE2_SS_RX0405\" )
					)
					( Status sCSetFlattened )
					( Origin gBackEnd )
				)
				( attribute "RELATIVE_PROPAGATION_DELAY" ",500.00 MIL"
					( Parent
						( matchGroupRef "@baseboard_fab2_lib.baseboard_fab2(sch_1):\MG_P3E_CPU0_PE2_SS_RX0405\" )
					)
					( Units "uMatchProp" "ns" 1.000000)
					( Status sCSetFlattened )
					( Origin gBackEnd )
				)
			)
			( pinPair "@baseboard_fab2_lib.baseboard_fab2(sch_1):\PP54\"
				( pinRef "@baseboard_fab2_lib.baseboard_fab2(sch_1):page117_i9:DMI_TXN(0)" )
				( pinRef "@baseboard_fab2_lib.baseboard_fab2(sch_1):page129_i80:A" )
				( attribute "RELATIVE_PROPAGATION_DELAY_SCOPE" "L"
					( Parent
						( matchGroupRef "@baseboard_fab2_lib.baseboard_fab2(sch_1):\MG_DMI_L0\" )
					)
					( Status sCSetFlattened )
					( Origin gBackEnd )
				)
				( attribute "RELATIVE_PROPAGATION_DELAY" ",5.00 MIL"
					( Parent
						( matchGroupRef "@baseboard_fab2_lib.baseboard_fab2(sch_1):\MG_DMI_L0\" )
					)
					( Units "uMatchProp" "ns" 1.000000)
					( Status sCSetFlattened )
					( Origin gBackEnd )
				)
			)
			( pinPair "@baseboard_fab2_lib.baseboard_fab2(sch_1):\PP55\"
				( pinRef "@baseboard_fab2_lib.baseboard_fab2(sch_1):page129_i80:B" )
				( pinRef "@baseboard_fab2_lib.baseboard_fab2(sch_1):page29_i61:DMI_RX_DN(0)" )
				( attribute "RELATIVE_PROPAGATION_DELAY_SCOPE" "L"
					( Parent
						( matchGroupRef "@baseboard_fab2_lib.baseboard_fab2(sch_1):\MG_DMI_L1\" )
					)
					( Status sCSetFlattened )
					( Origin gBackEnd )
				)
				( attribute "RELATIVE_PROPAGATION_DELAY" ",5.00 MIL"
					( Parent
						( matchGroupRef "@baseboard_fab2_lib.baseboard_fab2(sch_1):\MG_DMI_L1\" )
					)
					( Units "uMatchProp" "ns" 1.000000)
					( Status sCSetFlattened )
					( Origin gBackEnd )
				)
			)
			( pinPair "@baseboard_fab2_lib.baseboard_fab2(sch_1):\PP6088\"
				( pinRef "@baseboard_fab2_lib.baseboard_fab2(sch_1):page117_i9:DMI_TXN(0)" )
				( pinRef "@baseboard_fab2_lib.baseboard_fab2(sch_1):page29_i61:DMI_RX_DN(0)" )
				( attribute "PROPAGATION_DELAY_MAX" "15000.00 MIL"
					( Units "uMaxMinProp" "ns" 1.000000)
					( Status sCSetFlattened )
					( Origin gBackEnd )
				)
			)
			( pinPair "@baseboard_fab2_lib.baseboard_fab2(sch_1):\PP52\"
				( pinRef "@baseboard_fab2_lib.baseboard_fab2(sch_1):page117_i9:DMI_TXP(0)" )
				( pinRef "@baseboard_fab2_lib.baseboard_fab2(sch_1):page129_i72:A" )
				( attribute "RELATIVE_PROPAGATION_DELAY_SCOPE" "L"
					( Parent
						( matchGroupRef "@baseboard_fab2_lib.baseboard_fab2(sch_1):\MG_DMI_L0\" )
					)
					( Status sCSetFlattened )
					( Origin gBackEnd )
				)
				( attribute "RELATIVE_PROPAGATION_DELAY" ",5.00 MIL"
					( Parent
						( matchGroupRef "@baseboard_fab2_lib.baseboard_fab2(sch_1):\MG_DMI_L0\" )
					)
					( Units "uMatchProp" "ns" 1.000000)
					( Status sCSetFlattened )
					( Origin gBackEnd )
				)
			)
			( pinPair "@baseboard_fab2_lib.baseboard_fab2(sch_1):\PP53\"
				( pinRef "@baseboard_fab2_lib.baseboard_fab2(sch_1):page129_i72:B" )
				( pinRef "@baseboard_fab2_lib.baseboard_fab2(sch_1):page29_i61:DMI_RX_DP(0)" )
				( attribute "RELATIVE_PROPAGATION_DELAY_SCOPE" "L"
					( Parent
						( matchGroupRef "@baseboard_fab2_lib.baseboard_fab2(sch_1):\MG_DMI_L1\" )
					)
					( Status sCSetFlattened )
					( Origin gBackEnd )
				)
				( attribute "RELATIVE_PROPAGATION_DELAY" ",5.00 MIL"
					( Parent
						( matchGroupRef "@baseboard_fab2_lib.baseboard_fab2(sch_1):\MG_DMI_L1\" )
					)
					( Units "uMatchProp" "ns" 1.000000)
					( Status sCSetFlattened )
					( Origin gBackEnd )
				)
			)
			( pinPair "@baseboard_fab2_lib.baseboard_fab2(sch_1):\PP6089\"
				( pinRef "@baseboard_fab2_lib.baseboard_fab2(sch_1):page117_i9:DMI_TXP(0)" )
				( pinRef "@baseboard_fab2_lib.baseboard_fab2(sch_1):page29_i61:DMI_RX_DP(0)" )
				( attribute "PROPAGATION_DELAY_MAX" "15000.00 MIL"
					( Units "uMaxMinProp" "ns" 1.000000)
					( Status sCSetFlattened )
					( Origin gBackEnd )
				)
			)
			( pinPair "@baseboard_fab2_lib.baseboard_fab2(sch_1):\PP58\"
				( pinRef "@baseboard_fab2_lib.baseboard_fab2(sch_1):page117_i9:DMI_TXN(1)" )
				( pinRef "@baseboard_fab2_lib.baseboard_fab2(sch_1):page129_i81:A" )
				( attribute "RELATIVE_PROPAGATION_DELAY_SCOPE" "L"
					( Parent
						( matchGroupRef "@baseboard_fab2_lib.baseboard_fab2(sch_1):\MG_DMI_L0\" )
					)
					( Status sCSetFlattened )
					( Origin gBackEnd )
				)
				( attribute "RELATIVE_PROPAGATION_DELAY" ",5.00 MIL"
					( Parent
						( matchGroupRef "@baseboard_fab2_lib.baseboard_fab2(sch_1):\MG_DMI_L0\" )
					)
					( Units "uMatchProp" "ns" 1.000000)
					( Status sCSetFlattened )
					( Origin gBackEnd )
				)
			)
			( pinPair "@baseboard_fab2_lib.baseboard_fab2(sch_1):\PP59\"
				( pinRef "@baseboard_fab2_lib.baseboard_fab2(sch_1):page129_i81:B" )
				( pinRef "@baseboard_fab2_lib.baseboard_fab2(sch_1):page29_i61:DMI_RX_DN(1)" )
				( attribute "RELATIVE_PROPAGATION_DELAY_SCOPE" "L"
					( Parent
						( matchGroupRef "@baseboard_fab2_lib.baseboard_fab2(sch_1):\MG_DMI_L1\" )
					)
					( Status sCSetFlattened )
					( Origin gBackEnd )
				)
				( attribute "RELATIVE_PROPAGATION_DELAY" ",5.00 MIL"
					( Parent
						( matchGroupRef "@baseboard_fab2_lib.baseboard_fab2(sch_1):\MG_DMI_L1\" )
					)
					( Units "uMatchProp" "ns" 1.000000)
					( Status sCSetFlattened )
					( Origin gBackEnd )
				)
			)
			( pinPair "@baseboard_fab2_lib.baseboard_fab2(sch_1):\PP6085\"
				( pinRef "@baseboard_fab2_lib.baseboard_fab2(sch_1):page117_i9:DMI_TXN(1)" )
				( pinRef "@baseboard_fab2_lib.baseboard_fab2(sch_1):page29_i61:DMI_RX_DN(1)" )
				( attribute "PROPAGATION_DELAY_MAX" "15000.00 MIL"
					( Units "uMaxMinProp" "ns" 1.000000)
					( Status sCSetFlattened )
					( Origin gBackEnd )
				)
			)
			( pinPair "@baseboard_fab2_lib.baseboard_fab2(sch_1):\PP56\"
				( pinRef "@baseboard_fab2_lib.baseboard_fab2(sch_1):page117_i9:DMI_TXP(1)" )
				( pinRef "@baseboard_fab2_lib.baseboard_fab2(sch_1):page129_i73:A" )
				( attribute "RELATIVE_PROPAGATION_DELAY_SCOPE" "L"
					( Parent
						( matchGroupRef "@baseboard_fab2_lib.baseboard_fab2(sch_1):\MG_DMI_L0\" )
					)
					( Status sCSetFlattened )
					( Origin gBackEnd )
				)
				( attribute "RELATIVE_PROPAGATION_DELAY" ",5.00 MIL"
					( Parent
						( matchGroupRef "@baseboard_fab2_lib.baseboard_fab2(sch_1):\MG_DMI_L0\" )
					)
					( Units "uMatchProp" "ns" 1.000000)
					( Status sCSetFlattened )
					( Origin gBackEnd )
				)
			)
			( pinPair "@baseboard_fab2_lib.baseboard_fab2(sch_1):\PP57\"
				( pinRef "@baseboard_fab2_lib.baseboard_fab2(sch_1):page129_i73:B" )
				( pinRef "@baseboard_fab2_lib.baseboard_fab2(sch_1):page29_i61:DMI_RX_DP(1)" )
				( attribute "RELATIVE_PROPAGATION_DELAY_SCOPE" "L"
					( Parent
						( matchGroupRef "@baseboard_fab2_lib.baseboard_fab2(sch_1):\MG_DMI_L1\" )
					)
					( Status sCSetFlattened )
					( Origin gBackEnd )
				)
				( attribute "RELATIVE_PROPAGATION_DELAY" ",5.00 MIL"
					( Parent
						( matchGroupRef "@baseboard_fab2_lib.baseboard_fab2(sch_1):\MG_DMI_L1\" )
					)
					( Units "uMatchProp" "ns" 1.000000)
					( Status sCSetFlattened )
					( Origin gBackEnd )
				)
			)
			( pinPair "@baseboard_fab2_lib.baseboard_fab2(sch_1):\PP6087\"
				( pinRef "@baseboard_fab2_lib.baseboard_fab2(sch_1):page117_i9:DMI_TXP(1)" )
				( pinRef "@baseboard_fab2_lib.baseboard_fab2(sch_1):page29_i61:DMI_RX_DP(1)" )
				( attribute "PROPAGATION_DELAY_MAX" "15000.00 MIL"
					( Units "uMaxMinProp" "ns" 1.000000)
					( Status sCSetFlattened )
					( Origin gBackEnd )
				)
			)
			( pinPair "@baseboard_fab2_lib.baseboard_fab2(sch_1):\PP62\"
				( pinRef "@baseboard_fab2_lib.baseboard_fab2(sch_1):page117_i9:DMI_TXN(2)" )
				( pinRef "@baseboard_fab2_lib.baseboard_fab2(sch_1):page129_i82:A" )
				( attribute "RELATIVE_PROPAGATION_DELAY_SCOPE" "L"
					( Parent
						( matchGroupRef "@baseboard_fab2_lib.baseboard_fab2(sch_1):\MG_DMI_L0\" )
					)
					( Status sCSetFlattened )
					( Origin gBackEnd )
				)
				( attribute "RELATIVE_PROPAGATION_DELAY" ",5.00 MIL"
					( Parent
						( matchGroupRef "@baseboard_fab2_lib.baseboard_fab2(sch_1):\MG_DMI_L0\" )
					)
					( Units "uMatchProp" "ns" 1.000000)
					( Status sCSetFlattened )
					( Origin gBackEnd )
				)
			)
			( pinPair "@baseboard_fab2_lib.baseboard_fab2(sch_1):\PP63\"
				( pinRef "@baseboard_fab2_lib.baseboard_fab2(sch_1):page129_i82:B" )
				( pinRef "@baseboard_fab2_lib.baseboard_fab2(sch_1):page29_i61:DMI_RX_DN(2)" )
				( attribute "RELATIVE_PROPAGATION_DELAY_SCOPE" "L"
					( Parent
						( matchGroupRef "@baseboard_fab2_lib.baseboard_fab2(sch_1):\MG_DMI_L1\" )
					)
					( Status sCSetFlattened )
					( Origin gBackEnd )
				)
				( attribute "RELATIVE_PROPAGATION_DELAY" ",5.00 MIL"
					( Parent
						( matchGroupRef "@baseboard_fab2_lib.baseboard_fab2(sch_1):\MG_DMI_L1\" )
					)
					( Units "uMatchProp" "ns" 1.000000)
					( Status sCSetFlattened )
					( Origin gBackEnd )
				)
			)
			( pinPair "@baseboard_fab2_lib.baseboard_fab2(sch_1):\PP6077\"
				( pinRef "@baseboard_fab2_lib.baseboard_fab2(sch_1):page117_i9:DMI_TXN(2)" )
				( pinRef "@baseboard_fab2_lib.baseboard_fab2(sch_1):page29_i61:DMI_RX_DN(2)" )
				( attribute "PROPAGATION_DELAY_MAX" "15000.00 MIL"
					( Units "uMaxMinProp" "ns" 1.000000)
					( Status sCSetFlattened )
					( Origin gBackEnd )
				)
			)
			( pinPair "@baseboard_fab2_lib.baseboard_fab2(sch_1):\PP60\"
				( pinRef "@baseboard_fab2_lib.baseboard_fab2(sch_1):page117_i9:DMI_TXP(2)" )
				( pinRef "@baseboard_fab2_lib.baseboard_fab2(sch_1):page129_i74:A" )
				( attribute "RELATIVE_PROPAGATION_DELAY_SCOPE" "L"
					( Parent
						( matchGroupRef "@baseboard_fab2_lib.baseboard_fab2(sch_1):\MG_DMI_L0\" )
					)
					( Status sCSetFlattened )
					( Origin gBackEnd )
				)
				( attribute "RELATIVE_PROPAGATION_DELAY" ",5.00 MIL"
					( Parent
						( matchGroupRef "@baseboard_fab2_lib.baseboard_fab2(sch_1):\MG_DMI_L0\" )
					)
					( Units "uMatchProp" "ns" 1.000000)
					( Status sCSetFlattened )
					( Origin gBackEnd )
				)
			)
			( pinPair "@baseboard_fab2_lib.baseboard_fab2(sch_1):\PP61\"
				( pinRef "@baseboard_fab2_lib.baseboard_fab2(sch_1):page129_i74:B" )
				( pinRef "@baseboard_fab2_lib.baseboard_fab2(sch_1):page29_i61:DMI_RX_DP(2)" )
				( attribute "RELATIVE_PROPAGATION_DELAY_SCOPE" "L"
					( Parent
						( matchGroupRef "@baseboard_fab2_lib.baseboard_fab2(sch_1):\MG_DMI_L1\" )
					)
					( Status sCSetFlattened )
					( Origin gBackEnd )
				)
				( attribute "RELATIVE_PROPAGATION_DELAY" ",5.00 MIL"
					( Parent
						( matchGroupRef "@baseboard_fab2_lib.baseboard_fab2(sch_1):\MG_DMI_L1\" )
					)
					( Units "uMatchProp" "ns" 1.000000)
					( Status sCSetFlattened )
					( Origin gBackEnd )
				)
			)
			( pinPair "@baseboard_fab2_lib.baseboard_fab2(sch_1):\PP6084\"
				( pinRef "@baseboard_fab2_lib.baseboard_fab2(sch_1):page117_i9:DMI_TXP(2)" )
				( pinRef "@baseboard_fab2_lib.baseboard_fab2(sch_1):page29_i61:DMI_RX_DP(2)" )
				( attribute "PROPAGATION_DELAY_MAX" "15000.00 MIL"
					( Units "uMaxMinProp" "ns" 1.000000)
					( Status sCSetFlattened )
					( Origin gBackEnd )
				)
			)
			( pinPair "@baseboard_fab2_lib.baseboard_fab2(sch_1):\PP66\"
				( pinRef "@baseboard_fab2_lib.baseboard_fab2(sch_1):page117_i9:DMI_TXN(3)" )
				( pinRef "@baseboard_fab2_lib.baseboard_fab2(sch_1):page129_i83:A" )
				( attribute "RELATIVE_PROPAGATION_DELAY_SCOPE" "L"
					( Parent
						( matchGroupRef "@baseboard_fab2_lib.baseboard_fab2(sch_1):\MG_DMI_L0\" )
					)
					( Status sCSetFlattened )
					( Origin gBackEnd )
				)
				( attribute "RELATIVE_PROPAGATION_DELAY" ",5.00 MIL"
					( Parent
						( matchGroupRef "@baseboard_fab2_lib.baseboard_fab2(sch_1):\MG_DMI_L0\" )
					)
					( Units "uMatchProp" "ns" 1.000000)
					( Status sCSetFlattened )
					( Origin gBackEnd )
				)
			)
			( pinPair "@baseboard_fab2_lib.baseboard_fab2(sch_1):\PP67\"
				( pinRef "@baseboard_fab2_lib.baseboard_fab2(sch_1):page129_i83:B" )
				( pinRef "@baseboard_fab2_lib.baseboard_fab2(sch_1):page29_i61:DMI_RX_DN(3)" )
				( attribute "RELATIVE_PROPAGATION_DELAY_SCOPE" "L"
					( Parent
						( matchGroupRef "@baseboard_fab2_lib.baseboard_fab2(sch_1):\MG_DMI_L1\" )
					)
					( Status sCSetFlattened )
					( Origin gBackEnd )
				)
				( attribute "RELATIVE_PROPAGATION_DELAY" ",5.00 MIL"
					( Parent
						( matchGroupRef "@baseboard_fab2_lib.baseboard_fab2(sch_1):\MG_DMI_L1\" )
					)
					( Units "uMatchProp" "ns" 1.000000)
					( Status sCSetFlattened )
					( Origin gBackEnd )
				)
			)
			( pinPair "@baseboard_fab2_lib.baseboard_fab2(sch_1):\PP6083\"
				( pinRef "@baseboard_fab2_lib.baseboard_fab2(sch_1):page117_i9:DMI_TXN(3)" )
				( pinRef "@baseboard_fab2_lib.baseboard_fab2(sch_1):page29_i61:DMI_RX_DN(3)" )
				( attribute "PROPAGATION_DELAY_MAX" "15000.00 MIL"
					( Units "uMaxMinProp" "ns" 1.000000)
					( Status sCSetFlattened )
					( Origin gBackEnd )
				)
			)
			( pinPair "@baseboard_fab2_lib.baseboard_fab2(sch_1):\PP64\"
				( pinRef "@baseboard_fab2_lib.baseboard_fab2(sch_1):page117_i9:DMI_TXP(3)" )
				( pinRef "@baseboard_fab2_lib.baseboard_fab2(sch_1):page129_i75:A" )
				( attribute "RELATIVE_PROPAGATION_DELAY_SCOPE" "L"
					( Parent
						( matchGroupRef "@baseboard_fab2_lib.baseboard_fab2(sch_1):\MG_DMI_L0\" )
					)
					( Status sCSetFlattened )
					( Origin gBackEnd )
				)
				( attribute "RELATIVE_PROPAGATION_DELAY" ",5.00 MIL"
					( Parent
						( matchGroupRef "@baseboard_fab2_lib.baseboard_fab2(sch_1):\MG_DMI_L0\" )
					)
					( Units "uMatchProp" "ns" 1.000000)
					( Status sCSetFlattened )
					( Origin gBackEnd )
				)
			)
			( pinPair "@baseboard_fab2_lib.baseboard_fab2(sch_1):\PP65\"
				( pinRef "@baseboard_fab2_lib.baseboard_fab2(sch_1):page129_i75:B" )
				( pinRef "@baseboard_fab2_lib.baseboard_fab2(sch_1):page29_i61:DMI_RX_DP(3)" )
				( attribute "RELATIVE_PROPAGATION_DELAY_SCOPE" "L"
					( Parent
						( matchGroupRef "@baseboard_fab2_lib.baseboard_fab2(sch_1):\MG_DMI_L1\" )
					)
					( Status sCSetFlattened )
					( Origin gBackEnd )
				)
				( attribute "RELATIVE_PROPAGATION_DELAY" ",5.00 MIL"
					( Parent
						( matchGroupRef "@baseboard_fab2_lib.baseboard_fab2(sch_1):\MG_DMI_L1\" )
					)
					( Units "uMatchProp" "ns" 1.000000)
					( Status sCSetFlattened )
					( Origin gBackEnd )
				)
			)
			( pinPair "@baseboard_fab2_lib.baseboard_fab2(sch_1):\PP6081\"
				( pinRef "@baseboard_fab2_lib.baseboard_fab2(sch_1):page117_i9:DMI_TXP(3)" )
				( pinRef "@baseboard_fab2_lib.baseboard_fab2(sch_1):page29_i61:DMI_RX_DP(3)" )
				( attribute "PROPAGATION_DELAY_MAX" "15000.00 MIL"
					( Units "uMaxMinProp" "ns" 1.000000)
					( Status sCSetFlattened )
					( Origin gBackEnd )
				)
			)
			( pinPair "@baseboard_fab2_lib.baseboard_fab2(sch_1):\PP3093\"
				( pinRef "@baseboard_fab2_lib.baseboard_fab2(sch_1):page31_i106:PE2_RX_DP(6)" )
				( pinRef "@baseboard_fab2_lib.baseboard_fab2(sch_1):page109_i243:IO142" )
				( attribute "PROPAGATION_DELAY_MIN" "3000.00 MIL"
					( Units "uMaxMinProp" "ns" 1.000000)
					( Status sCSetFlattened )
					( Origin gBackEnd )
				)
				( attribute "PROPAGATION_DELAY_MAX" "16000.00 MIL"
					( Units "uMaxMinProp" "ns" 1.000000)
					( Status sCSetFlattened )
					( Origin gBackEnd )
				)
				( attribute "RELATIVE_PROPAGATION_DELAY_SCOPE" "G"
					( Parent
						( matchGroupRef "@baseboard_fab2_lib.baseboard_fab2(sch_1):\MG_P3E_CPU0_PE2_SS_RX0607\" )
					)
					( Status sCSetFlattened )
					( Origin gBackEnd )
				)
				( attribute "RELATIVE_PROPAGATION_DELAY" ",500.00 MIL"
					( Parent
						( matchGroupRef "@baseboard_fab2_lib.baseboard_fab2(sch_1):\MG_P3E_CPU0_PE2_SS_RX0607\" )
					)
					( Units "uMatchProp" "ns" 1.000000)
					( Status sCSetFlattened )
					( Origin gBackEnd )
				)
			)
			( pinPair "@baseboard_fab2_lib.baseboard_fab2(sch_1):\PP3091\"
				( pinRef "@baseboard_fab2_lib.baseboard_fab2(sch_1):page31_i106:PE2_RX_DN(6)" )
				( pinRef "@baseboard_fab2_lib.baseboard_fab2(sch_1):page109_i243:IO144" )
				( attribute "PROPAGATION_DELAY_MIN" "3000.00 MIL"
					( Units "uMaxMinProp" "ns" 1.000000)
					( Status sCSetFlattened )
					( Origin gBackEnd )
				)
				( attribute "PROPAGATION_DELAY_MAX" "16000.00 MIL"
					( Units "uMaxMinProp" "ns" 1.000000)
					( Status sCSetFlattened )
					( Origin gBackEnd )
				)
				( attribute "RELATIVE_PROPAGATION_DELAY_SCOPE" "G"
					( Parent
						( matchGroupRef "@baseboard_fab2_lib.baseboard_fab2(sch_1):\MG_P3E_CPU0_PE2_SS_RX0607\" )
					)
					( Status sCSetFlattened )
					( Origin gBackEnd )
				)
				( attribute "RELATIVE_PROPAGATION_DELAY" ",500.00 MIL"
					( Parent
						( matchGroupRef "@baseboard_fab2_lib.baseboard_fab2(sch_1):\MG_P3E_CPU0_PE2_SS_RX0607\" )
					)
					( Units "uMatchProp" "ns" 1.000000)
					( Status sCSetFlattened )
					( Origin gBackEnd )
				)
			)
			( pinPair "@baseboard_fab2_lib.baseboard_fab2(sch_1):\PP3094\"
				( pinRef "@baseboard_fab2_lib.baseboard_fab2(sch_1):page31_i106:PE2_RX_DP(7)" )
				( pinRef "@baseboard_fab2_lib.baseboard_fab2(sch_1):page109_i243:IO150" )
				( attribute "PROPAGATION_DELAY_MIN" "3000.00 MIL"
					( Units "uMaxMinProp" "ns" 1.000000)
					( Status sCSetFlattened )
					( Origin gBackEnd )
				)
				( attribute "PROPAGATION_DELAY_MAX" "16000.00 MIL"
					( Units "uMaxMinProp" "ns" 1.000000)
					( Status sCSetFlattened )
					( Origin gBackEnd )
				)
				( attribute "RELATIVE_PROPAGATION_DELAY_SCOPE" "G"
					( Parent
						( matchGroupRef "@baseboard_fab2_lib.baseboard_fab2(sch_1):\MG_P3E_CPU0_PE2_SS_RX0607\" )
					)
					( Status sCSetFlattened )
					( Origin gBackEnd )
				)
				( attribute "RELATIVE_PROPAGATION_DELAY" ",500.00 MIL"
					( Parent
						( matchGroupRef "@baseboard_fab2_lib.baseboard_fab2(sch_1):\MG_P3E_CPU0_PE2_SS_RX0607\" )
					)
					( Units "uMatchProp" "ns" 1.000000)
					( Status sCSetFlattened )
					( Origin gBackEnd )
				)
			)
			( pinPair "@baseboard_fab2_lib.baseboard_fab2(sch_1):\PP3092\"
				( pinRef "@baseboard_fab2_lib.baseboard_fab2(sch_1):page31_i106:PE2_RX_DN(7)" )
				( pinRef "@baseboard_fab2_lib.baseboard_fab2(sch_1):page109_i243:IO148" )
				( attribute "PROPAGATION_DELAY_MIN" "3000.00 MIL"
					( Units "uMaxMinProp" "ns" 1.000000)
					( Status sCSetFlattened )
					( Origin gBackEnd )
				)
				( attribute "PROPAGATION_DELAY_MAX" "16000.00 MIL"
					( Units "uMaxMinProp" "ns" 1.000000)
					( Status sCSetFlattened )
					( Origin gBackEnd )
				)
				( attribute "RELATIVE_PROPAGATION_DELAY_SCOPE" "G"
					( Parent
						( matchGroupRef "@baseboard_fab2_lib.baseboard_fab2(sch_1):\MG_P3E_CPU0_PE2_SS_RX0607\" )
					)
					( Status sCSetFlattened )
					( Origin gBackEnd )
				)
				( attribute "RELATIVE_PROPAGATION_DELAY" ",500.00 MIL"
					( Parent
						( matchGroupRef "@baseboard_fab2_lib.baseboard_fab2(sch_1):\MG_P3E_CPU0_PE2_SS_RX0607\" )
					)
					( Units "uMatchProp" "ns" 1.000000)
					( Status sCSetFlattened )
					( Origin gBackEnd )
				)
			)
			( pinPair "@baseboard_fab2_lib.baseboard_fab2(sch_1):\PP3089\"
				( pinRef "@baseboard_fab2_lib.baseboard_fab2(sch_1):page31_i106:PE2_RX_DP(8)" )
				( pinRef "@baseboard_fab2_lib.baseboard_fab2(sch_1):page109_i243:IO156" )
				( attribute "PROPAGATION_DELAY_MIN" "3000.00 MIL"
					( Units "uMaxMinProp" "ns" 1.000000)
					( Status sCSetFlattened )
					( Origin gBackEnd )
				)
				( attribute "PROPAGATION_DELAY_MAX" "16000.00 MIL"
					( Units "uMaxMinProp" "ns" 1.000000)
					( Status sCSetFlattened )
					( Origin gBackEnd )
				)
				( attribute "RELATIVE_PROPAGATION_DELAY_SCOPE" "G"
					( Parent
						( matchGroupRef "@baseboard_fab2_lib.baseboard_fab2(sch_1):\MG_P3E_CPU0_PE2_SS_RX0809\" )
					)
					( Status sCSetFlattened )
					( Origin gBackEnd )
				)
				( attribute "RELATIVE_PROPAGATION_DELAY" ",500.00 MIL"
					( Parent
						( matchGroupRef "@baseboard_fab2_lib.baseboard_fab2(sch_1):\MG_P3E_CPU0_PE2_SS_RX0809\" )
					)
					( Units "uMatchProp" "ns" 1.000000)
					( Status sCSetFlattened )
					( Origin gBackEnd )
				)
			)
			( pinPair "@baseboard_fab2_lib.baseboard_fab2(sch_1):\PP3087\"
				( pinRef "@baseboard_fab2_lib.baseboard_fab2(sch_1):page31_i106:PE2_RX_DN(8)" )
				( pinRef "@baseboard_fab2_lib.baseboard_fab2(sch_1):page109_i243:IO154" )
				( attribute "PROPAGATION_DELAY_MIN" "3000.00 MIL"
					( Units "uMaxMinProp" "ns" 1.000000)
					( Status sCSetFlattened )
					( Origin gBackEnd )
				)
				( attribute "PROPAGATION_DELAY_MAX" "16000.00 MIL"
					( Units "uMaxMinProp" "ns" 1.000000)
					( Status sCSetFlattened )
					( Origin gBackEnd )
				)
				( attribute "RELATIVE_PROPAGATION_DELAY_SCOPE" "G"
					( Parent
						( matchGroupRef "@baseboard_fab2_lib.baseboard_fab2(sch_1):\MG_P3E_CPU0_PE2_SS_RX0809\" )
					)
					( Status sCSetFlattened )
					( Origin gBackEnd )
				)
				( attribute "RELATIVE_PROPAGATION_DELAY" ",500.00 MIL"
					( Parent
						( matchGroupRef "@baseboard_fab2_lib.baseboard_fab2(sch_1):\MG_P3E_CPU0_PE2_SS_RX0809\" )
					)
					( Units "uMatchProp" "ns" 1.000000)
					( Status sCSetFlattened )
					( Origin gBackEnd )
				)
			)
			( pinPair "@baseboard_fab2_lib.baseboard_fab2(sch_1):\PP3078\"
				( pinRef "@baseboard_fab2_lib.baseboard_fab2(sch_1):page31_i106:PE2_RX_DP(15)" )
				( pinRef "@baseboard_fab2_lib.baseboard_fab2(sch_1):page109_i243:IO198" )
				( attribute "PROPAGATION_DELAY_MIN" "3000.00 MIL"
					( Units "uMaxMinProp" "ns" 1.000000)
					( Status sCSetFlattened )
					( Origin gBackEnd )
				)
				( attribute "PROPAGATION_DELAY_MAX" "16000.00 MIL"
					( Units "uMaxMinProp" "ns" 1.000000)
					( Status sCSetFlattened )
					( Origin gBackEnd )
				)
				( attribute "RELATIVE_PROPAGATION_DELAY_SCOPE" "G"
					( Parent
						( matchGroupRef "@baseboard_fab2_lib.baseboard_fab2(sch_1):\MG_P3E_CPU0_PE2_SS_RX1415\" )
					)
					( Status sCSetFlattened )
					( Origin gBackEnd )
				)
				( attribute "RELATIVE_PROPAGATION_DELAY" ",500.00 MIL"
					( Parent
						( matchGroupRef "@baseboard_fab2_lib.baseboard_fab2(sch_1):\MG_P3E_CPU0_PE2_SS_RX1415\" )
					)
					( Units "uMatchProp" "ns" 1.000000)
					( Status sCSetFlattened )
					( Origin gBackEnd )
				)
			)
			( pinPair "@baseboard_fab2_lib.baseboard_fab2(sch_1):\PP3076\"
				( pinRef "@baseboard_fab2_lib.baseboard_fab2(sch_1):page31_i106:PE2_RX_DN(15)" )
				( pinRef "@baseboard_fab2_lib.baseboard_fab2(sch_1):page109_i243:IO196" )
				( attribute "PROPAGATION_DELAY_MIN" "3000.00 MIL"
					( Units "uMaxMinProp" "ns" 1.000000)
					( Status sCSetFlattened )
					( Origin gBackEnd )
				)
				( attribute "PROPAGATION_DELAY_MAX" "16000.00 MIL"
					( Units "uMaxMinProp" "ns" 1.000000)
					( Status sCSetFlattened )
					( Origin gBackEnd )
				)
				( attribute "RELATIVE_PROPAGATION_DELAY_SCOPE" "G"
					( Parent
						( matchGroupRef "@baseboard_fab2_lib.baseboard_fab2(sch_1):\MG_P3E_CPU0_PE2_SS_RX1415\" )
					)
					( Status sCSetFlattened )
					( Origin gBackEnd )
				)
				( attribute "RELATIVE_PROPAGATION_DELAY" ",500.00 MIL"
					( Parent
						( matchGroupRef "@baseboard_fab2_lib.baseboard_fab2(sch_1):\MG_P3E_CPU0_PE2_SS_RX1415\" )
					)
					( Units "uMatchProp" "ns" 1.000000)
					( Status sCSetFlattened )
					( Origin gBackEnd )
				)
			)
			( pinPair "@baseboard_fab2_lib.baseboard_fab2(sch_1):\PP3077\"
				( pinRef "@baseboard_fab2_lib.baseboard_fab2(sch_1):page31_i106:PE2_RX_DP(14)" )
				( pinRef "@baseboard_fab2_lib.baseboard_fab2(sch_1):page109_i243:IO192" )
				( attribute "PROPAGATION_DELAY_MIN" "3000.00 MIL"
					( Units "uMaxMinProp" "ns" 1.000000)
					( Status sCSetFlattened )
					( Origin gBackEnd )
				)
				( attribute "PROPAGATION_DELAY_MAX" "16000.00 MIL"
					( Units "uMaxMinProp" "ns" 1.000000)
					( Status sCSetFlattened )
					( Origin gBackEnd )
				)
				( attribute "RELATIVE_PROPAGATION_DELAY_SCOPE" "G"
					( Parent
						( matchGroupRef "@baseboard_fab2_lib.baseboard_fab2(sch_1):\MG_P3E_CPU0_PE2_SS_RX1415\" )
					)
					( Status sCSetFlattened )
					( Origin gBackEnd )
				)
				( attribute "RELATIVE_PROPAGATION_DELAY" ",500.00 MIL"
					( Parent
						( matchGroupRef "@baseboard_fab2_lib.baseboard_fab2(sch_1):\MG_P3E_CPU0_PE2_SS_RX1415\" )
					)
					( Units "uMatchProp" "ns" 1.000000)
					( Status sCSetFlattened )
					( Origin gBackEnd )
				)
			)
			( pinPair "@baseboard_fab2_lib.baseboard_fab2(sch_1):\PP3075\"
				( pinRef "@baseboard_fab2_lib.baseboard_fab2(sch_1):page31_i106:PE2_RX_DN(14)" )
				( pinRef "@baseboard_fab2_lib.baseboard_fab2(sch_1):page109_i243:IO190" )
				( attribute "PROPAGATION_DELAY_MIN" "3000.00 MIL"
					( Units "uMaxMinProp" "ns" 1.000000)
					( Status sCSetFlattened )
					( Origin gBackEnd )
				)
				( attribute "PROPAGATION_DELAY_MAX" "16000.00 MIL"
					( Units "uMaxMinProp" "ns" 1.000000)
					( Status sCSetFlattened )
					( Origin gBackEnd )
				)
				( attribute "RELATIVE_PROPAGATION_DELAY_SCOPE" "G"
					( Parent
						( matchGroupRef "@baseboard_fab2_lib.baseboard_fab2(sch_1):\MG_P3E_CPU0_PE2_SS_RX1415\" )
					)
					( Status sCSetFlattened )
					( Origin gBackEnd )
				)
				( attribute "RELATIVE_PROPAGATION_DELAY" ",500.00 MIL"
					( Parent
						( matchGroupRef "@baseboard_fab2_lib.baseboard_fab2(sch_1):\MG_P3E_CPU0_PE2_SS_RX1415\" )
					)
					( Units "uMatchProp" "ns" 1.000000)
					( Status sCSetFlattened )
					( Origin gBackEnd )
				)
			)
			( pinPair "@baseboard_fab2_lib.baseboard_fab2(sch_1):\PP3082\"
				( pinRef "@baseboard_fab2_lib.baseboard_fab2(sch_1):page31_i106:PE2_RX_DP(13)" )
				( pinRef "@baseboard_fab2_lib.baseboard_fab2(sch_1):page109_i243:IO184" )
				( attribute "PROPAGATION_DELAY_MIN" "3000.00 MIL"
					( Units "uMaxMinProp" "ns" 1.000000)
					( Status sCSetFlattened )
					( Origin gBackEnd )
				)
				( attribute "PROPAGATION_DELAY_MAX" "16000.00 MIL"
					( Units "uMaxMinProp" "ns" 1.000000)
					( Status sCSetFlattened )
					( Origin gBackEnd )
				)
				( attribute "RELATIVE_PROPAGATION_DELAY_SCOPE" "G"
					( Parent
						( matchGroupRef "@baseboard_fab2_lib.baseboard_fab2(sch_1):\MG_P3E_CPU0_PE2_SS_RX1213\" )
					)
					( Status sCSetFlattened )
					( Origin gBackEnd )
				)
				( attribute "RELATIVE_PROPAGATION_DELAY" ",500.00 MIL"
					( Parent
						( matchGroupRef "@baseboard_fab2_lib.baseboard_fab2(sch_1):\MG_P3E_CPU0_PE2_SS_RX1213\" )
					)
					( Units "uMatchProp" "ns" 1.000000)
					( Status sCSetFlattened )
					( Origin gBackEnd )
				)
			)
			( pinPair "@baseboard_fab2_lib.baseboard_fab2(sch_1):\PP3080\"
				( pinRef "@baseboard_fab2_lib.baseboard_fab2(sch_1):page31_i106:PE2_RX_DN(13)" )
				( pinRef "@baseboard_fab2_lib.baseboard_fab2(sch_1):page109_i243:IO186" )
				( attribute "PROPAGATION_DELAY_MIN" "3000.00 MIL"
					( Units "uMaxMinProp" "ns" 1.000000)
					( Status sCSetFlattened )
					( Origin gBackEnd )
				)
				( attribute "PROPAGATION_DELAY_MAX" "16000.00 MIL"
					( Units "uMaxMinProp" "ns" 1.000000)
					( Status sCSetFlattened )
					( Origin gBackEnd )
				)
				( attribute "RELATIVE_PROPAGATION_DELAY_SCOPE" "G"
					( Parent
						( matchGroupRef "@baseboard_fab2_lib.baseboard_fab2(sch_1):\MG_P3E_CPU0_PE2_SS_RX1213\" )
					)
					( Status sCSetFlattened )
					( Origin gBackEnd )
				)
				( attribute "RELATIVE_PROPAGATION_DELAY" ",500.00 MIL"
					( Parent
						( matchGroupRef "@baseboard_fab2_lib.baseboard_fab2(sch_1):\MG_P3E_CPU0_PE2_SS_RX1213\" )
					)
					( Units "uMatchProp" "ns" 1.000000)
					( Status sCSetFlattened )
					( Origin gBackEnd )
				)
			)
			( pinPair "@baseboard_fab2_lib.baseboard_fab2(sch_1):\PP3081\"
				( pinRef "@baseboard_fab2_lib.baseboard_fab2(sch_1):page31_i106:PE2_RX_DP(12)" )
				( pinRef "@baseboard_fab2_lib.baseboard_fab2(sch_1):page109_i243:IO180" )
				( attribute "PROPAGATION_DELAY_MIN" "3000.00 MIL"
					( Units "uMaxMinProp" "ns" 1.000000)
					( Status sCSetFlattened )
					( Origin gBackEnd )
				)
				( attribute "PROPAGATION_DELAY_MAX" "16000.00 MIL"
					( Units "uMaxMinProp" "ns" 1.000000)
					( Status sCSetFlattened )
					( Origin gBackEnd )
				)
				( attribute "RELATIVE_PROPAGATION_DELAY_SCOPE" "G"
					( Parent
						( matchGroupRef "@baseboard_fab2_lib.baseboard_fab2(sch_1):\MG_P3E_CPU0_PE2_SS_RX1213\" )
					)
					( Status sCSetFlattened )
					( Origin gBackEnd )
				)
				( attribute "RELATIVE_PROPAGATION_DELAY" ",500.00 MIL"
					( Parent
						( matchGroupRef "@baseboard_fab2_lib.baseboard_fab2(sch_1):\MG_P3E_CPU0_PE2_SS_RX1213\" )
					)
					( Units "uMatchProp" "ns" 1.000000)
					( Status sCSetFlattened )
					( Origin gBackEnd )
				)
			)
			( pinPair "@baseboard_fab2_lib.baseboard_fab2(sch_1):\PP3079\"
				( pinRef "@baseboard_fab2_lib.baseboard_fab2(sch_1):page31_i106:PE2_RX_DN(12)" )
				( pinRef "@baseboard_fab2_lib.baseboard_fab2(sch_1):page109_i243:IO178" )
				( attribute "PROPAGATION_DELAY_MIN" "3000.00 MIL"
					( Units "uMaxMinProp" "ns" 1.000000)
					( Status sCSetFlattened )
					( Origin gBackEnd )
				)
				( attribute "PROPAGATION_DELAY_MAX" "16000.00 MIL"
					( Units "uMaxMinProp" "ns" 1.000000)
					( Status sCSetFlattened )
					( Origin gBackEnd )
				)
				( attribute "RELATIVE_PROPAGATION_DELAY_SCOPE" "G"
					( Parent
						( matchGroupRef "@baseboard_fab2_lib.baseboard_fab2(sch_1):\MG_P3E_CPU0_PE2_SS_RX1213\" )
					)
					( Status sCSetFlattened )
					( Origin gBackEnd )
				)
				( attribute "RELATIVE_PROPAGATION_DELAY" ",500.00 MIL"
					( Parent
						( matchGroupRef "@baseboard_fab2_lib.baseboard_fab2(sch_1):\MG_P3E_CPU0_PE2_SS_RX1213\" )
					)
					( Units "uMatchProp" "ns" 1.000000)
					( Status sCSetFlattened )
					( Origin gBackEnd )
				)
			)
			( pinPair "@baseboard_fab2_lib.baseboard_fab2(sch_1):\PP3086\"
				( pinRef "@baseboard_fab2_lib.baseboard_fab2(sch_1):page31_i106:PE2_RX_DP(11)" )
				( pinRef "@baseboard_fab2_lib.baseboard_fab2(sch_1):page109_i243:IO174" )
				( attribute "PROPAGATION_DELAY_MIN" "3000.00 MIL"
					( Units "uMaxMinProp" "ns" 1.000000)
					( Status sCSetFlattened )
					( Origin gBackEnd )
				)
				( attribute "PROPAGATION_DELAY_MAX" "16000.00 MIL"
					( Units "uMaxMinProp" "ns" 1.000000)
					( Status sCSetFlattened )
					( Origin gBackEnd )
				)
				( attribute "RELATIVE_PROPAGATION_DELAY_SCOPE" "G"
					( Parent
						( matchGroupRef "@baseboard_fab2_lib.baseboard_fab2(sch_1):\MG_P3E_CPU0_PE2_SS_RX1011\" )
					)
					( Status sCSetFlattened )
					( Origin gBackEnd )
				)
				( attribute "RELATIVE_PROPAGATION_DELAY" ",500.00 MIL"
					( Parent
						( matchGroupRef "@baseboard_fab2_lib.baseboard_fab2(sch_1):\MG_P3E_CPU0_PE2_SS_RX1011\" )
					)
					( Units "uMatchProp" "ns" 1.000000)
					( Status sCSetFlattened )
					( Origin gBackEnd )
				)
			)
			( pinPair "@baseboard_fab2_lib.baseboard_fab2(sch_1):\PP3084\"
				( pinRef "@baseboard_fab2_lib.baseboard_fab2(sch_1):page31_i106:PE2_RX_DN(11)" )
				( pinRef "@baseboard_fab2_lib.baseboard_fab2(sch_1):page109_i243:IO172" )
				( attribute "PROPAGATION_DELAY_MIN" "3000.00 MIL"
					( Units "uMaxMinProp" "ns" 1.000000)
					( Status sCSetFlattened )
					( Origin gBackEnd )
				)
				( attribute "PROPAGATION_DELAY_MAX" "16000.00 MIL"
					( Units "uMaxMinProp" "ns" 1.000000)
					( Status sCSetFlattened )
					( Origin gBackEnd )
				)
				( attribute "RELATIVE_PROPAGATION_DELAY_SCOPE" "G"
					( Parent
						( matchGroupRef "@baseboard_fab2_lib.baseboard_fab2(sch_1):\MG_P3E_CPU0_PE2_SS_RX1011\" )
					)
					( Status sCSetFlattened )
					( Origin gBackEnd )
				)
				( attribute "RELATIVE_PROPAGATION_DELAY" ",500.00 MIL"
					( Parent
						( matchGroupRef "@baseboard_fab2_lib.baseboard_fab2(sch_1):\MG_P3E_CPU0_PE2_SS_RX1011\" )
					)
					( Units "uMatchProp" "ns" 1.000000)
					( Status sCSetFlattened )
					( Origin gBackEnd )
				)
			)
			( pinPair "@baseboard_fab2_lib.baseboard_fab2(sch_1):\PP3085\"
				( pinRef "@baseboard_fab2_lib.baseboard_fab2(sch_1):page31_i106:PE2_RX_DP(10)" )
				( pinRef "@baseboard_fab2_lib.baseboard_fab2(sch_1):page109_i243:IO168" )
				( attribute "PROPAGATION_DELAY_MIN" "3000.00 MIL"
					( Units "uMaxMinProp" "ns" 1.000000)
					( Status sCSetFlattened )
					( Origin gBackEnd )
				)
				( attribute "PROPAGATION_DELAY_MAX" "16000.00 MIL"
					( Units "uMaxMinProp" "ns" 1.000000)
					( Status sCSetFlattened )
					( Origin gBackEnd )
				)
				( attribute "RELATIVE_PROPAGATION_DELAY_SCOPE" "G"
					( Parent
						( matchGroupRef "@baseboard_fab2_lib.baseboard_fab2(sch_1):\MG_P3E_CPU0_PE2_SS_RX1011\" )
					)
					( Status sCSetFlattened )
					( Origin gBackEnd )
				)
				( attribute "RELATIVE_PROPAGATION_DELAY" ",500.00 MIL"
					( Parent
						( matchGroupRef "@baseboard_fab2_lib.baseboard_fab2(sch_1):\MG_P3E_CPU0_PE2_SS_RX1011\" )
					)
					( Units "uMatchProp" "ns" 1.000000)
					( Status sCSetFlattened )
					( Origin gBackEnd )
				)
			)
			( pinPair "@baseboard_fab2_lib.baseboard_fab2(sch_1):\PP3083\"
				( pinRef "@baseboard_fab2_lib.baseboard_fab2(sch_1):page31_i106:PE2_RX_DN(10)" )
				( pinRef "@baseboard_fab2_lib.baseboard_fab2(sch_1):page109_i243:IO166" )
				( attribute "PROPAGATION_DELAY_MIN" "3000.00 MIL"
					( Units "uMaxMinProp" "ns" 1.000000)
					( Status sCSetFlattened )
					( Origin gBackEnd )
				)
				( attribute "PROPAGATION_DELAY_MAX" "16000.00 MIL"
					( Units "uMaxMinProp" "ns" 1.000000)
					( Status sCSetFlattened )
					( Origin gBackEnd )
				)
				( attribute "RELATIVE_PROPAGATION_DELAY_SCOPE" "G"
					( Parent
						( matchGroupRef "@baseboard_fab2_lib.baseboard_fab2(sch_1):\MG_P3E_CPU0_PE2_SS_RX1011\" )
					)
					( Status sCSetFlattened )
					( Origin gBackEnd )
				)
				( attribute "RELATIVE_PROPAGATION_DELAY" ",500.00 MIL"
					( Parent
						( matchGroupRef "@baseboard_fab2_lib.baseboard_fab2(sch_1):\MG_P3E_CPU0_PE2_SS_RX1011\" )
					)
					( Units "uMatchProp" "ns" 1.000000)
					( Status sCSetFlattened )
					( Origin gBackEnd )
				)
			)
			( pinPair "@baseboard_fab2_lib.baseboard_fab2(sch_1):\PP3090\"
				( pinRef "@baseboard_fab2_lib.baseboard_fab2(sch_1):page31_i106:PE2_RX_DP(9)" )
				( pinRef "@baseboard_fab2_lib.baseboard_fab2(sch_1):page109_i243:IO162" )
				( attribute "PROPAGATION_DELAY_MIN" "3000.00 MIL"
					( Units "uMaxMinProp" "ns" 1.000000)
					( Status sCSetFlattened )
					( Origin gBackEnd )
				)
				( attribute "PROPAGATION_DELAY_MAX" "16000.00 MIL"
					( Units "uMaxMinProp" "ns" 1.000000)
					( Status sCSetFlattened )
					( Origin gBackEnd )
				)
				( attribute "RELATIVE_PROPAGATION_DELAY_SCOPE" "G"
					( Parent
						( matchGroupRef "@baseboard_fab2_lib.baseboard_fab2(sch_1):\MG_P3E_CPU0_PE2_SS_RX0809\" )
					)
					( Status sCSetFlattened )
					( Origin gBackEnd )
				)
				( attribute "RELATIVE_PROPAGATION_DELAY" ",500.00 MIL"
					( Parent
						( matchGroupRef "@baseboard_fab2_lib.baseboard_fab2(sch_1):\MG_P3E_CPU0_PE2_SS_RX0809\" )
					)
					( Units "uMatchProp" "ns" 1.000000)
					( Status sCSetFlattened )
					( Origin gBackEnd )
				)
			)
			( pinPair "@baseboard_fab2_lib.baseboard_fab2(sch_1):\PP3088\"
				( pinRef "@baseboard_fab2_lib.baseboard_fab2(sch_1):page31_i106:PE2_RX_DN(9)" )
				( pinRef "@baseboard_fab2_lib.baseboard_fab2(sch_1):page109_i243:IO160" )
				( attribute "PROPAGATION_DELAY_MIN" "3000.00 MIL"
					( Units "uMaxMinProp" "ns" 1.000000)
					( Status sCSetFlattened )
					( Origin gBackEnd )
				)
				( attribute "PROPAGATION_DELAY_MAX" "16000.00 MIL"
					( Units "uMaxMinProp" "ns" 1.000000)
					( Status sCSetFlattened )
					( Origin gBackEnd )
				)
				( attribute "RELATIVE_PROPAGATION_DELAY_SCOPE" "G"
					( Parent
						( matchGroupRef "@baseboard_fab2_lib.baseboard_fab2(sch_1):\MG_P3E_CPU0_PE2_SS_RX0809\" )
					)
					( Status sCSetFlattened )
					( Origin gBackEnd )
				)
				( attribute "RELATIVE_PROPAGATION_DELAY" ",500.00 MIL"
					( Parent
						( matchGroupRef "@baseboard_fab2_lib.baseboard_fab2(sch_1):\MG_P3E_CPU0_PE2_SS_RX0809\" )
					)
					( Units "uMatchProp" "ns" 1.000000)
					( Status sCSetFlattened )
					( Origin gBackEnd )
				)
			)
			( pinPair "@baseboard_fab2_lib.baseboard_fab2(sch_1):\PP3017\"
				( pinRef "@baseboard_fab2_lib.baseboard_fab2(sch_1):page66_i84:PE3_RX_DP(8)" )
				( pinRef "@baseboard_fab2_lib.baseboard_fab2(sch_1):page182_i18:IOB1" )
				( attribute "PROPAGATION_DELAY_MIN" "3000.00 MIL"
					( Units "uMaxMinProp" "ns" 1.000000)
					( Status sCSetFlattened )
					( Origin gBackEnd )
				)
				( attribute "PROPAGATION_DELAY_MAX" "16000.00 MIL"
					( Units "uMaxMinProp" "ns" 1.000000)
					( Status sCSetFlattened )
					( Origin gBackEnd )
				)
				( attribute "RELATIVE_PROPAGATION_DELAY_SCOPE" "G"
					( Parent
						( matchGroupRef "@baseboard_fab2_lib.baseboard_fab2(sch_1):\MG_P3E_CPU1_PE3_MP_RX0809\" )
					)
					( Status sCSetFlattened )
					( Origin gBackEnd )
				)
				( attribute "RELATIVE_PROPAGATION_DELAY" ",500.00 MIL"
					( Parent
						( matchGroupRef "@baseboard_fab2_lib.baseboard_fab2(sch_1):\MG_P3E_CPU1_PE3_MP_RX0809\" )
					)
					( Units "uMatchProp" "ns" 1.000000)
					( Status sCSetFlattened )
					( Origin gBackEnd )
				)
			)
			( pinPair "@baseboard_fab2_lib.baseboard_fab2(sch_1):\PP3015\"
				( pinRef "@baseboard_fab2_lib.baseboard_fab2(sch_1):page66_i84:PE3_RX_DN(8)" )
				( pinRef "@baseboard_fab2_lib.baseboard_fab2(sch_1):page182_i18:IOA1" )
				( attribute "PROPAGATION_DELAY_MIN" "3000.00 MIL"
					( Units "uMaxMinProp" "ns" 1.000000)
					( Status sCSetFlattened )
					( Origin gBackEnd )
				)
				( attribute "PROPAGATION_DELAY_MAX" "16000.00 MIL"
					( Units "uMaxMinProp" "ns" 1.000000)
					( Status sCSetFlattened )
					( Origin gBackEnd )
				)
				( attribute "RELATIVE_PROPAGATION_DELAY_SCOPE" "G"
					( Parent
						( matchGroupRef "@baseboard_fab2_lib.baseboard_fab2(sch_1):\MG_P3E_CPU1_PE3_MP_RX0809\" )
					)
					( Status sCSetFlattened )
					( Origin gBackEnd )
				)
				( attribute "RELATIVE_PROPAGATION_DELAY" ",500.00 MIL"
					( Parent
						( matchGroupRef "@baseboard_fab2_lib.baseboard_fab2(sch_1):\MG_P3E_CPU1_PE3_MP_RX0809\" )
					)
					( Units "uMatchProp" "ns" 1.000000)
					( Status sCSetFlattened )
					( Origin gBackEnd )
				)
			)
			( pinPair "@baseboard_fab2_lib.baseboard_fab2(sch_1):\PP3018\"
				( pinRef "@baseboard_fab2_lib.baseboard_fab2(sch_1):page66_i84:PE3_RX_DP(9)" )
				( pinRef "@baseboard_fab2_lib.baseboard_fab2(sch_1):page182_i18:IOE1" )
				( attribute "PROPAGATION_DELAY_MIN" "3000.00 MIL"
					( Units "uMaxMinProp" "ns" 1.000000)
					( Status sCSetFlattened )
					( Origin gBackEnd )
				)
				( attribute "PROPAGATION_DELAY_MAX" "16000.00 MIL"
					( Units "uMaxMinProp" "ns" 1.000000)
					( Status sCSetFlattened )
					( Origin gBackEnd )
				)
				( attribute "RELATIVE_PROPAGATION_DELAY_SCOPE" "G"
					( Parent
						( matchGroupRef "@baseboard_fab2_lib.baseboard_fab2(sch_1):\MG_P3E_CPU1_PE3_MP_RX0809\" )
					)
					( Status sCSetFlattened )
					( Origin gBackEnd )
				)
				( attribute "RELATIVE_PROPAGATION_DELAY" ",500.00 MIL"
					( Parent
						( matchGroupRef "@baseboard_fab2_lib.baseboard_fab2(sch_1):\MG_P3E_CPU1_PE3_MP_RX0809\" )
					)
					( Units "uMatchProp" "ns" 1.000000)
					( Status sCSetFlattened )
					( Origin gBackEnd )
				)
			)
			( pinPair "@baseboard_fab2_lib.baseboard_fab2(sch_1):\PP3016\"
				( pinRef "@baseboard_fab2_lib.baseboard_fab2(sch_1):page66_i84:PE3_RX_DN(9)" )
				( pinRef "@baseboard_fab2_lib.baseboard_fab2(sch_1):page182_i18:IOD1" )
				( attribute "PROPAGATION_DELAY_MIN" "3000.00 MIL"
					( Units "uMaxMinProp" "ns" 1.000000)
					( Status sCSetFlattened )
					( Origin gBackEnd )
				)
				( attribute "PROPAGATION_DELAY_MAX" "16000.00 MIL"
					( Units "uMaxMinProp" "ns" 1.000000)
					( Status sCSetFlattened )
					( Origin gBackEnd )
				)
				( attribute "RELATIVE_PROPAGATION_DELAY_SCOPE" "G"
					( Parent
						( matchGroupRef "@baseboard_fab2_lib.baseboard_fab2(sch_1):\MG_P3E_CPU1_PE3_MP_RX0809\" )
					)
					( Status sCSetFlattened )
					( Origin gBackEnd )
				)
				( attribute "RELATIVE_PROPAGATION_DELAY" ",500.00 MIL"
					( Parent
						( matchGroupRef "@baseboard_fab2_lib.baseboard_fab2(sch_1):\MG_P3E_CPU1_PE3_MP_RX0809\" )
					)
					( Units "uMatchProp" "ns" 1.000000)
					( Status sCSetFlattened )
					( Origin gBackEnd )
				)
			)
			( pinPair "@baseboard_fab2_lib.baseboard_fab2(sch_1):\PP3013\"
				( pinRef "@baseboard_fab2_lib.baseboard_fab2(sch_1):page66_i84:PE3_RX_DP(10)" )
				( pinRef "@baseboard_fab2_lib.baseboard_fab2(sch_1):page182_i18:IOG1" )
				( attribute "PROPAGATION_DELAY_MIN" "3000.00 MIL"
					( Units "uMaxMinProp" "ns" 1.000000)
					( Status sCSetFlattened )
					( Origin gBackEnd )
				)
				( attribute "PROPAGATION_DELAY_MAX" "16000.00 MIL"
					( Units "uMaxMinProp" "ns" 1.000000)
					( Status sCSetFlattened )
					( Origin gBackEnd )
				)
				( attribute "RELATIVE_PROPAGATION_DELAY_SCOPE" "G"
					( Parent
						( matchGroupRef "@baseboard_fab2_lib.baseboard_fab2(sch_1):\MG_P3E_CPU1_PE3_MP_RX1011\" )
					)
					( Status sCSetFlattened )
					( Origin gBackEnd )
				)
				( attribute "RELATIVE_PROPAGATION_DELAY" ",500.00 MIL"
					( Parent
						( matchGroupRef "@baseboard_fab2_lib.baseboard_fab2(sch_1):\MG_P3E_CPU1_PE3_MP_RX1011\" )
					)
					( Units "uMatchProp" "ns" 1.000000)
					( Status sCSetFlattened )
					( Origin gBackEnd )
				)
			)
			( pinPair "@baseboard_fab2_lib.baseboard_fab2(sch_1):\PP3011\"
				( pinRef "@baseboard_fab2_lib.baseboard_fab2(sch_1):page66_i84:PE3_RX_DN(10)" )
				( pinRef "@baseboard_fab2_lib.baseboard_fab2(sch_1):page182_i18:IOH1" )
				( attribute "PROPAGATION_DELAY_MIN" "3000.00 MIL"
					( Units "uMaxMinProp" "ns" 1.000000)
					( Status sCSetFlattened )
					( Origin gBackEnd )
				)
				( attribute "PROPAGATION_DELAY_MAX" "16000.00 MIL"
					( Units "uMaxMinProp" "ns" 1.000000)
					( Status sCSetFlattened )
					( Origin gBackEnd )
				)
				( attribute "RELATIVE_PROPAGATION_DELAY_SCOPE" "G"
					( Parent
						( matchGroupRef "@baseboard_fab2_lib.baseboard_fab2(sch_1):\MG_P3E_CPU1_PE3_MP_RX1011\" )
					)
					( Status sCSetFlattened )
					( Origin gBackEnd )
				)
				( attribute "RELATIVE_PROPAGATION_DELAY" ",500.00 MIL"
					( Parent
						( matchGroupRef "@baseboard_fab2_lib.baseboard_fab2(sch_1):\MG_P3E_CPU1_PE3_MP_RX1011\" )
					)
					( Units "uMatchProp" "ns" 1.000000)
					( Status sCSetFlattened )
					( Origin gBackEnd )
				)
			)
			( pinPair "@baseboard_fab2_lib.baseboard_fab2(sch_1):\PP3014\"
				( pinRef "@baseboard_fab2_lib.baseboard_fab2(sch_1):page66_i84:PE3_RX_DP(11)" )
				( pinRef "@baseboard_fab2_lib.baseboard_fab2(sch_1):page182_i18:IOC2" )
				( attribute "PROPAGATION_DELAY_MIN" "3000.00 MIL"
					( Units "uMaxMinProp" "ns" 1.000000)
					( Status sCSetFlattened )
					( Origin gBackEnd )
				)
				( attribute "PROPAGATION_DELAY_MAX" "16000.00 MIL"
					( Units "uMaxMinProp" "ns" 1.000000)
					( Status sCSetFlattened )
					( Origin gBackEnd )
				)
				( attribute "RELATIVE_PROPAGATION_DELAY_SCOPE" "G"
					( Parent
						( matchGroupRef "@baseboard_fab2_lib.baseboard_fab2(sch_1):\MG_P3E_CPU1_PE3_MP_RX1011\" )
					)
					( Status sCSetFlattened )
					( Origin gBackEnd )
				)
				( attribute "RELATIVE_PROPAGATION_DELAY" ",500.00 MIL"
					( Parent
						( matchGroupRef "@baseboard_fab2_lib.baseboard_fab2(sch_1):\MG_P3E_CPU1_PE3_MP_RX1011\" )
					)
					( Units "uMatchProp" "ns" 1.000000)
					( Status sCSetFlattened )
					( Origin gBackEnd )
				)
			)
			( pinPair "@baseboard_fab2_lib.baseboard_fab2(sch_1):\PP3012\"
				( pinRef "@baseboard_fab2_lib.baseboard_fab2(sch_1):page66_i84:PE3_RX_DN(11)" )
				( pinRef "@baseboard_fab2_lib.baseboard_fab2(sch_1):page182_i18:IOB2" )
				( attribute "PROPAGATION_DELAY_MIN" "3000.00 MIL"
					( Units "uMaxMinProp" "ns" 1.000000)
					( Status sCSetFlattened )
					( Origin gBackEnd )
				)
				( attribute "PROPAGATION_DELAY_MAX" "16000.00 MIL"
					( Units "uMaxMinProp" "ns" 1.000000)
					( Status sCSetFlattened )
					( Origin gBackEnd )
				)
				( attribute "RELATIVE_PROPAGATION_DELAY_SCOPE" "G"
					( Parent
						( matchGroupRef "@baseboard_fab2_lib.baseboard_fab2(sch_1):\MG_P3E_CPU1_PE3_MP_RX1011\" )
					)
					( Status sCSetFlattened )
					( Origin gBackEnd )
				)
				( attribute "RELATIVE_PROPAGATION_DELAY" ",500.00 MIL"
					( Parent
						( matchGroupRef "@baseboard_fab2_lib.baseboard_fab2(sch_1):\MG_P3E_CPU1_PE3_MP_RX1011\" )
					)
					( Units "uMatchProp" "ns" 1.000000)
					( Status sCSetFlattened )
					( Origin gBackEnd )
				)
			)
			( pinPair "@baseboard_fab2_lib.baseboard_fab2(sch_1):\PP3009\"
				( pinRef "@baseboard_fab2_lib.baseboard_fab2(sch_1):page66_i84:PE3_RX_DN(12)" )
				( pinRef "@baseboard_fab2_lib.baseboard_fab2(sch_1):page182_i18:IOF2" )
				( attribute "PROPAGATION_DELAY_MIN" "3000.00 MIL"
					( Units "uMaxMinProp" "ns" 1.000000)
					( Status sCSetFlattened )
					( Origin gBackEnd )
				)
				( attribute "PROPAGATION_DELAY_MAX" "16000.00 MIL"
					( Units "uMaxMinProp" "ns" 1.000000)
					( Status sCSetFlattened )
					( Origin gBackEnd )
				)
				( attribute "RELATIVE_PROPAGATION_DELAY_SCOPE" "G"
					( Parent
						( matchGroupRef "@baseboard_fab2_lib.baseboard_fab2(sch_1):\MG_P3E_CPU1_PE3_MP_RX1213\" )
					)
					( Status sCSetFlattened )
					( Origin gBackEnd )
				)
				( attribute "RELATIVE_PROPAGATION_DELAY" ",500.00 MIL"
					( Parent
						( matchGroupRef "@baseboard_fab2_lib.baseboard_fab2(sch_1):\MG_P3E_CPU1_PE3_MP_RX1213\" )
					)
					( Units "uMatchProp" "ns" 1.000000)
					( Status sCSetFlattened )
					( Origin gBackEnd )
				)
			)
			( pinPair "@baseboard_fab2_lib.baseboard_fab2(sch_1):\PP3007\"
				( pinRef "@baseboard_fab2_lib.baseboard_fab2(sch_1):page66_i84:PE3_RX_DP(12)" )
				( pinRef "@baseboard_fab2_lib.baseboard_fab2(sch_1):page182_i18:IOE2" )
				( attribute "PROPAGATION_DELAY_MIN" "3000.00 MIL"
					( Units "uMaxMinProp" "ns" 1.000000)
					( Status sCSetFlattened )
					( Origin gBackEnd )
				)
				( attribute "PROPAGATION_DELAY_MAX" "16000.00 MIL"
					( Units "uMaxMinProp" "ns" 1.000000)
					( Status sCSetFlattened )
					( Origin gBackEnd )
				)
				( attribute "RELATIVE_PROPAGATION_DELAY_SCOPE" "G"
					( Parent
						( matchGroupRef "@baseboard_fab2_lib.baseboard_fab2(sch_1):\MG_P3E_CPU1_PE3_MP_RX1213\" )
					)
					( Status sCSetFlattened )
					( Origin gBackEnd )
				)
				( attribute "RELATIVE_PROPAGATION_DELAY" ",500.00 MIL"
					( Parent
						( matchGroupRef "@baseboard_fab2_lib.baseboard_fab2(sch_1):\MG_P3E_CPU1_PE3_MP_RX1213\" )
					)
					( Units "uMatchProp" "ns" 1.000000)
					( Status sCSetFlattened )
					( Origin gBackEnd )
				)
			)
			( pinPair "@baseboard_fab2_lib.baseboard_fab2(sch_1):\PP3010\"
				( pinRef "@baseboard_fab2_lib.baseboard_fab2(sch_1):page66_i84:PE3_RX_DP(13)" )
				( pinRef "@baseboard_fab2_lib.baseboard_fab2(sch_1):page182_i18:IOH2" )
				( attribute "PROPAGATION_DELAY_MIN" "3000.00 MIL"
					( Units "uMaxMinProp" "ns" 1.000000)
					( Status sCSetFlattened )
					( Origin gBackEnd )
				)
				( attribute "PROPAGATION_DELAY_MAX" "16000.00 MIL"
					( Units "uMaxMinProp" "ns" 1.000000)
					( Status sCSetFlattened )
					( Origin gBackEnd )
				)
				( attribute "RELATIVE_PROPAGATION_DELAY_SCOPE" "G"
					( Parent
						( matchGroupRef "@baseboard_fab2_lib.baseboard_fab2(sch_1):\MG_P3E_CPU1_PE3_MP_RX1213\" )
					)
					( Status sCSetFlattened )
					( Origin gBackEnd )
				)
				( attribute "RELATIVE_PROPAGATION_DELAY" ",500.00 MIL"
					( Parent
						( matchGroupRef "@baseboard_fab2_lib.baseboard_fab2(sch_1):\MG_P3E_CPU1_PE3_MP_RX1213\" )
					)
					( Units "uMatchProp" "ns" 1.000000)
					( Status sCSetFlattened )
					( Origin gBackEnd )
				)
			)
			( pinPair "@baseboard_fab2_lib.baseboard_fab2(sch_1):\PP3008\"
				( pinRef "@baseboard_fab2_lib.baseboard_fab2(sch_1):page66_i84:PE3_RX_DN(13)" )
				( pinRef "@baseboard_fab2_lib.baseboard_fab2(sch_1):page182_i18:IOI2" )
				( attribute "PROPAGATION_DELAY_MIN" "3000.00 MIL"
					( Units "uMaxMinProp" "ns" 1.000000)
					( Status sCSetFlattened )
					( Origin gBackEnd )
				)
				( attribute "PROPAGATION_DELAY_MAX" "16000.00 MIL"
					( Units "uMaxMinProp" "ns" 1.000000)
					( Status sCSetFlattened )
					( Origin gBackEnd )
				)
				( attribute "RELATIVE_PROPAGATION_DELAY_SCOPE" "G"
					( Parent
						( matchGroupRef "@baseboard_fab2_lib.baseboard_fab2(sch_1):\MG_P3E_CPU1_PE3_MP_RX1213\" )
					)
					( Status sCSetFlattened )
					( Origin gBackEnd )
				)
				( attribute "RELATIVE_PROPAGATION_DELAY" ",500.00 MIL"
					( Parent
						( matchGroupRef "@baseboard_fab2_lib.baseboard_fab2(sch_1):\MG_P3E_CPU1_PE3_MP_RX1213\" )
					)
					( Units "uMatchProp" "ns" 1.000000)
					( Status sCSetFlattened )
					( Origin gBackEnd )
				)
			)
			( pinPair "@baseboard_fab2_lib.baseboard_fab2(sch_1):\PP3005\"
				( pinRef "@baseboard_fab2_lib.baseboard_fab2(sch_1):page66_i84:PE3_RX_DP(14)" )
				( pinRef "@baseboard_fab2_lib.baseboard_fab2(sch_1):page182_i18:IOA3" )
				( attribute "PROPAGATION_DELAY_MIN" "3000.00 MIL"
					( Units "uMaxMinProp" "ns" 1.000000)
					( Status sCSetFlattened )
					( Origin gBackEnd )
				)
				( attribute "PROPAGATION_DELAY_MAX" "16000.00 MIL"
					( Units "uMaxMinProp" "ns" 1.000000)
					( Status sCSetFlattened )
					( Origin gBackEnd )
				)
				( attribute "RELATIVE_PROPAGATION_DELAY_SCOPE" "G"
					( Parent
						( matchGroupRef "@baseboard_fab2_lib.baseboard_fab2(sch_1):\MG_P3E_CPU1_PE3_MP_RX1415\" )
					)
					( Status sCSetFlattened )
					( Origin gBackEnd )
				)
				( attribute "RELATIVE_PROPAGATION_DELAY" ",500.00 MIL"
					( Parent
						( matchGroupRef "@baseboard_fab2_lib.baseboard_fab2(sch_1):\MG_P3E_CPU1_PE3_MP_RX1415\" )
					)
					( Units "uMatchProp" "ns" 1.000000)
					( Status sCSetFlattened )
					( Origin gBackEnd )
				)
			)
			( pinPair "@baseboard_fab2_lib.baseboard_fab2(sch_1):\PP3003\"
				( pinRef "@baseboard_fab2_lib.baseboard_fab2(sch_1):page66_i84:PE3_RX_DN(14)" )
				( pinRef "@baseboard_fab2_lib.baseboard_fab2(sch_1):page182_i18:IOB3" )
				( attribute "PROPAGATION_DELAY_MIN" "3000.00 MIL"
					( Units "uMaxMinProp" "ns" 1.000000)
					( Status sCSetFlattened )
					( Origin gBackEnd )
				)
				( attribute "PROPAGATION_DELAY_MAX" "16000.00 MIL"
					( Units "uMaxMinProp" "ns" 1.000000)
					( Status sCSetFlattened )
					( Origin gBackEnd )
				)
				( attribute "RELATIVE_PROPAGATION_DELAY_SCOPE" "G"
					( Parent
						( matchGroupRef "@baseboard_fab2_lib.baseboard_fab2(sch_1):\MG_P3E_CPU1_PE3_MP_RX1415\" )
					)
					( Status sCSetFlattened )
					( Origin gBackEnd )
				)
				( attribute "RELATIVE_PROPAGATION_DELAY" ",500.00 MIL"
					( Parent
						( matchGroupRef "@baseboard_fab2_lib.baseboard_fab2(sch_1):\MG_P3E_CPU1_PE3_MP_RX1415\" )
					)
					( Units "uMatchProp" "ns" 1.000000)
					( Status sCSetFlattened )
					( Origin gBackEnd )
				)
			)
			( pinPair "@baseboard_fab2_lib.baseboard_fab2(sch_1):\PP3006\"
				( pinRef "@baseboard_fab2_lib.baseboard_fab2(sch_1):page66_i84:PE3_RX_DP(15)" )
				( pinRef "@baseboard_fab2_lib.baseboard_fab2(sch_1):page182_i18:IOE3" )
				( attribute "PROPAGATION_DELAY_MIN" "3000.00 MIL"
					( Units "uMaxMinProp" "ns" 1.000000)
					( Status sCSetFlattened )
					( Origin gBackEnd )
				)
				( attribute "PROPAGATION_DELAY_MAX" "16000.00 MIL"
					( Units "uMaxMinProp" "ns" 1.000000)
					( Status sCSetFlattened )
					( Origin gBackEnd )
				)
				( attribute "RELATIVE_PROPAGATION_DELAY_SCOPE" "G"
					( Parent
						( matchGroupRef "@baseboard_fab2_lib.baseboard_fab2(sch_1):\MG_P3E_CPU1_PE3_MP_RX1415\" )
					)
					( Status sCSetFlattened )
					( Origin gBackEnd )
				)
				( attribute "RELATIVE_PROPAGATION_DELAY" ",500.00 MIL"
					( Parent
						( matchGroupRef "@baseboard_fab2_lib.baseboard_fab2(sch_1):\MG_P3E_CPU1_PE3_MP_RX1415\" )
					)
					( Units "uMatchProp" "ns" 1.000000)
					( Status sCSetFlattened )
					( Origin gBackEnd )
				)
			)
			( pinPair "@baseboard_fab2_lib.baseboard_fab2(sch_1):\PP3004\"
				( pinRef "@baseboard_fab2_lib.baseboard_fab2(sch_1):page66_i84:PE3_RX_DN(15)" )
				( pinRef "@baseboard_fab2_lib.baseboard_fab2(sch_1):page182_i18:IOD3" )
				( attribute "PROPAGATION_DELAY_MIN" "3000.00 MIL"
					( Units "uMaxMinProp" "ns" 1.000000)
					( Status sCSetFlattened )
					( Origin gBackEnd )
				)
				( attribute "PROPAGATION_DELAY_MAX" "16000.00 MIL"
					( Units "uMaxMinProp" "ns" 1.000000)
					( Status sCSetFlattened )
					( Origin gBackEnd )
				)
				( attribute "RELATIVE_PROPAGATION_DELAY_SCOPE" "G"
					( Parent
						( matchGroupRef "@baseboard_fab2_lib.baseboard_fab2(sch_1):\MG_P3E_CPU1_PE3_MP_RX1415\" )
					)
					( Status sCSetFlattened )
					( Origin gBackEnd )
				)
				( attribute "RELATIVE_PROPAGATION_DELAY" ",500.00 MIL"
					( Parent
						( matchGroupRef "@baseboard_fab2_lib.baseboard_fab2(sch_1):\MG_P3E_CPU1_PE3_MP_RX1415\" )
					)
					( Units "uMatchProp" "ns" 1.000000)
					( Status sCSetFlattened )
					( Origin gBackEnd )
				)
			)
			( electricalNet "@crescent_city_bb_fab1_lib.crescent_city_bb_fab1(sch_1):pu_bios_spi_wp0_n"
				( signalRef "@baseboard_fab2_lib.baseboard_fab2(sch_1):pu_bios_spi_wp0_n" )
				( signalRef "@baseboard_fab2_lib.baseboard_fab2(sch_1):spi_bios_socket_io2" )
				( electricalCSetRef "@crescent_city_bb_fab1_lib.crescent_city_bb_fab1(sch_1):\SPI_PCH_IO2\" )
				( objectStatus "SPI_BIOS_SOCKET_IO2" )
			)
			( electricalNet "@crescent_city_bb_fab1_lib.crescent_city_bb_fab1(sch_1):clk_100m_cpu1_mcp_dn"
				( signalRef "@baseboard_fab2_lib.baseboard_fab2(sch_1):clk_100m_cpu1_rc_refclk1_r_dn" )
				( signalRef "@baseboard_fab2_lib.baseboard_fab2(sch_1):clk_100m_cpu1_rc_refclk1_dn" )
				( electricalCSetRef "@crescent_city_bb_fab1_lib.crescent_city_bb_fab1(sch_1):\CLK_100M_CPU1_MCP_DN\" )
				( objectStatus "CLK_100M_CPU1_RC_REFCLK1_DN" )
			)
			( electricalNet "@crescent_city_bb_fab1_lib.crescent_city_bb_fab1(sch_1):clk_100m_cpu1_mcp_dp"
				( signalRef "@baseboard_fab2_lib.baseboard_fab2(sch_1):clk_100m_cpu1_rc_refclk1_dp" )
				( signalRef "@baseboard_fab2_lib.baseboard_fab2(sch_1):clk_100m_cpu1_rc_refclk1_r_dp" )
				( electricalCSetRef "@crescent_city_bb_fab1_lib.crescent_city_bb_fab1(sch_1):\CLK_100M_CPU1_MCP_DN\" )
				( objectStatus "CLK_100M_CPU1_RC_REFCLK1_DP" )
			)
			( electricalNet "@crescent_city_bb_fab1_lib.crescent_city_bb_fab1(sch_1):isense_tmp421_1_dxn"
				( signalRef "@baseboard_fab2_lib.baseboard_fab2(sch_1):isense_tmp421_1_dxn" )
				( signalRef "@baseboard_fab2_lib.baseboard_fab2(sch_1):isense_tmp421_1_bc" )
				( objectStatus "ISENSE_TMP421_1_DXN" )
			)
			( electricalNet "@crescent_city_bb_fab1_lib.crescent_city_bb_fab1(sch_1):isense_tmp421_1_dxp"
				( signalRef "@baseboard_fab2_lib.baseboard_fab2(sch_1):isense_tmp421_1_e" )
				( signalRef "@baseboard_fab2_lib.baseboard_fab2(sch_1):isense_tmp421_1_dxp" )
				( objectStatus "ISENSE_TMP421_1_DXP" )
			)
			( electricalNet "@crescent_city_bb_fab1_lib.crescent_city_bb_fab1(sch_1):isense_tmp421_2_dxn"
				( signalRef "@baseboard_fab2_lib.baseboard_fab2(sch_1):isense_tmp421_2_dxn" )
				( signalRef "@baseboard_fab2_lib.baseboard_fab2(sch_1):isense_tmp421_2_bc" )
				( objectStatus "ISENSE_TMP421_2_DXN" )
			)
			( electricalNet "@crescent_city_bb_fab1_lib.crescent_city_bb_fab1(sch_1):isense_tmp421_2_dxp"
				( signalRef "@baseboard_fab2_lib.baseboard_fab2(sch_1):isense_tmp421_2_e" )
				( signalRef "@baseboard_fab2_lib.baseboard_fab2(sch_1):isense_tmp421_2_dxp" )
				( objectStatus "ISENSE_TMP421_2_DXP" )
			)
			( electricalNet "@crescent_city_bb_fab1_lib.crescent_city_bb_fab1(sch_1):vsense_p3v3_stby"
				( signalRef "@baseboard_fab2_lib.baseboard_fab2(sch_1):vsense_vout_p3v3_stby" )
				( signalRef "@baseboard_fab2_lib.baseboard_fab2(sch_1):vsense_p3v3_stby" )
				( objectStatus "VSENSE_P3V3_STBY" )
			)
			( electricalNet "@baseboard_fab2_lib.baseboard_fab2(sch_1):kr_p0_ocp_rx_c_dp"
				( signalRef "@baseboard_fab2_lib.baseboard_fab2(sch_1):kr_p0_ocp_rx_c_dp" )
				( signalRef "@baseboard_fab2_lib.baseboard_fab2(sch_1):kr_p0_ocp_rx_dp" )
				( electricalCSetRef "@baseboard_fab2_lib.baseboard_fab2(sch_1):\DP_KR_P0_OCP_RX\" )
				( objectStatus "KR_P0_OCP_RX_C_DP" )
			)
			( electricalNet "@baseboard_fab2_lib.baseboard_fab2(sch_1):kr_p0_ocp_rx_c_dn"
				( signalRef "@baseboard_fab2_lib.baseboard_fab2(sch_1):kr_p0_ocp_rx_dn" )
				( signalRef "@baseboard_fab2_lib.baseboard_fab2(sch_1):kr_p0_ocp_rx_c_dn" )
				( electricalCSetRef "@baseboard_fab2_lib.baseboard_fab2(sch_1):\DP_KR_P0_OCP_RX\" )
				( objectStatus "KR_P0_OCP_RX_C_DN" )
			)
			( electricalNet "@baseboard_fab2_lib.baseboard_fab2(sch_1):kr_p1_ocp_rx_c_dp"
				( signalRef "@baseboard_fab2_lib.baseboard_fab2(sch_1):kr_p1_ocp_rx_c_dp" )
				( signalRef "@baseboard_fab2_lib.baseboard_fab2(sch_1):kr_p1_ocp_rx_dp" )
				( electricalCSetRef "@baseboard_fab2_lib.baseboard_fab2(sch_1):\DP_KR_P0_OCP_RX\" )
				( objectStatus "KR_P1_OCP_RX_C_DP" )
			)
			( electricalNet "@baseboard_fab2_lib.baseboard_fab2(sch_1):kr_p1_ocp_rx_c_dn"
				( signalRef "@baseboard_fab2_lib.baseboard_fab2(sch_1):kr_p1_ocp_rx_dn" )
				( signalRef "@baseboard_fab2_lib.baseboard_fab2(sch_1):kr_p1_ocp_rx_c_dn" )
				( electricalCSetRef "@baseboard_fab2_lib.baseboard_fab2(sch_1):\DP_KR_P0_OCP_RX\" )
				( objectStatus "KR_P1_OCP_RX_C_DN" )
			)
			( electricalNet "@baseboard_fab2_lib.baseboard_fab2(sch_1):kr_p2_ocp_rx_c_dp"
				( signalRef "@baseboard_fab2_lib.baseboard_fab2(sch_1):kr_p2_ocp_rx_c_dp" )
				( signalRef "@baseboard_fab2_lib.baseboard_fab2(sch_1):kr_p2_ocp_rx_dp" )
				( electricalCSetRef "@baseboard_fab2_lib.baseboard_fab2(sch_1):\DP_KR_P0_OCP_RX\" )
				( objectStatus "KR_P2_OCP_RX_C_DP" )
			)
			( electricalNet "@baseboard_fab2_lib.baseboard_fab2(sch_1):kr_p2_ocp_rx_c_dn"
				( signalRef "@baseboard_fab2_lib.baseboard_fab2(sch_1):kr_p2_ocp_rx_dn" )
				( signalRef "@baseboard_fab2_lib.baseboard_fab2(sch_1):kr_p2_ocp_rx_c_dn" )
				( electricalCSetRef "@baseboard_fab2_lib.baseboard_fab2(sch_1):\DP_KR_P0_OCP_RX\" )
				( objectStatus "KR_P2_OCP_RX_C_DN" )
			)
			( electricalNet "@baseboard_fab2_lib.baseboard_fab2(sch_1):kr_p3_ocp_rx_c_dp"
				( signalRef "@baseboard_fab2_lib.baseboard_fab2(sch_1):kr_p3_ocp_rx_c_dp" )
				( signalRef "@baseboard_fab2_lib.baseboard_fab2(sch_1):kr_p3_ocp_rx_dp" )
				( electricalCSetRef "@baseboard_fab2_lib.baseboard_fab2(sch_1):\DP_KR_P0_OCP_RX\" )
				( objectStatus "KR_P3_OCP_RX_C_DP" )
			)
			( electricalNet "@baseboard_fab2_lib.baseboard_fab2(sch_1):kr_p3_ocp_rx_c_dn"
				( signalRef "@baseboard_fab2_lib.baseboard_fab2(sch_1):kr_p3_ocp_rx_dn" )
				( signalRef "@baseboard_fab2_lib.baseboard_fab2(sch_1):kr_p3_ocp_rx_c_dn" )
				( electricalCSetRef "@baseboard_fab2_lib.baseboard_fab2(sch_1):\DP_KR_P0_OCP_RX\" )
				( objectStatus "KR_P3_OCP_RX_C_DN" )
			)
			( electricalNet "@crescent_city_bb_fab1_lib.crescent_city_bb_fab1(sch_1):vr_pvddq_abc_aiinsen"
				( signalRef "@baseboard_fab2_lib.baseboard_fab2(sch_1):vr_pvddq_abc_aiinsen_r" )
				( signalRef "@baseboard_fab2_lib.baseboard_fab2(sch_1):vr_pvddq_abc_aiinsen" )
				( objectStatus "VR_PVDDQ_ABC_AIINSEN" )
			)
			( electricalNet "@crescent_city_bb_fab1_lib.crescent_city_bb_fab1(sch_1):vr_pvddq_abc_ph1_boot"
				( signalRef "@baseboard_fab2_lib.baseboard_fab2(sch_1):vr_pvddq_abc_ph1_phase" )
				( signalRef "@baseboard_fab2_lib.baseboard_fab2(sch_1):vr_pvddq_abc_ph1_boot" )
				( objectStatus "VR_PVDDQ_ABC_PH1_BOOT" )
			)
			( electricalNet "@crescent_city_bb_fab1_lib.crescent_city_bb_fab1(sch_1):vr_pvddq_abc_ph2_boot"
				( signalRef "@baseboard_fab2_lib.baseboard_fab2(sch_1):vr_pvddq_abc_ph2_phase" )
				( signalRef "@baseboard_fab2_lib.baseboard_fab2(sch_1):vr_pvddq_abc_ph2_boot" )
				( objectStatus "VR_PVDDQ_ABC_PH2_BOOT" )
			)
			( electricalNet "@crescent_city_bb_fab1_lib.crescent_city_bb_fab1(sch_1):vr_pvddq_def_aiinsen"
				( signalRef "@baseboard_fab2_lib.baseboard_fab2(sch_1):vr_pvddq_def_aiinsen_r" )
				( signalRef "@baseboard_fab2_lib.baseboard_fab2(sch_1):vr_pvddq_def_aiinsen" )
				( objectStatus "VR_PVDDQ_DEF_AIINSEN" )
			)
			( electricalNet "@crescent_city_bb_fab1_lib.crescent_city_bb_fab1(sch_1):vr_pvddq_def_ph1_boot"
				( signalRef "@baseboard_fab2_lib.baseboard_fab2(sch_1):vr_pvddq_def_ph1_phase" )
				( signalRef "@baseboard_fab2_lib.baseboard_fab2(sch_1):vr_pvddq_def_ph1_boot" )
				( objectStatus "VR_PVDDQ_DEF_PH1_BOOT" )
			)
			( electricalNet "@crescent_city_bb_fab1_lib.crescent_city_bb_fab1(sch_1):vr_pvddq_def_ph2_boot"
				( signalRef "@baseboard_fab2_lib.baseboard_fab2(sch_1):vr_pvddq_def_ph2_phase" )
				( signalRef "@baseboard_fab2_lib.baseboard_fab2(sch_1):vr_pvddq_def_ph2_boot" )
				( objectStatus "VR_PVDDQ_DEF_PH2_BOOT" )
			)
			( electricalNet "@crescent_city_bb_fab1_lib.crescent_city_bb_fab1(sch_1):vr_pvddq_ghj_aiinsen"
				( signalRef "@baseboard_fab2_lib.baseboard_fab2(sch_1):vr_pvddq_ghj_aiinsen_r" )
				( signalRef "@baseboard_fab2_lib.baseboard_fab2(sch_1):vr_pvddq_ghj_aiinsen" )
				( objectStatus "VR_PVDDQ_GHJ_AIINSEN" )
			)
			( electricalNet "@crescent_city_bb_fab1_lib.crescent_city_bb_fab1(sch_1):vr_pvddq_ghj_ph1_boot"
				( signalRef "@baseboard_fab2_lib.baseboard_fab2(sch_1):vr_pvddq_ghj_ph1_phase" )
				( signalRef "@baseboard_fab2_lib.baseboard_fab2(sch_1):vr_pvddq_ghj_ph1_boot" )
				( objectStatus "VR_PVDDQ_GHJ_PH1_BOOT" )
			)
			( electricalNet "@crescent_city_bb_fab1_lib.crescent_city_bb_fab1(sch_1):vr_pvddq_ghj_ph2_boot"
				( signalRef "@baseboard_fab2_lib.baseboard_fab2(sch_1):vr_pvddq_ghj_ph2_phase" )
				( signalRef "@baseboard_fab2_lib.baseboard_fab2(sch_1):vr_pvddq_ghj_ph2_boot" )
				( objectStatus "VR_PVDDQ_GHJ_PH2_BOOT" )
			)
			( electricalNet "@crescent_city_bb_fab1_lib.crescent_city_bb_fab1(sch_1):vr_pvddq_klm_aiinsen"
				( signalRef "@baseboard_fab2_lib.baseboard_fab2(sch_1):vr_pvddq_klm_aiinsen_r" )
				( signalRef "@baseboard_fab2_lib.baseboard_fab2(sch_1):vr_pvddq_klm_aiinsen" )
				( objectStatus "VR_PVDDQ_KLM_AIINSEN" )
			)
			( electricalNet "@crescent_city_bb_fab1_lib.crescent_city_bb_fab1(sch_1):vr_pvddq_klm_ph1_boot"
				( signalRef "@baseboard_fab2_lib.baseboard_fab2(sch_1):vr_pvddq_klm_ph1_phase" )
				( signalRef "@baseboard_fab2_lib.baseboard_fab2(sch_1):vr_pvddq_klm_ph1_boot" )
				( objectStatus "VR_PVDDQ_KLM_PH1_BOOT" )
			)
			( electricalNet "@crescent_city_bb_fab1_lib.crescent_city_bb_fab1(sch_1):vr_pvddq_klm_ph2_boot"
				( signalRef "@baseboard_fab2_lib.baseboard_fab2(sch_1):vr_pvddq_klm_ph2_phase" )
				( signalRef "@baseboard_fab2_lib.baseboard_fab2(sch_1):vr_pvddq_klm_ph2_boot" )
				( objectStatus "VR_PVDDQ_KLM_PH2_BOOT" )
			)
			( electricalNet "@crescent_city_bb_fab1_lib.crescent_city_bb_fab1(sch_1):clk_100m_bmc_pe_r_dn"
				( signalRef "@baseboard_fab2_lib.baseboard_fab2(sch_1):clk_100m_bmc_pe_dn" )
				( signalRef "@baseboard_fab2_lib.baseboard_fab2(sch_1):clk_100m_bmc_pe_r_dn" )
				( objectStatus "CLK_100M_BMC_PE_R_DN" )
			)
			( electricalNet "@crescent_city_bb_fab1_lib.crescent_city_bb_fab1(sch_1):clk_100m_bmc_pe_r_dp"
				( signalRef "@baseboard_fab2_lib.baseboard_fab2(sch_1):clk_100m_bmc_pe_r_dp" )
				( signalRef "@baseboard_fab2_lib.baseboard_fab2(sch_1):clk_100m_bmc_pe_dp" )
				( objectStatus "CLK_100M_BMC_PE_R_DP" )
			)
			( electricalNet "@crescent_city_bb_fab1_lib.crescent_city_bb_fab1(sch_1):clk_100m_cpu0_bclk0_dn"
				( signalRef "@baseboard_fab2_lib.baseboard_fab2(sch_1):clk_100m_cpu0_bclk0_r_dn" )
				( signalRef "@baseboard_fab2_lib.baseboard_fab2(sch_1):clk_100m_cpu0_bclk0_dn" )
				( electricalCSetRef "@crescent_city_bb_fab1_lib.crescent_city_bb_fab1(sch_1):\BCLK\" )
				( pinPairRef "@baseboard_fab2_lib.baseboard_fab2(sch_1):\PP6070\" )
				( objectStatus "CLK_100M_CPU0_BCLK0_DN" )
			)
			( electricalNet "@crescent_city_bb_fab1_lib.crescent_city_bb_fab1(sch_1):clk_100m_cpu0_bclk0_dp"
				( signalRef "@baseboard_fab2_lib.baseboard_fab2(sch_1):clk_100m_cpu0_bclk0_r_dp" )
				( signalRef "@baseboard_fab2_lib.baseboard_fab2(sch_1):clk_100m_cpu0_bclk0_dp" )
				( electricalCSetRef "@crescent_city_bb_fab1_lib.crescent_city_bb_fab1(sch_1):\BCLK\" )
				( pinPairRef "@baseboard_fab2_lib.baseboard_fab2(sch_1):\PP6069\" )
				( objectStatus "CLK_100M_CPU0_BCLK0_DP" )
			)
			( electricalNet "@crescent_city_bb_fab1_lib.crescent_city_bb_fab1(sch_1):clk_100m_cpu0_bclk1_dn"
				( signalRef "@baseboard_fab2_lib.baseboard_fab2(sch_1):clk_100m_cpu0_bclk1_r_dn" )
				( signalRef "@baseboard_fab2_lib.baseboard_fab2(sch_1):clk_100m_cpu0_bclk1_dn" )
				( electricalCSetRef "@crescent_city_bb_fab1_lib.crescent_city_bb_fab1(sch_1):\BCLK\" )
				( pinPairRef "@baseboard_fab2_lib.baseboard_fab2(sch_1):\PP6068\" )
				( objectStatus "CLK_100M_CPU0_BCLK1_DN" )
			)
			( electricalNet "@crescent_city_bb_fab1_lib.crescent_city_bb_fab1(sch_1):clk_100m_cpu0_bclk1_dp"
				( signalRef "@baseboard_fab2_lib.baseboard_fab2(sch_1):clk_100m_cpu0_bclk1_r_dp" )
				( signalRef "@baseboard_fab2_lib.baseboard_fab2(sch_1):clk_100m_cpu0_bclk1_dp" )
				( electricalCSetRef "@crescent_city_bb_fab1_lib.crescent_city_bb_fab1(sch_1):\BCLK\" )
				( pinPairRef "@baseboard_fab2_lib.baseboard_fab2(sch_1):\PP6063\" )
				( objectStatus "CLK_100M_CPU0_BCLK1_DP" )
			)
			( electricalNet "@crescent_city_bb_fab1_lib.crescent_city_bb_fab1(sch_1):clk_100m_cpu0_bclk2_dn"
				( signalRef "@baseboard_fab2_lib.baseboard_fab2(sch_1):clk_100m_cpu0_bclk2_r_dn" )
				( signalRef "@baseboard_fab2_lib.baseboard_fab2(sch_1):clk_100m_cpu0_bclk2_dn" )
				( electricalCSetRef "@crescent_city_bb_fab1_lib.crescent_city_bb_fab1(sch_1):\BCLK\" )
				( pinPairRef "@baseboard_fab2_lib.baseboard_fab2(sch_1):\PP6057\" )
				( objectStatus "CLK_100M_CPU0_BCLK2_DN" )
			)
			( electricalNet "@crescent_city_bb_fab1_lib.crescent_city_bb_fab1(sch_1):clk_100m_cpu0_bclk2_dp"
				( signalRef "@baseboard_fab2_lib.baseboard_fab2(sch_1):clk_100m_cpu0_bclk2_r_dp" )
				( signalRef "@baseboard_fab2_lib.baseboard_fab2(sch_1):clk_100m_cpu0_bclk2_dp" )
				( electricalCSetRef "@crescent_city_bb_fab1_lib.crescent_city_bb_fab1(sch_1):\BCLK\" )
				( pinPairRef "@baseboard_fab2_lib.baseboard_fab2(sch_1):\PP6062\" )
				( objectStatus "CLK_100M_CPU0_BCLK2_DP" )
			)
			( electricalNet "@crescent_city_bb_fab1_lib.crescent_city_bb_fab1(sch_1):clk_100m_cpu0_rc_refclk_dn"
				( signalRef "@baseboard_fab2_lib.baseboard_fab2(sch_1):clk_100m_cpu0_rc_refclk0_r_dn" )
				( signalRef "@baseboard_fab2_lib.baseboard_fab2(sch_1):clk_100m_cpu0_rc_refclk0_dn" )
				( electricalCSetRef "@crescent_city_bb_fab1_lib.crescent_city_bb_fab1(sch_1):\CLK_100M_CPU0_MCP_DN\" )
				( pinPairRef "@baseboard_fab2_lib.baseboard_fab2(sch_1):\PP6053\" )
				( objectStatus "CLK_100M_CPU0_RC_REFCLK0_DN" )
			)
			( electricalNet "@crescent_city_bb_fab1_lib.crescent_city_bb_fab1(sch_1):clk_100m_cpu0_rc_refclk_dp"
				( signalRef "@baseboard_fab2_lib.baseboard_fab2(sch_1):clk_100m_cpu0_rc_refclk0_dp" )
				( signalRef "@baseboard_fab2_lib.baseboard_fab2(sch_1):clk_100m_cpu0_rc_refclk0_r_dp" )
				( electricalCSetRef "@crescent_city_bb_fab1_lib.crescent_city_bb_fab1(sch_1):\CLK_100M_CPU0_MCP_DN\" )
				( pinPairRef "@baseboard_fab2_lib.baseboard_fab2(sch_1):\PP6052\" )
				( objectStatus "CLK_100M_CPU0_RC_REFCLK0_DP" )
			)
			( electricalNet "@crescent_city_bb_fab1_lib.crescent_city_bb_fab1(sch_1):clk_100m_cpu0_mcp_dn"
				( signalRef "@baseboard_fab2_lib.baseboard_fab2(sch_1):clk_100m_cpu0_rc_refclk1_r_dn" )
				( signalRef "@baseboard_fab2_lib.baseboard_fab2(sch_1):clk_100m_cpu0_rc_refclk1_dn" )
				( electricalCSetRef "@crescent_city_bb_fab1_lib.crescent_city_bb_fab1(sch_1):\CLK_100M_CPU0_MCP_DN\" )
				( pinPairRef "@baseboard_fab2_lib.baseboard_fab2(sch_1):\PP6044\" )
				( objectStatus "CLK_100M_CPU0_RC_REFCLK1_DN" )
			)
			( electricalNet "@crescent_city_bb_fab1_lib.crescent_city_bb_fab1(sch_1):clk_100m_cpu0_mcp_dp"
				( signalRef "@baseboard_fab2_lib.baseboard_fab2(sch_1):clk_100m_cpu0_rc_refclk1_dp" )
				( signalRef "@baseboard_fab2_lib.baseboard_fab2(sch_1):clk_100m_cpu0_rc_refclk1_r_dp" )
				( electricalCSetRef "@crescent_city_bb_fab1_lib.crescent_city_bb_fab1(sch_1):\CLK_100M_CPU0_MCP_DN\" )
				( pinPairRef "@baseboard_fab2_lib.baseboard_fab2(sch_1):\PP6054\" )
				( objectStatus "CLK_100M_CPU0_RC_REFCLK1_DP" )
			)
			( electricalNet "@crescent_city_bb_fab1_lib.crescent_city_bb_fab1(sch_1):clk_100m_cpu0_pe_refclk_dn"
				( signalRef "@baseboard_fab2_lib.baseboard_fab2(sch_1):clk_100m_cpu0_pe_refclk_r_dn" )
				( signalRef "@baseboard_fab2_lib.baseboard_fab2(sch_1):clk_100m_cpu0_pe_refclk_dn" )
				( electricalCSetRef "@crescent_city_bb_fab1_lib.crescent_city_bb_fab1(sch_1):\CLK_100M_CPU0_MCP_DN\" )
				( pinPairRef "@baseboard_fab2_lib.baseboard_fab2(sch_1):\PP6056\" )
				( objectStatus "CLK_100M_CPU0_PE_REFCLK_DN" )
			)
			( electricalNet "@crescent_city_bb_fab1_lib.crescent_city_bb_fab1(sch_1):clk_100m_cpu0_pe_refclk_dp"
				( signalRef "@baseboard_fab2_lib.baseboard_fab2(sch_1):clk_100m_cpu0_pe_refclk_dp" )
				( signalRef "@baseboard_fab2_lib.baseboard_fab2(sch_1):clk_100m_cpu0_pe_refclk_r_dp" )
				( electricalCSetRef "@crescent_city_bb_fab1_lib.crescent_city_bb_fab1(sch_1):\CLK_100M_CPU0_MCP_DN\" )
				( pinPairRef "@baseboard_fab2_lib.baseboard_fab2(sch_1):\PP6055\" )
				( objectStatus "CLK_100M_CPU0_PE_REFCLK_DP" )
			)
			( electricalNet "@crescent_city_bb_fab1_lib.crescent_city_bb_fab1(sch_1):clk_100m_cpu1_bclk0_dn"
				( signalRef "@baseboard_fab2_lib.baseboard_fab2(sch_1):clk_100m_cpu1_bclk0_r_dn" )
				( signalRef "@baseboard_fab2_lib.baseboard_fab2(sch_1):clk_100m_cpu1_bclk0_dn" )
				( electricalCSetRef "@crescent_city_bb_fab1_lib.crescent_city_bb_fab1(sch_1):\BCLK\" )
				( pinPairRef "@baseboard_fab2_lib.baseboard_fab2(sch_1):\PP6061\" )
				( objectStatus "CLK_100M_CPU1_BCLK0_DN" )
			)
			( electricalNet "@crescent_city_bb_fab1_lib.crescent_city_bb_fab1(sch_1):clk_100m_cpu1_bclk0_dp"
				( signalRef "@baseboard_fab2_lib.baseboard_fab2(sch_1):clk_100m_cpu1_bclk0_r_dp" )
				( signalRef "@baseboard_fab2_lib.baseboard_fab2(sch_1):clk_100m_cpu1_bclk0_dp" )
				( electricalCSetRef "@crescent_city_bb_fab1_lib.crescent_city_bb_fab1(sch_1):\BCLK\" )
				( pinPairRef "@baseboard_fab2_lib.baseboard_fab2(sch_1):\PP6060\" )
				( objectStatus "CLK_100M_CPU1_BCLK0_DP" )
			)
			( electricalNet "@crescent_city_bb_fab1_lib.crescent_city_bb_fab1(sch_1):clk_100m_cpu1_bclk1_dn"
				( signalRef "@baseboard_fab2_lib.baseboard_fab2(sch_1):clk_100m_cpu1_bclk1_r_dn" )
				( signalRef "@baseboard_fab2_lib.baseboard_fab2(sch_1):clk_100m_cpu1_bclk1_dn" )
				( electricalCSetRef "@crescent_city_bb_fab1_lib.crescent_city_bb_fab1(sch_1):\BCLK\" )
				( pinPairRef "@baseboard_fab2_lib.baseboard_fab2(sch_1):\PP6059\" )
				( objectStatus "CLK_100M_CPU1_BCLK1_DN" )
			)
			( electricalNet "@crescent_city_bb_fab1_lib.crescent_city_bb_fab1(sch_1):clk_100m_cpu1_bclk1_dp"
				( signalRef "@baseboard_fab2_lib.baseboard_fab2(sch_1):clk_100m_cpu1_bclk1_r_dp" )
				( signalRef "@baseboard_fab2_lib.baseboard_fab2(sch_1):clk_100m_cpu1_bclk1_dp" )
				( electricalCSetRef "@crescent_city_bb_fab1_lib.crescent_city_bb_fab1(sch_1):\BCLK\" )
				( pinPairRef "@baseboard_fab2_lib.baseboard_fab2(sch_1):\PP6058\" )
				( objectStatus "CLK_100M_CPU1_BCLK1_DP" )
			)
			( electricalNet "@crescent_city_bb_fab1_lib.crescent_city_bb_fab1(sch_1):clk_100m_cpu1_bclk2_dn"
				( signalRef "@baseboard_fab2_lib.baseboard_fab2(sch_1):clk_100m_cpu1_bclk2_r_dn" )
				( signalRef "@baseboard_fab2_lib.baseboard_fab2(sch_1):clk_100m_cpu1_bclk2_dn" )
				( electricalCSetRef "@crescent_city_bb_fab1_lib.crescent_city_bb_fab1(sch_1):\BCLK\" )
				( pinPairRef "@baseboard_fab2_lib.baseboard_fab2(sch_1):\PP6010\" )
				( objectStatus "CLK_100M_CPU1_BCLK2_DN" )
			)
			( electricalNet "@crescent_city_bb_fab1_lib.crescent_city_bb_fab1(sch_1):clk_100m_cpu1_bclk2_dp"
				( signalRef "@baseboard_fab2_lib.baseboard_fab2(sch_1):clk_100m_cpu1_bclk2_r_dp" )
				( signalRef "@baseboard_fab2_lib.baseboard_fab2(sch_1):clk_100m_cpu1_bclk2_dp" )
				( electricalCSetRef "@crescent_city_bb_fab1_lib.crescent_city_bb_fab1(sch_1):\BCLK\" )
				( pinPairRef "@baseboard_fab2_lib.baseboard_fab2(sch_1):\PP6009\" )
				( objectStatus "CLK_100M_CPU1_BCLK2_DP" )
			)
			( electricalNet "@crescent_city_bb_fab1_lib.crescent_city_bb_fab1(sch_1):clk_100m_cpu1_rc_refclk_dn"
				( signalRef "@baseboard_fab2_lib.baseboard_fab2(sch_1):clk_100m_cpu1_rc_refclk0_r_dn" )
				( signalRef "@baseboard_fab2_lib.baseboard_fab2(sch_1):clk_100m_cpu1_rc_refclk0_dn" )
				( electricalCSetRef "@crescent_city_bb_fab1_lib.crescent_city_bb_fab1(sch_1):\CLK_100M_CPU0_MCP_DN\" )
				( pinPairRef "@baseboard_fab2_lib.baseboard_fab2(sch_1):\PP6048\" )
				( objectStatus "CLK_100M_CPU1_RC_REFCLK0_DN" )
			)
			( electricalNet "@crescent_city_bb_fab1_lib.crescent_city_bb_fab1(sch_1):clk_100m_cpu1_rc_refclk_dp"
				( signalRef "@baseboard_fab2_lib.baseboard_fab2(sch_1):clk_100m_cpu1_rc_refclk0_dp" )
				( signalRef "@baseboard_fab2_lib.baseboard_fab2(sch_1):clk_100m_cpu1_rc_refclk0_r_dp" )
				( electricalCSetRef "@crescent_city_bb_fab1_lib.crescent_city_bb_fab1(sch_1):\CLK_100M_CPU0_MCP_DN\" )
				( pinPairRef "@baseboard_fab2_lib.baseboard_fab2(sch_1):\PP6045\" )
				( objectStatus "CLK_100M_CPU1_RC_REFCLK0_DP" )
			)
			( electricalNet "@crescent_city_bb_fab1_lib.crescent_city_bb_fab1(sch_1):clk_100m_cpu1_pe_refclk_dn"
				( signalRef "@baseboard_fab2_lib.baseboard_fab2(sch_1):clk_100m_cpu1_pe_refclk_r_dn" )
				( signalRef "@baseboard_fab2_lib.baseboard_fab2(sch_1):clk_100m_cpu1_pe_refclk_dn" )
				( electricalCSetRef "@crescent_city_bb_fab1_lib.crescent_city_bb_fab1(sch_1):\CLK_100M_CPU0_MCP_DN\" )
				( pinPairRef "@baseboard_fab2_lib.baseboard_fab2(sch_1):\PP6051\" )
				( objectStatus "CLK_100M_CPU1_PE_REFCLK_DN" )
			)
			( electricalNet "@crescent_city_bb_fab1_lib.crescent_city_bb_fab1(sch_1):clk_100m_cpu1_pe_refclk_dp"
				( signalRef "@baseboard_fab2_lib.baseboard_fab2(sch_1):clk_100m_cpu1_pe_refclk_dp" )
				( signalRef "@baseboard_fab2_lib.baseboard_fab2(sch_1):clk_100m_cpu1_pe_refclk_r_dp" )
				( electricalCSetRef "@crescent_city_bb_fab1_lib.crescent_city_bb_fab1(sch_1):\CLK_100M_CPU0_MCP_DN\" )
				( pinPairRef "@baseboard_fab2_lib.baseboard_fab2(sch_1):\PP6050\" )
				( objectStatus "CLK_100M_CPU1_PE_REFCLK_DP" )
			)
			( electricalNet "@crescent_city_bb_fab1_lib.crescent_city_bb_fab1(sch_1):vr_comp_pvpp_abc"
				( signalRef "@baseboard_fab2_lib.baseboard_fab2(sch_1):vr_comp_pvpp_abc_3" )
				( signalRef "@baseboard_fab2_lib.baseboard_fab2(sch_1):vr_fb_pvpp_abc" )
				( signalRef "@baseboard_fab2_lib.baseboard_fab2(sch_1):vr_comp_rc_pvpp_abc" )
				( signalRef "@baseboard_fab2_lib.baseboard_fab2(sch_1):vsense_pvpp_abc" )
				( signalRef "@baseboard_fab2_lib.baseboard_fab2(sch_1):vr_comp_pvpp_abc" )
				( objectStatus "VR_COMP_PVPP_ABC" )
			)
			( electricalNet "@crescent_city_bb_fab1_lib.crescent_city_bb_fab1(sch_1):vr_comp_pvpp_def"
				( signalRef "@baseboard_fab2_lib.baseboard_fab2(sch_1):vr_comp_pvpp_def_3" )
				( signalRef "@baseboard_fab2_lib.baseboard_fab2(sch_1):vr_comp_rc_pvpp_def" )
				( signalRef "@baseboard_fab2_lib.baseboard_fab2(sch_1):vr_fb_pvpp_def" )
				( signalRef "@baseboard_fab2_lib.baseboard_fab2(sch_1):vsense_pvpp_def" )
				( signalRef "@baseboard_fab2_lib.baseboard_fab2(sch_1):vr_comp_pvpp_def" )
				( objectStatus "VR_COMP_PVPP_DEF" )
			)
			( electricalNet "@crescent_city_bb_fab1_lib.crescent_city_bb_fab1(sch_1):vr_comp_pvpp_ghj"
				( signalRef "@baseboard_fab2_lib.baseboard_fab2(sch_1):vr_comp_pvpp_ghj_3" )
				( signalRef "@baseboard_fab2_lib.baseboard_fab2(sch_1):vr_comp_rc_pvpp_ghj" )
				( signalRef "@baseboard_fab2_lib.baseboard_fab2(sch_1):vr_fb_pvpp_ghj" )
				( signalRef "@baseboard_fab2_lib.baseboard_fab2(sch_1):vsense_pvpp_ghj" )
				( signalRef "@baseboard_fab2_lib.baseboard_fab2(sch_1):vr_comp_pvpp_ghj" )
				( objectStatus "VR_COMP_PVPP_GHJ" )
			)
			( electricalNet "@crescent_city_bb_fab1_lib.crescent_city_bb_fab1(sch_1):vr_comp_pvpp_klm"
				( signalRef "@baseboard_fab2_lib.baseboard_fab2(sch_1):vr_comp_pvpp_klm_3" )
				( signalRef "@baseboard_fab2_lib.baseboard_fab2(sch_1):vr_fb_pvpp_klm" )
				( signalRef "@baseboard_fab2_lib.baseboard_fab2(sch_1):vr_comp_rc_pvpp_klm" )
				( signalRef "@baseboard_fab2_lib.baseboard_fab2(sch_1):vr_comp_pvpp_klm" )
				( signalRef "@baseboard_fab2_lib.baseboard_fab2(sch_1):vsense_pvpp_klm" )
				( objectStatus "VR_COMP_PVPP_KLM" )
			)
			( electricalNet "@crescent_city_bb_fab1_lib.crescent_city_bb_fab1(sch_1):rmii_sprngvlle_bmc_pch_rxd0"
				( signalRef "@baseboard_fab2_lib.baseboard_fab2(sch_1):rmii_sprngvlle_bmc_pch_rxd0_r1" )
				( signalRef "@baseboard_fab2_lib.baseboard_fab2(sch_1):rmii_sprngvlle_bmc_pch_rxd0" )
				( signalRef "@baseboard_fab2_lib.baseboard_fab2(sch_1):rmii_sprngvlle_bmc_pch_rxd0_r" )
				( electricalCSetRef "@crescent_city_bb_fab1_lib.crescent_city_bb_fab1(sch_1):\RMII_RX_NEW\" )
				( pinPairRef "@baseboard_fab2_lib.baseboard_fab2(sch_1):\PP6095\" )
				( objectStatus "RMII_SPRNGVLLE_BMC_PCH_RXD0" )
			)
			( electricalNet "@crescent_city_bb_fab1_lib.crescent_city_bb_fab1(sch_1):rmii_sprngvlle_bmc_pch_rxd1"
				( signalRef "@baseboard_fab2_lib.baseboard_fab2(sch_1):rmii_sprngvlle_bmc_pch_rxd1_r1" )
				( signalRef "@baseboard_fab2_lib.baseboard_fab2(sch_1):rmii_sprngvlle_bmc_pch_rxd1" )
				( signalRef "@baseboard_fab2_lib.baseboard_fab2(sch_1):rmii_sprngvlle_bmc_pch_rxd1_r" )
				( electricalCSetRef "@crescent_city_bb_fab1_lib.crescent_city_bb_fab1(sch_1):\RMII_RX_NEW\" )
				( pinPairRef "@baseboard_fab2_lib.baseboard_fab2(sch_1):\PP6086\" )
				( objectStatus "RMII_SPRNGVLLE_BMC_PCH_RXD1" )
			)
			( electricalNet "@crescent_city_bb_fab1_lib.crescent_city_bb_fab1(sch_1):rmii_bmc_ocp_txd0"
				( signalRef "@baseboard_fab2_lib.baseboard_fab2(sch_1):rmii_bmc_ocp_txd0_r" )
				( signalRef "@baseboard_fab2_lib.baseboard_fab2(sch_1):rmii_bmc_ocp_txd0" )
				( objectStatus "RMII_BMC_OCP_TXD0" )
			)
			( electricalNet "@crescent_city_bb_fab1_lib.crescent_city_bb_fab1(sch_1):rmii_bmc_ocp_txd1"
				( signalRef "@baseboard_fab2_lib.baseboard_fab2(sch_1):rmii_bmc_ocp_txd1_r" )
				( signalRef "@baseboard_fab2_lib.baseboard_fab2(sch_1):rmii_bmc_ocp_txd1" )
				( objectStatus "RMII_BMC_OCP_TXD1" )
			)
			( electricalNet "@crescent_city_bb_fab1_lib.crescent_city_bb_fab1(sch_1):rmii_bmc_ocp_txen"
				( signalRef "@baseboard_fab2_lib.baseboard_fab2(sch_1):rmii_bmc_ocp_txen_r" )
				( signalRef "@baseboard_fab2_lib.baseboard_fab2(sch_1):rmii_bmc_ocp_txen" )
				( objectStatus "RMII_BMC_OCP_TXEN" )
			)
			( electricalNet "@crescent_city_bb_fab1_lib.crescent_city_bb_fab1(sch_1):rmii_bmc_pch_sprngvlle_txd0"
				( signalRef "@baseboard_fab2_lib.baseboard_fab2(sch_1):rmii_bmc_pch_sprngvlle_txd0" )
				( signalRef "@baseboard_fab2_lib.baseboard_fab2(sch_1):rmii_bmc_pch_sprngvlle_txd0_r" )
				( electricalCSetRef "@crescent_city_bb_fab1_lib.crescent_city_bb_fab1(sch_1):\RMII_TX_NEW\" )
				( pinPairRef "@baseboard_fab2_lib.baseboard_fab2(sch_1):\PP6100\" )
				( objectStatus "RMII_BMC_PCH_SPRNGVLLE_TXD0" )
			)
			( electricalNet "@crescent_city_bb_fab1_lib.crescent_city_bb_fab1(sch_1):rmii_bmc_pch_sprngvlle_txd1"
				( signalRef "@baseboard_fab2_lib.baseboard_fab2(sch_1):rmii_bmc_pch_sprngvlle_txd1" )
				( signalRef "@baseboard_fab2_lib.baseboard_fab2(sch_1):rmii_bmc_pch_sprngvlle_txd1_r" )
				( electricalCSetRef "@crescent_city_bb_fab1_lib.crescent_city_bb_fab1(sch_1):\RMII_TX_NEW\" )
				( pinPairRef "@baseboard_fab2_lib.baseboard_fab2(sch_1):\PP6102\" )
				( objectStatus "RMII_BMC_PCH_SPRNGVLLE_TXD1" )
			)
			( electricalNet "@crescent_city_bb_fab1_lib.crescent_city_bb_fab1(sch_1):rmii_bmc_pch_sprngvlle_txen"
				( signalRef "@baseboard_fab2_lib.baseboard_fab2(sch_1):rmii_bmc_pch_sprngvlle_txen" )
				( signalRef "@baseboard_fab2_lib.baseboard_fab2(sch_1):rmii_bmc_sprngvlle_txen_r" )
				( electricalCSetRef "@crescent_city_bb_fab1_lib.crescent_city_bb_fab1(sch_1):\RMII_TX_1\" )
				( pinPairRef "@baseboard_fab2_lib.baseboard_fab2(sch_1):\PP6101\" )
				( objectStatus "RMII_BMC_PCH_SPRNGVLLE_TXEN" )
			)
			( electricalNet "@crescent_city_bb_fab1_lib.crescent_city_bb_fab1(sch_1):m_a_cpu_vref"
				( signalRef "@baseboard_fab2_lib.baseboard_fab2(sch_1):m_a_vref" )
				( signalRef "@baseboard_fab2_lib.baseboard_fab2(sch_1):m_a_cpu_vref" )
				( objectStatus "M_A_CPU_VREF" )
			)
			( electricalNet "@crescent_city_bb_fab1_lib.crescent_city_bb_fab1(sch_1):m_b_cpu_vref"
				( signalRef "@baseboard_fab2_lib.baseboard_fab2(sch_1):m_b_vref" )
				( signalRef "@baseboard_fab2_lib.baseboard_fab2(sch_1):m_b_cpu_vref" )
				( objectStatus "M_B_CPU_VREF" )
			)
			( electricalNet "@crescent_city_bb_fab1_lib.crescent_city_bb_fab1(sch_1):m_c_cpu_vref"
				( signalRef "@baseboard_fab2_lib.baseboard_fab2(sch_1):m_c_vref" )
				( signalRef "@baseboard_fab2_lib.baseboard_fab2(sch_1):m_c_cpu_vref" )
				( objectStatus "M_C_CPU_VREF" )
			)
			( electricalNet "@crescent_city_bb_fab1_lib.crescent_city_bb_fab1(sch_1):m_d_cpu_vref"
				( signalRef "@baseboard_fab2_lib.baseboard_fab2(sch_1):m_d_vref" )
				( signalRef "@baseboard_fab2_lib.baseboard_fab2(sch_1):m_d_cpu_vref" )
				( objectStatus "M_D_CPU_VREF" )
			)
			( electricalNet "@crescent_city_bb_fab1_lib.crescent_city_bb_fab1(sch_1):m_e_cpu_vref"
				( signalRef "@baseboard_fab2_lib.baseboard_fab2(sch_1):m_e_vref" )
				( signalRef "@baseboard_fab2_lib.baseboard_fab2(sch_1):m_e_cpu_vref" )
				( objectStatus "M_E_CPU_VREF" )
			)
			( electricalNet "@crescent_city_bb_fab1_lib.crescent_city_bb_fab1(sch_1):m_f_cpu_vref"
				( signalRef "@baseboard_fab2_lib.baseboard_fab2(sch_1):m_f_vref" )
				( signalRef "@baseboard_fab2_lib.baseboard_fab2(sch_1):m_f_cpu_vref" )
				( objectStatus "M_F_CPU_VREF" )
			)
			( electricalNet "@crescent_city_bb_fab1_lib.crescent_city_bb_fab1(sch_1):m_g_cpu_vref"
				( signalRef "@baseboard_fab2_lib.baseboard_fab2(sch_1):m_g_vref" )
				( signalRef "@baseboard_fab2_lib.baseboard_fab2(sch_1):m_g_cpu_vref" )
				( objectStatus "M_G_CPU_VREF" )
			)
			( electricalNet "@crescent_city_bb_fab1_lib.crescent_city_bb_fab1(sch_1):m_h_cpu_vref"
				( signalRef "@baseboard_fab2_lib.baseboard_fab2(sch_1):m_h_vref" )
				( signalRef "@baseboard_fab2_lib.baseboard_fab2(sch_1):m_h_cpu_vref" )
				( objectStatus "M_H_CPU_VREF" )
			)
			( electricalNet "@crescent_city_bb_fab1_lib.crescent_city_bb_fab1(sch_1):m_j_cpu_vref"
				( signalRef "@baseboard_fab2_lib.baseboard_fab2(sch_1):m_j_vref" )
				( signalRef "@baseboard_fab2_lib.baseboard_fab2(sch_1):m_j_cpu_vref" )
				( objectStatus "M_J_CPU_VREF" )
			)
			( electricalNet "@crescent_city_bb_fab1_lib.crescent_city_bb_fab1(sch_1):m_k_cpu_vref"
				( signalRef "@baseboard_fab2_lib.baseboard_fab2(sch_1):m_k_vref" )
				( signalRef "@baseboard_fab2_lib.baseboard_fab2(sch_1):m_k_cpu_vref" )
				( objectStatus "M_K_CPU_VREF" )
			)
			( electricalNet "@crescent_city_bb_fab1_lib.crescent_city_bb_fab1(sch_1):m_l_cpu_vref"
				( signalRef "@baseboard_fab2_lib.baseboard_fab2(sch_1):m_l_vref" )
				( signalRef "@baseboard_fab2_lib.baseboard_fab2(sch_1):m_l_cpu_vref" )
				( objectStatus "M_L_CPU_VREF" )
			)
			( electricalNet "@crescent_city_bb_fab1_lib.crescent_city_bb_fab1(sch_1):m_m_cpu_vref"
				( signalRef "@baseboard_fab2_lib.baseboard_fab2(sch_1):m_m_vref" )
				( signalRef "@baseboard_fab2_lib.baseboard_fab2(sch_1):m_m_cpu_vref" )
				( objectStatus "M_M_CPU_VREF" )
			)
			( electricalNet "@crescent_city_bb_fab1_lib.crescent_city_bb_fab1(sch_1):vr_p5v_stby_vsense"
				( signalRef "@baseboard_fab2_lib.baseboard_fab2(sch_1):vr_p5v_stby_vsense" )
				( signalRef "@baseboard_fab2_lib.baseboard_fab2(sch_1):vr_p5v_stby_vsense_r" )
				( objectStatus "VR_P5V_STBY_VSENSE" )
			)
			( electricalNet "@crescent_city_bb_fab1_lib.crescent_city_bb_fab1(sch_1):spi_cs0_primary_r_n"
				( signalRef "@baseboard_fab2_lib.baseboard_fab2(sch_1):spi_cs0_secondary_r_n" )
				( signalRef "@baseboard_fab2_lib.baseboard_fab2(sch_1):spi_cs0_secondary_n" )
				( signalRef "@baseboard_fab2_lib.baseboard_fab2(sch_1):spi_switch_cs0_n" )
				( signalRef "@baseboard_fab2_lib.baseboard_fab2(sch_1):spi_cs0_primary_n" )
				( signalRef "@baseboard_fab2_lib.baseboard_fab2(sch_1):spi_cs0_primary_r_n" )
				( electricalCSetRef "@crescent_city_bb_fab1_lib.crescent_city_bb_fab1(sch_1):\SPI_CS0_PRIMARY_R_N\" )
				( pinPairRef "@baseboard_fab2_lib.baseboard_fab2(sch_1):\PP6071\" )
				( pinPairRef "@baseboard_fab2_lib.baseboard_fab2(sch_1):\PP6072\" )
				( objectStatus "SPI_SWITCH_CS0_N" )
			)
			( electricalNet "@crescent_city_bb_fab1_lib.crescent_city_bb_fab1(sch_1):xdp_spi_pch_mosi_boot_halt_n"
				( signalRef "@baseboard_fab2_lib.baseboard_fab2(sch_1):xdp_spi_pch_mosi_boot_halt_n" )
				( signalRef "@baseboard_fab2_lib.baseboard_fab2(sch_1):spi_pch_mosi" )
				( signalRef "@baseboard_fab2_lib.baseboard_fab2(sch_1):spi_pch_mosi_r" )
				( signalRef "@baseboard_fab2_lib.baseboard_fab2(sch_1):spi_pch_tpm_mosi_r" )
				( electricalCSetRef "@crescent_city_bb_fab1_lib.crescent_city_bb_fab1(sch_1):\SPI_PCH_MOSI_R\" )
				( pinPairRef "@baseboard_fab2_lib.baseboard_fab2(sch_1):\PP6097\" )
				( pinPairRef "@baseboard_fab2_lib.baseboard_fab2(sch_1):\PP6098\" )
				( objectStatus "SPI_PCH_MOSI" )
			)
			( electricalNet "@crescent_city_bb_fab1_lib.crescent_city_bb_fab1(sch_1):xdp_debug_consent_n"
				( signalRef "@baseboard_fab2_lib.baseboard_fab2(sch_1):xdp_debug_consent_n" )
				( signalRef "@baseboard_fab2_lib.baseboard_fab2(sch_1):spi_pch_io2" )
				( signalRef "@baseboard_fab2_lib.baseboard_fab2(sch_1):spi_pch_io2_r1" )
				( electricalCSetRef "@crescent_city_bb_fab1_lib.crescent_city_bb_fab1(sch_1):\SPI_PCH_IO2_1\" )
				( pinPairRef "@baseboard_fab2_lib.baseboard_fab2(sch_1):\PP6111\" )
				( attribute "RATSNEST_SCHEDULE" "MIN_TREE"
					( Origin gBackEnd )
				)
				( objectStatus "SPI_PCH_IO2" )
			)
			( electricalNet "@crescent_city_bb_fab1_lib.crescent_city_bb_fab1(sch_1):spi_switch_mosi"
				( signalRef "@baseboard_fab2_lib.baseboard_fab2(sch_1):spi_switch_mosi_r1" )
				( signalRef "@baseboard_fab2_lib.baseboard_fab2(sch_1):spi_switch_mosi" )
				( signalRef "@baseboard_fab2_lib.baseboard_fab2(sch_1):spi_switch_mosi_r0" )
				( electricalCSetRef "@crescent_city_bb_fab1_lib.crescent_city_bb_fab1(sch_1):\SPI_SWITCH_MOSI\" )
				( pinPairRef "@baseboard_fab2_lib.baseboard_fab2(sch_1):\PP6090\" )
				( pinPairRef "@baseboard_fab2_lib.baseboard_fab2(sch_1):\PP6091\" )
				( objectStatus "SPI_SWITCH_MOSI" )
			)
			( electricalNet "@crescent_city_bb_fab1_lib.crescent_city_bb_fab1(sch_1):spi_pch_tpm_cs_n"
				( signalRef "@baseboard_fab2_lib.baseboard_fab2(sch_1):spi_pch_tpm_cs_n" )
				( signalRef "@baseboard_fab2_lib.baseboard_fab2(sch_1):spi_pch_tpm_cs_r_n" )
				( electricalCSetRef "@crescent_city_bb_fab1_lib.crescent_city_bb_fab1(sch_1):\SPI_PCH_TPM_CS_N\" )
				( pinPairRef "@baseboard_fab2_lib.baseboard_fab2(sch_1):\PP6099\" )
				( objectStatus "SPI_PCH_TPM_CS_N" )
			)
			( electricalNet "@crescent_city_bb_fab1_lib.crescent_city_bb_fab1(sch_1):spi_clk_r0"
				( signalRef "@baseboard_fab2_lib.baseboard_fab2(sch_1):spi_clk_r1" )
				( signalRef "@baseboard_fab2_lib.baseboard_fab2(sch_1):spi_switch_clk" )
				( signalRef "@baseboard_fab2_lib.baseboard_fab2(sch_1):spi_clk_r0" )
				( electricalCSetRef "@crescent_city_bb_fab1_lib.crescent_city_bb_fab1(sch_1):\SPI_SWITCH_CLK\" )
				( pinPairRef "@baseboard_fab2_lib.baseboard_fab2(sch_1):\PP6093\" )
				( pinPairRef "@baseboard_fab2_lib.baseboard_fab2(sch_1):\PP6094\" )
				( objectStatus "SPI_SWITCH_CLK" )
			)
			( electricalNet "@crescent_city_bb_fab1_lib.crescent_city_bb_fab1(sch_1):spi_pch_miso_r"
				( signalRef "@baseboard_fab2_lib.baseboard_fab2(sch_1):spi_pch_tpm_miso_r" )
				( signalRef "@baseboard_fab2_lib.baseboard_fab2(sch_1):spi_pch_miso" )
				( signalRef "@baseboard_fab2_lib.baseboard_fab2(sch_1):spi_pch_miso_r" )
				( electricalCSetRef "@crescent_city_bb_fab1_lib.crescent_city_bb_fab1(sch_1):\SPI_PCH_MISO_R\" )
				( pinPairRef "@baseboard_fab2_lib.baseboard_fab2(sch_1):\PP6104\" )
				( pinPairRef "@baseboard_fab2_lib.baseboard_fab2(sch_1):\PP6105\" )
				( objectStatus "SPI_PCH_MISO" )
			)
			( electricalNet "@crescent_city_bb_fab1_lib.crescent_city_bb_fab1(sch_1):spi_pch_clk"
				( signalRef "@baseboard_fab2_lib.baseboard_fab2(sch_1):spi_pch_clk" )
				( signalRef "@baseboard_fab2_lib.baseboard_fab2(sch_1):spi_pch_tpm_clk_r" )
				( electricalCSetRef "@crescent_city_bb_fab1_lib.crescent_city_bb_fab1(sch_1):\SPI_PCH_CLK\" )
				( pinPairRef "@baseboard_fab2_lib.baseboard_fab2(sch_1):\PP6103\" )
				( objectStatus "SPI_PCH_CLK" )
			)
			( electricalNet "@crescent_city_bb_fab1_lib.crescent_city_bb_fab1(sch_1):spi_bmc_bt_di"
				( signalRef "@baseboard_fab2_lib.baseboard_fab2(sch_1):spi_bmc_bt_di_r" )
				( signalRef "@baseboard_fab2_lib.baseboard_fab2(sch_1):spi_bmc_bt_di" )
				( pinPairRef "@baseboard_fab2_lib.baseboard_fab2(sch_1):\PP5809\" )
				( objectStatus "SPI_BMC_BT_DI" )
			)
			( electricalNet "@crescent_city_bb_fab1_lib.crescent_city_bb_fab1(sch_1):spi_bmc_bt_do"
				( signalRef "@baseboard_fab2_lib.baseboard_fab2(sch_1):spi_bmc_bt_do_r" )
				( signalRef "@baseboard_fab2_lib.baseboard_fab2(sch_1):spi_bmc_bt_do" )
				( pinPairRef "@baseboard_fab2_lib.baseboard_fab2(sch_1):\PP5801\" )
				( objectStatus "SPI_BMC_BT_DO" )
			)
			( electricalNet "@crescent_city_bb_fab1_lib.crescent_city_bb_fab1(sch_1):spi_bmc_bt_clk"
				( signalRef "@baseboard_fab2_lib.baseboard_fab2(sch_1):spi_bmc_bt_clk_r" )
				( signalRef "@baseboard_fab2_lib.baseboard_fab2(sch_1):spi_bmc_bt_clk" )
				( pinPairRef "@baseboard_fab2_lib.baseboard_fab2(sch_1):\PP5802\" )
				( objectStatus "SPI_BMC_BT_CLK" )
			)
			( electricalNet "@crescent_city_bb_fab1_lib.crescent_city_bb_fab1(sch_1):spi_bmc_bt_cs_n"
				( signalRef "@baseboard_fab2_lib.baseboard_fab2(sch_1):spi_bmc_bt_cs_r_n" )
				( signalRef "@baseboard_fab2_lib.baseboard_fab2(sch_1):spi_bmc_bt_cs_n" )
				( pinPairRef "@baseboard_fab2_lib.baseboard_fab2(sch_1):\PP5807\" )
				( objectStatus "SPI_BMC_BT_CS_N" )
			)
			( electricalNet "@crescent_city_bb_fab1_lib.crescent_city_bb_fab1(sch_1):spi_pch_io3"
				( signalRef "@baseboard_fab2_lib.baseboard_fab2(sch_1):spi_pch_io3" )
				( signalRef "@baseboard_fab2_lib.baseboard_fab2(sch_1):spi_pch_io3_r1" )
				( electricalCSetRef "@crescent_city_bb_fab1_lib.crescent_city_bb_fab1(sch_1):\SPI_PCH_IO3_1\" )
				( pinPairRef "@baseboard_fab2_lib.baseboard_fab2(sch_1):\PP6112\" )
				( attribute "RATSNEST_SCHEDULE" "MIN_TREE"
					( Origin gBackEnd )
				)
				( objectStatus "SPI_PCH_IO3" )
			)
			( electricalNet "@crescent_city_bb_fab1_lib.crescent_city_bb_fab1(sch_1):spi_miso_r0"
				( signalRef "@baseboard_fab2_lib.baseboard_fab2(sch_1):spi_switch_miso" )
				( signalRef "@baseboard_fab2_lib.baseboard_fab2(sch_1):spi_miso_r0" )
				( signalRef "@baseboard_fab2_lib.baseboard_fab2(sch_1):spi_miso_r1" )
				( electricalCSetRef "@crescent_city_bb_fab1_lib.crescent_city_bb_fab1(sch_1):\SPI_SWITCH_MISO\" )
				( pinPairRef "@baseboard_fab2_lib.baseboard_fab2(sch_1):\PP6108\" )
				( pinPairRef "@baseboard_fab2_lib.baseboard_fab2(sch_1):\PP6109\" )
				( objectStatus "SPI_SWITCH_MISO" )
			)
			( electricalNet "@crescent_city_bb_fab1_lib.crescent_city_bb_fab1(sch_1):spi_nic_cs_n"
				( signalRef "@baseboard_fab2_lib.baseboard_fab2(sch_1):spi_nic_cs_n" )
				( signalRef "@baseboard_fab2_lib.baseboard_fab2(sch_1):spi_nic_cs_r_n" )
				( pinPairRef "@baseboard_fab2_lib.baseboard_fab2(sch_1):\PP5803\" )
				( objectStatus "SPI_NIC_CS_N" )
			)
			( electricalNet "@crescent_city_bb_fab1_lib.crescent_city_bb_fab1(sch_1):spi_nic_miso"
				( signalRef "@baseboard_fab2_lib.baseboard_fab2(sch_1):spi_nic_miso_r" )
				( signalRef "@baseboard_fab2_lib.baseboard_fab2(sch_1):spi_nic_miso" )
				( pinPairRef "@baseboard_fab2_lib.baseboard_fab2(sch_1):\PP5808\" )
				( objectStatus "SPI_NIC_MISO" )
			)
			( electricalNet "@crescent_city_bb_fab1_lib.crescent_city_bb_fab1(sch_1):spi_nic_mosi"
				( signalRef "@baseboard_fab2_lib.baseboard_fab2(sch_1):spi_nic_mosi" )
				( signalRef "@baseboard_fab2_lib.baseboard_fab2(sch_1):spi_nic_mosi_r" )
				( pinPairRef "@baseboard_fab2_lib.baseboard_fab2(sch_1):\PP5805\" )
				( objectStatus "SPI_NIC_MOSI" )
			)
			( electricalNet "@crescent_city_bb_fab1_lib.crescent_city_bb_fab1(sch_1):spi_nic_sclk"
				( signalRef "@baseboard_fab2_lib.baseboard_fab2(sch_1):spi_nic_sclk" )
				( signalRef "@baseboard_fab2_lib.baseboard_fab2(sch_1):spi_nic_sclk_r" )
				( electricalCSetRef "@crescent_city_bb_fab1_lib.crescent_city_bb_fab1(sch_1):\SPI_NIC_SCLK\" )
				( pinPairRef "@baseboard_fab2_lib.baseboard_fab2(sch_1):\PP6110\" )
				( objectStatus "SPI_NIC_SCLK" )
			)
			( electricalNet "@baseboard_fab2_lib.baseboard_fab2(sch_1):spi_pch_cs0_n"
				( signalRef "@baseboard_fab2_lib.baseboard_fab2(sch_1):spi_pch_cs0_n" )
				( signalRef "@baseboard_fab2_lib.baseboard_fab2(sch_1):spi_pch_cs0_r_n" )
				( electricalCSetRef "@crescent_city_bb_fab1_lib.crescent_city_bb_fab1(sch_1):\SPI_PCH_CS0_R1_N\" )
				( pinPairRef "@baseboard_fab2_lib.baseboard_fab2(sch_1):\PP6096\" )
				( objectStatus "SPI_PCH_CS0_N" )
			)
			( electricalNet "@crescent_city_bb_fab1_lib.crescent_city_bb_fab1(sch_1):svid_dio0_cpu1"
				( signalRef "@baseboard_fab2_lib.baseboard_fab2(sch_1):svid_vdio_pvccio_cpu1" )
				( signalRef "@baseboard_fab2_lib.baseboard_fab2(sch_1):svid_dio0_cpu1_r" )
				( signalRef "@baseboard_fab2_lib.baseboard_fab2(sch_1):svid_dio0_cpu1" )
				( signalRef "@baseboard_fab2_lib.baseboard_fab2(sch_1):svid_vdio_pvccin_cpu1" )
				( objectStatus "SVID_DIO0_CPU1" )
			)
			( electricalNet "@crescent_city_bb_fab1_lib.crescent_city_bb_fab1(sch_1):svid_dio0_cpu0"
				( signalRef "@baseboard_fab2_lib.baseboard_fab2(sch_1):svid_vdio_pvccio_cpu0" )
				( signalRef "@baseboard_fab2_lib.baseboard_fab2(sch_1):svid_dio0_cpu0_r" )
				( signalRef "@baseboard_fab2_lib.baseboard_fab2(sch_1):svid_vdio_pvccin_cpu0" )
				( signalRef "@baseboard_fab2_lib.baseboard_fab2(sch_1):svid_dio0_cpu0" )
				( objectStatus "SVID_DIO0_CPU0" )
			)
			( electricalNet "@crescent_city_bb_fab1_lib.crescent_city_bb_fab1(sch_1):svid_clk_pvddq_ghj"
				( signalRef "@baseboard_fab2_lib.baseboard_fab2(sch_1):svid_clk_pvddq_klm" )
				( signalRef "@baseboard_fab2_lib.baseboard_fab2(sch_1):svid_clk1_cpu1_r" )
				( signalRef "@baseboard_fab2_lib.baseboard_fab2(sch_1):svid_clk1_cpu1" )
				( signalRef "@baseboard_fab2_lib.baseboard_fab2(sch_1):svid_clk_pvddq_ghj" )
				( objectStatus "SVID_CLK_PVDDQ_GHJ" )
			)
			( electricalNet "@crescent_city_bb_fab1_lib.crescent_city_bb_fab1(sch_1):svid_clk_pvddq_abc"
				( signalRef "@baseboard_fab2_lib.baseboard_fab2(sch_1):svid_clk_pvddq_def" )
				( signalRef "@baseboard_fab2_lib.baseboard_fab2(sch_1):svid_clk1_cpu0_r" )
				( signalRef "@baseboard_fab2_lib.baseboard_fab2(sch_1):svid_clk1_cpu0" )
				( signalRef "@baseboard_fab2_lib.baseboard_fab2(sch_1):svid_clk_pvddq_abc" )
				( objectStatus "SVID_CLK_PVDDQ_ABC" )
			)
			( electricalNet "@crescent_city_bb_fab1_lib.crescent_city_bb_fab1(sch_1):svid_clk_pvccio_cpu1"
				( signalRef "@baseboard_fab2_lib.baseboard_fab2(sch_1):svid_clk_pvccio_cpu1" )
				( signalRef "@baseboard_fab2_lib.baseboard_fab2(sch_1):svid_clk0_cpu1_r" )
				( signalRef "@baseboard_fab2_lib.baseboard_fab2(sch_1):svid_vclk_pvccin_cpu1" )
				( signalRef "@baseboard_fab2_lib.baseboard_fab2(sch_1):svid_clk0_cpu1" )
				( objectStatus "SVID_CLK_PVCCIO_CPU1" )
			)
			( electricalNet "@crescent_city_bb_fab1_lib.crescent_city_bb_fab1(sch_1):svid_clk_pvccio_cpu0"
				( signalRef "@baseboard_fab2_lib.baseboard_fab2(sch_1):svid_clk_pvccio_cpu0" )
				( signalRef "@baseboard_fab2_lib.baseboard_fab2(sch_1):svid_clk0_cpu0_r" )
				( signalRef "@baseboard_fab2_lib.baseboard_fab2(sch_1):svid_vclk_pvccin_cpu0" )
				( signalRef "@baseboard_fab2_lib.baseboard_fab2(sch_1):svid_clk0_cpu0" )
				( objectStatus "SVID_CLK_PVCCIO_CPU0" )
			)
			( electricalNet "@crescent_city_bb_fab1_lib.crescent_city_bb_fab1(sch_1):svid_alert0_cpu1_n"
				( signalRef "@baseboard_fab2_lib.baseboard_fab2(sch_1):svid_alert_pvccio_cpu1" )
				( signalRef "@baseboard_fab2_lib.baseboard_fab2(sch_1):svid_alert0_cpu1_r_n" )
				( signalRef "@baseboard_fab2_lib.baseboard_fab2(sch_1):svid_alert0_cpu1_n" )
				( signalRef "@baseboard_fab2_lib.baseboard_fab2(sch_1):svid_valert_vccin_cpu1" )
				( objectStatus "SVID_ALERT0_CPU1_N" )
			)
			( electricalNet "@crescent_city_bb_fab1_lib.crescent_city_bb_fab1(sch_1):svid_alert0_cpu0_n"
				( signalRef "@baseboard_fab2_lib.baseboard_fab2(sch_1):svid_alert_pvccio_cpu0" )
				( signalRef "@baseboard_fab2_lib.baseboard_fab2(sch_1):svid_alert0_cpu0_r_n" )
				( signalRef "@baseboard_fab2_lib.baseboard_fab2(sch_1):svid_valert_vccin_cpu0" )
				( signalRef "@baseboard_fab2_lib.baseboard_fab2(sch_1):svid_alert0_cpu0_n" )
				( objectStatus "SVID_ALERT0_CPU0_N" )
			)
			( electricalNet "@crescent_city_bb_fab1_lib.crescent_city_bb_fab1(sch_1):svid_dio1_cpu1_r"
				( signalRef "@baseboard_fab2_lib.baseboard_fab2(sch_1):svid_vdio_pvddq_klm" )
				( signalRef "@baseboard_fab2_lib.baseboard_fab2(sch_1):svid_dio1_cpu1_r" )
				( signalRef "@baseboard_fab2_lib.baseboard_fab2(sch_1):svid_vdio_pvddq_ghj" )
				( signalRef "@baseboard_fab2_lib.baseboard_fab2(sch_1):svid_dio1_cpu1" )
				( objectStatus "SVID_DIO1_CPU1" )
			)
			( electricalNet "@crescent_city_bb_fab1_lib.crescent_city_bb_fab1(sch_1):svid_dio1_cpu0_r"
				( signalRef "@baseboard_fab2_lib.baseboard_fab2(sch_1):svid_vdio_pvddq_def" )
				( signalRef "@baseboard_fab2_lib.baseboard_fab2(sch_1):svid_dio1_cpu0_r" )
				( signalRef "@baseboard_fab2_lib.baseboard_fab2(sch_1):svid_vdio_pvddq_abc" )
				( signalRef "@baseboard_fab2_lib.baseboard_fab2(sch_1):svid_dio1_cpu0" )
				( objectStatus "SVID_DIO1_CPU0" )
			)
			( electricalNet "@crescent_city_bb_fab1_lib.crescent_city_bb_fab1(sch_1):svid_alert1_cpu1_n"
				( signalRef "@baseboard_fab2_lib.baseboard_fab2(sch_1):svid_alert_pvddq_klm" )
				( signalRef "@baseboard_fab2_lib.baseboard_fab2(sch_1):svid_alert1_cpu1_r_n" )
				( signalRef "@baseboard_fab2_lib.baseboard_fab2(sch_1):svid_alert_pvddq_ghj" )
				( signalRef "@baseboard_fab2_lib.baseboard_fab2(sch_1):svid_alert1_cpu1_n" )
				( objectStatus "SVID_ALERT1_CPU1_N" )
			)
			( electricalNet "@crescent_city_bb_fab1_lib.crescent_city_bb_fab1(sch_1):svid_alert1_cpu0_n"
				( signalRef "@baseboard_fab2_lib.baseboard_fab2(sch_1):svid_alert_pvddq_def" )
				( signalRef "@baseboard_fab2_lib.baseboard_fab2(sch_1):svid_alert1_cpu0_r_n" )
				( signalRef "@baseboard_fab2_lib.baseboard_fab2(sch_1):svid_alert_pvddq_abc" )
				( signalRef "@baseboard_fab2_lib.baseboard_fab2(sch_1):svid_alert1_cpu0_n" )
				( objectStatus "SVID_ALERT1_CPU0_N" )
			)
			( electricalNet "@crescent_city_bb_fab1_lib.crescent_city_bb_fab1(sch_1):sgpio_pch_ssata_clock"
				( signalRef "@baseboard_fab2_lib.baseboard_fab2(sch_1):sgpio_pch_ssata_clock_r" )
				( signalRef "@baseboard_fab2_lib.baseboard_fab2(sch_1):sgpio_pch_ssata_clock" )
				( objectStatus "SGPIO_PCH_SSATA_CLOCK" )
			)
			( electricalNet "@crescent_city_bb_fab1_lib.crescent_city_bb_fab1(sch_1):sgpio_pch_ssata_dout0"
				( signalRef "@baseboard_fab2_lib.baseboard_fab2(sch_1):sgpio_pch_ssata_dout0" )
				( signalRef "@baseboard_fab2_lib.baseboard_fab2(sch_1):sgpio_pch_ssata_dout0_r" )
				( objectStatus "SGPIO_PCH_SSATA_DOUT0" )
			)
			( electricalNet "@crescent_city_bb_fab1_lib.crescent_city_bb_fab1(sch_1):sgpio_pch_ssata_load"
				( signalRef "@baseboard_fab2_lib.baseboard_fab2(sch_1):sgpio_pch_ssata_load_r" )
				( signalRef "@baseboard_fab2_lib.baseboard_fab2(sch_1):sgpio_pch_ssata_load" )
				( objectStatus "SGPIO_PCH_SSATA_LOAD" )
			)
			( electricalNet "@crescent_city_bb_fab1_lib.crescent_city_bb_fab1(sch_1):fan_tach3_r"
				( signalRef "@baseboard_fab2_lib.baseboard_fab2(sch_1):fan_tach3_r" )
				( signalRef "@baseboard_fab2_lib.baseboard_fab2(sch_1):fan_tach3" )
				( pinPairRef "@baseboard_fab2_lib.baseboard_fab2(sch_1):\PP5811\" )
				( objectStatus "FAN_TACH3_R" )
			)
			( electricalNet "@crescent_city_bb_fab1_lib.crescent_city_bb_fab1(sch_1):fan_tach2"
				( signalRef "@baseboard_fab2_lib.baseboard_fab2(sch_1):fan_tach2_r" )
				( signalRef "@baseboard_fab2_lib.baseboard_fab2(sch_1):fan_tach2" )
				( pinPairRef "@baseboard_fab2_lib.baseboard_fab2(sch_1):\PP5814\" )
				( objectStatus "FAN_TACH2" )
			)
			( electricalNet "@crescent_city_bb_fab1_lib.crescent_city_bb_fab1(sch_1):fan_tach1"
				( signalRef "@baseboard_fab2_lib.baseboard_fab2(sch_1):fan_tach1_r" )
				( signalRef "@baseboard_fab2_lib.baseboard_fab2(sch_1):fan_tach1" )
				( pinPairRef "@baseboard_fab2_lib.baseboard_fab2(sch_1):\PP5812\" )
				( objectStatus "FAN_TACH1" )
			)
			( electricalNet "@crescent_city_bb_fab1_lib.crescent_city_bb_fab1(sch_1):fan_pwm_out_sys0_r"
				( signalRef "@baseboard_fab2_lib.baseboard_fab2(sch_1):fan_pwm_out_sys0_r1" )
				( signalRef "@baseboard_fab2_lib.baseboard_fab2(sch_1):fan_pwm_out_sys0_r" )
				( signalRef "@baseboard_fab2_lib.baseboard_fab2(sch_1):fan_pwm_out_sys0_buf" )
				( pinPairRef "@baseboard_fab2_lib.baseboard_fab2(sch_1):\PP5813\" )
				( objectStatus "FAN_PWM_OUT_SYS0_R" )
			)
			( electricalNet "@crescent_city_bb_fab1_lib.crescent_city_bb_fab1(sch_1):fan_pwm_out_sys1_r"
				( signalRef "@baseboard_fab2_lib.baseboard_fab2(sch_1):fan_pwm_out_sys1_buf" )
				( signalRef "@baseboard_fab2_lib.baseboard_fab2(sch_1):fan_pwm_out_sys1_r" )
				( pinPairRef "@baseboard_fab2_lib.baseboard_fab2(sch_1):\PP5804\" )
				( objectStatus "FAN_PWM_OUT_SYS1_R" )
			)
			( electricalNet "@crescent_city_bb_fab1_lib.crescent_city_bb_fab1(sch_1):sp2_bmc_cm_uart_tx"
				( signalRef "@baseboard_fab2_lib.baseboard_fab2(sch_1):uart_mux_out_r" )
				( signalRef "@baseboard_fab2_lib.baseboard_fab2(sch_1):spa_mid_dbg_tx" )
				( signalRef "@baseboard_fab2_lib.baseboard_fab2(sch_1):sp2_bmc_cm_uart_tx" )
				( objectStatus "SP2_BMC_CM_UART_TX" )
			)
			( electricalNet "@crescent_city_bb_fab1_lib.crescent_city_bb_fab1(sch_1):sp2_bmc_cm_uart_rx"
				( signalRef "@baseboard_fab2_lib.baseboard_fab2(sch_1):uart_mux_in_r" )
				( signalRef "@baseboard_fab2_lib.baseboard_fab2(sch_1):spa_mid_dbg_rx" )
				( signalRef "@baseboard_fab2_lib.baseboard_fab2(sch_1):spa_sin_sw_r" )
				( signalRef "@baseboard_fab2_lib.baseboard_fab2(sch_1):sp2_bmc_cm_uart_rx" )
				( objectStatus "SP2_BMC_CM_UART_RX" )
			)
			( electricalNet "@crescent_city_bb_fab1_lib.crescent_city_bb_fab1(sch_1):jtag_pch_gbe_tms"
				( signalRef "@baseboard_fab2_lib.baseboard_fab2(sch_1):jtag_tms_r" )
				( signalRef "@baseboard_fab2_lib.baseboard_fab2(sch_1):jtag_tms" )
				( signalRef "@baseboard_fab2_lib.baseboard_fab2(sch_1):jtag_bmc_tms" )
				( signalRef "@baseboard_fab2_lib.baseboard_fab2(sch_1):jtag_pld_tms" )
				( signalRef "@baseboard_fab2_lib.baseboard_fab2(sch_1):jtag_pch_gbe_tms" )
				( signalRef "@baseboard_fab2_lib.baseboard_fab2(sch_1):jtag_pch_pld_tms" )
				( objectStatus "JTAG_PCH_GBE_TMS" )
			)
			( electricalNet "@crescent_city_bb_fab1_lib.crescent_city_bb_fab1(sch_1):jtag_pch_gbe_clk"
				( signalRef "@baseboard_fab2_lib.baseboard_fab2(sch_1):jtag_tck_r" )
				( signalRef "@baseboard_fab2_lib.baseboard_fab2(sch_1):jtag_tck" )
				( signalRef "@baseboard_fab2_lib.baseboard_fab2(sch_1):jtag_pch_pld_tck" )
				( signalRef "@baseboard_fab2_lib.baseboard_fab2(sch_1):jtag_pch_gbe_clk" )
				( signalRef "@baseboard_fab2_lib.baseboard_fab2(sch_1):jtag_bmc_tck" )
				( signalRef "@baseboard_fab2_lib.baseboard_fab2(sch_1):jtag_pld_tck" )
				( objectStatus "JTAG_PCH_GBE_CLK" )
			)
			( electricalNet "@crescent_city_bb_fab1_lib.crescent_city_bb_fab1(sch_1):jtag_pch_gbe_tdi"
				( signalRef "@baseboard_fab2_lib.baseboard_fab2(sch_1):jtag_tdi_r" )
				( signalRef "@baseboard_fab2_lib.baseboard_fab2(sch_1):jtag_tdi" )
				( signalRef "@baseboard_fab2_lib.baseboard_fab2(sch_1):jtag_pch_pld_tdi" )
				( signalRef "@baseboard_fab2_lib.baseboard_fab2(sch_1):jtag_pch_gbe_tdi" )
				( signalRef "@baseboard_fab2_lib.baseboard_fab2(sch_1):jtag_pld_tdi" )
				( signalRef "@baseboard_fab2_lib.baseboard_fab2(sch_1):jtag_bmc_tdi" )
				( objectStatus "JTAG_PCH_GBE_TDI" )
			)
			( electricalNet "@crescent_city_bb_fab1_lib.crescent_city_bb_fab1(sch_1):jtag_pch_gbe_tdo"
				( signalRef "@baseboard_fab2_lib.baseboard_fab2(sch_1):jtag_tdo_r" )
				( signalRef "@baseboard_fab2_lib.baseboard_fab2(sch_1):jtag_tdo" )
				( signalRef "@baseboard_fab2_lib.baseboard_fab2(sch_1):jtag_bmc_tdo" )
				( signalRef "@baseboard_fab2_lib.baseboard_fab2(sch_1):jtag_pch_gbe_tdo" )
				( signalRef "@baseboard_fab2_lib.baseboard_fab2(sch_1):jtag_pch_pld_tdo" )
				( signalRef "@baseboard_fab2_lib.baseboard_fab2(sch_1):jtag_pld_tdo" )
				( objectStatus "JTAG_PCH_GBE_TDO" )
			)
			( electricalNet "@crescent_city_bb_fab1_lib.crescent_city_bb_fab1(sch_1):jtag_pch_gbe_trst_n"
				( signalRef "@baseboard_fab2_lib.baseboard_fab2(sch_1):jtag_pch_gbe_trst_n" )
				( signalRef "@baseboard_fab2_lib.baseboard_fab2(sch_1):jtag_trst_n" )
				( signalRef "@baseboard_fab2_lib.baseboard_fab2(sch_1):jtag_bmc_trst_n" )
				( objectStatus "JTAG_PCH_GBE_TRST_N" )
			)
			( electricalNet "@baseboard_fab2_lib.baseboard_fab2(sch_1):jtag_mcp_cpu1_tdi"
				( signalRef "@baseboard_fab2_lib.baseboard_fab2(sch_1):jtag_mcp_mux_tdo" )
				( signalRef "@baseboard_fab2_lib.baseboard_fab2(sch_1):jtag_mcp_cpu0_tdo" )
				( signalRef "@baseboard_fab2_lib.baseboard_fab2(sch_1):jtag_mcp_cpu1_tdi" )
				( signalRef "@baseboard_fab2_lib.baseboard_fab2(sch_1):jtag_mcp_cpu1_tdi_r" )
				( signalRef "@baseboard_fab2_lib.baseboard_fab2(sch_1):jtag_mcp_cpu1_tdo" )
				( objectStatus "JTAG_MCP_CPU1_TDI" )
			)
			( electricalNet "@crescent_city_bb_fab1_lib.crescent_city_bb_fab1(sch_1):xdp_cpu1_tdi"
				( signalRef "@baseboard_fab2_lib.baseboard_fab2(sch_1):xdp_cpu1_tdo" )
				( signalRef "@baseboard_fab2_lib.baseboard_fab2(sch_1):xdp_cpu_tdo" )
				( signalRef "@baseboard_fab2_lib.baseboard_fab2(sch_1):xdp_tdo" )
				( signalRef "@baseboard_fab2_lib.baseboard_fab2(sch_1):xdp_cpu0_tdo" )
				( signalRef "@baseboard_fab2_lib.baseboard_fab2(sch_1):xdp_cpu1_tdi" )
				( attribute "RATSNEST_SCHEDULE" "MIN_TREE"
					( Origin gBackEnd )
				)
				( objectStatus "XDP_CPU1_TDI" )
			)
			( electricalNet "@crescent_city_bb_fab1_lib.crescent_city_bb_fab1(sch_1):xdp_cpu_tck0"
				( signalRef "@baseboard_fab2_lib.baseboard_fab2(sch_1):xdp_pch_cpu_tck0" )
				( signalRef "@baseboard_fab2_lib.baseboard_fab2(sch_1):xdp_cpu_gtl_tck_r2" )
				( signalRef "@baseboard_fab2_lib.baseboard_fab2(sch_1):xdp_cpu_tck0" )
				( objectStatus "XDP_CPU_TCK0" )
			)
			( electricalNet "@crescent_city_bb_fab1_lib.crescent_city_bb_fab1(sch_1):xdp_cpu_trst_n"
				( signalRef "@baseboard_fab2_lib.baseboard_fab2(sch_1):xdp_trst_n" )
				( signalRef "@baseboard_fab2_lib.baseboard_fab2(sch_1):xdp_cpu_trst_n" )
				( objectStatus "XDP_CPU_TRST_N" )
			)
			( electricalNet "@crescent_city_bb_fab1_lib.crescent_city_bb_fab1(sch_1):xdp_cpu_tms"
				( signalRef "@baseboard_fab2_lib.baseboard_fab2(sch_1):xdp_tms" )
				( signalRef "@baseboard_fab2_lib.baseboard_fab2(sch_1):xdp_cpu_tms" )
				( attribute "RATSNEST_SCHEDULE" "MIN_TREE"
					( Origin gBackEnd )
				)
				( objectStatus "XDP_CPU_TMS" )
			)
			( electricalNet "@crescent_city_bb_fab1_lib.crescent_city_bb_fab1(sch_1):xdp_cpu_tdi"
				( signalRef "@baseboard_fab2_lib.baseboard_fab2(sch_1):xdp_tdi" )
				( signalRef "@baseboard_fab2_lib.baseboard_fab2(sch_1):xdp_cpu_tdi" )
				( attribute "RATSNEST_SCHEDULE" "MIN_TREE"
					( Origin gBackEnd )
				)
				( objectStatus "XDP_CPU_TDI" )
			)
			( electricalNet "@crescent_city_bb_fab1_lib.crescent_city_bb_fab1(sch_1):xdp_rsmrst_n"
				( signalRef "@baseboard_fab2_lib.baseboard_fab2(sch_1):xdp_rsmrst_n" )
				( signalRef "@baseboard_fab2_lib.baseboard_fab2(sch_1):rst_rsmrst_n" )
				( signalRef "@baseboard_fab2_lib.baseboard_fab2(sch_1):rst_rsmrst_r_n" )
				( objectStatus "RST_RSMRST_N" )
			)
			( electricalNet "@crescent_city_bb_fab1_lib.crescent_city_bb_fab1(sch_1):xdp_cpu_preq_n"
				( signalRef "@baseboard_fab2_lib.baseboard_fab2(sch_1):xdp_preq_n" )
				( signalRef "@baseboard_fab2_lib.baseboard_fab2(sch_1):xdp_cpu_preq_n" )
				( attribute "RATSNEST_SCHEDULE" "MIN_TREE"
					( Origin gBackEnd )
				)
				( objectStatus "XDP_CPU_PREQ_N" )
			)
			( electricalNet "@crescent_city_bb_fab1_lib.crescent_city_bb_fab1(sch_1):xdp_cpu_prdy_n"
				( signalRef "@baseboard_fab2_lib.baseboard_fab2(sch_1):xdp_prdy_n" )
				( signalRef "@baseboard_fab2_lib.baseboard_fab2(sch_1):xdp_cpu_prdy_n" )
				( attribute "RATSNEST_SCHEDULE" "MIN_TREE"
					( Origin gBackEnd )
				)
				( objectStatus "XDP_CPU_PRDY_N" )
			)
			( electricalNet "@crescent_city_bb_fab1_lib.crescent_city_bb_fab1(sch_1):xdp_obsfn_b1_mbp7_n"
				( signalRef "@baseboard_fab2_lib.baseboard_fab2(sch_1):xdp_obsfn_b1_mbp7_n" )
				( signalRef "@baseboard_fab2_lib.baseboard_fab2(sch_1):xdp_cpu_obsfn_b1_mbp7_n" )
				( objectStatus "XDP_OBSFN_B1_MBP7_N" )
			)
			( electricalNet "@crescent_city_bb_fab1_lib.crescent_city_bb_fab1(sch_1):xdp_obsfn_b0_mbp6_n"
				( signalRef "@baseboard_fab2_lib.baseboard_fab2(sch_1):xdp_obsfn_b0_mbp6_n" )
				( signalRef "@baseboard_fab2_lib.baseboard_fab2(sch_1):xdp_cpu_obsfn_b0_mbp6_n" )
				( objectStatus "XDP_OBSFN_B0_MBP6_N" )
			)
			( electricalNet "@crescent_city_bb_fab1_lib.crescent_city_bb_fab1(sch_1):smb_slotx24_bmc_stby_lvc3_scl"
				( signalRef "@baseboard_fab2_lib.baseboard_fab2(sch_1):smb_pehpcpu1_stby_lvc3_r_scl" )
				( signalRef "@baseboard_fab2_lib.baseboard_fab2(sch_1):smb_slotx24_bmc_stby_lvc3_scl" )
				( signalRef "@baseboard_fab2_lib.baseboard_fab2(sch_1):smb_slotx24_stby_lvc3_scl_r2" )
				( signalRef "@baseboard_fab2_lib.baseboard_fab2(sch_1):smb_slotx24_pch_stby_lvc3_scl" )
				( signalRef "@baseboard_fab2_lib.baseboard_fab2(sch_1):smb_slotx24_stby_lvc3_scl_r1" )
				( signalRef "@baseboard_fab2_lib.baseboard_fab2(sch_1):smb_slotx24_stby_lvc3_scl_r" )
				( signalRef "@baseboard_fab2_lib.baseboard_fab2(sch_1):smb_pehpcpu1_stby_lvc3_scl" )
				( objectStatus "SMB_SLOTX24_BMC_STBY_LVC3_SCL" )
			)
			( electricalNet "@crescent_city_bb_fab1_lib.crescent_city_bb_fab1(sch_1):smb_sensor_pch_stby_lvc3_scl"
				( signalRef "@baseboard_fab2_lib.baseboard_fab2(sch_1):smb_sensor_stby_lvc3_scl" )
				( signalRef "@baseboard_fab2_lib.baseboard_fab2(sch_1):smb_sensor_tmp421_2_scl" )
				( signalRef "@baseboard_fab2_lib.baseboard_fab2(sch_1):smb_sensor_tmp421_1_scl" )
				( signalRef "@baseboard_fab2_lib.baseboard_fab2(sch_1):smb_sensor_bmc_stby_lvc3_scl" )
				( signalRef "@baseboard_fab2_lib.baseboard_fab2(sch_1):smb_sensor_pch_stby_lvc3_scl" )
				( signalRef "@baseboard_fab2_lib.baseboard_fab2(sch_1):smb_sensor_stby_lvc3_scl_r1" )
				( objectStatus "SMB_SENSOR_PCH_STBY_LVC3_SCL" )
			)
			( electricalNet "@crescent_city_bb_fab1_lib.crescent_city_bb_fab1(sch_1):smb_lan_stby_lvc3_sda"
				( signalRef "@baseboard_fab2_lib.baseboard_fab2(sch_1):smb_lan_stby_lvc3_sda" )
				( signalRef "@baseboard_fab2_lib.baseboard_fab2(sch_1):smb_lan_stby_lvc3_sda_r2" )
				( signalRef "@baseboard_fab2_lib.baseboard_fab2(sch_1):smb_lan_stby_lvc3_sda_r" )
				( signalRef "@baseboard_fab2_lib.baseboard_fab2(sch_1):smb_ocp_fru_stby_lvc3_sda" )
				( signalRef "@baseboard_fab2_lib.baseboard_fab2(sch_1):smb_ocp_fru_stby_lvc3_sda_r" )
				( signalRef "@baseboard_fab2_lib.baseboard_fab2(sch_1):smb_lan_stby_lvc3_sda_r1" )
				( objectStatus "SMB_LAN_STBY_LVC3_SDA" )
			)
			( electricalNet "@crescent_city_bb_fab1_lib.crescent_city_bb_fab1(sch_1):smb_lan_stby_lvc3_scl"
				( signalRef "@baseboard_fab2_lib.baseboard_fab2(sch_1):smb_lan_stby_lvc3_scl" )
				( signalRef "@baseboard_fab2_lib.baseboard_fab2(sch_1):smb_lan_stby_lvc3_scl_r2" )
				( signalRef "@baseboard_fab2_lib.baseboard_fab2(sch_1):smb_lan_stby_lvc3_scl_r" )
				( signalRef "@baseboard_fab2_lib.baseboard_fab2(sch_1):smb_ocp_fru_stby_lvc3_scl" )
				( signalRef "@baseboard_fab2_lib.baseboard_fab2(sch_1):smb_ocp_fru_stby_lvc3_scl_r" )
				( signalRef "@baseboard_fab2_lib.baseboard_fab2(sch_1):smb_lan_stby_lvc3_scl_r1" )
				( objectStatus "SMB_LAN_STBY_LVC3_SCL" )
			)
			( electricalNet "@crescent_city_bb_fab1_lib.crescent_city_bb_fab1(sch_1):smb_3v3sb_hsc_sda_r"
				( signalRef "@baseboard_fab2_lib.baseboard_fab2(sch_1):smb_pmbus_bmc_stby_lvc3_sda_r1" )
				( signalRef "@baseboard_fab2_lib.baseboard_fab2(sch_1):smb_bmc_pmbus_stby_lvc3_sda" )
				( signalRef "@baseboard_fab2_lib.baseboard_fab2(sch_1):smb_3v3sb_hsc_sda_r" )
				( signalRef "@baseboard_fab2_lib.baseboard_fab2(sch_1):smb_bmc_pmbus_stby_lvc3_sda_r" )
				( objectStatus "SMB_3V3SB_HSC_SDA_R" )
			)
			( electricalNet "@crescent_city_bb_fab1_lib.crescent_city_bb_fab1(sch_1):smb_3v3sb_hsc_scl_r"
				( signalRef "@baseboard_fab2_lib.baseboard_fab2(sch_1):smb_pmbus_bmc_stby_lvc3_scl_r1" )
				( signalRef "@baseboard_fab2_lib.baseboard_fab2(sch_1):smb_bmc_pmbus_stby_lvc3_scl" )
				( signalRef "@baseboard_fab2_lib.baseboard_fab2(sch_1):smb_3v3sb_hsc_scl_r" )
				( signalRef "@baseboard_fab2_lib.baseboard_fab2(sch_1):smb_bmc_pmbus_stby_lvc3_scl_r" )
				( objectStatus "SMB_3V3SB_HSC_SCL_R" )
			)
			( electricalNet "@crescent_city_bb_fab1_lib.crescent_city_bb_fab1(sch_1):smb_slotx24_bmc_stby_lvc3_sda"
				( signalRef "@baseboard_fab2_lib.baseboard_fab2(sch_1):smb_pehpcpu1_stby_lvc3_r_sda" )
				( signalRef "@baseboard_fab2_lib.baseboard_fab2(sch_1):smb_slotx24_bmc_stby_lvc3_sda" )
				( signalRef "@baseboard_fab2_lib.baseboard_fab2(sch_1):smb_slotx24_stby_lvc3_sda_r" )
				( signalRef "@baseboard_fab2_lib.baseboard_fab2(sch_1):smb_slotx24_stby_lvc3_sda_r2" )
				( signalRef "@baseboard_fab2_lib.baseboard_fab2(sch_1):smb_slotx24_pch_stby_lvc3_sda" )
				( signalRef "@baseboard_fab2_lib.baseboard_fab2(sch_1):smb_slotx24_stby_lvc3_sda_r1" )
				( signalRef "@baseboard_fab2_lib.baseboard_fab2(sch_1):smb_pehpcpu1_stby_lvc3_sda" )
				( objectStatus "SMB_SLOTX24_BMC_STBY_LVC3_SDA" )
			)
			( electricalNet "@crescent_city_bb_fab1_lib.crescent_city_bb_fab1(sch_1):smb_smlink0_stby_lvc3_sda"
				( signalRef "@baseboard_fab2_lib.baseboard_fab2(sch_1):smb_springville_stby_lvc3_sda" )
				( signalRef "@baseboard_fab2_lib.baseboard_fab2(sch_1):smb_smlink0_stby_lvc3_sda" )
				( signalRef "@baseboard_fab2_lib.baseboard_fab2(sch_1):smb_smlink0_stby_lvc3_sda_r" )
				( signalRef "@baseboard_fab2_lib.baseboard_fab2(sch_1):smb_smlink0_stby_lvc3_sda_r1" )
				( signalRef "@baseboard_fab2_lib.baseboard_fab2(sch_1):smb_ocp_lan_stby_lvc3_sda" )
				( signalRef "@baseboard_fab2_lib.baseboard_fab2(sch_1):smb_ocp_lan_stby_lvc3_sda_r" )
				( objectStatus "SMB_SMLINK0_STBY_LVC3_SDA" )
			)
			( electricalNet "@crescent_city_bb_fab1_lib.crescent_city_bb_fab1(sch_1):smb_smlink0_stby_lvc3_scl"
				( signalRef "@baseboard_fab2_lib.baseboard_fab2(sch_1):smb_springville_stby_lvc3_scl" )
				( signalRef "@baseboard_fab2_lib.baseboard_fab2(sch_1):smb_ocp_lan_stby_lvc3_scl" )
				( signalRef "@baseboard_fab2_lib.baseboard_fab2(sch_1):smb_ocp_lan_stby_lvc3_scl_r" )
				( signalRef "@baseboard_fab2_lib.baseboard_fab2(sch_1):smb_smlink0_stby_lvc3_scl" )
				( signalRef "@baseboard_fab2_lib.baseboard_fab2(sch_1):smb_smlink0_stby_lvc3_scl_r" )
				( signalRef "@baseboard_fab2_lib.baseboard_fab2(sch_1):smb_smlink0_stby_lvc3_scl_r1" )
				( objectStatus "SMB_SMLINK0_STBY_LVC3_SCL" )
			)
			( electricalNet "@crescent_city_bb_fab1_lib.crescent_city_bb_fab1(sch_1):smb_sensor_bmc_stby_lvc3_sda"
				( signalRef "@baseboard_fab2_lib.baseboard_fab2(sch_1):smb_sensor_stby_lvc3_sda" )
				( signalRef "@baseboard_fab2_lib.baseboard_fab2(sch_1):smb_sensor_pch_stby_lvc3_sda" )
				( signalRef "@baseboard_fab2_lib.baseboard_fab2(sch_1):smb_sensor_stby_lvc3_sda_r1" )
				( signalRef "@baseboard_fab2_lib.baseboard_fab2(sch_1):smb_sensor_bmc_stby_lvc3_sda" )
				( signalRef "@baseboard_fab2_lib.baseboard_fab2(sch_1):smb_sensor_tmp421_2_sda" )
				( signalRef "@baseboard_fab2_lib.baseboard_fab2(sch_1):smb_sensor_tmp421_1_sda" )
				( objectStatus "SMB_SENSOR_BMC_STBY_LVC3_SDA" )
			)
			( electricalNet "@crescent_city_bb_fab1_lib.crescent_city_bb_fab1(sch_1):smb_vr_sda_pvccio_cpu0"
				( signalRef "@baseboard_fab2_lib.baseboard_fab2(sch_1):smb_vr_sda_pvnn_pch" )
				( signalRef "@baseboard_fab2_lib.baseboard_fab2(sch_1):smb_vr_stby_lvc3_sda" )
				( signalRef "@baseboard_fab2_lib.baseboard_fab2(sch_1):smb_vr_sda_vddq_abc" )
				( signalRef "@baseboard_fab2_lib.baseboard_fab2(sch_1):smb_vr_sda_vddq_klm" )
				( signalRef "@baseboard_fab2_lib.baseboard_fab2(sch_1):smb_vr_sda_pvccio_cpu1" )
				( signalRef "@baseboard_fab2_lib.baseboard_fab2(sch_1):smb_vr_sda_pvccio_cpu0" )
				( signalRef "@baseboard_fab2_lib.baseboard_fab2(sch_1):smb_vr_stby_lvc3_sda_r1" )
				( signalRef "@baseboard_fab2_lib.baseboard_fab2(sch_1):smb_vr_sda_r" )
				( signalRef "@baseboard_fab2_lib.baseboard_fab2(sch_1):smb_vr_sda_r1" )
				( signalRef "@baseboard_fab2_lib.baseboard_fab2(sch_1):smb_vr_sda_vddq_def" )
				( signalRef "@baseboard_fab2_lib.baseboard_fab2(sch_1):smb_vr_stby_lvc3_sda_r" )
				( signalRef "@baseboard_fab2_lib.baseboard_fab2(sch_1):smb_vr_sda_vddq_ghj" )
				( objectStatus "SMB_VR_SDA_PVCCIO_CPU0" )
			)
			( electricalNet "@crescent_city_bb_fab1_lib.crescent_city_bb_fab1(sch_1):smb_vr_scl_pvccio_cpu0"
				( signalRef "@baseboard_fab2_lib.baseboard_fab2(sch_1):smb_vr_scl_pvnn_pch" )
				( signalRef "@baseboard_fab2_lib.baseboard_fab2(sch_1):smb_vr_stby_lvc3_scl" )
				( signalRef "@baseboard_fab2_lib.baseboard_fab2(sch_1):smb_vr_scl_vddq_klm" )
				( signalRef "@baseboard_fab2_lib.baseboard_fab2(sch_1):smb_vr_scl_pvccio_cpu0" )
				( signalRef "@baseboard_fab2_lib.baseboard_fab2(sch_1):smb_vr_scl_r" )
				( signalRef "@baseboard_fab2_lib.baseboard_fab2(sch_1):smb_vr_scl_pvccio_cpu1" )
				( signalRef "@baseboard_fab2_lib.baseboard_fab2(sch_1):smb_vr_scl_r1" )
				( signalRef "@baseboard_fab2_lib.baseboard_fab2(sch_1):smb_vr_scl_vddq_def" )
				( signalRef "@baseboard_fab2_lib.baseboard_fab2(sch_1):smb_vr_scl_vddq_ghj" )
				( signalRef "@baseboard_fab2_lib.baseboard_fab2(sch_1):smb_vr_stby_lvc3_scl_r1" )
				( signalRef "@baseboard_fab2_lib.baseboard_fab2(sch_1):smb_vr_stby_lvc3_scl_r" )
				( signalRef "@baseboard_fab2_lib.baseboard_fab2(sch_1):smb_vr_scl_vddq_abc" )
				( objectStatus "SMB_VR_SCL_PVCCIO_CPU0" )
			)
			( electricalNet "@crescent_city_bb_fab1_lib.crescent_city_bb_fab1(sch_1):smb_ddr_klm_vpp_sda"
				( signalRef "@baseboard_fab2_lib.baseboard_fab2(sch_1):smb_ddr_klm_vpp_sda_r" )
				( signalRef "@baseboard_fab2_lib.baseboard_fab2(sch_1):smb_ddr_klm_vpp_sda" )
				( objectStatus "SMB_DDR_KLM_VPP_SDA" )
			)
			( electricalNet "@crescent_city_bb_fab1_lib.crescent_city_bb_fab1(sch_1):smb_ddr_klm_vpp_scl"
				( signalRef "@baseboard_fab2_lib.baseboard_fab2(sch_1):smb_ddr_klm_vpp_scl_r" )
				( signalRef "@baseboard_fab2_lib.baseboard_fab2(sch_1):smb_ddr_klm_vpp_scl" )
				( objectStatus "SMB_DDR_KLM_VPP_SCL" )
			)
			( electricalNet "@crescent_city_bb_fab1_lib.crescent_city_bb_fab1(sch_1):smb_ddr_ghj_vpp_sda"
				( signalRef "@baseboard_fab2_lib.baseboard_fab2(sch_1):smb_ddr_ghj_vpp_sda_r" )
				( signalRef "@baseboard_fab2_lib.baseboard_fab2(sch_1):smb_ddr_ghj_vpp_sda" )
				( objectStatus "SMB_DDR_GHJ_VPP_SDA" )
			)
			( electricalNet "@crescent_city_bb_fab1_lib.crescent_city_bb_fab1(sch_1):smb_ddr_ghj_vpp_scl"
				( signalRef "@baseboard_fab2_lib.baseboard_fab2(sch_1):smb_ddr_ghj_vpp_scl_r" )
				( signalRef "@baseboard_fab2_lib.baseboard_fab2(sch_1):smb_ddr_ghj_vpp_scl" )
				( objectStatus "SMB_DDR_GHJ_VPP_SCL" )
			)
			( electricalNet "@crescent_city_bb_fab1_lib.crescent_city_bb_fab1(sch_1):smb_ddr_def_vpp_sda"
				( signalRef "@baseboard_fab2_lib.baseboard_fab2(sch_1):smb_ddr_def_vpp_sda_r" )
				( signalRef "@baseboard_fab2_lib.baseboard_fab2(sch_1):smb_ddr_def_vpp_sda" )
				( objectStatus "SMB_DDR_DEF_VPP_SDA" )
			)
			( electricalNet "@crescent_city_bb_fab1_lib.crescent_city_bb_fab1(sch_1):smb_ddr_def_vpp_scl"
				( signalRef "@baseboard_fab2_lib.baseboard_fab2(sch_1):smb_ddr_def_vpp_scl_r" )
				( signalRef "@baseboard_fab2_lib.baseboard_fab2(sch_1):smb_ddr_def_vpp_scl" )
				( objectStatus "SMB_DDR_DEF_VPP_SCL" )
			)
			( electricalNet "@crescent_city_bb_fab1_lib.crescent_city_bb_fab1(sch_1):smb_ddr_abc_vpp_sda"
				( signalRef "@baseboard_fab2_lib.baseboard_fab2(sch_1):smb_ddr_abc_vpp_sda_r" )
				( signalRef "@baseboard_fab2_lib.baseboard_fab2(sch_1):smb_ddr_abc_vpp_sda" )
				( objectStatus "SMB_DDR_ABC_VPP_SDA" )
			)
			( electricalNet "@crescent_city_bb_fab1_lib.crescent_city_bb_fab1(sch_1):smb_ddr_abc_vpp_scl"
				( signalRef "@baseboard_fab2_lib.baseboard_fab2(sch_1):smb_ddr_abc_vpp_scl_r" )
				( signalRef "@baseboard_fab2_lib.baseboard_fab2(sch_1):smb_ddr_abc_vpp_scl" )
				( objectStatus "SMB_DDR_ABC_VPP_SCL" )
			)
			( electricalNet "@crescent_city_bb_fab1_lib.crescent_city_bb_fab1(sch_1):smb_ddr_klm_sda_g"
				( signalRef "@baseboard_fab2_lib.baseboard_fab2(sch_1):smb_ddr_klm_sda_g_r" )
				( signalRef "@baseboard_fab2_lib.baseboard_fab2(sch_1):smb_ddr_klm_sda_g" )
				( objectStatus "SMB_DDR_KLM_SDA_G" )
			)
			( electricalNet "@crescent_city_bb_fab1_lib.crescent_city_bb_fab1(sch_1):smb_ddr_klm_scl_g"
				( signalRef "@baseboard_fab2_lib.baseboard_fab2(sch_1):smb_ddr_klm_scl_g_r" )
				( signalRef "@baseboard_fab2_lib.baseboard_fab2(sch_1):smb_ddr_klm_scl_g" )
				( objectStatus "SMB_DDR_KLM_SCL_G" )
			)
			( electricalNet "@crescent_city_bb_fab1_lib.crescent_city_bb_fab1(sch_1):smb_ddr_ghj_sda_g"
				( signalRef "@baseboard_fab2_lib.baseboard_fab2(sch_1):smb_ddr_ghj_sda_g_r" )
				( signalRef "@baseboard_fab2_lib.baseboard_fab2(sch_1):smb_ddr_ghj_sda_g" )
				( objectStatus "SMB_DDR_GHJ_SDA_G" )
			)
			( electricalNet "@crescent_city_bb_fab1_lib.crescent_city_bb_fab1(sch_1):smb_ddr_ghj_scl_g"
				( signalRef "@baseboard_fab2_lib.baseboard_fab2(sch_1):smb_ddr_ghj_scl_g_r" )
				( signalRef "@baseboard_fab2_lib.baseboard_fab2(sch_1):smb_ddr_ghj_scl_g" )
				( objectStatus "SMB_DDR_GHJ_SCL_G" )
			)
			( electricalNet "@crescent_city_bb_fab1_lib.crescent_city_bb_fab1(sch_1):smb_ddr_def_sda_g"
				( signalRef "@baseboard_fab2_lib.baseboard_fab2(sch_1):smb_ddr_def_sda_g_r" )
				( signalRef "@baseboard_fab2_lib.baseboard_fab2(sch_1):smb_ddr_def_sda_g" )
				( objectStatus "SMB_DDR_DEF_SDA_G" )
			)
			( electricalNet "@crescent_city_bb_fab1_lib.crescent_city_bb_fab1(sch_1):smb_ddr_def_scl_g"
				( signalRef "@baseboard_fab2_lib.baseboard_fab2(sch_1):smb_ddr_def_scl_g_r" )
				( signalRef "@baseboard_fab2_lib.baseboard_fab2(sch_1):smb_ddr_def_scl_g" )
				( objectStatus "SMB_DDR_DEF_SCL_G" )
			)
			( electricalNet "@crescent_city_bb_fab1_lib.crescent_city_bb_fab1(sch_1):smb_ddr_abc_sda_g"
				( signalRef "@baseboard_fab2_lib.baseboard_fab2(sch_1):smb_ddr_abc_sda_g_r" )
				( signalRef "@baseboard_fab2_lib.baseboard_fab2(sch_1):smb_ddr_abc_sda_g" )
				( objectStatus "SMB_DDR_ABC_SDA_G" )
			)
			( electricalNet "@crescent_city_bb_fab1_lib.crescent_city_bb_fab1(sch_1):smb_ddr_abc_scl_g"
				( signalRef "@baseboard_fab2_lib.baseboard_fab2(sch_1):smb_ddr_abc_scl_g_r" )
				( signalRef "@baseboard_fab2_lib.baseboard_fab2(sch_1):smb_ddr_abc_scl_g" )
				( objectStatus "SMB_DDR_ABC_SCL_G" )
			)
			( electricalNet "@crescent_city_bb_fab1_lib.crescent_city_bb_fab1(sch_1):pe_pch_sprv_tx_c_dn"
				( signalRef "@baseboard_fab2_lib.baseboard_fab2(sch_1):pe_pch_sprv_tx_dn" )
				( signalRef "@baseboard_fab2_lib.baseboard_fab2(sch_1):pe_pch_sprv_tx_c_dn" )
				( objectStatus "PE_PCH_SPRV_TX_C_DN" )
			)
			( electricalNet "@crescent_city_bb_fab1_lib.crescent_city_bb_fab1(sch_1):pe_pch_sprv_tx_c_dp"
				( signalRef "@baseboard_fab2_lib.baseboard_fab2(sch_1):pe_pch_sprv_tx_dp" )
				( signalRef "@baseboard_fab2_lib.baseboard_fab2(sch_1):pe_pch_sprv_tx_c_dp" )
				( objectStatus "PE_PCH_SPRV_TX_C_DP" )
			)
			( electricalNet "@crescent_city_bb_fab1_lib.crescent_city_bb_fab1(sch_1):nic_mdi_sprv_rj45_3_r_dn"
				( signalRef "@baseboard_fab2_lib.baseboard_fab2(sch_1):nic_ser_n_mdi_3_dn" )
				( signalRef "@baseboard_fab2_lib.baseboard_fab2(sch_1):nic_mdi_sprv_rj45_3_r_dn" )
				( electricalCSetRef "@crescent_city_bb_fab1_lib.crescent_city_bb_fab1(sch_1):\NIC_MDI_2-3\" )
				( objectStatus "NIC_SER_N_MDI_3_DN" )
			)
			( electricalNet "@crescent_city_bb_fab1_lib.crescent_city_bb_fab1(sch_1):nic_mdi_sprv_rj45_3_r_dp"
				( signalRef "@baseboard_fab2_lib.baseboard_fab2(sch_1):nic_ser_p_mdi_3_dp" )
				( signalRef "@baseboard_fab2_lib.baseboard_fab2(sch_1):nic_mdi_sprv_rj45_3_r_dp" )
				( electricalCSetRef "@crescent_city_bb_fab1_lib.crescent_city_bb_fab1(sch_1):\NIC_MDI_2-3\" )
				( objectStatus "NIC_SER_P_MDI_3_DP" )
			)
			( electricalNet "@crescent_city_bb_fab1_lib.crescent_city_bb_fab1(sch_1):nic_mdi_sprv_rj45_2_r_dn"
				( signalRef "@baseboard_fab2_lib.baseboard_fab2(sch_1):nic_set_n_mdi_2_dn" )
				( signalRef "@baseboard_fab2_lib.baseboard_fab2(sch_1):nic_mdi_sprv_rj45_2_r_dn" )
				( electricalCSetRef "@crescent_city_bb_fab1_lib.crescent_city_bb_fab1(sch_1):\NIC_MDI_2-3\" )
				( objectStatus "NIC_SET_N_MDI_2_DN" )
			)
			( electricalNet "@crescent_city_bb_fab1_lib.crescent_city_bb_fab1(sch_1):nic_mdi_sprv_rj45_2_r_dp"
				( signalRef "@baseboard_fab2_lib.baseboard_fab2(sch_1):nic_set_p_mdi_2_dp" )
				( signalRef "@baseboard_fab2_lib.baseboard_fab2(sch_1):nic_mdi_sprv_rj45_2_r_dp" )
				( objectStatus "NIC_SET_P_MDI_2_DP" )
			)
			( electricalNet "@crescent_city_bb_fab1_lib.crescent_city_bb_fab1(sch_1):sata6g_p0_rx_c_dn"
				( signalRef "@baseboard_fab2_lib.baseboard_fab2(sch_1):sata6g_p0_rx_c_dn" )
				( signalRef "@baseboard_fab2_lib.baseboard_fab2(sch_1):sata6g_pch_pcie_up_sata_rxn(0)" )
				( objectStatus "SATA6G_P0_RX_C_DN" )
			)
			( electricalNet "@crescent_city_bb_fab1_lib.crescent_city_bb_fab1(sch_1):sata6g_p0_rx_c_dp"
				( signalRef "@baseboard_fab2_lib.baseboard_fab2(sch_1):sata6g_pch_pcie_up_sata_rxp(0)" )
				( signalRef "@baseboard_fab2_lib.baseboard_fab2(sch_1):sata6g_p0_rx_c_dp" )
				( objectStatus "SATA6G_P0_RX_C_DP" )
			)
			( electricalNet "@crescent_city_bb_fab1_lib.crescent_city_bb_fab1(sch_1):sata6g_p1_rx_c_dn"
				( signalRef "@baseboard_fab2_lib.baseboard_fab2(sch_1):sata6g_p1_rx_c_dn" )
				( signalRef "@baseboard_fab2_lib.baseboard_fab2(sch_1):sata6g_pch_pcie_up_sata_rxn(1)" )
				( objectStatus "SATA6G_P1_RX_C_DN" )
			)
			( electricalNet "@crescent_city_bb_fab1_lib.crescent_city_bb_fab1(sch_1):sata6g_p1_rx_c_dp"
				( signalRef "@baseboard_fab2_lib.baseboard_fab2(sch_1):sata6g_pch_pcie_up_sata_rxp(1)" )
				( signalRef "@baseboard_fab2_lib.baseboard_fab2(sch_1):sata6g_p1_rx_c_dp" )
				( objectStatus "SATA6G_P1_RX_C_DP" )
			)
			( electricalNet "@crescent_city_bb_fab1_lib.crescent_city_bb_fab1(sch_1):sata6g_p2_rx_c_dn"
				( signalRef "@baseboard_fab2_lib.baseboard_fab2(sch_1):sata6g_p2_rx_c_dn" )
				( signalRef "@baseboard_fab2_lib.baseboard_fab2(sch_1):sata6g_pch_pcie_up_sata_rxn(2)" )
				( objectStatus "SATA6G_P2_RX_C_DN" )
			)
			( electricalNet "@crescent_city_bb_fab1_lib.crescent_city_bb_fab1(sch_1):sata6g_p2_rx_c_dp"
				( signalRef "@baseboard_fab2_lib.baseboard_fab2(sch_1):sata6g_pch_pcie_up_sata_rxp(2)" )
				( signalRef "@baseboard_fab2_lib.baseboard_fab2(sch_1):sata6g_p2_rx_c_dp" )
				( objectStatus "SATA6G_P2_RX_C_DP" )
			)
			( electricalNet "@crescent_city_bb_fab1_lib.crescent_city_bb_fab1(sch_1):sata6g_p3_rx_c_dn"
				( signalRef "@baseboard_fab2_lib.baseboard_fab2(sch_1):sata6g_p3_rx_c_dn" )
				( signalRef "@baseboard_fab2_lib.baseboard_fab2(sch_1):sata6g_pch_pcie_up_sata_rxn(3)" )
				( objectStatus "SATA6G_P3_RX_C_DN" )
			)
			( electricalNet "@crescent_city_bb_fab1_lib.crescent_city_bb_fab1(sch_1):sata6g_p3_rx_c_dp"
				( signalRef "@baseboard_fab2_lib.baseboard_fab2(sch_1):sata6g_pch_pcie_up_sata_rxp(3)" )
				( signalRef "@baseboard_fab2_lib.baseboard_fab2(sch_1):sata6g_p3_rx_c_dp" )
				( objectStatus "SATA6G_P3_RX_C_DP" )
			)
			( electricalNet "@crescent_city_bb_fab1_lib.crescent_city_bb_fab1(sch_1):sata6g_p4_rx_c_dn"
				( signalRef "@baseboard_fab2_lib.baseboard_fab2(sch_1):sata6g_p4_rx_c_dn" )
				( signalRef "@baseboard_fab2_lib.baseboard_fab2(sch_1):sata6g_pch_pcie_up_sata_rxn(4)" )
				( objectStatus "SATA6G_P4_RX_C_DN" )
			)
			( electricalNet "@crescent_city_bb_fab1_lib.crescent_city_bb_fab1(sch_1):sata6g_p4_rx_c_dp"
				( signalRef "@baseboard_fab2_lib.baseboard_fab2(sch_1):sata6g_pch_pcie_up_sata_rxp(4)" )
				( signalRef "@baseboard_fab2_lib.baseboard_fab2(sch_1):sata6g_p4_rx_c_dp" )
				( objectStatus "SATA6G_P4_RX_C_DP" )
			)
			( electricalNet "@crescent_city_bb_fab1_lib.crescent_city_bb_fab1(sch_1):sata6g_p5_rx_c_dn"
				( signalRef "@baseboard_fab2_lib.baseboard_fab2(sch_1):sata6g_p5_rx_c_dn" )
				( signalRef "@baseboard_fab2_lib.baseboard_fab2(sch_1):sata6g_pch_pcie_up_sata_rxn(5)" )
				( objectStatus "SATA6G_P5_RX_C_DN" )
			)
			( electricalNet "@crescent_city_bb_fab1_lib.crescent_city_bb_fab1(sch_1):sata6g_p5_rx_c_dp"
				( signalRef "@baseboard_fab2_lib.baseboard_fab2(sch_1):sata6g_pch_pcie_up_sata_rxp(5)" )
				( signalRef "@baseboard_fab2_lib.baseboard_fab2(sch_1):sata6g_p5_rx_c_dp" )
				( objectStatus "SATA6G_P5_RX_C_DP" )
			)
			( electricalNet "@crescent_city_bb_fab1_lib.crescent_city_bb_fab1(sch_1):sata6g_p6_rx_c_dn"
				( signalRef "@baseboard_fab2_lib.baseboard_fab2(sch_1):sata6g_p6_rx_c_dn" )
				( signalRef "@baseboard_fab2_lib.baseboard_fab2(sch_1):sata6g_pch_pcie_up_sata_rxn(6)" )
				( objectStatus "SATA6G_P6_RX_C_DN" )
			)
			( electricalNet "@crescent_city_bb_fab1_lib.crescent_city_bb_fab1(sch_1):sata6g_p6_rx_c_dp"
				( signalRef "@baseboard_fab2_lib.baseboard_fab2(sch_1):sata6g_pch_pcie_up_sata_rxp(6)" )
				( signalRef "@baseboard_fab2_lib.baseboard_fab2(sch_1):sata6g_p6_rx_c_dp" )
				( objectStatus "SATA6G_P6_RX_C_DP" )
			)
			( electricalNet "@crescent_city_bb_fab1_lib.crescent_city_bb_fab1(sch_1):sata6g_p7_rx_c_dn"
				( signalRef "@baseboard_fab2_lib.baseboard_fab2(sch_1):sata6g_p7_rx_c_dn" )
				( signalRef "@baseboard_fab2_lib.baseboard_fab2(sch_1):sata6g_pch_pcie_up_sata_rxn(7)" )
				( objectStatus "SATA6G_P7_RX_C_DN" )
			)
			( electricalNet "@crescent_city_bb_fab1_lib.crescent_city_bb_fab1(sch_1):sata6g_p7_rx_c_dp"
				( signalRef "@baseboard_fab2_lib.baseboard_fab2(sch_1):sata6g_pch_pcie_up_sata_rxp(7)" )
				( signalRef "@baseboard_fab2_lib.baseboard_fab2(sch_1):sata6g_p7_rx_c_dp" )
				( objectStatus "SATA6G_P7_RX_C_DP" )
			)
			( electricalNet "@crescent_city_bb_fab1_lib.crescent_city_bb_fab1(sch_1):sata6g_p0_tx_c_dn"
				( signalRef "@baseboard_fab2_lib.baseboard_fab2(sch_1):sata6g_pch_pcie_up_sata_txn(0)" )
				( signalRef "@baseboard_fab2_lib.baseboard_fab2(sch_1):sata6g_p0_tx_c_dn" )
				( objectStatus "SATA6G_P0_TX_C_DN" )
			)
			( electricalNet "@crescent_city_bb_fab1_lib.crescent_city_bb_fab1(sch_1):sata6g_p0_tx_c_dp"
				( signalRef "@baseboard_fab2_lib.baseboard_fab2(sch_1):sata6g_p0_tx_c_dp" )
				( signalRef "@baseboard_fab2_lib.baseboard_fab2(sch_1):sata6g_pch_pcie_up_sata_txp(0)" )
				( objectStatus "SATA6G_P0_TX_C_DP" )
			)
			( electricalNet "@crescent_city_bb_fab1_lib.crescent_city_bb_fab1(sch_1):sata6g_p1_tx_c_dn"
				( signalRef "@baseboard_fab2_lib.baseboard_fab2(sch_1):sata6g_pch_pcie_up_sata_txn(1)" )
				( signalRef "@baseboard_fab2_lib.baseboard_fab2(sch_1):sata6g_p1_tx_c_dn" )
				( objectStatus "SATA6G_P1_TX_C_DN" )
			)
			( electricalNet "@crescent_city_bb_fab1_lib.crescent_city_bb_fab1(sch_1):sata6g_p1_tx_c_dp"
				( signalRef "@baseboard_fab2_lib.baseboard_fab2(sch_1):sata6g_p1_tx_c_dp" )
				( signalRef "@baseboard_fab2_lib.baseboard_fab2(sch_1):sata6g_pch_pcie_up_sata_txp(1)" )
				( objectStatus "SATA6G_P1_TX_C_DP" )
			)
			( electricalNet "@crescent_city_bb_fab1_lib.crescent_city_bb_fab1(sch_1):sata6g_p2_tx_c_dn"
				( signalRef "@baseboard_fab2_lib.baseboard_fab2(sch_1):sata6g_pch_pcie_up_sata_txn(2)" )
				( signalRef "@baseboard_fab2_lib.baseboard_fab2(sch_1):sata6g_p2_tx_c_dn" )
				( objectStatus "SATA6G_P2_TX_C_DN" )
			)
			( electricalNet "@crescent_city_bb_fab1_lib.crescent_city_bb_fab1(sch_1):sata6g_p2_tx_c_dp"
				( signalRef "@baseboard_fab2_lib.baseboard_fab2(sch_1):sata6g_p2_tx_c_dp" )
				( signalRef "@baseboard_fab2_lib.baseboard_fab2(sch_1):sata6g_pch_pcie_up_sata_txp(2)" )
				( objectStatus "SATA6G_P2_TX_C_DP" )
			)
			( electricalNet "@crescent_city_bb_fab1_lib.crescent_city_bb_fab1(sch_1):sata6g_p3_tx_c_dn"
				( signalRef "@baseboard_fab2_lib.baseboard_fab2(sch_1):sata6g_pch_pcie_up_sata_txn(3)" )
				( signalRef "@baseboard_fab2_lib.baseboard_fab2(sch_1):sata6g_p3_tx_c_dn" )
				( objectStatus "SATA6G_P3_TX_C_DN" )
			)
			( electricalNet "@crescent_city_bb_fab1_lib.crescent_city_bb_fab1(sch_1):sata6g_p3_tx_c_dp"
				( signalRef "@baseboard_fab2_lib.baseboard_fab2(sch_1):sata6g_p3_tx_c_dp" )
				( signalRef "@baseboard_fab2_lib.baseboard_fab2(sch_1):sata6g_pch_pcie_up_sata_txp(3)" )
				( objectStatus "SATA6G_P3_TX_C_DP" )
			)
			( electricalNet "@crescent_city_bb_fab1_lib.crescent_city_bb_fab1(sch_1):sata6g_p4_tx_c_dn"
				( signalRef "@baseboard_fab2_lib.baseboard_fab2(sch_1):sata6g_pch_pcie_up_sata_txn(4)" )
				( signalRef "@baseboard_fab2_lib.baseboard_fab2(sch_1):sata6g_p4_tx_c_dn" )
				( objectStatus "SATA6G_P4_TX_C_DN" )
			)
			( electricalNet "@crescent_city_bb_fab1_lib.crescent_city_bb_fab1(sch_1):sata6g_p4_tx_c_dp"
				( signalRef "@baseboard_fab2_lib.baseboard_fab2(sch_1):sata6g_p4_tx_c_dp" )
				( signalRef "@baseboard_fab2_lib.baseboard_fab2(sch_1):sata6g_pch_pcie_up_sata_txp(4)" )
				( objectStatus "SATA6G_P4_TX_C_DP" )
			)
			( electricalNet "@crescent_city_bb_fab1_lib.crescent_city_bb_fab1(sch_1):sata6g_p5_tx_c_dn"
				( signalRef "@baseboard_fab2_lib.baseboard_fab2(sch_1):sata6g_pch_pcie_up_sata_txn(5)" )
				( signalRef "@baseboard_fab2_lib.baseboard_fab2(sch_1):sata6g_p5_tx_c_dn" )
				( objectStatus "SATA6G_P5_TX_C_DN" )
			)
			( electricalNet "@crescent_city_bb_fab1_lib.crescent_city_bb_fab1(sch_1):sata6g_p5_tx_c_dp"
				( signalRef "@baseboard_fab2_lib.baseboard_fab2(sch_1):sata6g_p5_tx_c_dp" )
				( signalRef "@baseboard_fab2_lib.baseboard_fab2(sch_1):sata6g_pch_pcie_up_sata_txp(5)" )
				( objectStatus "SATA6G_P5_TX_C_DP" )
			)
			( electricalNet "@crescent_city_bb_fab1_lib.crescent_city_bb_fab1(sch_1):sata6g_p6_tx_c_dn"
				( signalRef "@baseboard_fab2_lib.baseboard_fab2(sch_1):sata6g_pch_pcie_up_sata_txn(6)" )
				( signalRef "@baseboard_fab2_lib.baseboard_fab2(sch_1):sata6g_p6_tx_c_dn" )
				( objectStatus "SATA6G_P6_TX_C_DN" )
			)
			( electricalNet "@crescent_city_bb_fab1_lib.crescent_city_bb_fab1(sch_1):sata6g_p6_tx_c_dp"
				( signalRef "@baseboard_fab2_lib.baseboard_fab2(sch_1):sata6g_p6_tx_c_dp" )
				( signalRef "@baseboard_fab2_lib.baseboard_fab2(sch_1):sata6g_pch_pcie_up_sata_txp(6)" )
				( objectStatus "SATA6G_P6_TX_C_DP" )
			)
			( electricalNet "@crescent_city_bb_fab1_lib.crescent_city_bb_fab1(sch_1):sata6g_p7_tx_c_dn"
				( signalRef "@baseboard_fab2_lib.baseboard_fab2(sch_1):sata6g_pch_pcie_up_sata_txn(7)" )
				( signalRef "@baseboard_fab2_lib.baseboard_fab2(sch_1):sata6g_p7_tx_c_dn" )
				( objectStatus "SATA6G_P7_TX_C_DN" )
			)
			( electricalNet "@crescent_city_bb_fab1_lib.crescent_city_bb_fab1(sch_1):sata6g_p7_tx_c_dp"
				( signalRef "@baseboard_fab2_lib.baseboard_fab2(sch_1):sata6g_p7_tx_c_dp" )
				( signalRef "@baseboard_fab2_lib.baseboard_fab2(sch_1):sata6g_pch_pcie_up_sata_txp(7)" )
				( objectStatus "SATA6G_P7_TX_C_DP" )
			)
			( electricalNet "@crescent_city_bb_fab1_lib.crescent_city_bb_fab1(sch_1):sata6g_p8_rx_c_dn"
				( signalRef "@baseboard_fab2_lib.baseboard_fab2(sch_1):sata6g_rx_dn(0)" )
				( signalRef "@baseboard_fab2_lib.baseboard_fab2(sch_1):sata6g_p8_rx_c_dn" )
				( objectStatus "SATA6G_P8_RX_C_DN" )
			)
			( electricalNet "@crescent_city_bb_fab1_lib.crescent_city_bb_fab1(sch_1):sata6g_p8_rx_c_dp"
				( signalRef "@baseboard_fab2_lib.baseboard_fab2(sch_1):sata6g_p8_rx_c_dp" )
				( signalRef "@baseboard_fab2_lib.baseboard_fab2(sch_1):sata6g_rx_dp(0)" )
				( objectStatus "SATA6G_P8_RX_C_DP" )
			)
			( electricalNet "@crescent_city_bb_fab1_lib.crescent_city_bb_fab1(sch_1):sata6g_p9_rx_c_dn"
				( signalRef "@baseboard_fab2_lib.baseboard_fab2(sch_1):sata6g_rx_dn(1)" )
				( signalRef "@baseboard_fab2_lib.baseboard_fab2(sch_1):sata6g_p9_rx_c_dn" )
				( objectStatus "SATA6G_P9_RX_C_DN" )
			)
			( electricalNet "@crescent_city_bb_fab1_lib.crescent_city_bb_fab1(sch_1):sata6g_p9_rx_c_dp"
				( signalRef "@baseboard_fab2_lib.baseboard_fab2(sch_1):sata6g_p9_rx_c_dp" )
				( signalRef "@baseboard_fab2_lib.baseboard_fab2(sch_1):sata6g_rx_dp(1)" )
				( objectStatus "SATA6G_P9_RX_C_DP" )
			)
			( electricalNet "@crescent_city_bb_fab1_lib.crescent_city_bb_fab1(sch_1):sata6g_p10_rx_c_dn"
				( signalRef "@baseboard_fab2_lib.baseboard_fab2(sch_1):sata6g_rx_dn(2)" )
				( signalRef "@baseboard_fab2_lib.baseboard_fab2(sch_1):sata6g_p10_rx_c_dn" )
				( objectStatus "SATA6G_P10_RX_C_DN" )
			)
			( electricalNet "@crescent_city_bb_fab1_lib.crescent_city_bb_fab1(sch_1):sata6g_p10_rx_c_dp"
				( signalRef "@baseboard_fab2_lib.baseboard_fab2(sch_1):sata6g_p10_rx_c_dp" )
				( signalRef "@baseboard_fab2_lib.baseboard_fab2(sch_1):sata6g_rx_dp(2)" )
				( objectStatus "SATA6G_P10_RX_C_DP" )
			)
			( electricalNet "@crescent_city_bb_fab1_lib.crescent_city_bb_fab1(sch_1):sata6g_p11_rx_c_dn"
				( signalRef "@baseboard_fab2_lib.baseboard_fab2(sch_1):sata6g_rx_dn(3)" )
				( signalRef "@baseboard_fab2_lib.baseboard_fab2(sch_1):sata6g_p11_rx_c_dn" )
				( objectStatus "SATA6G_P11_RX_C_DN" )
			)
			( electricalNet "@crescent_city_bb_fab1_lib.crescent_city_bb_fab1(sch_1):sata6g_p11_rx_c_dp"
				( signalRef "@baseboard_fab2_lib.baseboard_fab2(sch_1):sata6g_p11_rx_c_dp" )
				( signalRef "@baseboard_fab2_lib.baseboard_fab2(sch_1):sata6g_rx_dp(3)" )
				( objectStatus "SATA6G_P11_RX_C_DP" )
			)
			( electricalNet "@crescent_city_bb_fab1_lib.crescent_city_bb_fab1(sch_1):sata6g_s1_rx_c_dn"
				( signalRef "@baseboard_fab2_lib.baseboard_fab2(sch_1):sata6g_s1_rx_c_dn" )
				( signalRef "@baseboard_fab2_lib.baseboard_fab2(sch_1):sata6g_s1_rx_dn" )
				( objectStatus "SATA6G_S1_RX_C_DN" )
			)
			( electricalNet "@crescent_city_bb_fab1_lib.crescent_city_bb_fab1(sch_1):sata6g_s1_rx_c_dp"
				( signalRef "@baseboard_fab2_lib.baseboard_fab2(sch_1):sata6g_s1_rx_dp" )
				( signalRef "@baseboard_fab2_lib.baseboard_fab2(sch_1):sata6g_s1_rx_c_dp" )
				( objectStatus "SATA6G_S1_RX_C_DP" )
			)
			( electricalNet "@crescent_city_bb_fab1_lib.crescent_city_bb_fab1(sch_1):sata6g_s1_tx_c_dn"
				( signalRef "@baseboard_fab2_lib.baseboard_fab2(sch_1):sata6g_s1_tx_c_dn" )
				( signalRef "@baseboard_fab2_lib.baseboard_fab2(sch_1):sata6g_s1_tx_dn" )
				( objectStatus "SATA6G_S1_TX_C_DN" )
			)
			( electricalNet "@crescent_city_bb_fab1_lib.crescent_city_bb_fab1(sch_1):sata6g_s1_tx_c_dp"
				( signalRef "@baseboard_fab2_lib.baseboard_fab2(sch_1):sata6g_s1_tx_dp" )
				( signalRef "@baseboard_fab2_lib.baseboard_fab2(sch_1):sata6g_s1_tx_c_dp" )
				( objectStatus "SATA6G_S1_TX_C_DP" )
			)
			( electricalNet "@crescent_city_bb_fab1_lib.crescent_city_bb_fab1(sch_1):sata6g_p8_tx_c_dn"
				( signalRef "@baseboard_fab2_lib.baseboard_fab2(sch_1):sata6g_tx_dn(0)" )
				( signalRef "@baseboard_fab2_lib.baseboard_fab2(sch_1):sata6g_p8_tx_c_dn" )
				( objectStatus "SATA6G_P8_TX_C_DN" )
			)
			( electricalNet "@crescent_city_bb_fab1_lib.crescent_city_bb_fab1(sch_1):sata6g_p8_tx_c_dp"
				( signalRef "@baseboard_fab2_lib.baseboard_fab2(sch_1):sata6g_p8_tx_c_dp" )
				( signalRef "@baseboard_fab2_lib.baseboard_fab2(sch_1):sata6g_tx_dp(0)" )
				( objectStatus "SATA6G_P8_TX_C_DP" )
			)
			( electricalNet "@crescent_city_bb_fab1_lib.crescent_city_bb_fab1(sch_1):sata6g_p9_tx_c_dn"
				( signalRef "@baseboard_fab2_lib.baseboard_fab2(sch_1):sata6g_tx_dn(1)" )
				( signalRef "@baseboard_fab2_lib.baseboard_fab2(sch_1):sata6g_p9_tx_c_dn" )
				( objectStatus "SATA6G_P9_TX_C_DN" )
			)
			( electricalNet "@crescent_city_bb_fab1_lib.crescent_city_bb_fab1(sch_1):sata6g_p9_tx_c_dp"
				( signalRef "@baseboard_fab2_lib.baseboard_fab2(sch_1):sata6g_p9_tx_c_dp" )
				( signalRef "@baseboard_fab2_lib.baseboard_fab2(sch_1):sata6g_tx_dp(1)" )
				( objectStatus "SATA6G_P9_TX_C_DP" )
			)
			( electricalNet "@crescent_city_bb_fab1_lib.crescent_city_bb_fab1(sch_1):sata6g_p10_tx_c_dn"
				( signalRef "@baseboard_fab2_lib.baseboard_fab2(sch_1):sata6g_tx_dn(2)" )
				( signalRef "@baseboard_fab2_lib.baseboard_fab2(sch_1):sata6g_p10_tx_c_dn" )
				( objectStatus "SATA6G_P10_TX_C_DN" )
			)
			( electricalNet "@crescent_city_bb_fab1_lib.crescent_city_bb_fab1(sch_1):sata6g_p10_tx_c_dp"
				( signalRef "@baseboard_fab2_lib.baseboard_fab2(sch_1):sata6g_p10_tx_c_dp" )
				( signalRef "@baseboard_fab2_lib.baseboard_fab2(sch_1):sata6g_tx_dp(2)" )
				( objectStatus "SATA6G_P10_TX_C_DP" )
			)
			( electricalNet "@crescent_city_bb_fab1_lib.crescent_city_bb_fab1(sch_1):sata6g_p11_tx_c_dn"
				( signalRef "@baseboard_fab2_lib.baseboard_fab2(sch_1):sata6g_tx_dn(3)" )
				( signalRef "@baseboard_fab2_lib.baseboard_fab2(sch_1):sata6g_p11_tx_c_dn" )
				( objectStatus "SATA6G_P11_TX_C_DN" )
			)
			( electricalNet "@crescent_city_bb_fab1_lib.crescent_city_bb_fab1(sch_1):sata6g_p11_tx_c_dp"
				( signalRef "@baseboard_fab2_lib.baseboard_fab2(sch_1):sata6g_p11_tx_c_dp" )
				( signalRef "@baseboard_fab2_lib.baseboard_fab2(sch_1):sata6g_tx_dp(3)" )
				( objectStatus "SATA6G_P11_TX_C_DP" )
			)
			( electricalNet "@crescent_city_bb_fab1_lib.crescent_city_bb_fab1(sch_1):rmii_bmc_pch_sprngvlle_rxer"
				( signalRef "@baseboard_fab2_lib.baseboard_fab2(sch_1):rmii_bmc_pch_sprngvlle_rxer_r" )
				( signalRef "@baseboard_fab2_lib.baseboard_fab2(sch_1):rmii_bmc_pch_sprngvlle_rxer" )
				( objectStatus "RMII_BMC_PCH_SPRNGVLLE_RXER" )
			)
			( electricalNet "@crescent_city_bb_fab1_lib.crescent_city_bb_fab1(sch_1):rmii_bmc_pch_sprngvlle_crsdv"
				( signalRef "@baseboard_fab2_lib.baseboard_fab2(sch_1):rmii_bmc_pch_sprngvlle_crsdv_r1" )
				( signalRef "@baseboard_fab2_lib.baseboard_fab2(sch_1):rmii_bmc_pch_sprngvlle_crsdv" )
				( signalRef "@baseboard_fab2_lib.baseboard_fab2(sch_1):rmii_bmc_pch_sprngvlle_crsdv_r" )
				( electricalCSetRef "@crescent_city_bb_fab1_lib.crescent_city_bb_fab1(sch_1):\RMII_RX_NEW\" )
				( pinPairRef "@baseboard_fab2_lib.baseboard_fab2(sch_1):\PP6092\" )
				( objectStatus "RMII_BMC_PCH_SPRNGVLLE_CRSDV" )
			)
			( electricalNet "@crescent_city_bb_fab1_lib.crescent_city_bb_fab1(sch_1):clk_50m_ckmng_ocp"
				( signalRef "@baseboard_fab2_lib.baseboard_fab2(sch_1):clk_50m_ckmng_ocp_r" )
				( signalRef "@baseboard_fab2_lib.baseboard_fab2(sch_1):clk_50m_ckmng_ocp" )
				( objectStatus "CLK_50M_CKMNG_OCP" )
			)
			( electricalNet "@crescent_city_bb_fab1_lib.crescent_city_bb_fab1(sch_1):clk_50m_ckmng_bmc_1"
				( signalRef "@baseboard_fab2_lib.baseboard_fab2(sch_1):clk_50m_ckmng_bmc_1_r" )
				( signalRef "@baseboard_fab2_lib.baseboard_fab2(sch_1):clk_50m_ckmng_bmc_1" )
				( pinPairRef "@baseboard_fab2_lib.baseboard_fab2(sch_1):\PP5810\" )
				( objectStatus "CLK_50M_CKMNG_BMC_1" )
			)
			( electricalNet "@crescent_city_bb_fab1_lib.crescent_city_bb_fab1(sch_1):clk_50m_nic"
				( signalRef "@baseboard_fab2_lib.baseboard_fab2(sch_1):clk_50m_ckmng_pch_10gbe_r" )
				( signalRef "@baseboard_fab2_lib.baseboard_fab2(sch_1):clk_50m_ckmng_pch_10gbe" )
				( objectStatus "CLK_50M_CKMNG_PCH_10GBE" )
			)
			( electricalNet "@crescent_city_bb_fab1_lib.crescent_city_bb_fab1(sch_1):clk_50m_ckmng_bmc_2"
				( signalRef "@baseboard_fab2_lib.baseboard_fab2(sch_1):clk_50m_ckmng_bmc_2" )
				( signalRef "@baseboard_fab2_lib.baseboard_fab2(sch_1):clk_50m_ckmng_bmc_2_r" )
				( pinPairRef "@baseboard_fab2_lib.baseboard_fab2(sch_1):\PP5800\" )
				( objectStatus "CLK_50M_CKMNG_BMC_2" )
			)
			( electricalNet "@crescent_city_bb_fab1_lib.crescent_city_bb_fab1(sch_1):clk_50m_ckmng_sprvlle"
				( signalRef "@baseboard_fab2_lib.baseboard_fab2(sch_1):clk_50m_ckmng_sprvlle" )
				( signalRef "@baseboard_fab2_lib.baseboard_fab2(sch_1):clk_50m_ckmng_sprvlle_r" )
				( objectStatus "CLK_50M_CKMNG_SPRVLLE" )
			)
			( electricalNet "@crescent_city_bb_fab1_lib.crescent_city_bb_fab1(sch_1):rmii_pch_sprngvlle_arb_out"
				( signalRef "@baseboard_fab2_lib.baseboard_fab2(sch_1):rmii_pch_sprngvlle_arb_out_r" )
				( signalRef "@baseboard_fab2_lib.baseboard_fab2(sch_1):rmii_pch_sprngvlle_arb_out" )
				( objectStatus "RMII_PCH_SPRNGVLLE_ARB_OUT" )
			)
			( electricalNet "@crescent_city_bb_fab1_lib.crescent_city_bb_fab1(sch_1):rmii_pch_sprngvlle_arb_in"
				( signalRef "@baseboard_fab2_lib.baseboard_fab2(sch_1):rmii_pch_sprngvlle_arb_in_r" )
				( signalRef "@baseboard_fab2_lib.baseboard_fab2(sch_1):rmii_pch_sprngvlle_arb_in" )
				( objectStatus "RMII_PCH_SPRNGVLLE_ARB_IN" )
			)
			( electricalNet "@crescent_city_bb_fab1_lib.crescent_city_bb_fab1(sch_1):usb2_p01_dn"
				( signalRef "@baseboard_fab2_lib.baseboard_fab2(sch_1):usb2_p01_esd_dn" )
				( signalRef "@baseboard_fab2_lib.baseboard_fab2(sch_1):usb2_p01_dn" )
				( objectStatus "USB2_P01_DN" )
			)
			( electricalNet "@crescent_city_bb_fab1_lib.crescent_city_bb_fab1(sch_1):usb2_p01_dp"
				( signalRef "@baseboard_fab2_lib.baseboard_fab2(sch_1):usb2_p01_esd_dp" )
				( signalRef "@baseboard_fab2_lib.baseboard_fab2(sch_1):usb2_p01_dp" )
				( objectStatus "USB2_P01_DP" )
			)
			( electricalNet "@crescent_city_bb_fab1_lib.crescent_city_bb_fab1(sch_1):clk_24m_bmc_lpc"
				( signalRef "@baseboard_fab2_lib.baseboard_fab2(sch_1):clk_24m_bmc_lpc_r" )
				( signalRef "@baseboard_fab2_lib.baseboard_fab2(sch_1):clk_24m_bmc_lpc" )
				( objectStatus "CLK_24M_BMC_LPC" )
			)
			( electricalNet "@crescent_city_bb_fab1_lib.crescent_city_bb_fab1(sch_1):h_pmsync_clk_24m_cpu0"
				( signalRef "@baseboard_fab2_lib.baseboard_fab2(sch_1):h_pmsync_clk_24m" )
				( signalRef "@baseboard_fab2_lib.baseboard_fab2(sch_1):h_pmsync_clk_24m_cpu0" )
				( signalRef "@baseboard_fab2_lib.baseboard_fab2(sch_1):h_pmsync_clk_24m_cpu1" )
				( signalRef "@baseboard_fab2_lib.baseboard_fab2(sch_1):h_pmsync_clk_24m_r" )
				( objectStatus "H_PMSYNC_CLK_24M_CPU0" )
			)
			( electricalNet "@crescent_city_bb_fab1_lib.crescent_city_bb_fab1(sch_1):clk_32k_susclk_pld"
				( signalRef "@baseboard_fab2_lib.baseboard_fab2(sch_1):clk_32k_susclk_pld" )
				( signalRef "@baseboard_fab2_lib.baseboard_fab2(sch_1):clk_32k_susclk_pld_r" )
				( objectStatus "CLK_32K_SUSCLK_PLD" )
			)
			( electricalNet "@crescent_city_bb_fab1_lib.crescent_city_bb_fab1(sch_1):clk_25m_bmc"
				( signalRef "@baseboard_fab2_lib.baseboard_fab2(sch_1):clk_25m_bmc" )
				( signalRef "@baseboard_fab2_lib.baseboard_fab2(sch_1):clk_25m_bmc_r" )
				( objectStatus "CLK_25M_BMC" )
			)
			( electricalNet "@crescent_city_bb_fab1_lib.crescent_city_bb_fab1(sch_1):clk_25m_cpld"
				( signalRef "@baseboard_fab2_lib.baseboard_fab2(sch_1):clk_25m_cpld_r" )
				( signalRef "@baseboard_fab2_lib.baseboard_fab2(sch_1):clk_25m_cpld" )
				( objectStatus "CLK_25M_CPLD" )
			)
			( electricalNet "@crescent_city_bb_fab1_lib.crescent_city_bb_fab1(sch_1):h_cpu_err2_g_r_n"
				( signalRef "@baseboard_fab2_lib.baseboard_fab2(sch_1):h_cpu_err2_gtl_n" )
				( signalRef "@baseboard_fab2_lib.baseboard_fab2(sch_1):h_cpu_err2_g_r_n" )
				( signalRef "@baseboard_fab2_lib.baseboard_fab2(sch_1):h_cpu1_err2_g_n" )
				( signalRef "@baseboard_fab2_lib.baseboard_fab2(sch_1):h_cpu0_err2_g_n" )
				( objectStatus "H_CPU_ERR2_G_R_N" )
			)
			( electricalNet "@crescent_city_bb_fab1_lib.crescent_city_bb_fab1(sch_1):h_cpu0_fast_wake_b_n"
				( signalRef "@baseboard_fab2_lib.baseboard_fab2(sch_1):h_cpu0_fast_wake_b_n" )
				( signalRef "@baseboard_fab2_lib.baseboard_fab2(sch_1):h_cpu0_fast_wake_n" )
				( signalRef "@baseboard_fab2_lib.baseboard_fab2(sch_1):h_cpu1_fast_wake_n" )
				( objectStatus "H_CPU0_FAST_WAKE_B_N" )
			)
			( electricalNet "@crescent_city_bb_fab1_lib.crescent_city_bb_fab1(sch_1):h_pm_sync_gtl_r1"
				( signalRef "@baseboard_fab2_lib.baseboard_fab2(sch_1):h_pm_sync_gtl" )
				( signalRef "@baseboard_fab2_lib.baseboard_fab2(sch_1):h_pm_sync1_gtl_r" )
				( signalRef "@baseboard_fab2_lib.baseboard_fab2(sch_1):h_pm_sync_gtl_r1" )
				( signalRef "@baseboard_fab2_lib.baseboard_fab2(sch_1):h_pm_sync_gtl_r2" )
				( electricalCSetRef "@crescent_city_bb_fab1_lib.crescent_city_bb_fab1(sch_1):\PMSYNC\" )
				( objectStatus "H_PM_SYNC_GTL_R1" )
			)
			( electricalNet "@crescent_city_bb_fab1_lib.crescent_city_bb_fab1(sch_1):h_cpu0_msmi_g_n"
				( signalRef "@baseboard_fab2_lib.baseboard_fab2(sch_1):h_cpu_msmi_g_n" )
				( signalRef "@baseboard_fab2_lib.baseboard_fab2(sch_1):h_cpu1_msmi_g_n" )
				( signalRef "@baseboard_fab2_lib.baseboard_fab2(sch_1):h_cpu0_msmi_g_n" )
				( electricalCSetRef "@crescent_city_bb_fab1_lib.crescent_city_bb_fab1(sch_1):\CATERR\" )
				( pinPairRef "@baseboard_fab2_lib.baseboard_fab2(sch_1):\PP6113\" )
				( pinPairRef "@baseboard_fab2_lib.baseboard_fab2(sch_1):\PP6114\" )
				( objectStatus "H_CPU0_MSMI_G_N" )
			)
			( electricalNet "@crescent_city_bb_fab1_lib.crescent_city_bb_fab1(sch_1):h_cpu0_caterr_g_n"
				( signalRef "@baseboard_fab2_lib.baseboard_fab2(sch_1):h_cpu_caterr_g_n" )
				( signalRef "@baseboard_fab2_lib.baseboard_fab2(sch_1):h_cpu0_caterr_g_n" )
				( signalRef "@baseboard_fab2_lib.baseboard_fab2(sch_1):h_cpu1_caterr_g_n" )
				( electricalCSetRef "@crescent_city_bb_fab1_lib.crescent_city_bb_fab1(sch_1):\CATERR\" )
				( pinPairRef "@baseboard_fab2_lib.baseboard_fab2(sch_1):\PP6106\" )
				( pinPairRef "@baseboard_fab2_lib.baseboard_fab2(sch_1):\PP6107\" )
				( objectStatus "H_CPU0_CATERR_G_N" )
			)
			( electricalNet "@baseboard_fab2_lib.baseboard_fab2(sch_1):fm_cpu1_prochot_lvt3_k_n"
				( signalRef "@baseboard_fab2_lib.baseboard_fab2(sch_1):h_cpu1_prochot_g_pch_n" )
				( signalRef "@baseboard_fab2_lib.baseboard_fab2(sch_1):h_cpu1_prochot_g_n" )
				( signalRef "@baseboard_fab2_lib.baseboard_fab2(sch_1):fm_cpu1_prochot_lvt3_n" )
				( signalRef "@baseboard_fab2_lib.baseboard_fab2(sch_1):fm_cpu1_prochot_lvt3_k_n" )
				( objectStatus "FM_CPU1_PROCHOT_LVT3_K_N" )
			)
			( electricalNet "@baseboard_fab2_lib.baseboard_fab2(sch_1):h_cpu1_memklm_memhot_g_pch_n"
				( signalRef "@baseboard_fab2_lib.baseboard_fab2(sch_1):h_cpu1_memklm_memhot_g_pch_n" )
				( signalRef "@baseboard_fab2_lib.baseboard_fab2(sch_1):h_cpu1_memklm_memhot_g_n" )
				( signalRef "@baseboard_fab2_lib.baseboard_fab2(sch_1):h_cpu1_memklm_memhot_lvt3_n" )
				( signalRef "@baseboard_fab2_lib.baseboard_fab2(sch_1):h_cpu1_memklm_memhot_lvt3_k_n" )
				( attribute "RATSNEST_SCHEDULE" "User Defined"
					( Origin gBackEnd )
				)
				( objectStatus "H_CPU1_MEMKLM_MEMHOT_G_PCH_N" )
			)
			( electricalNet "@baseboard_fab2_lib.baseboard_fab2(sch_1):h_cpu1_memghj_memhot_g_pch_n"
				( signalRef "@baseboard_fab2_lib.baseboard_fab2(sch_1):h_cpu1_memghj_memhot_g_pch_n" )
				( signalRef "@baseboard_fab2_lib.baseboard_fab2(sch_1):h_cpu1_memghj_memhot_g_n" )
				( signalRef "@baseboard_fab2_lib.baseboard_fab2(sch_1):h_cpu1_memghj_memhot_lvt3_n" )
				( signalRef "@baseboard_fab2_lib.baseboard_fab2(sch_1):h_cpu1_memghj_memhot_lvt3_k_n" )
				( attribute "RATSNEST_SCHEDULE" "User Defined"
					( Origin gBackEnd )
				)
				( objectStatus "H_CPU1_MEMGHJ_MEMHOT_G_PCH_N" )
			)
			( electricalNet "@baseboard_fab2_lib.baseboard_fab2(sch_1):fm_cpu0_prochot_lvt3_k_n"
				( signalRef "@baseboard_fab2_lib.baseboard_fab2(sch_1):h_cpu0_prochot_g_pch_n" )
				( signalRef "@baseboard_fab2_lib.baseboard_fab2(sch_1):h_cpu0_prochot_g_n" )
				( signalRef "@baseboard_fab2_lib.baseboard_fab2(sch_1):fm_cpu0_prochot_lvt3_n" )
				( signalRef "@baseboard_fab2_lib.baseboard_fab2(sch_1):fm_cpu0_prochot_lvt3_k_n" )
				( attribute "RATSNEST_SCHEDULE" "User Defined"
					( Origin gBackEnd )
				)
				( objectStatus "FM_CPU0_PROCHOT_LVT3_K_N" )
			)
			( electricalNet "@baseboard_fab2_lib.baseboard_fab2(sch_1):h_cpu0_memdef_memhot_g_pch_n"
				( signalRef "@baseboard_fab2_lib.baseboard_fab2(sch_1):h_cpu0_memdef_memhot_g_pch_n" )
				( signalRef "@baseboard_fab2_lib.baseboard_fab2(sch_1):h_cpu0_memdef_memhot_lvt3_n" )
				( signalRef "@baseboard_fab2_lib.baseboard_fab2(sch_1):h_cpu0_memdef_memhot_g_n" )
				( signalRef "@baseboard_fab2_lib.baseboard_fab2(sch_1):h_cpu0_memdef_memhot_lvt3_k_n" )
				( attribute "RATSNEST_SCHEDULE" "User Defined"
					( Origin gBackEnd )
				)
				( objectStatus "H_CPU0_MEMDEF_MEMHOT_G_PCH_N" )
			)
			( electricalNet "@baseboard_fab2_lib.baseboard_fab2(sch_1):h_cpu0_memabc_memhot_g_pch_n"
				( signalRef "@baseboard_fab2_lib.baseboard_fab2(sch_1):h_cpu0_memabc_memhot_g_pch_n" )
				( signalRef "@baseboard_fab2_lib.baseboard_fab2(sch_1):h_cpu0_memabc_memhot_g_n" )
				( signalRef "@baseboard_fab2_lib.baseboard_fab2(sch_1):h_cpu0_memabc_memhot_lvt3_n" )
				( signalRef "@baseboard_fab2_lib.baseboard_fab2(sch_1):h_cpu0_memabc_memhot_lvt3_k_n" )
				( attribute "RATSNEST_SCHEDULE" "User Defined"
					( Origin gBackEnd )
				)
				( objectStatus "H_CPU0_MEMABC_MEMHOT_G_PCH_N" )
			)
			( electricalNet "@baseboard_fab2_lib.baseboard_fab2(sch_1):fm_cpu_err0_lvt3_k_n"
				( signalRef "@baseboard_fab2_lib.baseboard_fab2(sch_1):fm_cpu_err0_lvt3_k_n" )
				( signalRef "@baseboard_fab2_lib.baseboard_fab2(sch_1):fm_cpu_err1_lvt3_n" )
				( signalRef "@baseboard_fab2_lib.baseboard_fab2(sch_1):fm_cpu_err0_lvt3_n" )
				( signalRef "@baseboard_fab2_lib.baseboard_fab2(sch_1):h_cpu_err1_pch_n" )
				( signalRef "@baseboard_fab2_lib.baseboard_fab2(sch_1):h_cpu_err1_gtl_r_n" )
				( signalRef "@baseboard_fab2_lib.baseboard_fab2(sch_1):h_cpu_err1_gtl_n" )
				( signalRef "@baseboard_fab2_lib.baseboard_fab2(sch_1):h_cpu0_err1_g_n" )
				( signalRef "@baseboard_fab2_lib.baseboard_fab2(sch_1):h_cpu1_err1_g_n" )
				( signalRef "@baseboard_fab2_lib.baseboard_fab2(sch_1):h_cpu_err0_pch_n" )
				( signalRef "@baseboard_fab2_lib.baseboard_fab2(sch_1):h_cpu_err0_gtl_r_n" )
				( signalRef "@baseboard_fab2_lib.baseboard_fab2(sch_1):h_cpu_err0_gtl_n" )
				( signalRef "@baseboard_fab2_lib.baseboard_fab2(sch_1):h_cpu0_err0_g_n" )
				( signalRef "@baseboard_fab2_lib.baseboard_fab2(sch_1):h_cpu1_err0_g_n" )
				( objectStatus "FM_CPU_ERR0_LVT3_K_N" )
			)
			( electricalNet "@crescent_city_bb_fab1_lib.crescent_city_bb_fab1(sch_1):dmi_cpu0_pch_tx_c_dn(0)"
				( signalRef "@baseboard_fab2_lib.baseboard_fab2(sch_1):dmi_cpu0_pch_tx_c_dn(0)" )
				( signalRef "@baseboard_fab2_lib.baseboard_fab2(sch_1):dmi_cpu0_pch_tx_dn(0)" )
				( electricalCSetRef "@crescent_city_bb_fab1_lib.crescent_city_bb_fab1(sch_1):\DMI_CPU0_PCH_RX_C_DN_0_\" )
				( pinPairRef "@baseboard_fab2_lib.baseboard_fab2(sch_1):\PP6082\" )
				( objectStatus "DMI_CPU0_PCH_TX_C_DN<0>" )
			)
			( electricalNet "@crescent_city_bb_fab1_lib.crescent_city_bb_fab1(sch_1):dmi_cpu0_pch_tx_c_dp(0)"
				( signalRef "@baseboard_fab2_lib.baseboard_fab2(sch_1):dmi_cpu0_pch_tx_dp(0)" )
				( signalRef "@baseboard_fab2_lib.baseboard_fab2(sch_1):dmi_cpu0_pch_tx_c_dp(0)" )
				( electricalCSetRef "@crescent_city_bb_fab1_lib.crescent_city_bb_fab1(sch_1):\DMI_CPU0_PCH_RX_C_DN_0_\" )
				( pinPairRef "@baseboard_fab2_lib.baseboard_fab2(sch_1):\PP6080\" )
				( objectStatus "DMI_CPU0_PCH_TX_C_DP<0>" )
			)
			( electricalNet "@crescent_city_bb_fab1_lib.crescent_city_bb_fab1(sch_1):dmi_cpu0_pch_tx_c_dn(1)"
				( signalRef "@baseboard_fab2_lib.baseboard_fab2(sch_1):dmi_cpu0_pch_tx_c_dn(1)" )
				( signalRef "@baseboard_fab2_lib.baseboard_fab2(sch_1):dmi_cpu0_pch_tx_dn(1)" )
				( electricalCSetRef "@crescent_city_bb_fab1_lib.crescent_city_bb_fab1(sch_1):\DMI_CPU0_PCH_RX_C_DN_0_\" )
				( pinPairRef "@baseboard_fab2_lib.baseboard_fab2(sch_1):\PP6079\" )
				( objectStatus "DMI_CPU0_PCH_TX_C_DN<1>" )
			)
			( electricalNet "@crescent_city_bb_fab1_lib.crescent_city_bb_fab1(sch_1):dmi_cpu0_pch_tx_c_dp(1)"
				( signalRef "@baseboard_fab2_lib.baseboard_fab2(sch_1):dmi_cpu0_pch_tx_dp(1)" )
				( signalRef "@baseboard_fab2_lib.baseboard_fab2(sch_1):dmi_cpu0_pch_tx_c_dp(1)" )
				( electricalCSetRef "@crescent_city_bb_fab1_lib.crescent_city_bb_fab1(sch_1):\DMI_CPU0_PCH_RX_C_DN_0_\" )
				( pinPairRef "@baseboard_fab2_lib.baseboard_fab2(sch_1):\PP6078\" )
				( objectStatus "DMI_CPU0_PCH_TX_C_DP<1>" )
			)
			( electricalNet "@crescent_city_bb_fab1_lib.crescent_city_bb_fab1(sch_1):dmi_cpu0_pch_tx_c_dn(2)"
				( signalRef "@baseboard_fab2_lib.baseboard_fab2(sch_1):dmi_cpu0_pch_tx_c_dn(2)" )
				( signalRef "@baseboard_fab2_lib.baseboard_fab2(sch_1):dmi_cpu0_pch_tx_dn(2)" )
				( electricalCSetRef "@crescent_city_bb_fab1_lib.crescent_city_bb_fab1(sch_1):\DMI_CPU0_PCH_RX_C_DN_0_\" )
				( pinPairRef "@baseboard_fab2_lib.baseboard_fab2(sch_1):\PP6076\" )
				( objectStatus "DMI_CPU0_PCH_TX_C_DN<2>" )
			)
			( electricalNet "@crescent_city_bb_fab1_lib.crescent_city_bb_fab1(sch_1):dmi_cpu0_pch_tx_c_dp(2)"
				( signalRef "@baseboard_fab2_lib.baseboard_fab2(sch_1):dmi_cpu0_pch_tx_dp(2)" )
				( signalRef "@baseboard_fab2_lib.baseboard_fab2(sch_1):dmi_cpu0_pch_tx_c_dp(2)" )
				( electricalCSetRef "@crescent_city_bb_fab1_lib.crescent_city_bb_fab1(sch_1):\DMI_CPU0_PCH_RX_C_DN_0_\" )
				( pinPairRef "@baseboard_fab2_lib.baseboard_fab2(sch_1):\PP6066\" )
				( objectStatus "DMI_CPU0_PCH_TX_C_DP<2>" )
			)
			( electricalNet "@crescent_city_bb_fab1_lib.crescent_city_bb_fab1(sch_1):dmi_cpu0_pch_tx_c_dn(3)"
				( signalRef "@baseboard_fab2_lib.baseboard_fab2(sch_1):dmi_cpu0_pch_tx_c_dn(3)" )
				( signalRef "@baseboard_fab2_lib.baseboard_fab2(sch_1):dmi_cpu0_pch_tx_dn(3)" )
				( electricalCSetRef "@crescent_city_bb_fab1_lib.crescent_city_bb_fab1(sch_1):\DMI_CPU0_PCH_RX_C_DN_0_\" )
				( pinPairRef "@baseboard_fab2_lib.baseboard_fab2(sch_1):\PP6033\" )
				( objectStatus "DMI_CPU0_PCH_TX_C_DN<3>" )
			)
			( electricalNet "@crescent_city_bb_fab1_lib.crescent_city_bb_fab1(sch_1):dmi_cpu0_pch_tx_c_dp(3)"
				( signalRef "@baseboard_fab2_lib.baseboard_fab2(sch_1):dmi_cpu0_pch_tx_dp(3)" )
				( signalRef "@baseboard_fab2_lib.baseboard_fab2(sch_1):dmi_cpu0_pch_tx_c_dp(3)" )
				( electricalCSetRef "@crescent_city_bb_fab1_lib.crescent_city_bb_fab1(sch_1):\DMI_CPU0_PCH_RX_C_DN_0_\" )
				( pinPairRef "@baseboard_fab2_lib.baseboard_fab2(sch_1):\PP6065\" )
				( objectStatus "DMI_CPU0_PCH_TX_C_DP<3>" )
			)
			( electricalNet "@crescent_city_bb_fab1_lib.crescent_city_bb_fab1(sch_1):nic_mdi_sprv_rj45_0_dn"
				( signalRef "@baseboard_fab2_lib.baseboard_fab2(sch_1):nic_mdi_sprv_rj45_0_r_dn" )
				( signalRef "@baseboard_fab2_lib.baseboard_fab2(sch_1):nic_mdi_sprv_rj45_0_dn" )
				( electricalCSetRef "@crescent_city_bb_fab1_lib.crescent_city_bb_fab1(sch_1):\NIC_MDI_0-1\" )
				( objectStatus "NIC_MDI_SPRV_RJ45_0_DN" )
			)
			( electricalNet "@crescent_city_bb_fab1_lib.crescent_city_bb_fab1(sch_1):nic_mdi_sprv_rj45_0_dp"
				( signalRef "@baseboard_fab2_lib.baseboard_fab2(sch_1):nic_mdi_sprv_rj45_0_r_dp" )
				( signalRef "@baseboard_fab2_lib.baseboard_fab2(sch_1):nic_mdi_sprv_rj45_0_dp" )
				( electricalCSetRef "@crescent_city_bb_fab1_lib.crescent_city_bb_fab1(sch_1):\NIC_MDI_0-1\" )
				( objectStatus "NIC_MDI_SPRV_RJ45_0_DP" )
			)
			( electricalNet "@crescent_city_bb_fab1_lib.crescent_city_bb_fab1(sch_1):nic_mdi_sprv_rj45_1_dn"
				( signalRef "@baseboard_fab2_lib.baseboard_fab2(sch_1):nic_mdi_sprv_rj45_1_r_dn" )
				( signalRef "@baseboard_fab2_lib.baseboard_fab2(sch_1):nic_mdi_sprv_rj45_1_dn" )
				( electricalCSetRef "@crescent_city_bb_fab1_lib.crescent_city_bb_fab1(sch_1):\NIC_MDI_0-1\" )
				( objectStatus "NIC_MDI_SPRV_RJ45_1_DN" )
			)
			( electricalNet "@crescent_city_bb_fab1_lib.crescent_city_bb_fab1(sch_1):nic_mdi_sprv_rj45_1_dp"
				( signalRef "@baseboard_fab2_lib.baseboard_fab2(sch_1):nic_mdi_sprv_rj45_1_r_dp" )
				( signalRef "@baseboard_fab2_lib.baseboard_fab2(sch_1):nic_mdi_sprv_rj45_1_dp" )
				( electricalCSetRef "@crescent_city_bb_fab1_lib.crescent_city_bb_fab1(sch_1):\NIC_MDI_0-1\" )
				( objectStatus "NIC_MDI_SPRV_RJ45_1_DP" )
			)
			( electricalNet "@crescent_city_bb_fab1_lib.crescent_city_bb_fab1(sch_1):p3e_pch_m2_tx_c_dn(1)"
				( signalRef "@baseboard_fab2_lib.baseboard_fab2(sch_1):p3e_pch_m2_tx_dn(1)" )
				( signalRef "@baseboard_fab2_lib.baseboard_fab2(sch_1):p3e_pch_m2_tx_c_dn(1)" )
				( electricalCSetRef "@crescent_city_bb_fab1_lib.crescent_city_bb_fab1(sch_1):\PCIE_SLOT_C_A\" )
				( pinPairRef "@baseboard_fab2_lib.baseboard_fab2(sch_1):\PP6064\" )
				( objectStatus "P3E_PCH_M2_TX_C_DN<1>" )
			)
			( electricalNet "@crescent_city_bb_fab1_lib.crescent_city_bb_fab1(sch_1):p3e_pch_m2_tx_c_dp(1)"
				( signalRef "@baseboard_fab2_lib.baseboard_fab2(sch_1):p3e_pch_m2_tx_dp(1)" )
				( signalRef "@baseboard_fab2_lib.baseboard_fab2(sch_1):p3e_pch_m2_tx_c_dp(1)" )
				( electricalCSetRef "@crescent_city_bb_fab1_lib.crescent_city_bb_fab1(sch_1):\PCIE_SLOT_C_A\" )
				( pinPairRef "@baseboard_fab2_lib.baseboard_fab2(sch_1):\PP6067\" )
				( objectStatus "P3E_PCH_M2_TX_C_DP<1>" )
			)
			( electricalNet "@crescent_city_bb_fab1_lib.crescent_city_bb_fab1(sch_1):p3e_pch_m2_tx_c_dn(2)"
				( signalRef "@baseboard_fab2_lib.baseboard_fab2(sch_1):p3e_pch_m2_tx_dn(2)" )
				( signalRef "@baseboard_fab2_lib.baseboard_fab2(sch_1):p3e_pch_m2_tx_c_dn(2)" )
				( electricalCSetRef "@crescent_city_bb_fab1_lib.crescent_city_bb_fab1(sch_1):\PCIE_SLOT_C_A\" )
				( pinPairRef "@baseboard_fab2_lib.baseboard_fab2(sch_1):\PP6049\" )
				( objectStatus "P3E_PCH_M2_TX_C_DN<2>" )
			)
			( electricalNet "@crescent_city_bb_fab1_lib.crescent_city_bb_fab1(sch_1):p3e_pch_m2_tx_c_dp(2)"
				( signalRef "@baseboard_fab2_lib.baseboard_fab2(sch_1):p3e_pch_m2_tx_dp(2)" )
				( signalRef "@baseboard_fab2_lib.baseboard_fab2(sch_1):p3e_pch_m2_tx_c_dp(2)" )
				( electricalCSetRef "@crescent_city_bb_fab1_lib.crescent_city_bb_fab1(sch_1):\PCIE_SLOT_C_A\" )
				( pinPairRef "@baseboard_fab2_lib.baseboard_fab2(sch_1):\PP6074\" )
				( objectStatus "P3E_PCH_M2_TX_C_DP<2>" )
			)
			( electricalNet "@crescent_city_bb_fab1_lib.crescent_city_bb_fab1(sch_1):p3e_pch_m2_tx_c_dn(3)"
				( signalRef "@baseboard_fab2_lib.baseboard_fab2(sch_1):p3e_pch_m2_tx_dn(3)" )
				( signalRef "@baseboard_fab2_lib.baseboard_fab2(sch_1):p3e_pch_m2_tx_c_dn(3)" )
				( electricalCSetRef "@crescent_city_bb_fab1_lib.crescent_city_bb_fab1(sch_1):\PCIE_SLOT_C_A\" )
				( pinPairRef "@baseboard_fab2_lib.baseboard_fab2(sch_1):\PP6075\" )
				( objectStatus "P3E_PCH_M2_TX_C_DN<3>" )
			)
			( electricalNet "@crescent_city_bb_fab1_lib.crescent_city_bb_fab1(sch_1):p3e_pch_m2_tx_c_dp(3)"
				( signalRef "@baseboard_fab2_lib.baseboard_fab2(sch_1):p3e_pch_m2_tx_dp(3)" )
				( signalRef "@baseboard_fab2_lib.baseboard_fab2(sch_1):p3e_pch_m2_tx_c_dp(3)" )
				( electricalCSetRef "@crescent_city_bb_fab1_lib.crescent_city_bb_fab1(sch_1):\PCIE_SLOT_C_A\" )
				( pinPairRef "@baseboard_fab2_lib.baseboard_fab2(sch_1):\PP6073\" )
				( objectStatus "P3E_PCH_M2_TX_C_DP<3>" )
			)
			( electricalNet "@crescent_city_bb_fab1_lib.crescent_city_bb_fab1(sch_1):p3e_pch_m2_sata6g_tx_r_dn"
				( signalRef "@baseboard_fab2_lib.baseboard_fab2(sch_1):p3e_pch_tx_0_dn" )
				( signalRef "@baseboard_fab2_lib.baseboard_fab2(sch_1):p3e_pch_m2_sata6g_tx_r_dn" )
				( objectStatus "P3E_PCH_M2_SATA6G_TX_R_DN" )
			)
			( electricalNet "@crescent_city_bb_fab1_lib.crescent_city_bb_fab1(sch_1):p3e_pch_m2_sata6g_tx_r_dp"
				( signalRef "@baseboard_fab2_lib.baseboard_fab2(sch_1):p3e_pch_tx_0_dp" )
				( signalRef "@baseboard_fab2_lib.baseboard_fab2(sch_1):p3e_pch_m2_sata6g_tx_r_dp" )
				( objectStatus "P3E_PCH_M2_SATA6G_TX_R_DP" )
			)
			( electricalNet "@crescent_city_bb_fab1_lib.crescent_city_bb_fab1(sch_1):p3e_pch_m2_sata6g_rx_r_dn"
				( signalRef "@baseboard_fab2_lib.baseboard_fab2(sch_1):p3e_pch_rx_0_dn" )
				( signalRef "@baseboard_fab2_lib.baseboard_fab2(sch_1):p3e_pch_m2_sata6g_rx_r_dn" )
				( objectStatus "P3E_PCH_M2_SATA6G_RX_R_DN" )
			)
			( electricalNet "@crescent_city_bb_fab1_lib.crescent_city_bb_fab1(sch_1):p3e_pch_m2_sata6g_rx_r_dp"
				( signalRef "@baseboard_fab2_lib.baseboard_fab2(sch_1):p3e_pch_rx_0_dp" )
				( signalRef "@baseboard_fab2_lib.baseboard_fab2(sch_1):p3e_pch_m2_sata6g_rx_r_dp" )
				( objectStatus "P3E_PCH_M2_SATA6G_RX_R_DP" )
			)
			( electricalNet "@crescent_city_bb_fab1_lib.crescent_city_bb_fab1(sch_1):a_cbot"
				( signalRef "@baseboard_fab2_lib.baseboard_fab2(sch_1):a_cbot" )
				( signalRef "@baseboard_fab2_lib.baseboard_fab2(sch_1):a_ctop" )
				( objectStatus "A_CBOT" )
			)
			( electricalNet "@crescent_city_bb_fab1_lib.crescent_city_bb_fab1(sch_1):a_hsc_csout"
				( signalRef "@baseboard_fab2_lib.baseboard_fab2(sch_1):a_hsc_low" )
				( signalRef "@baseboard_fab2_lib.baseboard_fab2(sch_1):a_hsc_csout" )
				( signalRef "@baseboard_fab2_lib.baseboard_fab2(sch_1):a_hsc_high" )
				( objectStatus "A_HSC_CSOUT" )
			)
			( electricalNet "@crescent_city_bb_fab1_lib.crescent_city_bb_fab1(sch_1):a_hsc_gate1_r"
				( signalRef "@baseboard_fab2_lib.baseboard_fab2(sch_1):a_hsc_c" )
				( signalRef "@baseboard_fab2_lib.baseboard_fab2(sch_1):a_hsc_gate" )
				( signalRef "@baseboard_fab2_lib.baseboard_fab2(sch_1):a_hsc_gate3_r" )
				( signalRef "@baseboard_fab2_lib.baseboard_fab2(sch_1):a_hsc_gate2_r" )
				( signalRef "@baseboard_fab2_lib.baseboard_fab2(sch_1):a_hsc_gate1_r" )
				( objectStatus "A_HSC_GATE1_R" )
			)
			( electricalNet "@crescent_city_bb_fab1_lib.crescent_city_bb_fab1(sch_1):a_hsc_hsn"
				( signalRef "@baseboard_fab2_lib.baseboard_fab2(sch_1):a_hsc_mon" )
				( signalRef "@baseboard_fab2_lib.baseboard_fab2(sch_1):a_hsc_hsn" )
				( objectStatus "A_HSC_HSN" )
			)
			( electricalNet "@crescent_city_bb_fab1_lib.crescent_city_bb_fab1(sch_1):a_hsc_hsp"
				( signalRef "@baseboard_fab2_lib.baseboard_fab2(sch_1):a_hsc_mop" )
				( signalRef "@baseboard_fab2_lib.baseboard_fab2(sch_1):a_hsc_hsp" )
				( objectStatus "A_HSC_HSP" )
			)
			( electricalNet "@crescent_city_bb_fab1_lib.crescent_city_bb_fab1(sch_1):a_hsc_timer"
				( signalRef "@baseboard_fab2_lib.baseboard_fab2(sch_1):a_hsc_timer" )
				( signalRef "@baseboard_fab2_lib.baseboard_fab2(sch_1):a_hsc_timer_r" )
				( objectStatus "A_HSC_TIMER" )
			)
			( electricalNet "@crescent_city_bb_fab1_lib.crescent_city_bb_fab1(sch_1):peci_bmc"
				( signalRef "@baseboard_fab2_lib.baseboard_fab2(sch_1):peci_bmc_r" )
				( signalRef "@baseboard_fab2_lib.baseboard_fab2(sch_1):peci_bmc" )
				( signalRef "@baseboard_fab2_lib.baseboard_fab2(sch_1):peci_cpu_g" )
				( signalRef "@baseboard_fab2_lib.baseboard_fab2(sch_1):peci_pch" )
				( objectStatus "PECI_BMC" )
			)
			( electricalNet "@crescent_city_bb_fab1_lib.crescent_city_bb_fab1(sch_1):usb3_p01_c_txn"
				( signalRef "@baseboard_fab2_lib.baseboard_fab2(sch_1):usb3_p01_fb_txn" )
				( signalRef "@baseboard_fab2_lib.baseboard_fab2(sch_1):usb3_p01_c_txn" )
				( signalRef "@baseboard_fab2_lib.baseboard_fab2(sch_1):usb3_p01_txn" )
				( objectStatus "USB3_P01_C_TXN" )
			)
			( electricalNet "@crescent_city_bb_fab1_lib.crescent_city_bb_fab1(sch_1):usb3_p01_c_txp"
				( signalRef "@baseboard_fab2_lib.baseboard_fab2(sch_1):usb3_p01_txp" )
				( signalRef "@baseboard_fab2_lib.baseboard_fab2(sch_1):usb3_p01_c_txp" )
				( signalRef "@baseboard_fab2_lib.baseboard_fab2(sch_1):usb3_p01_fb_txp" )
				( objectStatus "USB3_P01_C_TXP" )
			)
			( electricalNet "@crescent_city_bb_fab1_lib.crescent_city_bb_fab1(sch_1):vr_p5v_stby_boot"
				( signalRef "@baseboard_fab2_lib.baseboard_fab2(sch_1):vr_p5v_stby_phase" )
				( signalRef "@baseboard_fab2_lib.baseboard_fab2(sch_1):vr_p5v_stby_boot" )
				( objectStatus "VR_P5V_STBY_BOOT" )
			)
			( electricalNet "@crescent_city_bb_fab1_lib.crescent_city_bb_fab1(sch_1):vr_p5v_stby_rc_comp"
				( signalRef "@baseboard_fab2_lib.baseboard_fab2(sch_1):vr_p5v_stby_rc_comp" )
				( signalRef "@baseboard_fab2_lib.baseboard_fab2(sch_1):vr_p5v_stby_comp" )
				( objectStatus "VR_P5V_STBY_RC_COMP" )
			)
			( electricalNet "@crescent_city_bb_fab1_lib.crescent_city_bb_fab1(sch_1):vr_pvccio_cpu1_ph1_boot"
				( signalRef "@baseboard_fab2_lib.baseboard_fab2(sch_1):vr_pvccio_cpu1_ph1_phase" )
				( signalRef "@baseboard_fab2_lib.baseboard_fab2(sch_1):vr_pvccio_cpu1_ph1_boot" )
				( objectStatus "VR_PVCCIO_CPU1_PH1_BOOT" )
			)
			( electricalNet "@crescent_city_bb_fab1_lib.crescent_city_bb_fab1(sch_1):vr_pvnn_pch_ph1_boot"
				( signalRef "@baseboard_fab2_lib.baseboard_fab2(sch_1):vr_pvnn_pch_ph1_phase" )
				( signalRef "@baseboard_fab2_lib.baseboard_fab2(sch_1):vr_pvnn_pch_ph1_boot" )
				( objectStatus "VR_PVNN_PCH_PH1_BOOT" )
			)
			( electricalNet "@crescent_city_bb_fab1_lib.crescent_city_bb_fab1(sch_1):vr_pvpp_abc_boot"
				( signalRef "@baseboard_fab2_lib.baseboard_fab2(sch_1):vr_pvpp_abc_phase" )
				( signalRef "@baseboard_fab2_lib.baseboard_fab2(sch_1):vr_pvpp_abc_boot_r" )
				( signalRef "@baseboard_fab2_lib.baseboard_fab2(sch_1):vr_pvpp_abc_boot" )
				( objectStatus "VR_PVPP_ABC_BOOT" )
			)
			( electricalNet "@crescent_city_bb_fab1_lib.crescent_city_bb_fab1(sch_1):vr_pvpp_def_boot"
				( signalRef "@baseboard_fab2_lib.baseboard_fab2(sch_1):vr_pvpp_def_boot_r" )
				( signalRef "@baseboard_fab2_lib.baseboard_fab2(sch_1):vr_pvpp_def_boot" )
				( signalRef "@baseboard_fab2_lib.baseboard_fab2(sch_1):vr_pvpp_def_phase" )
				( objectStatus "VR_PVPP_DEF_BOOT" )
			)
			( electricalNet "@crescent_city_bb_fab1_lib.crescent_city_bb_fab1(sch_1):vr_pvpp_ghj_boot"
				( signalRef "@baseboard_fab2_lib.baseboard_fab2(sch_1):vr_pvpp_ghj_boot_r" )
				( signalRef "@baseboard_fab2_lib.baseboard_fab2(sch_1):vr_pvpp_ghj_boot" )
				( signalRef "@baseboard_fab2_lib.baseboard_fab2(sch_1):vr_pvpp_ghj_phase" )
				( objectStatus "VR_PVPP_GHJ_BOOT" )
			)
			( electricalNet "@crescent_city_bb_fab1_lib.crescent_city_bb_fab1(sch_1):vr_pvpp_klm_boot"
				( signalRef "@baseboard_fab2_lib.baseboard_fab2(sch_1):vr_pvpp_klm_boot_r" )
				( signalRef "@baseboard_fab2_lib.baseboard_fab2(sch_1):vr_pvpp_klm_boot" )
				( signalRef "@baseboard_fab2_lib.baseboard_fab2(sch_1):vr_pvpp_klm_phase" )
				( objectStatus "VR_PVPP_KLM_BOOT" )
			)
			( electricalNet "@crescent_city_bb_fab1_lib.crescent_city_bb_fab1(sch_1):vr_p1v05_pch_stby_ph1_boot"
				( signalRef "@baseboard_fab2_lib.baseboard_fab2(sch_1):vr_p1v05_pch_stby_ph1_phase" )
				( signalRef "@baseboard_fab2_lib.baseboard_fab2(sch_1):vr_p1v05_pch_stby_ph1_boot" )
				( objectStatus "VR_P1V05_PCH_STBY_PH1_BOOT" )
			)
			( electricalNet "@crescent_city_bb_fab1_lib.crescent_city_bb_fab1(sch_1):vr_p3v3_stby_boot"
				( signalRef "@baseboard_fab2_lib.baseboard_fab2(sch_1):vr_p3v3_stby_phase" )
				( signalRef "@baseboard_fab2_lib.baseboard_fab2(sch_1):vr_p3v3_stby_boot_r" )
				( signalRef "@baseboard_fab2_lib.baseboard_fab2(sch_1):vr_p3v3_stby_boot" )
				( objectStatus "VR_P3V3_STBY_BOOT" )
			)
			( electricalNet "@baseboard_fab2_lib.baseboard_fab2(sch_1):vsense_pvsa_cpu1_n"
				( signalRef "@baseboard_fab2_lib.baseboard_fab2(sch_1):vsense_pvsa_cpu1_skt_vrtn" )
				( signalRef "@baseboard_fab2_lib.baseboard_fab2(sch_1):vsense_pvsa_cpu1_n" )
				( objectStatus "VSENSE_PVSA_CPU1_N" )
			)
			( electricalNet "@baseboard_fab2_lib.baseboard_fab2(sch_1):vsense_pvsa_cpu1_p"
				( signalRef "@baseboard_fab2_lib.baseboard_fab2(sch_1):vsense_pvsa_cpu1_skt_vsen" )
				( signalRef "@baseboard_fab2_lib.baseboard_fab2(sch_1):vsense_pvsa_cpu1_p" )
				( objectStatus "VSENSE_PVSA_CPU1_P" )
			)
			( electricalNet "@baseboard_fab2_lib.baseboard_fab2(sch_1):vsense_pvsa_cpu0_n"
				( signalRef "@baseboard_fab2_lib.baseboard_fab2(sch_1):vsense_pvsa_cpu0_n" )
				( signalRef "@baseboard_fab2_lib.baseboard_fab2(sch_1):vsense_pvsa_cpu0_skt_vrtn" )
				( objectStatus "VSENSE_PVSA_CPU0_N" )
			)
			( electricalNet "@baseboard_fab2_lib.baseboard_fab2(sch_1):vsense_pvsa_cpu0_p"
				( signalRef "@baseboard_fab2_lib.baseboard_fab2(sch_1):vsense_pvsa_cpu0_skt_vsen" )
				( signalRef "@baseboard_fab2_lib.baseboard_fab2(sch_1):vsense_pvsa_cpu0_p" )
				( objectStatus "VSENSE_PVSA_CPU0_P" )
			)
			( electricalNet "@baseboard_fab2_lib.baseboard_fab2(sch_1):vsense_pvccio_cpu1_avsn"
				( signalRef "@baseboard_fab2_lib.baseboard_fab2(sch_1):vsense_pvccio_cpu1_avsn" )
				( signalRef "@baseboard_fab2_lib.baseboard_fab2(sch_1):vsense_pvccio_cpu1_skt_vrtn" )
				( objectStatus "VSENSE_PVCCIO_CPU1_AVSN" )
			)
			( electricalNet "@baseboard_fab2_lib.baseboard_fab2(sch_1):vsense_pvccio_cpu1_avsp"
				( signalRef "@baseboard_fab2_lib.baseboard_fab2(sch_1):vsense_pvccio_cpu1_skt_vsen" )
				( signalRef "@baseboard_fab2_lib.baseboard_fab2(sch_1):vsense_pvccio_cpu1_avsp" )
				( objectStatus "VSENSE_PVCCIO_CPU1_AVSP" )
			)
			( electricalNet "@baseboard_fab2_lib.baseboard_fab2(sch_1):vsense_pvccin_cpu1_n"
				( signalRef "@baseboard_fab2_lib.baseboard_fab2(sch_1):vsense_pvccin_cpu1_n" )
				( signalRef "@baseboard_fab2_lib.baseboard_fab2(sch_1):vsense_pvccin_cpu1_skt_vrtn" )
				( objectStatus "VSENSE_PVCCIN_CPU1_N" )
			)
			( electricalNet "@baseboard_fab2_lib.baseboard_fab2(sch_1):vsense_pvccin_cpu1_p"
				( signalRef "@baseboard_fab2_lib.baseboard_fab2(sch_1):vsense_pvccin_cpu1_skt_vsen" )
				( signalRef "@baseboard_fab2_lib.baseboard_fab2(sch_1):vsense_pvccin_cpu1_p" )
				( objectStatus "VSENSE_PVCCIN_CPU1_P" )
			)
			( electricalNet "@crescent_city_bb_fab1_lib.crescent_city_bb_fab1(sch_1):vr_p1v05_pch_stby_avsp"
				( signalRef "@baseboard_fab2_lib.baseboard_fab2(sch_1):vsense_p1v05_pch_stby_avsp" )
				( signalRef "@baseboard_fab2_lib.baseboard_fab2(sch_1):vr_p1v05_pch_stby_avsp" )
				( objectStatus "VR_P1V05_PCH_STBY_AVSP" )
			)
			( electricalNet "@baseboard_fab2_lib.baseboard_fab2(sch_1):vsense_pvccio_cpu0_avsn"
				( signalRef "@baseboard_fab2_lib.baseboard_fab2(sch_1):vsense_pvccio_cpu0_avsn" )
				( signalRef "@baseboard_fab2_lib.baseboard_fab2(sch_1):vsense_pvccio_cpu0_skt_vrtn" )
				( objectStatus "VSENSE_PVCCIO_CPU0_AVSN" )
			)
			( electricalNet "@baseboard_fab2_lib.baseboard_fab2(sch_1):vsense_pvccio_cpu0_avsp"
				( signalRef "@baseboard_fab2_lib.baseboard_fab2(sch_1):vsense_pvccio_cpu0_skt_vsen" )
				( signalRef "@baseboard_fab2_lib.baseboard_fab2(sch_1):vsense_pvccio_cpu0_avsp" )
				( objectStatus "VSENSE_PVCCIO_CPU0_AVSP" )
			)
			( electricalNet "@crescent_city_bb_fab1_lib.crescent_city_bb_fab1(sch_1):led_lan_0_n"
				( signalRef "@baseboard_fab2_lib.baseboard_fab2(sch_1):led_lan_0_r_n" )
				( signalRef "@baseboard_fab2_lib.baseboard_fab2(sch_1):led_lan_0_n" )
				( objectStatus "LED_LAN_0_N" )
			)
			( electricalNet "@crescent_city_bb_fab1_lib.crescent_city_bb_fab1(sch_1):led_lan_1_n"
				( signalRef "@baseboard_fab2_lib.baseboard_fab2(sch_1):led_lan_1_r_n" )
				( signalRef "@baseboard_fab2_lib.baseboard_fab2(sch_1):led_lan_1_n" )
				( objectStatus "LED_LAN_1_N" )
			)
			( electricalNet "@crescent_city_bb_fab1_lib.crescent_city_bb_fab1(sch_1):led_lan_2_n"
				( signalRef "@baseboard_fab2_lib.baseboard_fab2(sch_1):led_lan_2_r_n" )
				( signalRef "@baseboard_fab2_lib.baseboard_fab2(sch_1):led_lan_2_n" )
				( objectStatus "LED_LAN_2_N" )
			)
			( electricalNet "@crescent_city_bb_fab1_lib.crescent_city_bb_fab1(sch_1):led_postcode_0"
				( signalRef "@baseboard_fab2_lib.baseboard_fab2(sch_1):led_postcode_0" )
				( signalRef "@baseboard_fab2_lib.baseboard_fab2(sch_1):led_postcode_0_r" )
				( objectStatus "LED_POSTCODE_0" )
			)
			( electricalNet "@crescent_city_bb_fab1_lib.crescent_city_bb_fab1(sch_1):led_postcode_1"
				( signalRef "@baseboard_fab2_lib.baseboard_fab2(sch_1):led_postcode_1" )
				( signalRef "@baseboard_fab2_lib.baseboard_fab2(sch_1):led_postcode_1_r" )
				( objectStatus "LED_POSTCODE_1" )
			)
			( electricalNet "@crescent_city_bb_fab1_lib.crescent_city_bb_fab1(sch_1):led_postcode_2"
				( signalRef "@baseboard_fab2_lib.baseboard_fab2(sch_1):led_postcode_2" )
				( signalRef "@baseboard_fab2_lib.baseboard_fab2(sch_1):led_postcode_2_r" )
				( objectStatus "LED_POSTCODE_2" )
			)
			( electricalNet "@crescent_city_bb_fab1_lib.crescent_city_bb_fab1(sch_1):led_postcode_3"
				( signalRef "@baseboard_fab2_lib.baseboard_fab2(sch_1):led_postcode_3" )
				( signalRef "@baseboard_fab2_lib.baseboard_fab2(sch_1):led_postcode_3_r" )
				( objectStatus "LED_POSTCODE_3" )
			)
			( electricalNet "@crescent_city_bb_fab1_lib.crescent_city_bb_fab1(sch_1):led_postcode_4"
				( signalRef "@baseboard_fab2_lib.baseboard_fab2(sch_1):led_postcode_4" )
				( signalRef "@baseboard_fab2_lib.baseboard_fab2(sch_1):led_postcode_4_r" )
				( objectStatus "LED_POSTCODE_4" )
			)
			( electricalNet "@crescent_city_bb_fab1_lib.crescent_city_bb_fab1(sch_1):led_postcode_5"
				( signalRef "@baseboard_fab2_lib.baseboard_fab2(sch_1):led_postcode_5" )
				( signalRef "@baseboard_fab2_lib.baseboard_fab2(sch_1):led_postcode_5_r" )
				( objectStatus "LED_POSTCODE_5" )
			)
			( electricalNet "@crescent_city_bb_fab1_lib.crescent_city_bb_fab1(sch_1):led_postcode_6"
				( signalRef "@baseboard_fab2_lib.baseboard_fab2(sch_1):led_postcode_6" )
				( signalRef "@baseboard_fab2_lib.baseboard_fab2(sch_1):led_postcode_6_r" )
				( objectStatus "LED_POSTCODE_6" )
			)
			( electricalNet "@crescent_city_bb_fab1_lib.crescent_city_bb_fab1(sch_1):led_postcode_7"
				( signalRef "@baseboard_fab2_lib.baseboard_fab2(sch_1):led_postcode_7" )
				( signalRef "@baseboard_fab2_lib.baseboard_fab2(sch_1):led_postcode_7_r" )
				( objectStatus "LED_POSTCODE_7" )
			)
			( electricalNet "@crescent_city_bb_fab1_lib.crescent_city_bb_fab1(sch_1):rst_pltrst_sprv_r_n"
				( signalRef "@baseboard_fab2_lib.baseboard_fab2(sch_1):rst_pltrst_sprv_r_n" )
				( signalRef "@baseboard_fab2_lib.baseboard_fab2(sch_1):rst_pltrst_n" )
				( objectStatus "RST_PLTRST_SPRV_R_N" )
			)
			( electricalNet "@crescent_city_bb_fab1_lib.crescent_city_bb_fab1(sch_1):rst_system_btn_buf_n"
				( signalRef "@baseboard_fab2_lib.baseboard_fab2(sch_1):rst_system_btn_buf_n" )
				( signalRef "@baseboard_fab2_lib.baseboard_fab2(sch_1):rst_system_btn_n" )
				( objectStatus "RST_SYSTEM_BTN_BUF_N" )
			)
			( electricalNet "@crescent_city_bb_fab1_lib.crescent_city_bb_fab1(sch_1):sgpio_bmc_clk"
				( signalRef "@baseboard_fab2_lib.baseboard_fab2(sch_1):sgpio_bmc_clk" )
				( signalRef "@baseboard_fab2_lib.baseboard_fab2(sch_1):sgpio_bmc_clk_r" )
				( objectStatus "SGPIO_BMC_CLK" )
			)
			( electricalNet "@crescent_city_bb_fab1_lib.crescent_city_bb_fab1(sch_1):sgpio_bmc_din"
				( signalRef "@baseboard_fab2_lib.baseboard_fab2(sch_1):sgpio_bmc_din_r" )
				( signalRef "@baseboard_fab2_lib.baseboard_fab2(sch_1):sgpio_bmc_din" )
				( objectStatus "SGPIO_BMC_DIN" )
			)
			( electricalNet "@crescent_city_bb_fab1_lib.crescent_city_bb_fab1(sch_1):sgpio_bmc_dout"
				( signalRef "@baseboard_fab2_lib.baseboard_fab2(sch_1):sgpio_bmc_dout" )
				( signalRef "@baseboard_fab2_lib.baseboard_fab2(sch_1):sgpio_bmc_dout_r" )
				( objectStatus "SGPIO_BMC_DOUT" )
			)
			( electricalNet "@crescent_city_bb_fab1_lib.crescent_city_bb_fab1(sch_1):sgpio_bmc_ld_n"
				( signalRef "@baseboard_fab2_lib.baseboard_fab2(sch_1):sgpio_bmc_ld_n" )
				( signalRef "@baseboard_fab2_lib.baseboard_fab2(sch_1):sgpio_bmc_ld_r_n" )
				( objectStatus "SGPIO_BMC_LD_N" )
			)
			( electricalNet "@crescent_city_bb_fab1_lib.crescent_city_bb_fab1(sch_1):sgpio_pch_sata_clock"
				( signalRef "@baseboard_fab2_lib.baseboard_fab2(sch_1):sgpio_pch_sata_clock_r" )
				( signalRef "@baseboard_fab2_lib.baseboard_fab2(sch_1):sgpio_pch_sata_clock" )
				( objectStatus "SGPIO_PCH_SATA_CLOCK" )
			)
			( electricalNet "@crescent_city_bb_fab1_lib.crescent_city_bb_fab1(sch_1):sgpio_pch_sata_dout0"
				( signalRef "@baseboard_fab2_lib.baseboard_fab2(sch_1):sgpio_pch_sata_dout0_r" )
				( signalRef "@baseboard_fab2_lib.baseboard_fab2(sch_1):sgpio_pch_sata_dout0" )
				( objectStatus "SGPIO_PCH_SATA_DOUT0" )
			)
			( electricalNet "@crescent_city_bb_fab1_lib.crescent_city_bb_fab1(sch_1):sgpio_pch_sata_load"
				( signalRef "@baseboard_fab2_lib.baseboard_fab2(sch_1):sgpio_pch_sata_load_r" )
				( signalRef "@baseboard_fab2_lib.baseboard_fab2(sch_1):sgpio_pch_sata_load" )
				( objectStatus "SGPIO_PCH_SATA_LOAD" )
			)
			( electricalNet "@crescent_city_bb_fab1_lib.crescent_city_bb_fab1(sch_1):smb_host_stby_lvc3_scl"
				( signalRef "@baseboard_fab2_lib.baseboard_fab2(sch_1):smb_host_stby_lvc3_scl" )
				( signalRef "@baseboard_fab2_lib.baseboard_fab2(sch_1):smb_host_stby_lvc3_scl_r" )
				( signalRef "@baseboard_fab2_lib.baseboard_fab2(sch_1):smb_host_stby_lvc3_scl_r1" )
				( signalRef "@baseboard_fab2_lib.baseboard_fab2(sch_1):smb_host_stby_lvc3_scl_r2" )
				( objectStatus "SMB_HOST_STBY_LVC3_SCL" )
			)
			( electricalNet "@crescent_city_bb_fab1_lib.crescent_city_bb_fab1(sch_1):smb_host_stby_lvc3_sda"
				( signalRef "@baseboard_fab2_lib.baseboard_fab2(sch_1):smb_host_stby_lvc3_sda" )
				( signalRef "@baseboard_fab2_lib.baseboard_fab2(sch_1):smb_host_stby_lvc3_sda_r1" )
				( signalRef "@baseboard_fab2_lib.baseboard_fab2(sch_1):smb_host_stby_lvc3_sda_r" )
				( signalRef "@baseboard_fab2_lib.baseboard_fab2(sch_1):smb_host_stby_lvc3_sda_r2" )
				( objectStatus "SMB_HOST_STBY_LVC3_SDA" )
			)
			( electricalNet "@crescent_city_bb_fab1_lib.crescent_city_bb_fab1(sch_1):xtal_pch_48m_in"
				( signalRef "@baseboard_fab2_lib.baseboard_fab2(sch_1):xtal_pch_48m_out" )
				( signalRef "@baseboard_fab2_lib.baseboard_fab2(sch_1):xtal_pch_48m_in" )
				( objectStatus "XTAL_PCH_48M_IN" )
			)
			( electricalNet "@crescent_city_bb_fab1_lib.crescent_city_bb_fab1(sch_1):xtal_24mhz_in_r"
				( signalRef "@baseboard_fab2_lib.baseboard_fab2(sch_1):xtal_24mhz_pi7c9x1172_in" )
				( signalRef "@baseboard_fab2_lib.baseboard_fab2(sch_1):xtal_24mhz_in_r" )
				( objectStatus "XTAL_24MHZ_IN_R" )
			)
			( electricalNet "@crescent_city_bb_fab1_lib.crescent_city_bb_fab1(sch_1):xtal_24mhz_pi7c9x1172_out"
				( signalRef "@baseboard_fab2_lib.baseboard_fab2(sch_1):xtal_24mhz_pi7c9x1172_out" )
				( signalRef "@baseboard_fab2_lib.baseboard_fab2(sch_1):xtal_24mhz_out_r" )
				( objectStatus "XTAL_24MHZ_PI7C9X1172_OUT" )
			)
			( electricalNet "@crescent_city_bb_fab1_lib.crescent_city_bb_fab1(sch_1):xtal_25mhz_in_r"
				( signalRef "@baseboard_fab2_lib.baseboard_fab2(sch_1):xtal_25mhz_in_r" )
				( signalRef "@baseboard_fab2_lib.baseboard_fab2(sch_1):xtal_25mhz_in" )
				( objectStatus "XTAL_25MHZ_IN_R" )
			)
			( electricalNet "@crescent_city_bb_fab1_lib.crescent_city_bb_fab1(sch_1):xtal_25mhz_out_r"
				( signalRef "@baseboard_fab2_lib.baseboard_fab2(sch_1):xtal_25mhz_out_r" )
				( signalRef "@baseboard_fab2_lib.baseboard_fab2(sch_1):xtal_25mhz_out" )
				( objectStatus "XTAL_25MHZ_OUT_R" )
			)
			( electricalNet "@crescent_city_bb_fab1_lib.crescent_city_bb_fab1(sch_1):xtal_33k_rtc1"
				( signalRef "@baseboard_fab2_lib.baseboard_fab2(sch_1):xtal_33k_rtc2" )
				( signalRef "@baseboard_fab2_lib.baseboard_fab2(sch_1):xtal_33k_rtc1" )
				( objectStatus "XTAL_33K_RTC1" )
			)
			( electricalNet "@crescent_city_bb_fab1_lib.crescent_city_bb_fab1(sch_1):vr_p3v3_stby_en"
				( signalRef "@baseboard_fab2_lib.baseboard_fab2(sch_1):vr_p3v3_stby_en" )
				( signalRef "@baseboard_fab2_lib.baseboard_fab2(sch_1):pwrgd_p5v_stby" )
				( signalRef "@baseboard_fab2_lib.baseboard_fab2(sch_1):pwrgd_p5v_stby_r" )
				( objectStatus "VR_P3V3_STBY_EN" )
			)
			( electricalNet "@crescent_city_bb_fab1_lib.crescent_city_bb_fab1(sch_1):vr_pvddq_abc_vren"
				( signalRef "@baseboard_fab2_lib.baseboard_fab2(sch_1):fm_pvddq_abc_en" )
				( signalRef "@baseboard_fab2_lib.baseboard_fab2(sch_1):vr_pvddq_abc_vren" )
				( objectStatus "VR_PVDDQ_ABC_VREN" )
			)
			( electricalNet "@crescent_city_bb_fab1_lib.crescent_city_bb_fab1(sch_1):vr_pvddq_def_vren"
				( signalRef "@baseboard_fab2_lib.baseboard_fab2(sch_1):fm_pvddq_def_en" )
				( signalRef "@baseboard_fab2_lib.baseboard_fab2(sch_1):vr_pvddq_def_vren" )
				( objectStatus "VR_PVDDQ_DEF_VREN" )
			)
			( electricalNet "@crescent_city_bb_fab1_lib.crescent_city_bb_fab1(sch_1):vr_pvddq_ghj_vren"
				( signalRef "@baseboard_fab2_lib.baseboard_fab2(sch_1):fm_pvddq_ghj_en" )
				( signalRef "@baseboard_fab2_lib.baseboard_fab2(sch_1):vr_pvddq_ghj_vren" )
				( objectStatus "VR_PVDDQ_GHJ_VREN" )
			)
			( electricalNet "@crescent_city_bb_fab1_lib.crescent_city_bb_fab1(sch_1):vr_pvddq_klm_vren"
				( signalRef "@baseboard_fab2_lib.baseboard_fab2(sch_1):fm_pvddq_klm_en" )
				( signalRef "@baseboard_fab2_lib.baseboard_fab2(sch_1):vr_pvddq_klm_vren" )
				( objectStatus "VR_PVDDQ_KLM_VREN" )
			)
			( electricalNet "@crescent_city_bb_fab1_lib.crescent_city_bb_fab1(sch_1):vr_pvnn_pch_vren"
				( signalRef "@baseboard_fab2_lib.baseboard_fab2(sch_1):vr_pvnn_pch_vren" )
				( signalRef "@baseboard_fab2_lib.baseboard_fab2(sch_1):pwrgd_p1v8_pch_stby" )
				( signalRef "@baseboard_fab2_lib.baseboard_fab2(sch_1):pwrgd_p1v8_pch_stby_r" )
				( objectStatus "VR_PVNN_PCH_VREN" )
			)
			( electricalNet "@baseboard_fab2_lib.baseboard_fab2(sch_1):jtag_mcp_cpu0_tdi"
				( signalRef "@baseboard_fab2_lib.baseboard_fab2(sch_1):jtag_mcp_cpu0_tdi_r" )
				( signalRef "@baseboard_fab2_lib.baseboard_fab2(sch_1):jtag_mcp_cpu0_tdi" )
				( objectStatus "JTAG_MCP_CPU0_TDI" )
			)
			( electricalNet "@crescent_city_bb_fab1_lib.crescent_city_bb_fab1(sch_1):fm_adr_complete_r"
				( signalRef "@baseboard_fab2_lib.baseboard_fab2(sch_1):fm_adr_complete_r1" )
				( signalRef "@baseboard_fab2_lib.baseboard_fab2(sch_1):fm_adr_complete" )
				( signalRef "@baseboard_fab2_lib.baseboard_fab2(sch_1):fm_adr_complete_r" )
				( signalRef "@baseboard_fab2_lib.baseboard_fab2(sch_1):fm_adr_complete_dly" )
				( objectStatus "FM_ADR_COMPLETE_R" )
			)
			( electricalNet "@crescent_city_bb_fab1_lib.crescent_city_bb_fab1(sch_1):fm_db_uart_sel0_n"
				( signalRef "@baseboard_fab2_lib.baseboard_fab2(sch_1):fm_uart_switch_n" )
				( signalRef "@baseboard_fab2_lib.baseboard_fab2(sch_1):fm_db_uart_sel0_n" )
				( signalRef "@baseboard_fab2_lib.baseboard_fab2(sch_1):fm_uart_sel_n" )
				( objectStatus "FM_DB_UART_SEL0_N" )
			)
			( electricalNet "@crescent_city_bb_fab1_lib.crescent_city_bb_fab1(sch_1):fm_pvtt_abc_en_r"
				( signalRef "@baseboard_fab2_lib.baseboard_fab2(sch_1):fm_pvtt_abc_en_r" )
				( signalRef "@baseboard_fab2_lib.baseboard_fab2(sch_1):pwrgd_pvddq_abc" )
				( signalRef "@baseboard_fab2_lib.baseboard_fab2(sch_1):pwrgd_pvddq_abc_r" )
				( objectStatus "FM_PVTT_ABC_EN_R" )
			)
			( electricalNet "@crescent_city_bb_fab1_lib.crescent_city_bb_fab1(sch_1):fm_pvtt_def_en_r"
				( signalRef "@baseboard_fab2_lib.baseboard_fab2(sch_1):fm_pvtt_def_en_r" )
				( signalRef "@baseboard_fab2_lib.baseboard_fab2(sch_1):pwrgd_pvddq_def" )
				( signalRef "@baseboard_fab2_lib.baseboard_fab2(sch_1):pwrgd_pvddq_def_r" )
				( objectStatus "FM_PVTT_DEF_EN_R" )
			)
			( electricalNet "@crescent_city_bb_fab1_lib.crescent_city_bb_fab1(sch_1):fm_pvtt_ghj_en_r"
				( signalRef "@baseboard_fab2_lib.baseboard_fab2(sch_1):fm_pvtt_ghj_en_r" )
				( signalRef "@baseboard_fab2_lib.baseboard_fab2(sch_1):pwrgd_pvddq_ghj" )
				( signalRef "@baseboard_fab2_lib.baseboard_fab2(sch_1):pwrgd_pvddq_ghj_r" )
				( objectStatus "FM_PVTT_GHJ_EN_R" )
			)
			( electricalNet "@crescent_city_bb_fab1_lib.crescent_city_bb_fab1(sch_1):fm_pvtt_klm_en_r"
				( signalRef "@baseboard_fab2_lib.baseboard_fab2(sch_1):fm_pvtt_klm_en_r" )
				( signalRef "@baseboard_fab2_lib.baseboard_fab2(sch_1):pwrgd_pvddq_klm" )
				( signalRef "@baseboard_fab2_lib.baseboard_fab2(sch_1):pwrgd_pvddq_klm_r" )
				( objectStatus "FM_PVTT_KLM_EN_R" )
			)
			( electricalNet "@baseboard_fab2_lib.baseboard_fab2(sch_1):vr_pvccio_cpu0_en"
				( signalRef "@baseboard_fab2_lib.baseboard_fab2(sch_1):vr_pvccio_cpu0_en" )
				( signalRef "@baseboard_fab2_lib.baseboard_fab2(sch_1):fm_pvccio_cpu0_en" )
				( objectStatus "VR_PVCCIO_CPU0_EN" )
			)
			( electricalNet "@baseboard_fab2_lib.baseboard_fab2(sch_1):jtag_mcp_tck_r"
				( signalRef "@baseboard_fab2_lib.baseboard_fab2(sch_1):jtag_mcp_tck_r" )
				( signalRef "@baseboard_fab2_lib.baseboard_fab2(sch_1):jtag_mcp_tck" )
				( objectStatus "JTAG_MCP_TCK_R" )
			)
			( electricalNet "@crescent_city_bb_fab1_lib.crescent_city_bb_fab1(sch_1):smb_cpu1_pe_hp_gtl_r_scl"
				( signalRef "@baseboard_fab2_lib.baseboard_fab2(sch_1):smb_cpu1_pe_hp_gtl_scl" )
				( signalRef "@baseboard_fab2_lib.baseboard_fab2(sch_1):smb_cpu1_pe_hp_gtl_r_scl" )
				( objectStatus "SMB_CPU1_PE_HP_GTL_R_SCL" )
			)
			( electricalNet "@crescent_city_bb_fab1_lib.crescent_city_bb_fab1(sch_1):smb_cpu1_pe_hp_gtl_r_sda"
				( signalRef "@baseboard_fab2_lib.baseboard_fab2(sch_1):smb_cpu1_pe_hp_gtl_sda" )
				( signalRef "@baseboard_fab2_lib.baseboard_fab2(sch_1):smb_cpu1_pe_hp_gtl_r_sda" )
				( objectStatus "SMB_CPU1_PE_HP_GTL_R_SDA" )
			)
			( electricalNet "@crescent_city_bb_fab1_lib.crescent_city_bb_fab1(sch_1):lpc_lad1_io1"
				( signalRef "@baseboard_fab2_lib.baseboard_fab2(sch_1):lpc_lad1_io1" )
				( signalRef "@baseboard_fab2_lib.baseboard_fab2(sch_1):lpc_lad1_io1_r" )
				( objectStatus "LPC_LAD1_IO1" )
			)
			( electricalNet "@crescent_city_bb_fab1_lib.crescent_city_bb_fab1(sch_1):irq_pvddq_klm_vrhot_lvt3_n"
				( signalRef "@baseboard_fab2_lib.baseboard_fab2(sch_1):irq_pvddq_klm_vrhot_lvt3_r_n" )
				( signalRef "@baseboard_fab2_lib.baseboard_fab2(sch_1):irq_pvddq_klm_vrhot_lvt3_n" )
				( objectStatus "IRQ_PVDDQ_KLM_VRHOT_LVT3_N" )
			)
			( electricalNet "@crescent_city_bb_fab1_lib.crescent_city_bb_fab1(sch_1):irq_bmc_pch_nmi_stby_n"
				( signalRef "@baseboard_fab2_lib.baseboard_fab2(sch_1):irq_bmc_pch_nmi_stby_r_n" )
				( signalRef "@baseboard_fab2_lib.baseboard_fab2(sch_1):irq_bmc_pch_nmi_stby_n" )
				( objectStatus "IRQ_BMC_PCH_NMI_STBY_N" )
			)
			( electricalNet "@crescent_city_bb_fab1_lib.crescent_city_bb_fab1(sch_1):fm_thermtrip_dly_r"
				( signalRef "@baseboard_fab2_lib.baseboard_fab2(sch_1):fm_thermtrip_dly_r" )
				( signalRef "@baseboard_fab2_lib.baseboard_fab2(sch_1):fm_thermtrip_dly" )
				( objectStatus "FM_THERMTRIP_DLY_R" )
			)
			( electricalNet "@crescent_city_bb_fab1_lib.crescent_city_bb_fab1(sch_1):fm_throttle_r_n"
				( signalRef "@baseboard_fab2_lib.baseboard_fab2(sch_1):fm_throttle_r_n" )
				( signalRef "@baseboard_fab2_lib.baseboard_fab2(sch_1):fm_throttle_n" )
				( signalRef "@baseboard_fab2_lib.baseboard_fab2(sch_1):fm_throttle_r1_n" )
				( objectStatus "FM_THROTTLE_R_N" )
			)
			( electricalNet "@crescent_city_bb_fab1_lib.crescent_city_bb_fab1(sch_1):fm_1gb_lom_disable_n"
				( signalRef "@baseboard_fab2_lib.baseboard_fab2(sch_1):fm_1gb_lom_disable_n" )
				( signalRef "@baseboard_fab2_lib.baseboard_fab2(sch_1):fm_gbe_lom_disable_n" )
				( signalRef "@baseboard_fab2_lib.baseboard_fab2(sch_1):fm_10gbe_lom_disable_n" )
				( objectStatus "FM_1GB_LOM_DISABLE_N" )
			)
			( electricalNet "@crescent_city_bb_fab1_lib.crescent_city_bb_fab1(sch_1):fp_nmi_btn_n"
				( signalRef "@baseboard_fab2_lib.baseboard_fab2(sch_1):fp_nmi_btn_r_n" )
				( signalRef "@baseboard_fab2_lib.baseboard_fab2(sch_1):fp_nmi_btn_n" )
				( objectStatus "FP_NMI_BTN_N" )
			)
			( electricalNet "@crescent_city_bb_fab1_lib.crescent_city_bb_fab1(sch_1):irq_sml1_pmbus_alert_n"
				( signalRef "@baseboard_fab2_lib.baseboard_fab2(sch_1):irq_sml1_pmbus_alert_r_n" )
				( signalRef "@baseboard_fab2_lib.baseboard_fab2(sch_1):irq_sml1_pmbus_alert_n" )
				( objectStatus "IRQ_SML1_PMBUS_ALERT_N" )
			)
			( electricalNet "@crescent_city_bb_fab1_lib.crescent_city_bb_fab1(sch_1):lpc_lad2_io2"
				( signalRef "@baseboard_fab2_lib.baseboard_fab2(sch_1):lpc_lad2_io2" )
				( signalRef "@baseboard_fab2_lib.baseboard_fab2(sch_1):lpc_lad2_io2_r" )
				( objectStatus "LPC_LAD2_IO2" )
			)
			( electricalNet "@crescent_city_bb_fab1_lib.crescent_city_bb_fab1(sch_1):fm_cpu1_thermtrip_lvt3_n"
				( signalRef "@baseboard_fab2_lib.baseboard_fab2(sch_1):fm_cpu1_thermtrip_lvt3_r_n" )
				( signalRef "@baseboard_fab2_lib.baseboard_fab2(sch_1):fm_cpu1_thermtrip_lvt3_n" )
				( objectStatus "FM_CPU1_THERMTRIP_LVT3_N" )
			)
			( electricalNet "@crescent_city_bb_fab1_lib.crescent_city_bb_fab1(sch_1):fm_m2_det_lvc3"
				( signalRef "@baseboard_fab2_lib.baseboard_fab2(sch_1):fm_ssata_pcie_m2_sel" )
				( signalRef "@baseboard_fab2_lib.baseboard_fab2(sch_1):fm_m2_det_lvc3" )
				( objectStatus "FM_M2_DET_LVC3" )
			)
			( electricalNet "@crescent_city_bb_fab1_lib.crescent_city_bb_fab1(sch_1):fm_flash_desc_override"
				( signalRef "@baseboard_fab2_lib.baseboard_fab2(sch_1):fm_flash_desc_override_r" )
				( signalRef "@baseboard_fab2_lib.baseboard_fab2(sch_1):fm_flash_desc_override" )
				( objectStatus "FM_FLASH_DESC_OVERRIDE" )
			)
			( electricalNet "@crescent_city_bb_fab1_lib.crescent_city_bb_fab1(sch_1):fm_cpu1_fivr_fault_lvt3"
				( signalRef "@baseboard_fab2_lib.baseboard_fab2(sch_1):fm_cpu1_fivr_fault_lvt3_r1_n" )
				( signalRef "@baseboard_fab2_lib.baseboard_fab2(sch_1):fm_cpu1_fivr_fault_lvt3" )
				( objectStatus "FM_CPU1_FIVR_FAULT_LVT3" )
			)
			( electricalNet "@crescent_city_bb_fab1_lib.crescent_city_bb_fab1(sch_1):fm_pch_pld_data"
				( signalRef "@baseboard_fab2_lib.baseboard_fab2(sch_1):fm_pch_pld_data_r" )
				( signalRef "@baseboard_fab2_lib.baseboard_fab2(sch_1):fm_pch_pld_data" )
				( objectStatus "FM_PCH_PLD_DATA" )
			)
			( electricalNet "@crescent_city_bb_fab1_lib.crescent_city_bb_fab1(sch_1):fm_cpu1_fivr_fault_lvt3_n"
				( signalRef "@baseboard_fab2_lib.baseboard_fab2(sch_1):fm_cpu1_fivr_fault_lvt3_n" )
				( signalRef "@baseboard_fab2_lib.baseboard_fab2(sch_1):fm_cpu1_fivr_fault_lvt3_r_n" )
				( objectStatus "FM_CPU1_FIVR_FAULT_LVT3_N" )
			)
			( electricalNet "@crescent_city_bb_fab1_lib.crescent_city_bb_fab1(sch_1):fm_pwr_btn_n"
				( signalRef "@baseboard_fab2_lib.baseboard_fab2(sch_1):fm_pwr_btn_r_n" )
				( signalRef "@baseboard_fab2_lib.baseboard_fab2(sch_1):fm_pwr_btn_n" )
				( objectStatus "FM_PWR_BTN_N" )
			)
			( electricalNet "@crescent_city_bb_fab1_lib.crescent_city_bb_fab1(sch_1):fm_pch_sata_raid_key"
				( signalRef "@baseboard_fab2_lib.baseboard_fab2(sch_1):fm_pch_sata_raid_key_r" )
				( signalRef "@baseboard_fab2_lib.baseboard_fab2(sch_1):fm_pch_sata_raid_key" )
				( objectStatus "FM_PCH_SATA_RAID_KEY" )
			)
			( electricalNet "@crescent_city_bb_fab1_lib.crescent_city_bb_fab1(sch_1):fm_pvpp_pvddq_cpu1_en_ghj"
				( signalRef "@baseboard_fab2_lib.baseboard_fab2(sch_1):fm_pvpp_pvddq_cpu1_en_klm" )
				( signalRef "@baseboard_fab2_lib.baseboard_fab2(sch_1):fm_pvpp_cpu1_en" )
				( signalRef "@baseboard_fab2_lib.baseboard_fab2(sch_1):fm_pvpp_pvddq_cpu1_en_ghj" )
				( objectStatus "FM_PVPP_PVDDQ_CPU1_EN_GHJ" )
			)
			( electricalNet "@crescent_city_bb_fab1_lib.crescent_city_bb_fab1(sch_1):fm_ctnr_ps_on"
				( signalRef "@baseboard_fab2_lib.baseboard_fab2(sch_1):fm_ctnr_ps_on_r" )
				( signalRef "@baseboard_fab2_lib.baseboard_fab2(sch_1):fm_ctnr_ps_on" )
				( objectStatus "FM_CTNR_PS_ON" )
			)
			( electricalNet "@crescent_city_bb_fab1_lib.crescent_city_bb_fab1(sch_1):fm_pvpp_pvddq_cpu0_en_abc"
				( signalRef "@baseboard_fab2_lib.baseboard_fab2(sch_1):fm_pvpp_pvddq_cpu0_en_def" )
				( signalRef "@baseboard_fab2_lib.baseboard_fab2(sch_1):fm_pvpp_cpu0_en" )
				( signalRef "@baseboard_fab2_lib.baseboard_fab2(sch_1):fm_pvpp_pvddq_cpu0_en_abc" )
				( objectStatus "FM_PVPP_PVDDQ_CPU0_EN_ABC" )
			)
			( electricalNet "@crescent_city_bb_fab1_lib.crescent_city_bb_fab1(sch_1):fm_cpu0_thermtrip_lvt3_n"
				( signalRef "@baseboard_fab2_lib.baseboard_fab2(sch_1):fm_cpu0_thermtrip_lvt3_r_n" )
				( signalRef "@baseboard_fab2_lib.baseboard_fab2(sch_1):fm_cpu0_thermtrip_lvt3_n" )
				( objectStatus "FM_CPU0_THERMTRIP_LVT3_N" )
			)
			( electricalNet "@crescent_city_bb_fab1_lib.crescent_city_bb_fab1(sch_1):fm_all_wake_n"
				( signalRef "@baseboard_fab2_lib.baseboard_fab2(sch_1):fm_all_wake_n" )
				( signalRef "@baseboard_fab2_lib.baseboard_fab2(sch_1):fm_pe_ocp_wake_n" )
				( signalRef "@baseboard_fab2_lib.baseboard_fab2(sch_1):fm_pe_m2_wake_n" )
				( signalRef "@baseboard_fab2_lib.baseboard_fab2(sch_1):fm_pe_bmc_wake_n" )
				( signalRef "@baseboard_fab2_lib.baseboard_fab2(sch_1):fm_pe_slotx24_wake_n" )
				( signalRef "@baseboard_fab2_lib.baseboard_fab2(sch_1):fm_pe_sprv_wake_n" )
				( objectStatus "FM_ALL_WAKE_N" )
			)
			( electricalNet "@crescent_city_bb_fab1_lib.crescent_city_bb_fab1(sch_1):fm_adr_smi_gpio_n"
				( signalRef "@baseboard_fab2_lib.baseboard_fab2(sch_1):fm_adr_smi_gpio_r_n" )
				( signalRef "@baseboard_fab2_lib.baseboard_fab2(sch_1):fm_adr_smi_gpio_n" )
				( signalRef "@baseboard_fab2_lib.baseboard_fab2(sch_1):fm_mem_therm_event_lvt3_n" )
				( signalRef "@baseboard_fab2_lib.baseboard_fab2(sch_1):irq_dimm_save_lvt3_n" )
				( objectStatus "FM_ADR_SMI_GPIO_N" )
			)
			( electricalNet "@crescent_city_bb_fab1_lib.crescent_city_bb_fab1(sch_1):fm_adr_mode_sel"
				( signalRef "@baseboard_fab2_lib.baseboard_fab2(sch_1):fm_adr_mode_sel_r" )
				( signalRef "@baseboard_fab2_lib.baseboard_fab2(sch_1):fm_adr_mode_sel" )
				( objectStatus "FM_ADR_MODE_SEL" )
			)
			( electricalNet "@crescent_city_bb_fab1_lib.crescent_city_bb_fab1(sch_1):fp_rst_btn_r_n"
				( signalRef "@baseboard_fab2_lib.baseboard_fab2(sch_1):fp_rst_btn_r_n" )
				( signalRef "@baseboard_fab2_lib.baseboard_fab2(sch_1):fm_debug_rst_btn_n" )
				( signalRef "@baseboard_fab2_lib.baseboard_fab2(sch_1):fm_debug_rst_btn_r1_n" )
				( objectStatus "FP_RST_BTN_R_N" )
			)
			( electricalNet "@crescent_city_bb_fab1_lib.crescent_city_bb_fab1(sch_1):fm_bmc_nmi_n"
				( signalRef "@baseboard_fab2_lib.baseboard_fab2(sch_1):fm_bmc_nmi_n" )
				( signalRef "@baseboard_fab2_lib.baseboard_fab2(sch_1):fm_nmi_event_n" )
				( objectStatus "FM_BMC_NMI_N" )
			)
			( electricalNet "@crescent_city_bb_fab1_lib.crescent_city_bb_fab1(sch_1):fm_bios_top_swap_spkr"
				( signalRef "@baseboard_fab2_lib.baseboard_fab2(sch_1):fm_bios_top_swap_spkr_r" )
				( signalRef "@baseboard_fab2_lib.baseboard_fab2(sch_1):fm_bios_top_swap_spkr" )
				( objectStatus "FM_BIOS_TOP_SWAP_SPKR" )
			)
			( electricalNet "@crescent_city_bb_fab1_lib.crescent_city_bb_fab1(sch_1):fm_bmc_enable_n"
				( signalRef "@baseboard_fab2_lib.baseboard_fab2(sch_1):rst_bmc_srst_r_n" )
				( signalRef "@baseboard_fab2_lib.baseboard_fab2(sch_1):rst_bmc_srst_n" )
				( signalRef "@baseboard_fab2_lib.baseboard_fab2(sch_1):fm_bmc_enable_n" )
				( signalRef "@baseboard_fab2_lib.baseboard_fab2(sch_1):fm_roma(0)" )
				( signalRef "@baseboard_fab2_lib.baseboard_fab2(sch_1):rst_bmc_srst_r2_n" )
				( objectStatus "FM_BMC_ENABLE_N" )
			)
			( electricalNet "@crescent_city_bb_fab1_lib.crescent_city_bb_fab1(sch_1):fm_bmc_sys_throttle_r_n"
				( signalRef "@baseboard_fab2_lib.baseboard_fab2(sch_1):irq_force_nm_throttle_n" )
				( signalRef "@baseboard_fab2_lib.baseboard_fab2(sch_1):fm_bmc_sys_throttle_r_n" )
				( signalRef "@baseboard_fab2_lib.baseboard_fab2(sch_1):irq_force_nm_throttle_r_n" )
				( objectStatus "FM_BMC_SYS_THROTTLE_R_N" )
			)
			( electricalNet "@crescent_city_bb_fab1_lib.crescent_city_bb_fab1(sch_1):fm_bmc_onctl_r_n"
				( signalRef "@baseboard_fab2_lib.baseboard_fab2(sch_1):fm_bmc_onctl_r_n" )
				( signalRef "@baseboard_fab2_lib.baseboard_fab2(sch_1):fm_bmc_onctl_n" )
				( objectStatus "FM_BMC_ONCTL_R_N" )
			)
			( electricalNet "@crescent_city_bb_fab1_lib.crescent_city_bb_fab1(sch_1):irq_pvddq_def_vrhot_lvt3_n"
				( signalRef "@baseboard_fab2_lib.baseboard_fab2(sch_1):irq_pvddq_def_vrhot_lvt3_r_n" )
				( signalRef "@baseboard_fab2_lib.baseboard_fab2(sch_1):irq_pvddq_def_vrhot_lvt3_n" )
				( objectStatus "IRQ_PVDDQ_DEF_VRHOT_LVT3_N" )
			)
			( electricalNet "@crescent_city_bb_fab1_lib.crescent_city_bb_fab1(sch_1):fm_cpu_caterr_dly_lvt3_n"
				( signalRef "@baseboard_fab2_lib.baseboard_fab2(sch_1):fm_cpu_caterr_dly_lvt3_n" )
				( signalRef "@baseboard_fab2_lib.baseboard_fab2(sch_1):fm_cpu_caterr_dly_lvt3_r_n" )
				( objectStatus "FM_CPU_CATERR_DLY_LVT3_N" )
			)
			( electricalNet "@crescent_city_bb_fab1_lib.crescent_city_bb_fab1(sch_1):fm_cpu_err2_lvt3_n"
				( signalRef "@baseboard_fab2_lib.baseboard_fab2(sch_1):fm_cpu_err2_lvt3_n" )
				( signalRef "@baseboard_fab2_lib.baseboard_fab2(sch_1):fm_cpu_err2_lvt3_r_n" )
				( objectStatus "FM_CPU_ERR2_LVT3_N" )
			)
			( electricalNet "@crescent_city_bb_fab1_lib.crescent_city_bb_fab1(sch_1):fm_cpu_msmi_lvt3_n"
				( signalRef "@baseboard_fab2_lib.baseboard_fab2(sch_1):fm_cpu_msmi_lvt3_r_n" )
				( signalRef "@baseboard_fab2_lib.baseboard_fab2(sch_1):fm_cpu_msmi_lvt3_n" )
				( objectStatus "FM_CPU_MSMI_LVT3_N" )
			)
			( electricalNet "@crescent_city_bb_fab1_lib.crescent_city_bb_fab1(sch_1):fm_cpu0_fivr_fault_lvt3"
				( signalRef "@baseboard_fab2_lib.baseboard_fab2(sch_1):fm_cpu0_fivr_fault_lvt3_r2_n" )
				( signalRef "@baseboard_fab2_lib.baseboard_fab2(sch_1):fm_cpu0_fivr_fault_lvt3" )
				( objectStatus "FM_CPU0_FIVR_FAULT_LVT3" )
			)
			( electricalNet "@crescent_city_bb_fab1_lib.crescent_city_bb_fab1(sch_1):fm_cpu0_fivr_fault_lvt3_n"
				( signalRef "@baseboard_fab2_lib.baseboard_fab2(sch_1):fm_cpu0_fivr_fault_lvt3_n" )
				( signalRef "@baseboard_fab2_lib.baseboard_fab2(sch_1):fm_cpu0_fivr_fault_lvt3_r_n" )
				( objectStatus "FM_CPU0_FIVR_FAULT_LVT3_N" )
			)
			( electricalNet "@crescent_city_bb_fab1_lib.crescent_city_bb_fab1(sch_1):a_hsc_low_drain"
				( signalRef "@baseboard_fab2_lib.baseboard_fab2(sch_1):a_hsc_low_drain" )
				( signalRef "@baseboard_fab2_lib.baseboard_fab2(sch_1):irq_oc_detect_n" )
				( objectStatus "A_HSC_LOW_DRAIN" )
			)
			( electricalNet "@crescent_city_bb_fab1_lib.crescent_city_bb_fab1(sch_1):fm_cpld_adr_trigger_n"
				( signalRef "@baseboard_fab2_lib.baseboard_fab2(sch_1):fm_cpld_adr_trigger_r_n" )
				( signalRef "@baseboard_fab2_lib.baseboard_fab2(sch_1):fm_cpld_adr_trigger_n" )
				( objectStatus "FM_CPLD_ADR_TRIGGER_N" )
			)
			( electricalNet "@crescent_city_bb_fab1_lib.crescent_city_bb_fab1(sch_1):fm_cpu_caterr_lvt3_n"
				( signalRef "@baseboard_fab2_lib.baseboard_fab2(sch_1):fm_cpu_caterr_lvt3_n" )
				( signalRef "@baseboard_fab2_lib.baseboard_fab2(sch_1):fm_cpu_caterr_lvt3_r2_n" )
				( objectStatus "FM_CPU_CATERR_LVT3_N" )
			)
			( electricalNet "@crescent_city_bb_fab1_lib.crescent_city_bb_fab1(sch_1):irq_dimm_save_n"
				( signalRef "@baseboard_fab2_lib.baseboard_fab2(sch_1):irq_dimm_save_n" )
				( signalRef "@baseboard_fab2_lib.baseboard_fab2(sch_1):fm_adr_complete_klm_n" )
				( signalRef "@baseboard_fab2_lib.baseboard_fab2(sch_1):fm_adr_complete_abc_n" )
				( signalRef "@baseboard_fab2_lib.baseboard_fab2(sch_1):fm_adr_complete_ghj_n" )
				( signalRef "@baseboard_fab2_lib.baseboard_fab2(sch_1):fm_adr_complete_def_n" )
				( signalRef "@baseboard_fab2_lib.baseboard_fab2(sch_1):irq_dimm_save_r_n" )
				( objectStatus "IRQ_DIMM_SAVE_N" )
			)
			( electricalNet "@crescent_city_bb_fab1_lib.crescent_city_bb_fab1(sch_1):irq_hsc_fault_r_n"
				( signalRef "@baseboard_fab2_lib.baseboard_fab2(sch_1):irq_hsc_fault_r_n" )
				( signalRef "@baseboard_fab2_lib.baseboard_fab2(sch_1):irq_hsc_fault_n" )
				( objectStatus "IRQ_HSC_FAULT_R_N" )
			)
			( electricalNet "@baseboard_fab2_lib.baseboard_fab2(sch_1):jtag_mcp_tms"
				( signalRef "@baseboard_fab2_lib.baseboard_fab2(sch_1):jtag_mcp_tms_r1" )
				( signalRef "@baseboard_fab2_lib.baseboard_fab2(sch_1):jtag_mcp_tms" )
				( objectStatus "JTAG_MCP_TMS" )
			)
			( electricalNet "@crescent_city_bb_fab1_lib.crescent_city_bb_fab1(sch_1):irq_lpc_serirq_n"
				( signalRef "@baseboard_fab2_lib.baseboard_fab2(sch_1):irq_lpc_serirq_r" )
				( signalRef "@baseboard_fab2_lib.baseboard_fab2(sch_1):irq_lpc_serirq_n" )
				( objectStatus "IRQ_LPC_SERIRQ_N" )
			)
			( electricalNet "@crescent_city_bb_fab1_lib.crescent_city_bb_fab1(sch_1):irq_lvc3_wake_n"
				( signalRef "@baseboard_fab2_lib.baseboard_fab2(sch_1):irq_lvc3_wake_r_n" )
				( signalRef "@baseboard_fab2_lib.baseboard_fab2(sch_1):irq_lvc3_wake_n" )
				( objectStatus "IRQ_LVC3_WAKE_N" )
			)
			( electricalNet "@crescent_city_bb_fab1_lib.crescent_city_bb_fab1(sch_1):irq_pirqa_spi_tpm_n"
				( signalRef "@baseboard_fab2_lib.baseboard_fab2(sch_1):irq_pirqa_spi_tpm_n" )
				( signalRef "@baseboard_fab2_lib.baseboard_fab2(sch_1):irq_spi_tpm_n_r" )
				( objectStatus "IRQ_PIRQA_SPI_TPM_N" )
			)
			( electricalNet "@crescent_city_bb_fab1_lib.crescent_city_bb_fab1(sch_1):fp_pwr_btn_r1_n"
				( signalRef "@baseboard_fab2_lib.baseboard_fab2(sch_1):fp_pwr_btn_r_n" )
				( signalRef "@baseboard_fab2_lib.baseboard_fab2(sch_1):fp_pwr_btn_r1_n" )
				( objectStatus "FP_PWR_BTN_R1_N" )
			)
			( electricalNet "@crescent_city_bb_fab1_lib.crescent_city_bb_fab1(sch_1):irq_vm_int_n"
				( signalRef "@baseboard_fab2_lib.baseboard_fab2(sch_1):irq_vm_int_r_n" )
				( signalRef "@baseboard_fab2_lib.baseboard_fab2(sch_1):irq_vm_int_n" )
				( objectStatus "IRQ_VM_INT_N" )
			)
			( electricalNet "@crescent_city_bb_fab1_lib.crescent_city_bb_fab1(sch_1):irq_pvddq_ghj_vrhot_lvt3_n"
				( signalRef "@baseboard_fab2_lib.baseboard_fab2(sch_1):irq_pvddq_ghj_vrhot_lvt3_r_n" )
				( signalRef "@baseboard_fab2_lib.baseboard_fab2(sch_1):irq_pvddq_ghj_vrhot_lvt3_n" )
				( objectStatus "IRQ_PVDDQ_GHJ_VRHOT_LVT3_N" )
			)
			( electricalNet "@crescent_city_bb_fab1_lib.crescent_city_bb_fab1(sch_1):irq_pvccin_cpu0_vrhot_lvc3_n"
				( signalRef "@baseboard_fab2_lib.baseboard_fab2(sch_1):irq_pvccin_cpu0_vrhot_lvc3_r_n" )
				( signalRef "@baseboard_fab2_lib.baseboard_fab2(sch_1):irq_pvccin_cpu0_vrhot_lvc3_n" )
				( objectStatus "IRQ_PVCCIN_CPU0_VRHOT_LVC3_N" )
			)
			( electricalNet "@crescent_city_bb_fab1_lib.crescent_city_bb_fab1(sch_1):irq_pvddq_abc_vrhot_lvt3_n"
				( signalRef "@baseboard_fab2_lib.baseboard_fab2(sch_1):irq_pvddq_abc_vrhot_lvt3_r_n" )
				( signalRef "@baseboard_fab2_lib.baseboard_fab2(sch_1):irq_pvddq_abc_vrhot_lvt3_n" )
				( objectStatus "IRQ_PVDDQ_ABC_VRHOT_LVT3_N" )
			)
			( electricalNet "@crescent_city_bb_fab1_lib.crescent_city_bb_fab1(sch_1):fp_nmi_btn_out_n"
				( signalRef "@baseboard_fab2_lib.baseboard_fab2(sch_1):fp_nmi_btn_out_r_n" )
				( signalRef "@baseboard_fab2_lib.baseboard_fab2(sch_1):fp_nmi_btn_out_n" )
				( objectStatus "FP_NMI_BTN_OUT_N" )
			)
			( electricalNet "@crescent_city_bb_fab1_lib.crescent_city_bb_fab1(sch_1):lpc_lad0_io0"
				( signalRef "@baseboard_fab2_lib.baseboard_fab2(sch_1):lpc_lad0_io0" )
				( signalRef "@baseboard_fab2_lib.baseboard_fab2(sch_1):lpc_lad0_io0_r" )
				( objectStatus "LPC_LAD0_IO0" )
			)
			( electricalNet "@crescent_city_bb_fab1_lib.crescent_city_bb_fab1(sch_1):pwrgd_pvpp_ghj"
				( signalRef "@baseboard_fab2_lib.baseboard_fab2(sch_1):pwrgd_pvpp_ghj_r" )
				( signalRef "@baseboard_fab2_lib.baseboard_fab2(sch_1):pwrgd_pvpp_ghj" )
				( objectStatus "PWRGD_PVPP_GHJ" )
			)
			( electricalNet "@crescent_city_bb_fab1_lib.crescent_city_bb_fab1(sch_1):irq_pvccin_cpu1_vrhot_lvc3_n"
				( signalRef "@baseboard_fab2_lib.baseboard_fab2(sch_1):irq_pvccin_cpu1_vrhot_lvc3_r_n" )
				( signalRef "@baseboard_fab2_lib.baseboard_fab2(sch_1):irq_pvccin_cpu1_vrhot_lvc3_n" )
				( objectStatus "IRQ_PVCCIN_CPU1_VRHOT_LVC3_N" )
			)
			( electricalNet "@crescent_city_bb_fab1_lib.crescent_city_bb_fab1(sch_1):pwrgd_pvpp_def"
				( signalRef "@baseboard_fab2_lib.baseboard_fab2(sch_1):pwrgd_pvpp_def_r" )
				( signalRef "@baseboard_fab2_lib.baseboard_fab2(sch_1):pwrgd_pvpp_def" )
				( objectStatus "PWRGD_PVPP_DEF" )
			)
			( electricalNet "@crescent_city_bb_fab1_lib.crescent_city_bb_fab1(sch_1):lpc_lframe_n_cs0_n"
				( signalRef "@baseboard_fab2_lib.baseboard_fab2(sch_1):lpc_lframe_n_cs0_r_n" )
				( signalRef "@baseboard_fab2_lib.baseboard_fab2(sch_1):lpc_lframe_n_cs0_n" )
				( objectStatus "LPC_LFRAME_N_CS0_N" )
			)
			( electricalNet "@crescent_city_bb_fab1_lib.crescent_city_bb_fab1(sch_1):pwrgd_pvtt_cpu1"
				( signalRef "@baseboard_fab2_lib.baseboard_fab2(sch_1):pwrgd_pvtt_cpu1" )
				( signalRef "@baseboard_fab2_lib.baseboard_fab2(sch_1):pwrgd_pvtt_klm_cpu1_r" )
				( signalRef "@baseboard_fab2_lib.baseboard_fab2(sch_1):pwrgd_pvtt_ghj_cpu1_r" )
				( objectStatus "PWRGD_PVTT_CPU1" )
			)
			( electricalNet "@crescent_city_bb_fab1_lib.crescent_city_bb_fab1(sch_1):pwrgd_pvsa_cpu1"
				( signalRef "@baseboard_fab2_lib.baseboard_fab2(sch_1):pwrgd_pvsa_cpu1_r" )
				( signalRef "@baseboard_fab2_lib.baseboard_fab2(sch_1):pwrgd_pvsa_cpu1" )
				( objectStatus "PWRGD_PVSA_CPU1" )
			)
			( electricalNet "@crescent_city_bb_fab1_lib.crescent_city_bb_fab1(sch_1):pwrgd_pvtt_abc_cpu0_r"
				( signalRef "@baseboard_fab2_lib.baseboard_fab2(sch_1):pwrgd_pvtt_cpu0" )
				( signalRef "@baseboard_fab2_lib.baseboard_fab2(sch_1):pwrgd_pvtt_def_cpu0_r" )
				( signalRef "@baseboard_fab2_lib.baseboard_fab2(sch_1):pwrgd_pvtt_abc_cpu0_r" )
				( objectStatus "PWRGD_PVTT_ABC_CPU0_R" )
			)
			( electricalNet "@crescent_city_bb_fab1_lib.crescent_city_bb_fab1(sch_1):lpc_lad3_io3"
				( signalRef "@baseboard_fab2_lib.baseboard_fab2(sch_1):lpc_lad3_io3_r" )
				( signalRef "@baseboard_fab2_lib.baseboard_fab2(sch_1):lpc_lad3_io3" )
				( objectStatus "LPC_LAD3_IO3" )
			)
			( electricalNet "@crescent_city_bb_fab1_lib.crescent_city_bb_fab1(sch_1):pwrgd_pvpp_klm"
				( signalRef "@baseboard_fab2_lib.baseboard_fab2(sch_1):pwrgd_pvpp_klm_r" )
				( signalRef "@baseboard_fab2_lib.baseboard_fab2(sch_1):pwrgd_pvpp_klm" )
				( objectStatus "PWRGD_PVPP_KLM" )
			)
			( electricalNet "@crescent_city_bb_fab1_lib.crescent_city_bb_fab1(sch_1):pwrgd_p3v3_stby_r"
				( signalRef "@baseboard_fab2_lib.baseboard_fab2(sch_1):pwrgd_p3v3_stby_r" )
				( signalRef "@baseboard_fab2_lib.baseboard_fab2(sch_1):pwrgd_p3v3_stby" )
				( objectStatus "PWRGD_P3V3_STBY_R" )
			)
			( electricalNet "@crescent_city_bb_fab1_lib.crescent_city_bb_fab1(sch_1):pwrgd_pvccio_cpu0"
				( signalRef "@baseboard_fab2_lib.baseboard_fab2(sch_1):pwrgd_pvccio_cpu0" )
				( signalRef "@baseboard_fab2_lib.baseboard_fab2(sch_1):pwrgd_pvccio_cpu0_r" )
				( objectStatus "PWRGD_PVCCIO_CPU0" )
			)
			( electricalNet "@crescent_city_bb_fab1_lib.crescent_city_bb_fab1(sch_1):pwrgd_p3v3_r"
				( signalRef "@baseboard_fab2_lib.baseboard_fab2(sch_1):pwrgd_p3v3_r1" )
				( signalRef "@baseboard_fab2_lib.baseboard_fab2(sch_1):pwrgd_p3v3" )
				( signalRef "@baseboard_fab2_lib.baseboard_fab2(sch_1):pwrgd_p3v3_r" )
				( objectStatus "PWRGD_P3V3_R" )
			)
			( electricalNet "@crescent_city_bb_fab1_lib.crescent_city_bb_fab1(sch_1):pwrgd_cpupwrgd"
				( signalRef "@baseboard_fab2_lib.baseboard_fab2(sch_1):pwrgd_cpupwrgd_r1" )
				( signalRef "@baseboard_fab2_lib.baseboard_fab2(sch_1):pwrgd_cpupwrgd" )
				( objectStatus "PWRGD_CPUPWRGD" )
			)
			( electricalNet "@crescent_city_bb_fab1_lib.crescent_city_bb_fab1(sch_1):pwrgd_pvpp_abc"
				( signalRef "@baseboard_fab2_lib.baseboard_fab2(sch_1):pwrgd_pvpp_abc_r" )
				( signalRef "@baseboard_fab2_lib.baseboard_fab2(sch_1):pwrgd_pvpp_abc" )
				( objectStatus "PWRGD_PVPP_ABC" )
			)
			( electricalNet "@crescent_city_bb_fab1_lib.crescent_city_bb_fab1(sch_1):pwrgd_p5v"
				( signalRef "@baseboard_fab2_lib.baseboard_fab2(sch_1):pwrgd_p5v_r" )
				( signalRef "@baseboard_fab2_lib.baseboard_fab2(sch_1):pwrgd_p5v" )
				( objectStatus "PWRGD_P5V" )
			)
			( electricalNet "@crescent_city_bb_fab1_lib.crescent_city_bb_fab1(sch_1):pwrgd_pvccio_cpu1"
				( signalRef "@baseboard_fab2_lib.baseboard_fab2(sch_1):pwrgd_pvccio_cpu1" )
				( signalRef "@baseboard_fab2_lib.baseboard_fab2(sch_1):pwrgd_pvccio_cpu1_r" )
				( objectStatus "PWRGD_PVCCIO_CPU1" )
			)
			( electricalNet "@crescent_city_bb_fab1_lib.crescent_city_bb_fab1(sch_1):pwrgd_pvnn_p1v05_pch"
				( signalRef "@baseboard_fab2_lib.baseboard_fab2(sch_1):pwrgd_pvnn_p1v05_pch" )
				( signalRef "@baseboard_fab2_lib.baseboard_fab2(sch_1):pwrgd_pvnn_pch_r" )
				( objectStatus "PWRGD_PVNN_P1V05_PCH" )
			)
			( electricalNet "@crescent_city_bb_fab1_lib.crescent_city_bb_fab1(sch_1):pwrgd_p1v538_bmc_stby"
				( signalRef "@baseboard_fab2_lib.baseboard_fab2(sch_1):pwrgd_p1v538_bmc_stby_r" )
				( signalRef "@baseboard_fab2_lib.baseboard_fab2(sch_1):pwrgd_p1v538_bmc_stby" )
				( objectStatus "PWRGD_P1V538_BMC_STBY" )
			)
			( electricalNet "@crescent_city_bb_fab1_lib.crescent_city_bb_fab1(sch_1):pwrgd_p12v_hsc"
				( signalRef "@baseboard_fab2_lib.baseboard_fab2(sch_1):pwrgd_p12v_r" )
				( signalRef "@baseboard_fab2_lib.baseboard_fab2(sch_1):pwrgd_p12v_hsc" )
				( objectStatus "PWRGD_P12V_HSC" )
			)
			( electricalNet "@crescent_city_bb_fab1_lib.crescent_city_bb_fab1(sch_1):pwrgd_p12v_hsc_dly"
				( signalRef "@baseboard_fab2_lib.baseboard_fab2(sch_1):vr_p5v_stby_en" )
				( signalRef "@baseboard_fab2_lib.baseboard_fab2(sch_1):pwrgd_p12v_hsc_dly" )
				( signalRef "@baseboard_fab2_lib.baseboard_fab2(sch_1):pwrgd_p12v_hsc_dly_r" )
				( objectStatus "PWRGD_P12V_HSC_DLY" )
			)
			( electricalNet "@crescent_city_bb_fab1_lib.crescent_city_bb_fab1(sch_1):pwrgd_pvsa_cpu0"
				( signalRef "@baseboard_fab2_lib.baseboard_fab2(sch_1):pwrgd_pvsa_cpu0_r" )
				( signalRef "@baseboard_fab2_lib.baseboard_fab2(sch_1):pwrgd_pvsa_cpu0" )
				( objectStatus "PWRGD_PVSA_CPU0" )
			)
			( electricalNet "@crescent_city_bb_fab1_lib.crescent_city_bb_fab1(sch_1):pwrgd_p1v26_bmc_stby"
				( signalRef "@baseboard_fab2_lib.baseboard_fab2(sch_1):pwrgd_p1v26_bmc_stby_r" )
				( signalRef "@baseboard_fab2_lib.baseboard_fab2(sch_1):pwrgd_p1v26_bmc_stby" )
				( objectStatus "PWRGD_P1V26_BMC_STBY" )
			)
			( electricalNet "@crescent_city_bb_fab1_lib.crescent_city_bb_fab1(sch_1):rst_pcie_riser1_perst_n"
				( signalRef "@baseboard_fab2_lib.baseboard_fab2(sch_1):rst_pcie_riser1_perst_r_n" )
				( signalRef "@baseboard_fab2_lib.baseboard_fab2(sch_1):rst_pcie_riser1_perst_n" )
				( objectStatus "RST_PCIE_RISER1_PERST_N" )
			)
			( electricalNet "@crescent_city_bb_fab1_lib.crescent_city_bb_fab1(sch_1):rst_pcie_cpu_dev3_n"
				( signalRef "@baseboard_fab2_lib.baseboard_fab2(sch_1):rst_pcie_cpu_dev3_r_n" )
				( signalRef "@baseboard_fab2_lib.baseboard_fab2(sch_1):rst_pcie_cpu_dev3_n" )
				( objectStatus "RST_PCIE_CPU_DEV3_N" )
			)
			( electricalNet "@crescent_city_bb_fab1_lib.crescent_city_bb_fab1(sch_1):rst_pcie_cpu_dev2_n"
				( signalRef "@baseboard_fab2_lib.baseboard_fab2(sch_1):rst_pcie_cpu_dev2_r_n" )
				( signalRef "@baseboard_fab2_lib.baseboard_fab2(sch_1):rst_pcie_cpu_dev2_n" )
				( objectStatus "RST_PCIE_CPU_DEV2_N" )
			)
			( electricalNet "@crescent_city_bb_fab1_lib.crescent_city_bb_fab1(sch_1):rst_bmc_ddr3_n"
				( signalRef "@baseboard_fab2_lib.baseboard_fab2(sch_1):rst_bmc_ddr3_r_n" )
				( signalRef "@baseboard_fab2_lib.baseboard_fab2(sch_1):rst_bmc_ddr3_n" )
				( objectStatus "RST_BMC_DDR3_N" )
			)
			( electricalNet "@crescent_city_bb_fab1_lib.crescent_city_bb_fab1(sch_1):rst_pcie_cpu_dev1_n"
				( signalRef "@baseboard_fab2_lib.baseboard_fab2(sch_1):rst_pcie_cpu_dev1_r_n" )
				( signalRef "@baseboard_fab2_lib.baseboard_fab2(sch_1):rst_pcie_cpu_dev1_n" )
				( objectStatus "RST_PCIE_CPU_DEV1_N" )
			)
			( electricalNet "@crescent_city_bb_fab1_lib.crescent_city_bb_fab1(sch_1):rst_cpu0_lvc3_n"
				( signalRef "@baseboard_fab2_lib.baseboard_fab2(sch_1):rst_cpu0_lvc3_r1_n" )
				( signalRef "@baseboard_fab2_lib.baseboard_fab2(sch_1):rst_cpu0_lvc3_n" )
				( objectStatus "RST_CPU0_LVC3_N" )
			)
			( electricalNet "@crescent_city_bb_fab1_lib.crescent_city_bb_fab1(sch_1):rst_pcie_cpu_dev0_n"
				( signalRef "@baseboard_fab2_lib.baseboard_fab2(sch_1):rst_pcie_cpu_dev0_n" )
				( signalRef "@baseboard_fab2_lib.baseboard_fab2(sch_1):rst_pcie_cpu_dev0_r_n" )
				( objectStatus "RST_PCIE_CPU_DEV0_N" )
			)
			( electricalNet "@crescent_city_bb_fab1_lib.crescent_city_bb_fab1(sch_1):rst_bmc_lvc3_n"
				( signalRef "@baseboard_fab2_lib.baseboard_fab2(sch_1):rst_pltrst_buf_n" )
				( signalRef "@baseboard_fab2_lib.baseboard_fab2(sch_1):rst_bmc_lvc3_n" )
				( objectStatus "RST_BMC_LVC3_N" )
			)
			( electricalNet "@crescent_city_bb_fab1_lib.crescent_city_bb_fab1(sch_1):rst_cpu1_lvc3_n"
				( signalRef "@baseboard_fab2_lib.baseboard_fab2(sch_1):rst_cpu1_lvc3_r1_n" )
				( signalRef "@baseboard_fab2_lib.baseboard_fab2(sch_1):rst_cpu1_lvc3_n" )
				( objectStatus "RST_CPU1_LVC3_N" )
			)
			( electricalNet "@crescent_city_bb_fab1_lib.crescent_city_bb_fab1(sch_1):fm_pch_pwrbtn_n"
				( signalRef "@baseboard_fab2_lib.baseboard_fab2(sch_1):fm_pch_pwrbtn_r_n" )
				( signalRef "@baseboard_fab2_lib.baseboard_fab2(sch_1):fm_pch_pwrbtn_n" )
				( objectStatus "FM_PCH_PWRBTN_N" )
			)
			( electricalNet "@crescent_city_bb_fab1_lib.crescent_city_bb_fab1(sch_1):p3e_cpu1_pe3_mp_c_txn(10)"
				( signalRef "@baseboard_fab2_lib.baseboard_fab2(sch_1):p3e_cpu1_pe3_mp_txn(10)" )
				( signalRef "@baseboard_fab2_lib.baseboard_fab2(sch_1):p3e_cpu1_pe3_mp_c_txn(10)" )
				( pinPairRef "@baseboard_fab2_lib.baseboard_fab2(sch_1):\PP5832\" )
				( objectStatus "P3E_CPU1_PE3_MP_C_TXN<10>" )
			)
			( electricalNet "@crescent_city_bb_fab1_lib.crescent_city_bb_fab1(sch_1):p3e_cpu1_pe3_mp_c_txp(10)"
				( signalRef "@baseboard_fab2_lib.baseboard_fab2(sch_1):p3e_cpu1_pe3_mp_c_txp(10)" )
				( signalRef "@baseboard_fab2_lib.baseboard_fab2(sch_1):p3e_cpu1_pe3_mp_txp(10)" )
				( pinPairRef "@baseboard_fab2_lib.baseboard_fab2(sch_1):\PP5828\" )
				( objectStatus "P3E_CPU1_PE3_MP_C_TXP<10>" )
			)
			( electricalNet "@crescent_city_bb_fab1_lib.crescent_city_bb_fab1(sch_1):usb3_p01_fb_rxn"
				( signalRef "@baseboard_fab2_lib.baseboard_fab2(sch_1):usb3_p01_fb_rxn" )
				( signalRef "@baseboard_fab2_lib.baseboard_fab2(sch_1):usb3_p01_rxn" )
				( objectStatus "USB3_P01_FB_RXN" )
			)
			( electricalNet "@crescent_city_bb_fab1_lib.crescent_city_bb_fab1(sch_1):usb3_p01_fb_rxp"
				( signalRef "@baseboard_fab2_lib.baseboard_fab2(sch_1):usb3_p01_rxp" )
				( signalRef "@baseboard_fab2_lib.baseboard_fab2(sch_1):usb3_p01_fb_rxp" )
				( objectStatus "USB3_P01_FB_RXP" )
			)
			( electricalNet "@crescent_city_bb_fab1_lib.crescent_city_bb_fab1(sch_1):p3e_cpu0_pe1_pch_rxn(10)"
				( signalRef "@baseboard_fab2_lib.baseboard_fab2(sch_1):p3e_cpu0_pe1_pch_r_rxn(10)" )
				( signalRef "@baseboard_fab2_lib.baseboard_fab2(sch_1):p3e_cpu0_pe1_pch_rxn(10)" )
				( pinPairRef "@baseboard_fab2_lib.baseboard_fab2(sch_1):\PP5838\" )
				( objectStatus "P3E_CPU0_PE1_PCH_RXN<10>" )
			)
			( electricalNet "@crescent_city_bb_fab1_lib.crescent_city_bb_fab1(sch_1):p3e_cpu0_pe1_pch_rxp(10)"
				( signalRef "@baseboard_fab2_lib.baseboard_fab2(sch_1):p3e_cpu0_pe1_pch_r_rxp(10)" )
				( signalRef "@baseboard_fab2_lib.baseboard_fab2(sch_1):p3e_cpu0_pe1_pch_rxp(10)" )
				( pinPairRef "@baseboard_fab2_lib.baseboard_fab2(sch_1):\PP5839\" )
				( objectStatus "P3E_CPU0_PE1_PCH_RXP<10>" )
			)
			( electricalNet "@crescent_city_bb_fab1_lib.crescent_city_bb_fab1(sch_1):p3e_cpu0_pe1_pch_rxn(11)"
				( signalRef "@baseboard_fab2_lib.baseboard_fab2(sch_1):p3e_cpu0_pe1_pch_r_rxn(11)" )
				( signalRef "@baseboard_fab2_lib.baseboard_fab2(sch_1):p3e_cpu0_pe1_pch_rxn(11)" )
				( pinPairRef "@baseboard_fab2_lib.baseboard_fab2(sch_1):\PP5840\" )
				( objectStatus "P3E_CPU0_PE1_PCH_RXN<11>" )
			)
			( electricalNet "@crescent_city_bb_fab1_lib.crescent_city_bb_fab1(sch_1):p3e_cpu0_pe1_pch_rxp(11)"
				( signalRef "@baseboard_fab2_lib.baseboard_fab2(sch_1):p3e_cpu0_pe1_pch_r_rxp(11)" )
				( signalRef "@baseboard_fab2_lib.baseboard_fab2(sch_1):p3e_cpu0_pe1_pch_rxp(11)" )
				( pinPairRef "@baseboard_fab2_lib.baseboard_fab2(sch_1):\PP5833\" )
				( objectStatus "P3E_CPU0_PE1_PCH_RXP<11>" )
			)
			( electricalNet "@crescent_city_bb_fab1_lib.crescent_city_bb_fab1(sch_1):p3e_cpu0_pe1_pch_rxn(12)"
				( signalRef "@baseboard_fab2_lib.baseboard_fab2(sch_1):p3e_cpu0_pe1_pch_r_rxn(12)" )
				( signalRef "@baseboard_fab2_lib.baseboard_fab2(sch_1):p3e_cpu0_pe1_pch_rxn(12)" )
				( pinPairRef "@baseboard_fab2_lib.baseboard_fab2(sch_1):\PP5834\" )
				( objectStatus "P3E_CPU0_PE1_PCH_RXN<12>" )
			)
			( electricalNet "@crescent_city_bb_fab1_lib.crescent_city_bb_fab1(sch_1):p3e_cpu0_pe1_pch_rxp(12)"
				( signalRef "@baseboard_fab2_lib.baseboard_fab2(sch_1):p3e_cpu0_pe1_pch_r_rxp(12)" )
				( signalRef "@baseboard_fab2_lib.baseboard_fab2(sch_1):p3e_cpu0_pe1_pch_rxp(12)" )
				( pinPairRef "@baseboard_fab2_lib.baseboard_fab2(sch_1):\PP5844\" )
				( objectStatus "P3E_CPU0_PE1_PCH_RXP<12>" )
			)
			( electricalNet "@crescent_city_bb_fab1_lib.crescent_city_bb_fab1(sch_1):p3e_cpu0_pe1_pch_rxn(13)"
				( signalRef "@baseboard_fab2_lib.baseboard_fab2(sch_1):p3e_cpu0_pe1_pch_r_rxn(13)" )
				( signalRef "@baseboard_fab2_lib.baseboard_fab2(sch_1):p3e_cpu0_pe1_pch_rxn(13)" )
				( pinPairRef "@baseboard_fab2_lib.baseboard_fab2(sch_1):\PP5843\" )
				( objectStatus "P3E_CPU0_PE1_PCH_RXN<13>" )
			)
			( electricalNet "@crescent_city_bb_fab1_lib.crescent_city_bb_fab1(sch_1):p3e_cpu0_pe1_pch_rxp(13)"
				( signalRef "@baseboard_fab2_lib.baseboard_fab2(sch_1):p3e_cpu0_pe1_pch_r_rxp(13)" )
				( signalRef "@baseboard_fab2_lib.baseboard_fab2(sch_1):p3e_cpu0_pe1_pch_rxp(13)" )
				( pinPairRef "@baseboard_fab2_lib.baseboard_fab2(sch_1):\PP5845\" )
				( objectStatus "P3E_CPU0_PE1_PCH_RXP<13>" )
			)
			( electricalNet "@crescent_city_bb_fab1_lib.crescent_city_bb_fab1(sch_1):p3e_cpu0_pe1_pch_rxn(14)"
				( signalRef "@baseboard_fab2_lib.baseboard_fab2(sch_1):p3e_cpu0_pe1_pch_r_rxn(14)" )
				( signalRef "@baseboard_fab2_lib.baseboard_fab2(sch_1):p3e_cpu0_pe1_pch_rxn(14)" )
				( pinPairRef "@baseboard_fab2_lib.baseboard_fab2(sch_1):\PP5846\" )
				( objectStatus "P3E_CPU0_PE1_PCH_RXN<14>" )
			)
			( electricalNet "@crescent_city_bb_fab1_lib.crescent_city_bb_fab1(sch_1):p3e_cpu0_pe1_pch_rxp(14)"
				( signalRef "@baseboard_fab2_lib.baseboard_fab2(sch_1):p3e_cpu0_pe1_pch_r_rxp(14)" )
				( signalRef "@baseboard_fab2_lib.baseboard_fab2(sch_1):p3e_cpu0_pe1_pch_rxp(14)" )
				( pinPairRef "@baseboard_fab2_lib.baseboard_fab2(sch_1):\PP5847\" )
				( objectStatus "P3E_CPU0_PE1_PCH_RXP<14>" )
			)
			( electricalNet "@crescent_city_bb_fab1_lib.crescent_city_bb_fab1(sch_1):p3e_cpu0_pe1_pch_rxn(15)"
				( signalRef "@baseboard_fab2_lib.baseboard_fab2(sch_1):p3e_cpu0_pe1_pch_r_rxn(15)" )
				( signalRef "@baseboard_fab2_lib.baseboard_fab2(sch_1):p3e_cpu0_pe1_pch_rxn(15)" )
				( pinPairRef "@baseboard_fab2_lib.baseboard_fab2(sch_1):\PP5848\" )
				( objectStatus "P3E_CPU0_PE1_PCH_RXN<15>" )
			)
			( electricalNet "@crescent_city_bb_fab1_lib.crescent_city_bb_fab1(sch_1):p3e_cpu0_pe1_pch_rxp(15)"
				( signalRef "@baseboard_fab2_lib.baseboard_fab2(sch_1):p3e_cpu0_pe1_pch_r_rxp(15)" )
				( signalRef "@baseboard_fab2_lib.baseboard_fab2(sch_1):p3e_cpu0_pe1_pch_rxp(15)" )
				( pinPairRef "@baseboard_fab2_lib.baseboard_fab2(sch_1):\PP5841\" )
				( objectStatus "P3E_CPU0_PE1_PCH_RXP<15>" )
			)
			( electricalNet "@crescent_city_bb_fab1_lib.crescent_city_bb_fab1(sch_1):p3e_cpu1_pe3_mp_c_txn(8)"
				( signalRef "@baseboard_fab2_lib.baseboard_fab2(sch_1):p3e_cpu1_pe3_mp_txn(8)" )
				( signalRef "@baseboard_fab2_lib.baseboard_fab2(sch_1):p3e_cpu1_pe3_mp_c_txn(8)" )
				( pinPairRef "@baseboard_fab2_lib.baseboard_fab2(sch_1):\PP5830\" )
				( objectStatus "P3E_CPU1_PE3_MP_C_TXN<8>" )
			)
			( electricalNet "@crescent_city_bb_fab1_lib.crescent_city_bb_fab1(sch_1):p3e_cpu1_pe3_mp_c_txp(8)"
				( signalRef "@baseboard_fab2_lib.baseboard_fab2(sch_1):p3e_cpu1_pe3_mp_c_txp(8)" )
				( signalRef "@baseboard_fab2_lib.baseboard_fab2(sch_1):p3e_cpu1_pe3_mp_txp(8)" )
				( pinPairRef "@baseboard_fab2_lib.baseboard_fab2(sch_1):\PP5831\" )
				( objectStatus "P3E_CPU1_PE3_MP_C_TXP<8>" )
			)
			( electricalNet "@crescent_city_bb_fab1_lib.crescent_city_bb_fab1(sch_1):pe_pch_sprv_rx_c_dn"
				( signalRef "@baseboard_fab2_lib.baseboard_fab2(sch_1):pe_pch_sprv_rx_dn" )
				( signalRef "@baseboard_fab2_lib.baseboard_fab2(sch_1):pe_pch_sprv_rx_c_dn" )
				( objectStatus "PE_PCH_SPRV_RX_C_DN" )
			)
			( electricalNet "@crescent_city_bb_fab1_lib.crescent_city_bb_fab1(sch_1):pe_pch_sprv_rx_c_dp"
				( signalRef "@baseboard_fab2_lib.baseboard_fab2(sch_1):pe_pch_sprv_rx_dp" )
				( signalRef "@baseboard_fab2_lib.baseboard_fab2(sch_1):pe_pch_sprv_rx_c_dp" )
				( objectStatus "PE_PCH_SPRV_RX_C_DP" )
			)
			( electricalNet "@crescent_city_bb_fab1_lib.crescent_city_bb_fab1(sch_1):p3e_cpu0_pe1_ss_rxn(7)"
				( signalRef "@baseboard_fab2_lib.baseboard_fab2(sch_1):p3e_cpu0_pe1_pch_rxn(7)" )
				( signalRef "@baseboard_fab2_lib.baseboard_fab2(sch_1):p3e_cpu0_pe1_ss_rxn(7)" )
				( signalRef "@baseboard_fab2_lib.baseboard_fab2(sch_1):p3e_cpu0_pe1_ss_r_rxn(7)" )
				( electricalCSetRef "@crescent_city_bb_fab1_lib.crescent_city_bb_fab1(sch_1):\PCIE_C_D\" )
				( pinPairRef "@baseboard_fab2_lib.baseboard_fab2(sch_1):\PP5994\" )
				( pinPairRef "@baseboard_fab2_lib.baseboard_fab2(sch_1):\PP5995\" )
				( pinPairRef "@baseboard_fab2_lib.baseboard_fab2(sch_1):\PP5996\" )
				( objectStatus "P3E_CPU0_PE1_SS_RXN<7>" )
			)
			( electricalNet "@crescent_city_bb_fab1_lib.crescent_city_bb_fab1(sch_1):p3e_cpu0_pe1_ss_rxp(7)"
				( signalRef "@baseboard_fab2_lib.baseboard_fab2(sch_1):p3e_cpu0_pe1_ss_r_rxp(7)" )
				( signalRef "@baseboard_fab2_lib.baseboard_fab2(sch_1):p3e_cpu0_pe1_ss_rxp(7)" )
				( signalRef "@baseboard_fab2_lib.baseboard_fab2(sch_1):p3e_cpu0_pe1_pch_rxp(7)" )
				( electricalCSetRef "@crescent_city_bb_fab1_lib.crescent_city_bb_fab1(sch_1):\PCIE_C_D\" )
				( pinPairRef "@baseboard_fab2_lib.baseboard_fab2(sch_1):\PP5991\" )
				( pinPairRef "@baseboard_fab2_lib.baseboard_fab2(sch_1):\PP5992\" )
				( pinPairRef "@baseboard_fab2_lib.baseboard_fab2(sch_1):\PP5993\" )
				( objectStatus "P3E_CPU0_PE1_SS_RXP<7>" )
			)
			( electricalNet "@crescent_city_bb_fab1_lib.crescent_city_bb_fab1(sch_1):p3e_cpu0_pe1_pch_c_txn(8)"
				( signalRef "@baseboard_fab2_lib.baseboard_fab2(sch_1):p3e_cpu0_pe1_pch_txn(8)" )
				( signalRef "@baseboard_fab2_lib.baseboard_fab2(sch_1):p3e_cpu0_pe1_pch_c_txn(8)" )
				( pinPairRef "@baseboard_fab2_lib.baseboard_fab2(sch_1):\PP5852\" )
				( objectStatus "P3E_CPU0_PE1_PCH_C_TXN<8>" )
			)
			( electricalNet "@crescent_city_bb_fab1_lib.crescent_city_bb_fab1(sch_1):p3e_cpu0_pe1_pch_c_txp(8)"
				( signalRef "@baseboard_fab2_lib.baseboard_fab2(sch_1):p3e_cpu0_pe1_pch_c_txp(8)" )
				( signalRef "@baseboard_fab2_lib.baseboard_fab2(sch_1):p3e_cpu0_pe1_pch_txp(8)" )
				( pinPairRef "@baseboard_fab2_lib.baseboard_fab2(sch_1):\PP5842\" )
				( objectStatus "P3E_CPU0_PE1_PCH_C_TXP<8>" )
			)
			( electricalNet "@crescent_city_bb_fab1_lib.crescent_city_bb_fab1(sch_1):p3e_cpu0_pe1_pch_c_txn(9)"
				( signalRef "@baseboard_fab2_lib.baseboard_fab2(sch_1):p3e_cpu0_pe1_pch_txn(9)" )
				( signalRef "@baseboard_fab2_lib.baseboard_fab2(sch_1):p3e_cpu0_pe1_pch_c_txn(9)" )
				( pinPairRef "@baseboard_fab2_lib.baseboard_fab2(sch_1):\PP5853\" )
				( objectStatus "P3E_CPU0_PE1_PCH_C_TXN<9>" )
			)
			( electricalNet "@crescent_city_bb_fab1_lib.crescent_city_bb_fab1(sch_1):p3e_cpu0_pe1_pch_c_txp(9)"
				( signalRef "@baseboard_fab2_lib.baseboard_fab2(sch_1):p3e_cpu0_pe1_pch_c_txp(9)" )
				( signalRef "@baseboard_fab2_lib.baseboard_fab2(sch_1):p3e_cpu0_pe1_pch_txp(9)" )
				( pinPairRef "@baseboard_fab2_lib.baseboard_fab2(sch_1):\PP5851\" )
				( objectStatus "P3E_CPU0_PE1_PCH_C_TXP<9>" )
			)
			( electricalNet "@crescent_city_bb_fab1_lib.crescent_city_bb_fab1(sch_1):p3e_cpu0_pe1_pch_c_txn(10)"
				( signalRef "@baseboard_fab2_lib.baseboard_fab2(sch_1):p3e_cpu0_pe1_pch_txn(10)" )
				( signalRef "@baseboard_fab2_lib.baseboard_fab2(sch_1):p3e_cpu0_pe1_pch_c_txn(10)" )
				( pinPairRef "@baseboard_fab2_lib.baseboard_fab2(sch_1):\PP5855\" )
				( objectStatus "P3E_CPU0_PE1_PCH_C_TXN<10>" )
			)
			( electricalNet "@crescent_city_bb_fab1_lib.crescent_city_bb_fab1(sch_1):p3e_cpu0_pe1_pch_c_txp(10)"
				( signalRef "@baseboard_fab2_lib.baseboard_fab2(sch_1):p3e_cpu0_pe1_pch_c_txp(10)" )
				( signalRef "@baseboard_fab2_lib.baseboard_fab2(sch_1):p3e_cpu0_pe1_pch_txp(10)" )
				( pinPairRef "@baseboard_fab2_lib.baseboard_fab2(sch_1):\PP5854\" )
				( objectStatus "P3E_CPU0_PE1_PCH_C_TXP<10>" )
			)
			( electricalNet "@crescent_city_bb_fab1_lib.crescent_city_bb_fab1(sch_1):p3e_cpu0_pe1_pch_c_txn(11)"
				( signalRef "@baseboard_fab2_lib.baseboard_fab2(sch_1):p3e_cpu0_pe1_pch_txn(11)" )
				( signalRef "@baseboard_fab2_lib.baseboard_fab2(sch_1):p3e_cpu0_pe1_pch_c_txn(11)" )
				( pinPairRef "@baseboard_fab2_lib.baseboard_fab2(sch_1):\PP5849\" )
				( objectStatus "P3E_CPU0_PE1_PCH_C_TXN<11>" )
			)
			( electricalNet "@crescent_city_bb_fab1_lib.crescent_city_bb_fab1(sch_1):p3e_cpu0_pe1_pch_c_txp(11)"
				( signalRef "@baseboard_fab2_lib.baseboard_fab2(sch_1):p3e_cpu0_pe1_pch_c_txp(11)" )
				( signalRef "@baseboard_fab2_lib.baseboard_fab2(sch_1):p3e_cpu0_pe1_pch_txp(11)" )
				( pinPairRef "@baseboard_fab2_lib.baseboard_fab2(sch_1):\PP5856\" )
				( objectStatus "P3E_CPU0_PE1_PCH_C_TXP<11>" )
			)
			( electricalNet "@crescent_city_bb_fab1_lib.crescent_city_bb_fab1(sch_1):p3e_cpu0_pe1_pch_c_txn(12)"
				( signalRef "@baseboard_fab2_lib.baseboard_fab2(sch_1):p3e_cpu0_pe1_pch_txn(12)" )
				( signalRef "@baseboard_fab2_lib.baseboard_fab2(sch_1):p3e_cpu0_pe1_pch_c_txn(12)" )
				( pinPairRef "@baseboard_fab2_lib.baseboard_fab2(sch_1):\PP5859\" )
				( objectStatus "P3E_CPU0_PE1_PCH_C_TXN<12>" )
			)
			( electricalNet "@crescent_city_bb_fab1_lib.crescent_city_bb_fab1(sch_1):p3e_cpu0_pe1_pch_c_txp(12)"
				( signalRef "@baseboard_fab2_lib.baseboard_fab2(sch_1):p3e_cpu0_pe1_pch_c_txp(12)" )
				( signalRef "@baseboard_fab2_lib.baseboard_fab2(sch_1):p3e_cpu0_pe1_pch_txp(12)" )
				( pinPairRef "@baseboard_fab2_lib.baseboard_fab2(sch_1):\PP5850\" )
				( objectStatus "P3E_CPU0_PE1_PCH_C_TXP<12>" )
			)
			( electricalNet "@crescent_city_bb_fab1_lib.crescent_city_bb_fab1(sch_1):p3e_cpu0_pe1_pch_c_txn(13)"
				( signalRef "@baseboard_fab2_lib.baseboard_fab2(sch_1):p3e_cpu0_pe1_pch_txn(13)" )
				( signalRef "@baseboard_fab2_lib.baseboard_fab2(sch_1):p3e_cpu0_pe1_pch_c_txn(13)" )
				( pinPairRef "@baseboard_fab2_lib.baseboard_fab2(sch_1):\PP5860\" )
				( objectStatus "P3E_CPU0_PE1_PCH_C_TXN<13>" )
			)
			( electricalNet "@crescent_city_bb_fab1_lib.crescent_city_bb_fab1(sch_1):p3e_cpu0_pe1_pch_c_txp(13)"
				( signalRef "@baseboard_fab2_lib.baseboard_fab2(sch_1):p3e_cpu0_pe1_pch_c_txp(13)" )
				( signalRef "@baseboard_fab2_lib.baseboard_fab2(sch_1):p3e_cpu0_pe1_pch_txp(13)" )
				( pinPairRef "@baseboard_fab2_lib.baseboard_fab2(sch_1):\PP5858\" )
				( objectStatus "P3E_CPU0_PE1_PCH_C_TXP<13>" )
			)
			( electricalNet "@crescent_city_bb_fab1_lib.crescent_city_bb_fab1(sch_1):p3e_cpu0_pe1_pch_c_txn(14)"
				( signalRef "@baseboard_fab2_lib.baseboard_fab2(sch_1):p3e_cpu0_pe1_pch_txn(14)" )
				( signalRef "@baseboard_fab2_lib.baseboard_fab2(sch_1):p3e_cpu0_pe1_pch_c_txn(14)" )
				( pinPairRef "@baseboard_fab2_lib.baseboard_fab2(sch_1):\PP5863\" )
				( objectStatus "P3E_CPU0_PE1_PCH_C_TXN<14>" )
			)
			( electricalNet "@crescent_city_bb_fab1_lib.crescent_city_bb_fab1(sch_1):p3e_cpu0_pe1_pch_c_txp(14)"
				( signalRef "@baseboard_fab2_lib.baseboard_fab2(sch_1):p3e_cpu0_pe1_pch_c_txp(14)" )
				( signalRef "@baseboard_fab2_lib.baseboard_fab2(sch_1):p3e_cpu0_pe1_pch_txp(14)" )
				( pinPairRef "@baseboard_fab2_lib.baseboard_fab2(sch_1):\PP5861\" )
				( objectStatus "P3E_CPU0_PE1_PCH_C_TXP<14>" )
			)
			( electricalNet "@crescent_city_bb_fab1_lib.crescent_city_bb_fab1(sch_1):p3e_cpu0_pe1_pch_c_txn(15)"
				( signalRef "@baseboard_fab2_lib.baseboard_fab2(sch_1):p3e_cpu0_pe1_pch_txn(15)" )
				( signalRef "@baseboard_fab2_lib.baseboard_fab2(sch_1):p3e_cpu0_pe1_pch_c_txn(15)" )
				( pinPairRef "@baseboard_fab2_lib.baseboard_fab2(sch_1):\PP5867\" )
				( objectStatus "P3E_CPU0_PE1_PCH_C_TXN<15>" )
			)
			( electricalNet "@crescent_city_bb_fab1_lib.crescent_city_bb_fab1(sch_1):p3e_cpu0_pe1_pch_c_txp(15)"
				( signalRef "@baseboard_fab2_lib.baseboard_fab2(sch_1):p3e_cpu0_pe1_pch_c_txp(15)" )
				( signalRef "@baseboard_fab2_lib.baseboard_fab2(sch_1):p3e_cpu0_pe1_pch_txp(15)" )
				( pinPairRef "@baseboard_fab2_lib.baseboard_fab2(sch_1):\PP5862\" )
				( objectStatus "P3E_CPU0_PE1_PCH_C_TXP<15>" )
			)
			( electricalNet "@crescent_city_bb_fab1_lib.crescent_city_bb_fab1(sch_1):p3e_cpu0_pe1_pch_txn(0)"
				( signalRef "@baseboard_fab2_lib.baseboard_fab2(sch_1):p3e_cpu0_pe1_ss_txn(0)" )
				( signalRef "@baseboard_fab2_lib.baseboard_fab2(sch_1):p3e_cpu0_pe1_pch_txn(0)" )
				( signalRef "@baseboard_fab2_lib.baseboard_fab2(sch_1):p3e_cpu0_pe1_ss_c_txn(0)" )
				( pinPairRef "@baseboard_fab2_lib.baseboard_fab2(sch_1):\PP5877\" )
				( pinPairRef "@baseboard_fab2_lib.baseboard_fab2(sch_1):\PP5878\" )
				( pinPairRef "@baseboard_fab2_lib.baseboard_fab2(sch_1):\PP5879\" )
				( objectStatus "P3E_CPU0_PE1_PCH_TXN<0>" )
			)
			( electricalNet "@crescent_city_bb_fab1_lib.crescent_city_bb_fab1(sch_1):p3e_cpu0_pe1_pch_txp(0)"
				( signalRef "@baseboard_fab2_lib.baseboard_fab2(sch_1):p3e_cpu0_pe1_ss_c_txp(0)" )
				( signalRef "@baseboard_fab2_lib.baseboard_fab2(sch_1):p3e_cpu0_pe1_ss_txp(0)" )
				( signalRef "@baseboard_fab2_lib.baseboard_fab2(sch_1):p3e_cpu0_pe1_pch_txp(0)" )
				( pinPairRef "@baseboard_fab2_lib.baseboard_fab2(sch_1):\PP5864\" )
				( pinPairRef "@baseboard_fab2_lib.baseboard_fab2(sch_1):\PP5865\" )
				( pinPairRef "@baseboard_fab2_lib.baseboard_fab2(sch_1):\PP5866\" )
				( objectStatus "P3E_CPU0_PE1_PCH_TXP<0>" )
			)
			( electricalNet "@crescent_city_bb_fab1_lib.crescent_city_bb_fab1(sch_1):p3e_cpu0_pe1_pch_txn(1)"
				( signalRef "@baseboard_fab2_lib.baseboard_fab2(sch_1):p3e_cpu0_pe1_ss_txn(1)" )
				( signalRef "@baseboard_fab2_lib.baseboard_fab2(sch_1):p3e_cpu0_pe1_pch_txn(1)" )
				( signalRef "@baseboard_fab2_lib.baseboard_fab2(sch_1):p3e_cpu0_pe1_ss_c_txn(1)" )
				( pinPairRef "@baseboard_fab2_lib.baseboard_fab2(sch_1):\PP5880\" )
				( pinPairRef "@baseboard_fab2_lib.baseboard_fab2(sch_1):\PP5881\" )
				( pinPairRef "@baseboard_fab2_lib.baseboard_fab2(sch_1):\PP5882\" )
				( objectStatus "P3E_CPU0_PE1_PCH_TXN<1>" )
			)
			( electricalNet "@crescent_city_bb_fab1_lib.crescent_city_bb_fab1(sch_1):p3e_cpu0_pe1_pch_txp(1)"
				( signalRef "@baseboard_fab2_lib.baseboard_fab2(sch_1):p3e_cpu0_pe1_ss_c_txp(1)" )
				( signalRef "@baseboard_fab2_lib.baseboard_fab2(sch_1):p3e_cpu0_pe1_ss_txp(1)" )
				( signalRef "@baseboard_fab2_lib.baseboard_fab2(sch_1):p3e_cpu0_pe1_pch_txp(1)" )
				( pinPairRef "@baseboard_fab2_lib.baseboard_fab2(sch_1):\PP5874\" )
				( pinPairRef "@baseboard_fab2_lib.baseboard_fab2(sch_1):\PP5875\" )
				( pinPairRef "@baseboard_fab2_lib.baseboard_fab2(sch_1):\PP5876\" )
				( objectStatus "P3E_CPU0_PE1_PCH_TXP<1>" )
			)
			( electricalNet "@crescent_city_bb_fab1_lib.crescent_city_bb_fab1(sch_1):p3e_cpu0_pe1_pch_txn(2)"
				( signalRef "@baseboard_fab2_lib.baseboard_fab2(sch_1):p3e_cpu0_pe1_ss_txn(2)" )
				( signalRef "@baseboard_fab2_lib.baseboard_fab2(sch_1):p3e_cpu0_pe1_ss_c_txn(2)" )
				( signalRef "@baseboard_fab2_lib.baseboard_fab2(sch_1):p3e_cpu0_pe1_pch_txn(2)" )
				( pinPairRef "@baseboard_fab2_lib.baseboard_fab2(sch_1):\PP5886\" )
				( pinPairRef "@baseboard_fab2_lib.baseboard_fab2(sch_1):\PP5887\" )
				( pinPairRef "@baseboard_fab2_lib.baseboard_fab2(sch_1):\PP5888\" )
				( objectStatus "P3E_CPU0_PE1_PCH_TXN<2>" )
			)
			( electricalNet "@crescent_city_bb_fab1_lib.crescent_city_bb_fab1(sch_1):p3e_cpu0_pe1_pch_txp(2)"
				( signalRef "@baseboard_fab2_lib.baseboard_fab2(sch_1):p3e_cpu0_pe1_ss_c_txp(2)" )
				( signalRef "@baseboard_fab2_lib.baseboard_fab2(sch_1):p3e_cpu0_pe1_ss_txp(2)" )
				( signalRef "@baseboard_fab2_lib.baseboard_fab2(sch_1):p3e_cpu0_pe1_pch_txp(2)" )
				( pinPairRef "@baseboard_fab2_lib.baseboard_fab2(sch_1):\PP5883\" )
				( pinPairRef "@baseboard_fab2_lib.baseboard_fab2(sch_1):\PP5884\" )
				( pinPairRef "@baseboard_fab2_lib.baseboard_fab2(sch_1):\PP5885\" )
				( objectStatus "P3E_CPU0_PE1_PCH_TXP<2>" )
			)
			( electricalNet "@crescent_city_bb_fab1_lib.crescent_city_bb_fab1(sch_1):p3e_cpu0_pe1_pch_txn(3)"
				( signalRef "@baseboard_fab2_lib.baseboard_fab2(sch_1):p3e_cpu0_pe1_ss_txn(3)" )
				( signalRef "@baseboard_fab2_lib.baseboard_fab2(sch_1):p3e_cpu0_pe1_ss_c_txn(3)" )
				( signalRef "@baseboard_fab2_lib.baseboard_fab2(sch_1):p3e_cpu0_pe1_pch_txn(3)" )
				( pinPairRef "@baseboard_fab2_lib.baseboard_fab2(sch_1):\PP5868\" )
				( pinPairRef "@baseboard_fab2_lib.baseboard_fab2(sch_1):\PP5869\" )
				( pinPairRef "@baseboard_fab2_lib.baseboard_fab2(sch_1):\PP5870\" )
				( objectStatus "P3E_CPU0_PE1_PCH_TXN<3>" )
			)
			( electricalNet "@crescent_city_bb_fab1_lib.crescent_city_bb_fab1(sch_1):p3e_cpu0_pe1_pch_txp(3)"
				( signalRef "@baseboard_fab2_lib.baseboard_fab2(sch_1):p3e_cpu0_pe1_ss_c_txp(3)" )
				( signalRef "@baseboard_fab2_lib.baseboard_fab2(sch_1):p3e_cpu0_pe1_ss_txp(3)" )
				( signalRef "@baseboard_fab2_lib.baseboard_fab2(sch_1):p3e_cpu0_pe1_pch_txp(3)" )
				( pinPairRef "@baseboard_fab2_lib.baseboard_fab2(sch_1):\PP5889\" )
				( pinPairRef "@baseboard_fab2_lib.baseboard_fab2(sch_1):\PP5890\" )
				( pinPairRef "@baseboard_fab2_lib.baseboard_fab2(sch_1):\PP5891\" )
				( objectStatus "P3E_CPU0_PE1_PCH_TXP<3>" )
			)
			( electricalNet "@crescent_city_bb_fab1_lib.crescent_city_bb_fab1(sch_1):p3e_cpu0_pe1_pch_txn(4)"
				( signalRef "@baseboard_fab2_lib.baseboard_fab2(sch_1):p3e_cpu0_pe1_ss_txn(4)" )
				( signalRef "@baseboard_fab2_lib.baseboard_fab2(sch_1):p3e_cpu0_pe1_pch_txn(4)" )
				( signalRef "@baseboard_fab2_lib.baseboard_fab2(sch_1):p3e_cpu0_pe1_ss_c_txn(4)" )
				( pinPairRef "@baseboard_fab2_lib.baseboard_fab2(sch_1):\PP5822\" )
				( pinPairRef "@baseboard_fab2_lib.baseboard_fab2(sch_1):\PP5823\" )
				( pinPairRef "@baseboard_fab2_lib.baseboard_fab2(sch_1):\PP5824\" )
				( objectStatus "P3E_CPU0_PE1_PCH_TXN<4>" )
			)
			( electricalNet "@crescent_city_bb_fab1_lib.crescent_city_bb_fab1(sch_1):p3e_cpu0_pe1_pch_txp(4)"
				( signalRef "@baseboard_fab2_lib.baseboard_fab2(sch_1):p3e_cpu0_pe1_ss_c_txp(4)" )
				( signalRef "@baseboard_fab2_lib.baseboard_fab2(sch_1):p3e_cpu0_pe1_ss_txp(4)" )
				( signalRef "@baseboard_fab2_lib.baseboard_fab2(sch_1):p3e_cpu0_pe1_pch_txp(4)" )
				( pinPairRef "@baseboard_fab2_lib.baseboard_fab2(sch_1):\PP5871\" )
				( pinPairRef "@baseboard_fab2_lib.baseboard_fab2(sch_1):\PP5872\" )
				( pinPairRef "@baseboard_fab2_lib.baseboard_fab2(sch_1):\PP5873\" )
				( objectStatus "P3E_CPU0_PE1_PCH_TXP<4>" )
			)
			( electricalNet "@crescent_city_bb_fab1_lib.crescent_city_bb_fab1(sch_1):p3e_cpu0_pe1_pch_txn(5)"
				( signalRef "@baseboard_fab2_lib.baseboard_fab2(sch_1):p3e_cpu0_pe1_ss_txn(5)" )
				( signalRef "@baseboard_fab2_lib.baseboard_fab2(sch_1):p3e_cpu0_pe1_ss_c_txn(5)" )
				( signalRef "@baseboard_fab2_lib.baseboard_fab2(sch_1):p3e_cpu0_pe1_pch_txn(5)" )
				( pinPairRef "@baseboard_fab2_lib.baseboard_fab2(sch_1):\PP5897\" )
				( pinPairRef "@baseboard_fab2_lib.baseboard_fab2(sch_1):\PP5898\" )
				( pinPairRef "@baseboard_fab2_lib.baseboard_fab2(sch_1):\PP5899\" )
				( objectStatus "P3E_CPU0_PE1_PCH_TXN<5>" )
			)
			( electricalNet "@crescent_city_bb_fab1_lib.crescent_city_bb_fab1(sch_1):p3e_cpu0_pe1_pch_txp(5)"
				( signalRef "@baseboard_fab2_lib.baseboard_fab2(sch_1):p3e_cpu0_pe1_ss_c_txp(5)" )
				( signalRef "@baseboard_fab2_lib.baseboard_fab2(sch_1):p3e_cpu0_pe1_ss_txp(5)" )
				( signalRef "@baseboard_fab2_lib.baseboard_fab2(sch_1):p3e_cpu0_pe1_pch_txp(5)" )
				( pinPairRef "@baseboard_fab2_lib.baseboard_fab2(sch_1):\PP5816\" )
				( pinPairRef "@baseboard_fab2_lib.baseboard_fab2(sch_1):\PP5817\" )
				( pinPairRef "@baseboard_fab2_lib.baseboard_fab2(sch_1):\PP5818\" )
				( objectStatus "P3E_CPU0_PE1_PCH_TXP<5>" )
			)
			( electricalNet "@crescent_city_bb_fab1_lib.crescent_city_bb_fab1(sch_1):p3e_cpu0_pe1_pch_txn(6)"
				( signalRef "@baseboard_fab2_lib.baseboard_fab2(sch_1):p3e_cpu0_pe1_ss_txn(6)" )
				( signalRef "@baseboard_fab2_lib.baseboard_fab2(sch_1):p3e_cpu0_pe1_ss_c_txn(6)" )
				( signalRef "@baseboard_fab2_lib.baseboard_fab2(sch_1):p3e_cpu0_pe1_pch_txn(6)" )
				( pinPairRef "@baseboard_fab2_lib.baseboard_fab2(sch_1):\PP5901\" )
				( pinPairRef "@baseboard_fab2_lib.baseboard_fab2(sch_1):\PP5902\" )
				( pinPairRef "@baseboard_fab2_lib.baseboard_fab2(sch_1):\PP5903\" )
				( objectStatus "P3E_CPU0_PE1_PCH_TXN<6>" )
			)
			( electricalNet "@crescent_city_bb_fab1_lib.crescent_city_bb_fab1(sch_1):p3e_cpu0_pe1_pch_txp(6)"
				( signalRef "@baseboard_fab2_lib.baseboard_fab2(sch_1):p3e_cpu0_pe1_ss_c_txp(6)" )
				( signalRef "@baseboard_fab2_lib.baseboard_fab2(sch_1):p3e_cpu0_pe1_ss_txp(6)" )
				( signalRef "@baseboard_fab2_lib.baseboard_fab2(sch_1):p3e_cpu0_pe1_pch_txp(6)" )
				( pinPairRef "@baseboard_fab2_lib.baseboard_fab2(sch_1):\PP5894\" )
				( pinPairRef "@baseboard_fab2_lib.baseboard_fab2(sch_1):\PP5895\" )
				( pinPairRef "@baseboard_fab2_lib.baseboard_fab2(sch_1):\PP5896\" )
				( objectStatus "P3E_CPU0_PE1_PCH_TXP<6>" )
			)
			( electricalNet "@crescent_city_bb_fab1_lib.crescent_city_bb_fab1(sch_1):p3e_cpu0_pe1_pch_txn(7)"
				( signalRef "@baseboard_fab2_lib.baseboard_fab2(sch_1):p3e_cpu0_pe1_ss_txn(7)" )
				( signalRef "@baseboard_fab2_lib.baseboard_fab2(sch_1):p3e_cpu0_pe1_ss_c_txn(7)" )
				( signalRef "@baseboard_fab2_lib.baseboard_fab2(sch_1):p3e_cpu0_pe1_pch_txn(7)" )
				( pinPairRef "@baseboard_fab2_lib.baseboard_fab2(sch_1):\PP5907\" )
				( pinPairRef "@baseboard_fab2_lib.baseboard_fab2(sch_1):\PP5908\" )
				( pinPairRef "@baseboard_fab2_lib.baseboard_fab2(sch_1):\PP5909\" )
				( objectStatus "P3E_CPU0_PE1_PCH_TXN<7>" )
			)
			( electricalNet "@crescent_city_bb_fab1_lib.crescent_city_bb_fab1(sch_1):p3e_cpu0_pe1_pch_txp(7)"
				( signalRef "@baseboard_fab2_lib.baseboard_fab2(sch_1):p3e_cpu0_pe1_ss_c_txp(7)" )
				( signalRef "@baseboard_fab2_lib.baseboard_fab2(sch_1):p3e_cpu0_pe1_ss_txp(7)" )
				( signalRef "@baseboard_fab2_lib.baseboard_fab2(sch_1):p3e_cpu0_pe1_pch_txp(7)" )
				( pinPairRef "@baseboard_fab2_lib.baseboard_fab2(sch_1):\PP5904\" )
				( pinPairRef "@baseboard_fab2_lib.baseboard_fab2(sch_1):\PP5905\" )
				( pinPairRef "@baseboard_fab2_lib.baseboard_fab2(sch_1):\PP5906\" )
				( objectStatus "P3E_CPU0_PE1_PCH_TXP<7>" )
			)
			( electricalNet "@crescent_city_bb_fab1_lib.crescent_city_bb_fab1(sch_1):p3e_cpu0_pe2_ss_c_txn(0)"
				( signalRef "@baseboard_fab2_lib.baseboard_fab2(sch_1):p3e_cpu0_pe2_ss_txn(0)" )
				( signalRef "@baseboard_fab2_lib.baseboard_fab2(sch_1):p3e_cpu0_pe2_ss_c_txn(0)" )
				( pinPairRef "@baseboard_fab2_lib.baseboard_fab2(sch_1):\PP5911\" )
				( objectStatus "P3E_CPU0_PE2_SS_C_TXN<0>" )
			)
			( electricalNet "@crescent_city_bb_fab1_lib.crescent_city_bb_fab1(sch_1):p3e_cpu0_pe2_ss_c_txp(0)"
				( signalRef "@baseboard_fab2_lib.baseboard_fab2(sch_1):p3e_cpu0_pe2_ss_c_txp(0)" )
				( signalRef "@baseboard_fab2_lib.baseboard_fab2(sch_1):p3e_cpu0_pe2_ss_txp(0)" )
				( pinPairRef "@baseboard_fab2_lib.baseboard_fab2(sch_1):\PP5910\" )
				( objectStatus "P3E_CPU0_PE2_SS_C_TXP<0>" )
			)
			( electricalNet "@crescent_city_bb_fab1_lib.crescent_city_bb_fab1(sch_1):p3e_cpu0_pe2_ss_c_txn(1)"
				( signalRef "@baseboard_fab2_lib.baseboard_fab2(sch_1):p3e_cpu0_pe2_ss_txn(1)" )
				( signalRef "@baseboard_fab2_lib.baseboard_fab2(sch_1):p3e_cpu0_pe2_ss_c_txn(1)" )
				( pinPairRef "@baseboard_fab2_lib.baseboard_fab2(sch_1):\PP5819\" )
				( objectStatus "P3E_CPU0_PE2_SS_C_TXN<1>" )
			)
			( electricalNet "@crescent_city_bb_fab1_lib.crescent_city_bb_fab1(sch_1):p3e_cpu0_pe2_ss_c_txp(1)"
				( signalRef "@baseboard_fab2_lib.baseboard_fab2(sch_1):p3e_cpu0_pe2_ss_c_txp(1)" )
				( signalRef "@baseboard_fab2_lib.baseboard_fab2(sch_1):p3e_cpu0_pe2_ss_txp(1)" )
				( pinPairRef "@baseboard_fab2_lib.baseboard_fab2(sch_1):\PP5900\" )
				( objectStatus "P3E_CPU0_PE2_SS_C_TXP<1>" )
			)
			( electricalNet "@crescent_city_bb_fab1_lib.crescent_city_bb_fab1(sch_1):p3e_cpu0_pe2_ss_c_txn(2)"
				( signalRef "@baseboard_fab2_lib.baseboard_fab2(sch_1):p3e_cpu0_pe2_ss_txn(2)" )
				( signalRef "@baseboard_fab2_lib.baseboard_fab2(sch_1):p3e_cpu0_pe2_ss_c_txn(2)" )
				( pinPairRef "@baseboard_fab2_lib.baseboard_fab2(sch_1):\PP5826\" )
				( objectStatus "P3E_CPU0_PE2_SS_C_TXN<2>" )
			)
			( electricalNet "@crescent_city_bb_fab1_lib.crescent_city_bb_fab1(sch_1):p3e_cpu0_pe2_ss_c_txp(2)"
				( signalRef "@baseboard_fab2_lib.baseboard_fab2(sch_1):p3e_cpu0_pe2_ss_c_txp(2)" )
				( signalRef "@baseboard_fab2_lib.baseboard_fab2(sch_1):p3e_cpu0_pe2_ss_txp(2)" )
				( pinPairRef "@baseboard_fab2_lib.baseboard_fab2(sch_1):\PP5825\" )
				( objectStatus "P3E_CPU0_PE2_SS_C_TXP<2>" )
			)
			( electricalNet "@crescent_city_bb_fab1_lib.crescent_city_bb_fab1(sch_1):p3e_cpu0_pe2_ss_c_txn(3)"
				( signalRef "@baseboard_fab2_lib.baseboard_fab2(sch_1):p3e_cpu0_pe2_ss_txn(3)" )
				( signalRef "@baseboard_fab2_lib.baseboard_fab2(sch_1):p3e_cpu0_pe2_ss_c_txn(3)" )
				( pinPairRef "@baseboard_fab2_lib.baseboard_fab2(sch_1):\PP5857\" )
				( objectStatus "P3E_CPU0_PE2_SS_C_TXN<3>" )
			)
			( electricalNet "@crescent_city_bb_fab1_lib.crescent_city_bb_fab1(sch_1):p3e_cpu0_pe2_ss_c_txp(3)"
				( signalRef "@baseboard_fab2_lib.baseboard_fab2(sch_1):p3e_cpu0_pe2_ss_c_txp(3)" )
				( signalRef "@baseboard_fab2_lib.baseboard_fab2(sch_1):p3e_cpu0_pe2_ss_txp(3)" )
				( pinPairRef "@baseboard_fab2_lib.baseboard_fab2(sch_1):\PP5815\" )
				( objectStatus "P3E_CPU0_PE2_SS_C_TXP<3>" )
			)
			( electricalNet "@crescent_city_bb_fab1_lib.crescent_city_bb_fab1(sch_1):p3e_cpu0_pe2_ss_c_txn(4)"
				( signalRef "@baseboard_fab2_lib.baseboard_fab2(sch_1):p3e_cpu0_pe2_ss_txn(4)" )
				( signalRef "@baseboard_fab2_lib.baseboard_fab2(sch_1):p3e_cpu0_pe2_ss_c_txn(4)" )
				( pinPairRef "@baseboard_fab2_lib.baseboard_fab2(sch_1):\PP5821\" )
				( objectStatus "P3E_CPU0_PE2_SS_C_TXN<4>" )
			)
			( electricalNet "@crescent_city_bb_fab1_lib.crescent_city_bb_fab1(sch_1):p3e_cpu0_pe2_ss_c_txp(4)"
				( signalRef "@baseboard_fab2_lib.baseboard_fab2(sch_1):p3e_cpu0_pe2_ss_c_txp(4)" )
				( signalRef "@baseboard_fab2_lib.baseboard_fab2(sch_1):p3e_cpu0_pe2_ss_txp(4)" )
				( pinPairRef "@baseboard_fab2_lib.baseboard_fab2(sch_1):\PP5820\" )
				( objectStatus "P3E_CPU0_PE2_SS_C_TXP<4>" )
			)
			( electricalNet "@crescent_city_bb_fab1_lib.crescent_city_bb_fab1(sch_1):p3e_cpu0_pe2_ss_c_txn(5)"
				( signalRef "@baseboard_fab2_lib.baseboard_fab2(sch_1):p3e_cpu0_pe2_ss_txn(5)" )
				( signalRef "@baseboard_fab2_lib.baseboard_fab2(sch_1):p3e_cpu0_pe2_ss_c_txn(5)" )
				( pinPairRef "@baseboard_fab2_lib.baseboard_fab2(sch_1):\PP5912\" )
				( objectStatus "P3E_CPU0_PE2_SS_C_TXN<5>" )
			)
			( electricalNet "@crescent_city_bb_fab1_lib.crescent_city_bb_fab1(sch_1):p3e_cpu0_pe2_ss_c_txp(5)"
				( signalRef "@baseboard_fab2_lib.baseboard_fab2(sch_1):p3e_cpu0_pe2_ss_c_txp(5)" )
				( signalRef "@baseboard_fab2_lib.baseboard_fab2(sch_1):p3e_cpu0_pe2_ss_txp(5)" )
				( pinPairRef "@baseboard_fab2_lib.baseboard_fab2(sch_1):\PP5827\" )
				( objectStatus "P3E_CPU0_PE2_SS_C_TXP<5>" )
			)
			( electricalNet "@crescent_city_bb_fab1_lib.crescent_city_bb_fab1(sch_1):p3e_cpu0_pe2_ss_c_txn(6)"
				( signalRef "@baseboard_fab2_lib.baseboard_fab2(sch_1):p3e_cpu0_pe2_ss_txn(6)" )
				( signalRef "@baseboard_fab2_lib.baseboard_fab2(sch_1):p3e_cpu0_pe2_ss_c_txn(6)" )
				( pinPairRef "@baseboard_fab2_lib.baseboard_fab2(sch_1):\PP5917\" )
				( objectStatus "P3E_CPU0_PE2_SS_C_TXN<6>" )
			)
			( electricalNet "@crescent_city_bb_fab1_lib.crescent_city_bb_fab1(sch_1):p3e_cpu0_pe2_ss_c_txp(6)"
				( signalRef "@baseboard_fab2_lib.baseboard_fab2(sch_1):p3e_cpu0_pe2_ss_c_txp(6)" )
				( signalRef "@baseboard_fab2_lib.baseboard_fab2(sch_1):p3e_cpu0_pe2_ss_txp(6)" )
				( pinPairRef "@baseboard_fab2_lib.baseboard_fab2(sch_1):\PP5913\" )
				( objectStatus "P3E_CPU0_PE2_SS_C_TXP<6>" )
			)
			( electricalNet "@crescent_city_bb_fab1_lib.crescent_city_bb_fab1(sch_1):p3e_cpu0_pe2_ss_c_txn(7)"
				( signalRef "@baseboard_fab2_lib.baseboard_fab2(sch_1):p3e_cpu0_pe2_ss_txn(7)" )
				( signalRef "@baseboard_fab2_lib.baseboard_fab2(sch_1):p3e_cpu0_pe2_ss_c_txn(7)" )
				( pinPairRef "@baseboard_fab2_lib.baseboard_fab2(sch_1):\PP5919\" )
				( objectStatus "P3E_CPU0_PE2_SS_C_TXN<7>" )
			)
			( electricalNet "@crescent_city_bb_fab1_lib.crescent_city_bb_fab1(sch_1):p3e_cpu0_pe2_ss_c_txp(7)"
				( signalRef "@baseboard_fab2_lib.baseboard_fab2(sch_1):p3e_cpu0_pe2_ss_c_txp(7)" )
				( signalRef "@baseboard_fab2_lib.baseboard_fab2(sch_1):p3e_cpu0_pe2_ss_txp(7)" )
				( pinPairRef "@baseboard_fab2_lib.baseboard_fab2(sch_1):\PP5918\" )
				( objectStatus "P3E_CPU0_PE2_SS_C_TXP<7>" )
			)
			( electricalNet "@crescent_city_bb_fab1_lib.crescent_city_bb_fab1(sch_1):p3e_cpu0_pe2_ss_c_txn(8)"
				( signalRef "@baseboard_fab2_lib.baseboard_fab2(sch_1):p3e_cpu0_pe2_ss_txn(8)" )
				( signalRef "@baseboard_fab2_lib.baseboard_fab2(sch_1):p3e_cpu0_pe2_ss_c_txn(8)" )
				( pinPairRef "@baseboard_fab2_lib.baseboard_fab2(sch_1):\PP5915\" )
				( objectStatus "P3E_CPU0_PE2_SS_C_TXN<8>" )
			)
			( electricalNet "@crescent_city_bb_fab1_lib.crescent_city_bb_fab1(sch_1):p3e_cpu0_pe2_ss_c_txp(8)"
				( signalRef "@baseboard_fab2_lib.baseboard_fab2(sch_1):p3e_cpu0_pe2_ss_c_txp(8)" )
				( signalRef "@baseboard_fab2_lib.baseboard_fab2(sch_1):p3e_cpu0_pe2_ss_txp(8)" )
				( pinPairRef "@baseboard_fab2_lib.baseboard_fab2(sch_1):\PP5920\" )
				( objectStatus "P3E_CPU0_PE2_SS_C_TXP<8>" )
			)
			( electricalNet "@crescent_city_bb_fab1_lib.crescent_city_bb_fab1(sch_1):p3e_cpu0_pe2_ss_c_txn(9)"
				( signalRef "@baseboard_fab2_lib.baseboard_fab2(sch_1):p3e_cpu0_pe2_ss_txn(9)" )
				( signalRef "@baseboard_fab2_lib.baseboard_fab2(sch_1):p3e_cpu0_pe2_ss_c_txn(9)" )
				( pinPairRef "@baseboard_fab2_lib.baseboard_fab2(sch_1):\PP5925\" )
				( objectStatus "P3E_CPU0_PE2_SS_C_TXN<9>" )
			)
			( electricalNet "@crescent_city_bb_fab1_lib.crescent_city_bb_fab1(sch_1):p3e_cpu0_pe2_ss_c_txp(9)"
				( signalRef "@baseboard_fab2_lib.baseboard_fab2(sch_1):p3e_cpu0_pe2_ss_c_txp(9)" )
				( signalRef "@baseboard_fab2_lib.baseboard_fab2(sch_1):p3e_cpu0_pe2_ss_txp(9)" )
				( pinPairRef "@baseboard_fab2_lib.baseboard_fab2(sch_1):\PP5914\" )
				( objectStatus "P3E_CPU0_PE2_SS_C_TXP<9>" )
			)
			( electricalNet "@crescent_city_bb_fab1_lib.crescent_city_bb_fab1(sch_1):p3e_cpu0_pe2_ss_c_txn(10)"
				( signalRef "@baseboard_fab2_lib.baseboard_fab2(sch_1):p3e_cpu0_pe2_ss_txn(10)" )
				( signalRef "@baseboard_fab2_lib.baseboard_fab2(sch_1):p3e_cpu0_pe2_ss_c_txn(10)" )
				( pinPairRef "@baseboard_fab2_lib.baseboard_fab2(sch_1):\PP5927\" )
				( objectStatus "P3E_CPU0_PE2_SS_C_TXN<10>" )
			)
			( electricalNet "@crescent_city_bb_fab1_lib.crescent_city_bb_fab1(sch_1):p3e_cpu0_pe2_ss_c_txp(10)"
				( signalRef "@baseboard_fab2_lib.baseboard_fab2(sch_1):p3e_cpu0_pe2_ss_c_txp(10)" )
				( signalRef "@baseboard_fab2_lib.baseboard_fab2(sch_1):p3e_cpu0_pe2_ss_txp(10)" )
				( pinPairRef "@baseboard_fab2_lib.baseboard_fab2(sch_1):\PP5924\" )
				( objectStatus "P3E_CPU0_PE2_SS_C_TXP<10>" )
			)
			( electricalNet "@crescent_city_bb_fab1_lib.crescent_city_bb_fab1(sch_1):p3e_cpu0_pe2_ss_c_txn(11)"
				( signalRef "@baseboard_fab2_lib.baseboard_fab2(sch_1):p3e_cpu0_pe2_ss_txn(11)" )
				( signalRef "@baseboard_fab2_lib.baseboard_fab2(sch_1):p3e_cpu0_pe2_ss_c_txn(11)" )
				( pinPairRef "@baseboard_fab2_lib.baseboard_fab2(sch_1):\PP5929\" )
				( objectStatus "P3E_CPU0_PE2_SS_C_TXN<11>" )
			)
			( electricalNet "@crescent_city_bb_fab1_lib.crescent_city_bb_fab1(sch_1):p3e_cpu0_pe2_ss_c_txp(11)"
				( signalRef "@baseboard_fab2_lib.baseboard_fab2(sch_1):p3e_cpu0_pe2_ss_c_txp(11)" )
				( signalRef "@baseboard_fab2_lib.baseboard_fab2(sch_1):p3e_cpu0_pe2_ss_txp(11)" )
				( pinPairRef "@baseboard_fab2_lib.baseboard_fab2(sch_1):\PP5928\" )
				( objectStatus "P3E_CPU0_PE2_SS_C_TXP<11>" )
			)
			( electricalNet "@crescent_city_bb_fab1_lib.crescent_city_bb_fab1(sch_1):p3e_cpu0_pe2_ss_c_txn(12)"
				( signalRef "@baseboard_fab2_lib.baseboard_fab2(sch_1):p3e_cpu0_pe2_ss_txn(12)" )
				( signalRef "@baseboard_fab2_lib.baseboard_fab2(sch_1):p3e_cpu0_pe2_ss_c_txn(12)" )
				( pinPairRef "@baseboard_fab2_lib.baseboard_fab2(sch_1):\PP5931\" )
				( objectStatus "P3E_CPU0_PE2_SS_C_TXN<12>" )
			)
			( electricalNet "@crescent_city_bb_fab1_lib.crescent_city_bb_fab1(sch_1):p3e_cpu0_pe2_ss_c_txp(12)"
				( signalRef "@baseboard_fab2_lib.baseboard_fab2(sch_1):p3e_cpu0_pe2_ss_c_txp(12)" )
				( signalRef "@baseboard_fab2_lib.baseboard_fab2(sch_1):p3e_cpu0_pe2_ss_txp(12)" )
				( pinPairRef "@baseboard_fab2_lib.baseboard_fab2(sch_1):\PP5930\" )
				( objectStatus "P3E_CPU0_PE2_SS_C_TXP<12>" )
			)
			( electricalNet "@crescent_city_bb_fab1_lib.crescent_city_bb_fab1(sch_1):p3e_cpu0_pe2_ss_c_txn(13)"
				( signalRef "@baseboard_fab2_lib.baseboard_fab2(sch_1):p3e_cpu0_pe2_ss_txn(13)" )
				( signalRef "@baseboard_fab2_lib.baseboard_fab2(sch_1):p3e_cpu0_pe2_ss_c_txn(13)" )
				( pinPairRef "@baseboard_fab2_lib.baseboard_fab2(sch_1):\PP5933\" )
				( objectStatus "P3E_CPU0_PE2_SS_C_TXN<13>" )
			)
			( electricalNet "@crescent_city_bb_fab1_lib.crescent_city_bb_fab1(sch_1):p3e_cpu0_pe2_ss_c_txp(13)"
				( signalRef "@baseboard_fab2_lib.baseboard_fab2(sch_1):p3e_cpu0_pe2_ss_c_txp(13)" )
				( signalRef "@baseboard_fab2_lib.baseboard_fab2(sch_1):p3e_cpu0_pe2_ss_txp(13)" )
				( pinPairRef "@baseboard_fab2_lib.baseboard_fab2(sch_1):\PP5926\" )
				( objectStatus "P3E_CPU0_PE2_SS_C_TXP<13>" )
			)
			( electricalNet "@crescent_city_bb_fab1_lib.crescent_city_bb_fab1(sch_1):p3e_cpu0_pe2_ss_c_txn(14)"
				( signalRef "@baseboard_fab2_lib.baseboard_fab2(sch_1):p3e_cpu0_pe2_ss_txn(14)" )
				( signalRef "@baseboard_fab2_lib.baseboard_fab2(sch_1):p3e_cpu0_pe2_ss_c_txn(14)" )
				( pinPairRef "@baseboard_fab2_lib.baseboard_fab2(sch_1):\PP5938\" )
				( objectStatus "P3E_CPU0_PE2_SS_C_TXN<14>" )
			)
			( electricalNet "@crescent_city_bb_fab1_lib.crescent_city_bb_fab1(sch_1):p3e_cpu0_pe2_ss_c_txp(14)"
				( signalRef "@baseboard_fab2_lib.baseboard_fab2(sch_1):p3e_cpu0_pe2_ss_c_txp(14)" )
				( signalRef "@baseboard_fab2_lib.baseboard_fab2(sch_1):p3e_cpu0_pe2_ss_txp(14)" )
				( pinPairRef "@baseboard_fab2_lib.baseboard_fab2(sch_1):\PP5937\" )
				( objectStatus "P3E_CPU0_PE2_SS_C_TXP<14>" )
			)
			( electricalNet "@crescent_city_bb_fab1_lib.crescent_city_bb_fab1(sch_1):p3e_cpu0_pe2_ss_c_txn(15)"
				( signalRef "@baseboard_fab2_lib.baseboard_fab2(sch_1):p3e_cpu0_pe2_ss_txn(15)" )
				( signalRef "@baseboard_fab2_lib.baseboard_fab2(sch_1):p3e_cpu0_pe2_ss_c_txn(15)" )
				( pinPairRef "@baseboard_fab2_lib.baseboard_fab2(sch_1):\PP5941\" )
				( objectStatus "P3E_CPU0_PE2_SS_C_TXN<15>" )
			)
			( electricalNet "@crescent_city_bb_fab1_lib.crescent_city_bb_fab1(sch_1):p3e_cpu0_pe2_ss_c_txp(15)"
				( signalRef "@baseboard_fab2_lib.baseboard_fab2(sch_1):p3e_cpu0_pe2_ss_c_txp(15)" )
				( signalRef "@baseboard_fab2_lib.baseboard_fab2(sch_1):p3e_cpu0_pe2_ss_txp(15)" )
				( pinPairRef "@baseboard_fab2_lib.baseboard_fab2(sch_1):\PP5939\" )
				( objectStatus "P3E_CPU0_PE2_SS_C_TXP<15>" )
			)
			( electricalNet "@crescent_city_bb_fab1_lib.crescent_city_bb_fab1(sch_1):p3e_cpu0_pe3_ocp_txn(0)"
				( signalRef "@baseboard_fab2_lib.baseboard_fab2(sch_1):p3e_cpu0_pe3_ocp_txn(0)" )
				( signalRef "@baseboard_fab2_lib.baseboard_fab2(sch_1):p3e_ocp_cpu0_pe3_c_txn(0)" )
				( pinPairRef "@baseboard_fab2_lib.baseboard_fab2(sch_1):\PP5940\" )
				( objectStatus "P3E_CPU0_PE3_OCP_TXN<0>" )
			)
			( electricalNet "@crescent_city_bb_fab1_lib.crescent_city_bb_fab1(sch_1):p3e_cpu0_pe3_ocp_txp(0)"
				( signalRef "@baseboard_fab2_lib.baseboard_fab2(sch_1):p3e_ocp_cpu0_pe3_c_txp(0)" )
				( signalRef "@baseboard_fab2_lib.baseboard_fab2(sch_1):p3e_cpu0_pe3_ocp_txp(0)" )
				( pinPairRef "@baseboard_fab2_lib.baseboard_fab2(sch_1):\PP5942\" )
				( objectStatus "P3E_CPU0_PE3_OCP_TXP<0>" )
			)
			( electricalNet "@crescent_city_bb_fab1_lib.crescent_city_bb_fab1(sch_1):p3e_cpu0_pe3_ocp_txn(1)"
				( signalRef "@baseboard_fab2_lib.baseboard_fab2(sch_1):p3e_cpu0_pe3_ocp_txn(1)" )
				( signalRef "@baseboard_fab2_lib.baseboard_fab2(sch_1):p3e_ocp_cpu0_pe3_c_txn(1)" )
				( pinPairRef "@baseboard_fab2_lib.baseboard_fab2(sch_1):\PP5944\" )
				( objectStatus "P3E_CPU0_PE3_OCP_TXN<1>" )
			)
			( electricalNet "@crescent_city_bb_fab1_lib.crescent_city_bb_fab1(sch_1):p3e_cpu0_pe3_ocp_txp(1)"
				( signalRef "@baseboard_fab2_lib.baseboard_fab2(sch_1):p3e_ocp_cpu0_pe3_c_txp(1)" )
				( signalRef "@baseboard_fab2_lib.baseboard_fab2(sch_1):p3e_cpu0_pe3_ocp_txp(1)" )
				( pinPairRef "@baseboard_fab2_lib.baseboard_fab2(sch_1):\PP5932\" )
				( objectStatus "P3E_CPU0_PE3_OCP_TXP<1>" )
			)
			( electricalNet "@crescent_city_bb_fab1_lib.crescent_city_bb_fab1(sch_1):p3e_cpu0_pe3_ocp_txn(2)"
				( signalRef "@baseboard_fab2_lib.baseboard_fab2(sch_1):p3e_cpu0_pe3_ocp_txn(2)" )
				( signalRef "@baseboard_fab2_lib.baseboard_fab2(sch_1):p3e_ocp_cpu0_pe3_c_txn(2)" )
				( pinPairRef "@baseboard_fab2_lib.baseboard_fab2(sch_1):\PP5945\" )
				( objectStatus "P3E_CPU0_PE3_OCP_TXN<2>" )
			)
			( electricalNet "@crescent_city_bb_fab1_lib.crescent_city_bb_fab1(sch_1):p3e_cpu0_pe3_ocp_txp(2)"
				( signalRef "@baseboard_fab2_lib.baseboard_fab2(sch_1):p3e_ocp_cpu0_pe3_c_txp(2)" )
				( signalRef "@baseboard_fab2_lib.baseboard_fab2(sch_1):p3e_cpu0_pe3_ocp_txp(2)" )
				( pinPairRef "@baseboard_fab2_lib.baseboard_fab2(sch_1):\PP5943\" )
				( objectStatus "P3E_CPU0_PE3_OCP_TXP<2>" )
			)
			( electricalNet "@crescent_city_bb_fab1_lib.crescent_city_bb_fab1(sch_1):p3e_cpu0_pe3_ocp_txn(3)"
				( signalRef "@baseboard_fab2_lib.baseboard_fab2(sch_1):p3e_cpu0_pe3_ocp_txn(3)" )
				( signalRef "@baseboard_fab2_lib.baseboard_fab2(sch_1):p3e_ocp_cpu0_pe3_c_txn(3)" )
				( pinPairRef "@baseboard_fab2_lib.baseboard_fab2(sch_1):\PP5948\" )
				( objectStatus "P3E_CPU0_PE3_OCP_TXN<3>" )
			)
			( electricalNet "@crescent_city_bb_fab1_lib.crescent_city_bb_fab1(sch_1):p3e_cpu0_pe3_ocp_txp(3)"
				( signalRef "@baseboard_fab2_lib.baseboard_fab2(sch_1):p3e_ocp_cpu0_pe3_c_txp(3)" )
				( signalRef "@baseboard_fab2_lib.baseboard_fab2(sch_1):p3e_cpu0_pe3_ocp_txp(3)" )
				( pinPairRef "@baseboard_fab2_lib.baseboard_fab2(sch_1):\PP5946\" )
				( objectStatus "P3E_CPU0_PE3_OCP_TXP<3>" )
			)
			( electricalNet "@crescent_city_bb_fab1_lib.crescent_city_bb_fab1(sch_1):p3e_cpu0_pe3_ocp_txn(4)"
				( signalRef "@baseboard_fab2_lib.baseboard_fab2(sch_1):p3e_cpu0_pe3_ocp_txn(4)" )
				( signalRef "@baseboard_fab2_lib.baseboard_fab2(sch_1):p3e_ocp_cpu0_pe3_c_txn(4)" )
				( pinPairRef "@baseboard_fab2_lib.baseboard_fab2(sch_1):\PP5950\" )
				( objectStatus "P3E_CPU0_PE3_OCP_TXN<4>" )
			)
			( electricalNet "@crescent_city_bb_fab1_lib.crescent_city_bb_fab1(sch_1):p3e_cpu0_pe3_ocp_txp(4)"
				( signalRef "@baseboard_fab2_lib.baseboard_fab2(sch_1):p3e_ocp_cpu0_pe3_c_txp(4)" )
				( signalRef "@baseboard_fab2_lib.baseboard_fab2(sch_1):p3e_cpu0_pe3_ocp_txp(4)" )
				( pinPairRef "@baseboard_fab2_lib.baseboard_fab2(sch_1):\PP5947\" )
				( objectStatus "P3E_CPU0_PE3_OCP_TXP<4>" )
			)
			( electricalNet "@crescent_city_bb_fab1_lib.crescent_city_bb_fab1(sch_1):p3e_cpu0_pe3_ocp_txn(5)"
				( signalRef "@baseboard_fab2_lib.baseboard_fab2(sch_1):p3e_cpu0_pe3_ocp_txn(5)" )
				( signalRef "@baseboard_fab2_lib.baseboard_fab2(sch_1):p3e_ocp_cpu0_pe3_c_txn(5)" )
				( pinPairRef "@baseboard_fab2_lib.baseboard_fab2(sch_1):\PP5955\" )
				( objectStatus "P3E_CPU0_PE3_OCP_TXN<5>" )
			)
			( electricalNet "@crescent_city_bb_fab1_lib.crescent_city_bb_fab1(sch_1):p3e_cpu0_pe3_ocp_txp(5)"
				( signalRef "@baseboard_fab2_lib.baseboard_fab2(sch_1):p3e_ocp_cpu0_pe3_c_txp(5)" )
				( signalRef "@baseboard_fab2_lib.baseboard_fab2(sch_1):p3e_cpu0_pe3_ocp_txp(5)" )
				( pinPairRef "@baseboard_fab2_lib.baseboard_fab2(sch_1):\PP5949\" )
				( objectStatus "P3E_CPU0_PE3_OCP_TXP<5>" )
			)
			( electricalNet "@crescent_city_bb_fab1_lib.crescent_city_bb_fab1(sch_1):p3e_cpu0_pe3_ocp_txn(6)"
				( signalRef "@baseboard_fab2_lib.baseboard_fab2(sch_1):p3e_cpu0_pe3_ocp_txn(6)" )
				( signalRef "@baseboard_fab2_lib.baseboard_fab2(sch_1):p3e_ocp_cpu0_pe3_c_txn(6)" )
				( pinPairRef "@baseboard_fab2_lib.baseboard_fab2(sch_1):\PP5956\" )
				( objectStatus "P3E_CPU0_PE3_OCP_TXN<6>" )
			)
			( electricalNet "@crescent_city_bb_fab1_lib.crescent_city_bb_fab1(sch_1):p3e_cpu0_pe3_ocp_txp(6)"
				( signalRef "@baseboard_fab2_lib.baseboard_fab2(sch_1):p3e_ocp_cpu0_pe3_c_txp(6)" )
				( signalRef "@baseboard_fab2_lib.baseboard_fab2(sch_1):p3e_cpu0_pe3_ocp_txp(6)" )
				( pinPairRef "@baseboard_fab2_lib.baseboard_fab2(sch_1):\PP5954\" )
				( objectStatus "P3E_CPU0_PE3_OCP_TXP<6>" )
			)
			( electricalNet "@crescent_city_bb_fab1_lib.crescent_city_bb_fab1(sch_1):p3e_cpu0_pe3_ocp_txn(7)"
				( signalRef "@baseboard_fab2_lib.baseboard_fab2(sch_1):p3e_cpu0_pe3_ocp_txn(7)" )
				( signalRef "@baseboard_fab2_lib.baseboard_fab2(sch_1):p3e_ocp_cpu0_pe3_c_txn(7)" )
				( pinPairRef "@baseboard_fab2_lib.baseboard_fab2(sch_1):\PP5958\" )
				( objectStatus "P3E_CPU0_PE3_OCP_TXN<7>" )
			)
			( electricalNet "@crescent_city_bb_fab1_lib.crescent_city_bb_fab1(sch_1):p3e_cpu0_pe3_ocp_txp(7)"
				( signalRef "@baseboard_fab2_lib.baseboard_fab2(sch_1):p3e_ocp_cpu0_pe3_c_txp(7)" )
				( signalRef "@baseboard_fab2_lib.baseboard_fab2(sch_1):p3e_cpu0_pe3_ocp_txp(7)" )
				( pinPairRef "@baseboard_fab2_lib.baseboard_fab2(sch_1):\PP5957\" )
				( objectStatus "P3E_CPU0_PE3_OCP_TXP<7>" )
			)
			( electricalNet "@crescent_city_bb_fab1_lib.crescent_city_bb_fab1(sch_1):p3e_cpu0_pe3_ocp_txn(8)"
				( signalRef "@baseboard_fab2_lib.baseboard_fab2(sch_1):p3e_cpu0_pe3_ocp_txn(8)" )
				( signalRef "@baseboard_fab2_lib.baseboard_fab2(sch_1):p3e_ocp_cpu0_pe3_c_txn(8)" )
				( electricalCSetRef "@crescent_city_bb_fab1_lib.crescent_city_bb_fab1(sch_1):\PCIE_SLOT\" )
				( pinPairRef "@baseboard_fab2_lib.baseboard_fab2(sch_1):\PP6034\" )
				( objectStatus "P3E_CPU0_PE3_OCP_TXN<8>" )
			)
			( electricalNet "@crescent_city_bb_fab1_lib.crescent_city_bb_fab1(sch_1):p3e_cpu0_pe3_ocp_txp(8)"
				( signalRef "@baseboard_fab2_lib.baseboard_fab2(sch_1):p3e_ocp_cpu0_pe3_c_txp(8)" )
				( signalRef "@baseboard_fab2_lib.baseboard_fab2(sch_1):p3e_cpu0_pe3_ocp_txp(8)" )
				( electricalCSetRef "@crescent_city_bb_fab1_lib.crescent_city_bb_fab1(sch_1):\PCIE_SLOT\" )
				( pinPairRef "@baseboard_fab2_lib.baseboard_fab2(sch_1):\PP5892\" )
				( objectStatus "P3E_CPU0_PE3_OCP_TXP<8>" )
			)
			( electricalNet "@crescent_city_bb_fab1_lib.crescent_city_bb_fab1(sch_1):p3e_cpu0_pe3_ocp_txn(9)"
				( signalRef "@baseboard_fab2_lib.baseboard_fab2(sch_1):p3e_cpu0_pe3_ocp_txn(9)" )
				( signalRef "@baseboard_fab2_lib.baseboard_fab2(sch_1):p3e_ocp_cpu0_pe3_c_txn(9)" )
				( electricalCSetRef "@crescent_city_bb_fab1_lib.crescent_city_bb_fab1(sch_1):\PCIE_SLOT\" )
				( pinPairRef "@baseboard_fab2_lib.baseboard_fab2(sch_1):\PP5951\" )
				( objectStatus "P3E_CPU0_PE3_OCP_TXN<9>" )
			)
			( electricalNet "@crescent_city_bb_fab1_lib.crescent_city_bb_fab1(sch_1):p3e_cpu0_pe3_ocp_txp(9)"
				( signalRef "@baseboard_fab2_lib.baseboard_fab2(sch_1):p3e_ocp_cpu0_pe3_c_txp(9)" )
				( signalRef "@baseboard_fab2_lib.baseboard_fab2(sch_1):p3e_cpu0_pe3_ocp_txp(9)" )
				( electricalCSetRef "@crescent_city_bb_fab1_lib.crescent_city_bb_fab1(sch_1):\PCIE_SLOT\" )
				( pinPairRef "@baseboard_fab2_lib.baseboard_fab2(sch_1):\PP5988\" )
				( objectStatus "P3E_CPU0_PE3_OCP_TXP<9>" )
			)
			( electricalNet "@crescent_city_bb_fab1_lib.crescent_city_bb_fab1(sch_1):p3e_cpu0_pe3_ocp_txn(10)"
				( signalRef "@baseboard_fab2_lib.baseboard_fab2(sch_1):p3e_cpu0_pe3_ocp_txn(10)" )
				( signalRef "@baseboard_fab2_lib.baseboard_fab2(sch_1):p3e_ocp_cpu0_pe3_c_txn(10)" )
				( electricalCSetRef "@crescent_city_bb_fab1_lib.crescent_city_bb_fab1(sch_1):\PCIE_SLOT\" )
				( pinPairRef "@baseboard_fab2_lib.baseboard_fab2(sch_1):\PP6046\" )
				( objectStatus "P3E_CPU0_PE3_OCP_TXN<10>" )
			)
			( electricalNet "@crescent_city_bb_fab1_lib.crescent_city_bb_fab1(sch_1):p3e_cpu0_pe3_ocp_txp(10)"
				( signalRef "@baseboard_fab2_lib.baseboard_fab2(sch_1):p3e_ocp_cpu0_pe3_c_txp(10)" )
				( signalRef "@baseboard_fab2_lib.baseboard_fab2(sch_1):p3e_cpu0_pe3_ocp_txp(10)" )
				( electricalCSetRef "@crescent_city_bb_fab1_lib.crescent_city_bb_fab1(sch_1):\PCIE_SLOT\" )
				( pinPairRef "@baseboard_fab2_lib.baseboard_fab2(sch_1):\PP6047\" )
				( objectStatus "P3E_CPU0_PE3_OCP_TXP<10>" )
			)
			( electricalNet "@crescent_city_bb_fab1_lib.crescent_city_bb_fab1(sch_1):p3e_cpu0_pe3_ocp_txn(11)"
				( signalRef "@baseboard_fab2_lib.baseboard_fab2(sch_1):p3e_cpu0_pe3_ocp_txn(11)" )
				( signalRef "@baseboard_fab2_lib.baseboard_fab2(sch_1):p3e_ocp_cpu0_pe3_c_txn(11)" )
				( electricalCSetRef "@crescent_city_bb_fab1_lib.crescent_city_bb_fab1(sch_1):\PCIE_SLOT\" )
				( pinPairRef "@baseboard_fab2_lib.baseboard_fab2(sch_1):\PP6043\" )
				( objectStatus "P3E_CPU0_PE3_OCP_TXN<11>" )
			)
			( electricalNet "@crescent_city_bb_fab1_lib.crescent_city_bb_fab1(sch_1):p3e_cpu0_pe3_ocp_txp(11)"
				( signalRef "@baseboard_fab2_lib.baseboard_fab2(sch_1):p3e_ocp_cpu0_pe3_c_txp(11)" )
				( signalRef "@baseboard_fab2_lib.baseboard_fab2(sch_1):p3e_cpu0_pe3_ocp_txp(11)" )
				( electricalCSetRef "@crescent_city_bb_fab1_lib.crescent_city_bb_fab1(sch_1):\PCIE_SLOT\" )
				( pinPairRef "@baseboard_fab2_lib.baseboard_fab2(sch_1):\PP6042\" )
				( objectStatus "P3E_CPU0_PE3_OCP_TXP<11>" )
			)
			( electricalNet "@crescent_city_bb_fab1_lib.crescent_city_bb_fab1(sch_1):p3e_cpu0_pe3_ocp_txn(12)"
				( signalRef "@baseboard_fab2_lib.baseboard_fab2(sch_1):p3e_cpu0_pe3_ocp_txn(12)" )
				( signalRef "@baseboard_fab2_lib.baseboard_fab2(sch_1):p3e_ocp_cpu0_pe3_c_txn(12)" )
				( electricalCSetRef "@crescent_city_bb_fab1_lib.crescent_city_bb_fab1(sch_1):\PCIE_SLOT\" )
				( pinPairRef "@baseboard_fab2_lib.baseboard_fab2(sch_1):\PP6040\" )
				( objectStatus "P3E_CPU0_PE3_OCP_TXN<12>" )
			)
			( electricalNet "@crescent_city_bb_fab1_lib.crescent_city_bb_fab1(sch_1):p3e_cpu0_pe3_ocp_txp(12)"
				( signalRef "@baseboard_fab2_lib.baseboard_fab2(sch_1):p3e_ocp_cpu0_pe3_c_txp(12)" )
				( signalRef "@baseboard_fab2_lib.baseboard_fab2(sch_1):p3e_cpu0_pe3_ocp_txp(12)" )
				( electricalCSetRef "@crescent_city_bb_fab1_lib.crescent_city_bb_fab1(sch_1):\PCIE_SLOT\" )
				( pinPairRef "@baseboard_fab2_lib.baseboard_fab2(sch_1):\PP6041\" )
				( objectStatus "P3E_CPU0_PE3_OCP_TXP<12>" )
			)
			( electricalNet "@crescent_city_bb_fab1_lib.crescent_city_bb_fab1(sch_1):p3e_cpu0_pe3_ocp_txn(13)"
				( signalRef "@baseboard_fab2_lib.baseboard_fab2(sch_1):p3e_cpu0_pe3_ocp_txn(13)" )
				( signalRef "@baseboard_fab2_lib.baseboard_fab2(sch_1):p3e_ocp_cpu0_pe3_c_txn(13)" )
				( electricalCSetRef "@crescent_city_bb_fab1_lib.crescent_city_bb_fab1(sch_1):\PCIE_SLOT\" )
				( pinPairRef "@baseboard_fab2_lib.baseboard_fab2(sch_1):\PP6032\" )
				( objectStatus "P3E_CPU0_PE3_OCP_TXN<13>" )
			)
			( electricalNet "@crescent_city_bb_fab1_lib.crescent_city_bb_fab1(sch_1):p3e_cpu0_pe3_ocp_txp(13)"
				( signalRef "@baseboard_fab2_lib.baseboard_fab2(sch_1):p3e_ocp_cpu0_pe3_c_txp(13)" )
				( signalRef "@baseboard_fab2_lib.baseboard_fab2(sch_1):p3e_cpu0_pe3_ocp_txp(13)" )
				( electricalCSetRef "@crescent_city_bb_fab1_lib.crescent_city_bb_fab1(sch_1):\PCIE_SLOT\" )
				( pinPairRef "@baseboard_fab2_lib.baseboard_fab2(sch_1):\PP6037\" )
				( objectStatus "P3E_CPU0_PE3_OCP_TXP<13>" )
			)
			( electricalNet "@crescent_city_bb_fab1_lib.crescent_city_bb_fab1(sch_1):p3e_cpu0_pe3_ocp_txn(14)"
				( signalRef "@baseboard_fab2_lib.baseboard_fab2(sch_1):p3e_cpu0_pe3_ocp_txn(14)" )
				( signalRef "@baseboard_fab2_lib.baseboard_fab2(sch_1):p3e_ocp_cpu0_pe3_c_txn(14)" )
				( electricalCSetRef "@crescent_city_bb_fab1_lib.crescent_city_bb_fab1(sch_1):\PCIE_SLOT\" )
				( pinPairRef "@baseboard_fab2_lib.baseboard_fab2(sch_1):\PP6039\" )
				( objectStatus "P3E_CPU0_PE3_OCP_TXN<14>" )
			)
			( electricalNet "@crescent_city_bb_fab1_lib.crescent_city_bb_fab1(sch_1):p3e_cpu0_pe3_ocp_txp(14)"
				( signalRef "@baseboard_fab2_lib.baseboard_fab2(sch_1):p3e_ocp_cpu0_pe3_c_txp(14)" )
				( signalRef "@baseboard_fab2_lib.baseboard_fab2(sch_1):p3e_cpu0_pe3_ocp_txp(14)" )
				( electricalCSetRef "@crescent_city_bb_fab1_lib.crescent_city_bb_fab1(sch_1):\PCIE_SLOT\" )
				( pinPairRef "@baseboard_fab2_lib.baseboard_fab2(sch_1):\PP6038\" )
				( objectStatus "P3E_CPU0_PE3_OCP_TXP<14>" )
			)
			( electricalNet "@crescent_city_bb_fab1_lib.crescent_city_bb_fab1(sch_1):p3e_cpu0_pe3_ocp_txn(15)"
				( signalRef "@baseboard_fab2_lib.baseboard_fab2(sch_1):p3e_cpu0_pe3_ocp_txn(15)" )
				( signalRef "@baseboard_fab2_lib.baseboard_fab2(sch_1):p3e_ocp_cpu0_pe3_c_txn(15)" )
				( electricalCSetRef "@crescent_city_bb_fab1_lib.crescent_city_bb_fab1(sch_1):\PCIE_SLOT\" )
				( pinPairRef "@baseboard_fab2_lib.baseboard_fab2(sch_1):\PP6036\" )
				( objectStatus "P3E_CPU0_PE3_OCP_TXN<15>" )
			)
			( electricalNet "@crescent_city_bb_fab1_lib.crescent_city_bb_fab1(sch_1):p3e_cpu0_pe3_ocp_txp(15)"
				( signalRef "@baseboard_fab2_lib.baseboard_fab2(sch_1):p3e_ocp_cpu0_pe3_c_txp(15)" )
				( signalRef "@baseboard_fab2_lib.baseboard_fab2(sch_1):p3e_cpu0_pe3_ocp_txp(15)" )
				( electricalCSetRef "@crescent_city_bb_fab1_lib.crescent_city_bb_fab1(sch_1):\PCIE_SLOT\" )
				( pinPairRef "@baseboard_fab2_lib.baseboard_fab2(sch_1):\PP6035\" )
				( objectStatus "P3E_CPU0_PE3_OCP_TXP<15>" )
			)
			( electricalNet "@crescent_city_bb_fab1_lib.crescent_city_bb_fab1(sch_1):p3e_cpu1_pe3_mp_c_txn(0)"
				( signalRef "@baseboard_fab2_lib.baseboard_fab2(sch_1):p3e_cpu1_pe3_mp_txn(0)" )
				( signalRef "@baseboard_fab2_lib.baseboard_fab2(sch_1):p3e_cpu1_pe3_mp_c_txn(0)" )
				( pinPairRef "@baseboard_fab2_lib.baseboard_fab2(sch_1):\PP5952\" )
				( objectStatus "P3E_CPU1_PE3_MP_C_TXN<0>" )
			)
			( electricalNet "@crescent_city_bb_fab1_lib.crescent_city_bb_fab1(sch_1):p3e_cpu1_pe3_mp_c_txp(0)"
				( signalRef "@baseboard_fab2_lib.baseboard_fab2(sch_1):p3e_cpu1_pe3_mp_txp(0)" )
				( signalRef "@baseboard_fab2_lib.baseboard_fab2(sch_1):p3e_cpu1_pe3_mp_c_txp(0)" )
				( pinPairRef "@baseboard_fab2_lib.baseboard_fab2(sch_1):\PP5959\" )
				( objectStatus "P3E_CPU1_PE3_MP_C_TXP<0>" )
			)
			( electricalNet "@crescent_city_bb_fab1_lib.crescent_city_bb_fab1(sch_1):p3e_cpu1_pe3_mp_c_txn(1)"
				( signalRef "@baseboard_fab2_lib.baseboard_fab2(sch_1):p3e_cpu1_pe3_mp_txn(1)" )
				( signalRef "@baseboard_fab2_lib.baseboard_fab2(sch_1):p3e_cpu1_pe3_mp_c_txn(1)" )
				( pinPairRef "@baseboard_fab2_lib.baseboard_fab2(sch_1):\PP5961\" )
				( objectStatus "P3E_CPU1_PE3_MP_C_TXN<1>" )
			)
			( electricalNet "@crescent_city_bb_fab1_lib.crescent_city_bb_fab1(sch_1):p3e_cpu1_pe3_mp_c_txp(1)"
				( signalRef "@baseboard_fab2_lib.baseboard_fab2(sch_1):p3e_cpu1_pe3_mp_txp(1)" )
				( signalRef "@baseboard_fab2_lib.baseboard_fab2(sch_1):p3e_cpu1_pe3_mp_c_txp(1)" )
				( pinPairRef "@baseboard_fab2_lib.baseboard_fab2(sch_1):\PP5953\" )
				( objectStatus "P3E_CPU1_PE3_MP_C_TXP<1>" )
			)
			( electricalNet "@crescent_city_bb_fab1_lib.crescent_city_bb_fab1(sch_1):p3e_cpu0_pe1_ss_rxn(0)"
				( signalRef "@baseboard_fab2_lib.baseboard_fab2(sch_1):p3e_cpu0_pe1_ss_r_rxn(0)" )
				( signalRef "@baseboard_fab2_lib.baseboard_fab2(sch_1):p3e_cpu0_pe1_ss_rxn(0)" )
				( signalRef "@baseboard_fab2_lib.baseboard_fab2(sch_1):p3e_cpu0_pe1_pch_rxn(0)" )
				( electricalCSetRef "@crescent_city_bb_fab1_lib.crescent_city_bb_fab1(sch_1):\PCIE_C_D\" )
				( pinPairRef "@baseboard_fab2_lib.baseboard_fab2(sch_1):\PP6023\" )
				( pinPairRef "@baseboard_fab2_lib.baseboard_fab2(sch_1):\PP6024\" )
				( pinPairRef "@baseboard_fab2_lib.baseboard_fab2(sch_1):\PP6025\" )
				( objectStatus "P3E_CPU0_PE1_SS_RXN<0>" )
			)
			( electricalNet "@crescent_city_bb_fab1_lib.crescent_city_bb_fab1(sch_1):p3e_cpu0_pe1_ss_rxp(0)"
				( signalRef "@baseboard_fab2_lib.baseboard_fab2(sch_1):p3e_cpu0_pe1_ss_r_rxp(0)" )
				( signalRef "@baseboard_fab2_lib.baseboard_fab2(sch_1):p3e_cpu0_pe1_ss_rxp(0)" )
				( signalRef "@baseboard_fab2_lib.baseboard_fab2(sch_1):p3e_cpu0_pe1_pch_rxp(0)" )
				( electricalCSetRef "@crescent_city_bb_fab1_lib.crescent_city_bb_fab1(sch_1):\PCIE_C_D\" )
				( pinPairRef "@baseboard_fab2_lib.baseboard_fab2(sch_1):\PP6029\" )
				( pinPairRef "@baseboard_fab2_lib.baseboard_fab2(sch_1):\PP6030\" )
				( pinPairRef "@baseboard_fab2_lib.baseboard_fab2(sch_1):\PP6031\" )
				( objectStatus "P3E_CPU0_PE1_SS_RXP<0>" )
			)
			( electricalNet "@crescent_city_bb_fab1_lib.crescent_city_bb_fab1(sch_1):p3e_cpu0_pe1_ss_rxn(1)"
				( signalRef "@baseboard_fab2_lib.baseboard_fab2(sch_1):p3e_cpu0_pe1_ss_r_rxn(1)" )
				( signalRef "@baseboard_fab2_lib.baseboard_fab2(sch_1):p3e_cpu0_pe1_ss_rxn(1)" )
				( signalRef "@baseboard_fab2_lib.baseboard_fab2(sch_1):p3e_cpu0_pe1_pch_rxn(1)" )
				( electricalCSetRef "@crescent_city_bb_fab1_lib.crescent_city_bb_fab1(sch_1):\PCIE_C_D\" )
				( pinPairRef "@baseboard_fab2_lib.baseboard_fab2(sch_1):\PP6026\" )
				( pinPairRef "@baseboard_fab2_lib.baseboard_fab2(sch_1):\PP6027\" )
				( pinPairRef "@baseboard_fab2_lib.baseboard_fab2(sch_1):\PP6028\" )
				( objectStatus "P3E_CPU0_PE1_SS_RXN<1>" )
			)
			( electricalNet "@crescent_city_bb_fab1_lib.crescent_city_bb_fab1(sch_1):p3e_cpu0_pe1_ss_rxp(1)"
				( signalRef "@baseboard_fab2_lib.baseboard_fab2(sch_1):p3e_cpu0_pe1_ss_r_rxp(1)" )
				( signalRef "@baseboard_fab2_lib.baseboard_fab2(sch_1):p3e_cpu0_pe1_ss_rxp(1)" )
				( signalRef "@baseboard_fab2_lib.baseboard_fab2(sch_1):p3e_cpu0_pe1_pch_rxp(1)" )
				( electricalCSetRef "@crescent_city_bb_fab1_lib.crescent_city_bb_fab1(sch_1):\PCIE_C_D\" )
				( pinPairRef "@baseboard_fab2_lib.baseboard_fab2(sch_1):\PP6020\" )
				( pinPairRef "@baseboard_fab2_lib.baseboard_fab2(sch_1):\PP6021\" )
				( pinPairRef "@baseboard_fab2_lib.baseboard_fab2(sch_1):\PP6022\" )
				( objectStatus "P3E_CPU0_PE1_SS_RXP<1>" )
			)
			( electricalNet "@crescent_city_bb_fab1_lib.crescent_city_bb_fab1(sch_1):p3e_cpu0_pe1_ss_rxn(2)"
				( signalRef "@baseboard_fab2_lib.baseboard_fab2(sch_1):p3e_cpu0_pe1_ss_r_rxn(2)" )
				( signalRef "@baseboard_fab2_lib.baseboard_fab2(sch_1):p3e_cpu0_pe1_ss_rxn(2)" )
				( signalRef "@baseboard_fab2_lib.baseboard_fab2(sch_1):p3e_cpu0_pe1_pch_rxn(2)" )
				( electricalCSetRef "@crescent_city_bb_fab1_lib.crescent_city_bb_fab1(sch_1):\PCIE_C_D\" )
				( pinPairRef "@baseboard_fab2_lib.baseboard_fab2(sch_1):\PP6017\" )
				( pinPairRef "@baseboard_fab2_lib.baseboard_fab2(sch_1):\PP6018\" )
				( pinPairRef "@baseboard_fab2_lib.baseboard_fab2(sch_1):\PP6019\" )
				( objectStatus "P3E_CPU0_PE1_SS_RXN<2>" )
			)
			( electricalNet "@crescent_city_bb_fab1_lib.crescent_city_bb_fab1(sch_1):p3e_cpu0_pe1_ss_rxp(2)"
				( signalRef "@baseboard_fab2_lib.baseboard_fab2(sch_1):p3e_cpu0_pe1_ss_r_rxp(2)" )
				( signalRef "@baseboard_fab2_lib.baseboard_fab2(sch_1):p3e_cpu0_pe1_ss_rxp(2)" )
				( signalRef "@baseboard_fab2_lib.baseboard_fab2(sch_1):p3e_cpu0_pe1_pch_rxp(2)" )
				( electricalCSetRef "@crescent_city_bb_fab1_lib.crescent_city_bb_fab1(sch_1):\PCIE_C_D\" )
				( pinPairRef "@baseboard_fab2_lib.baseboard_fab2(sch_1):\PP6014\" )
				( pinPairRef "@baseboard_fab2_lib.baseboard_fab2(sch_1):\PP6015\" )
				( pinPairRef "@baseboard_fab2_lib.baseboard_fab2(sch_1):\PP6016\" )
				( objectStatus "P3E_CPU0_PE1_SS_RXP<2>" )
			)
			( electricalNet "@crescent_city_bb_fab1_lib.crescent_city_bb_fab1(sch_1):p3e_cpu0_pe1_ss_rxn(3)"
				( signalRef "@baseboard_fab2_lib.baseboard_fab2(sch_1):p3e_cpu0_pe1_ss_r_rxn(3)" )
				( signalRef "@baseboard_fab2_lib.baseboard_fab2(sch_1):p3e_cpu0_pe1_ss_rxn(3)" )
				( signalRef "@baseboard_fab2_lib.baseboard_fab2(sch_1):p3e_cpu0_pe1_pch_rxn(3)" )
				( electricalCSetRef "@crescent_city_bb_fab1_lib.crescent_city_bb_fab1(sch_1):\PCIE_C_D\" )
				( pinPairRef "@baseboard_fab2_lib.baseboard_fab2(sch_1):\PP6011\" )
				( pinPairRef "@baseboard_fab2_lib.baseboard_fab2(sch_1):\PP6012\" )
				( pinPairRef "@baseboard_fab2_lib.baseboard_fab2(sch_1):\PP6013\" )
				( objectStatus "P3E_CPU0_PE1_SS_RXN<3>" )
			)
			( electricalNet "@crescent_city_bb_fab1_lib.crescent_city_bb_fab1(sch_1):p3e_cpu0_pe1_ss_rxp(3)"
				( signalRef "@baseboard_fab2_lib.baseboard_fab2(sch_1):p3e_cpu0_pe1_ss_r_rxp(3)" )
				( signalRef "@baseboard_fab2_lib.baseboard_fab2(sch_1):p3e_cpu0_pe1_ss_rxp(3)" )
				( signalRef "@baseboard_fab2_lib.baseboard_fab2(sch_1):p3e_cpu0_pe1_pch_rxp(3)" )
				( electricalCSetRef "@crescent_city_bb_fab1_lib.crescent_city_bb_fab1(sch_1):\PCIE_C_D\" )
				( pinPairRef "@baseboard_fab2_lib.baseboard_fab2(sch_1):\PP5934\" )
				( pinPairRef "@baseboard_fab2_lib.baseboard_fab2(sch_1):\PP5935\" )
				( pinPairRef "@baseboard_fab2_lib.baseboard_fab2(sch_1):\PP5936\" )
				( objectStatus "P3E_CPU0_PE1_SS_RXP<3>" )
			)
			( electricalNet "@crescent_city_bb_fab1_lib.crescent_city_bb_fab1(sch_1):p3e_cpu0_pe1_ss_rxn(4)"
				( signalRef "@baseboard_fab2_lib.baseboard_fab2(sch_1):p3e_cpu0_pe1_ss_r_rxn(4)" )
				( signalRef "@baseboard_fab2_lib.baseboard_fab2(sch_1):p3e_cpu0_pe1_ss_rxn(4)" )
				( signalRef "@baseboard_fab2_lib.baseboard_fab2(sch_1):p3e_cpu0_pe1_pch_rxn(4)" )
				( electricalCSetRef "@crescent_city_bb_fab1_lib.crescent_city_bb_fab1(sch_1):\PCIE_C_D\" )
				( pinPairRef "@baseboard_fab2_lib.baseboard_fab2(sch_1):\PP5921\" )
				( pinPairRef "@baseboard_fab2_lib.baseboard_fab2(sch_1):\PP5922\" )
				( pinPairRef "@baseboard_fab2_lib.baseboard_fab2(sch_1):\PP5923\" )
				( objectStatus "P3E_CPU0_PE1_SS_RXN<4>" )
			)
			( electricalNet "@crescent_city_bb_fab1_lib.crescent_city_bb_fab1(sch_1):p3e_cpu0_pe1_ss_rxp(4)"
				( signalRef "@baseboard_fab2_lib.baseboard_fab2(sch_1):p3e_cpu0_pe1_ss_r_rxp(4)" )
				( signalRef "@baseboard_fab2_lib.baseboard_fab2(sch_1):p3e_cpu0_pe1_ss_rxp(4)" )
				( signalRef "@baseboard_fab2_lib.baseboard_fab2(sch_1):p3e_cpu0_pe1_pch_rxp(4)" )
				( electricalCSetRef "@crescent_city_bb_fab1_lib.crescent_city_bb_fab1(sch_1):\PCIE_C_D\" )
				( pinPairRef "@baseboard_fab2_lib.baseboard_fab2(sch_1):\PP5984\" )
				( pinPairRef "@baseboard_fab2_lib.baseboard_fab2(sch_1):\PP5985\" )
				( pinPairRef "@baseboard_fab2_lib.baseboard_fab2(sch_1):\PP5986\" )
				( objectStatus "P3E_CPU0_PE1_SS_RXP<4>" )
			)
			( electricalNet "@crescent_city_bb_fab1_lib.crescent_city_bb_fab1(sch_1):p3e_cpu0_pe1_ss_rxn(5)"
				( signalRef "@baseboard_fab2_lib.baseboard_fab2(sch_1):p3e_cpu0_pe1_ss_r_rxn(5)" )
				( signalRef "@baseboard_fab2_lib.baseboard_fab2(sch_1):p3e_cpu0_pe1_ss_rxn(5)" )
				( signalRef "@baseboard_fab2_lib.baseboard_fab2(sch_1):p3e_cpu0_pe1_pch_rxn(5)" )
				( electricalCSetRef "@crescent_city_bb_fab1_lib.crescent_city_bb_fab1(sch_1):\PCIE_C_D\" )
				( pinPairRef "@baseboard_fab2_lib.baseboard_fab2(sch_1):\PP6000\" )
				( pinPairRef "@baseboard_fab2_lib.baseboard_fab2(sch_1):\PP6001\" )
				( pinPairRef "@baseboard_fab2_lib.baseboard_fab2(sch_1):\PP6002\" )
				( objectStatus "P3E_CPU0_PE1_SS_RXN<5>" )
			)
			( electricalNet "@crescent_city_bb_fab1_lib.crescent_city_bb_fab1(sch_1):p3e_cpu0_pe1_ss_rxp(5)"
				( signalRef "@baseboard_fab2_lib.baseboard_fab2(sch_1):p3e_cpu0_pe1_ss_r_rxp(5)" )
				( signalRef "@baseboard_fab2_lib.baseboard_fab2(sch_1):p3e_cpu0_pe1_ss_rxp(5)" )
				( signalRef "@baseboard_fab2_lib.baseboard_fab2(sch_1):p3e_cpu0_pe1_pch_rxp(5)" )
				( electricalCSetRef "@crescent_city_bb_fab1_lib.crescent_city_bb_fab1(sch_1):\PCIE_C_D\" )
				( pinPairRef "@baseboard_fab2_lib.baseboard_fab2(sch_1):\PP6006\" )
				( pinPairRef "@baseboard_fab2_lib.baseboard_fab2(sch_1):\PP6007\" )
				( pinPairRef "@baseboard_fab2_lib.baseboard_fab2(sch_1):\PP6008\" )
				( objectStatus "P3E_CPU0_PE1_SS_RXP<5>" )
			)
			( electricalNet "@crescent_city_bb_fab1_lib.crescent_city_bb_fab1(sch_1):p3e_cpu0_pe1_ss_rxn(6)"
				( signalRef "@baseboard_fab2_lib.baseboard_fab2(sch_1):p3e_cpu0_pe1_ss_r_rxn(6)" )
				( signalRef "@baseboard_fab2_lib.baseboard_fab2(sch_1):p3e_cpu0_pe1_ss_rxn(6)" )
				( signalRef "@baseboard_fab2_lib.baseboard_fab2(sch_1):p3e_cpu0_pe1_pch_rxn(6)" )
				( electricalCSetRef "@crescent_city_bb_fab1_lib.crescent_city_bb_fab1(sch_1):\PCIE_C_D\" )
				( pinPairRef "@baseboard_fab2_lib.baseboard_fab2(sch_1):\PP6003\" )
				( pinPairRef "@baseboard_fab2_lib.baseboard_fab2(sch_1):\PP6004\" )
				( pinPairRef "@baseboard_fab2_lib.baseboard_fab2(sch_1):\PP6005\" )
				( objectStatus "P3E_CPU0_PE1_SS_RXN<6>" )
			)
			( electricalNet "@crescent_city_bb_fab1_lib.crescent_city_bb_fab1(sch_1):p3e_cpu0_pe1_ss_rxp(6)"
				( signalRef "@baseboard_fab2_lib.baseboard_fab2(sch_1):p3e_cpu0_pe1_ss_r_rxp(6)" )
				( signalRef "@baseboard_fab2_lib.baseboard_fab2(sch_1):p3e_cpu0_pe1_ss_rxp(6)" )
				( signalRef "@baseboard_fab2_lib.baseboard_fab2(sch_1):p3e_cpu0_pe1_pch_rxp(6)" )
				( electricalCSetRef "@crescent_city_bb_fab1_lib.crescent_city_bb_fab1(sch_1):\PCIE_C_D\" )
				( pinPairRef "@baseboard_fab2_lib.baseboard_fab2(sch_1):\PP5997\" )
				( pinPairRef "@baseboard_fab2_lib.baseboard_fab2(sch_1):\PP5998\" )
				( pinPairRef "@baseboard_fab2_lib.baseboard_fab2(sch_1):\PP5999\" )
				( objectStatus "P3E_CPU0_PE1_SS_RXP<6>" )
			)
			( electricalNet "@crescent_city_bb_fab1_lib.crescent_city_bb_fab1(sch_1):p3e_cpu0_pe1_pch_rxn(8)"
				( signalRef "@baseboard_fab2_lib.baseboard_fab2(sch_1):p3e_cpu0_pe1_pch_r_rxn(8)" )
				( signalRef "@baseboard_fab2_lib.baseboard_fab2(sch_1):p3e_cpu0_pe1_pch_rxn(8)" )
				( pinPairRef "@baseboard_fab2_lib.baseboard_fab2(sch_1):\PP5829\" )
				( objectStatus "P3E_CPU0_PE1_PCH_RXN<8>" )
			)
			( electricalNet "@crescent_city_bb_fab1_lib.crescent_city_bb_fab1(sch_1):p3e_cpu0_pe1_pch_rxp(8)"
				( signalRef "@baseboard_fab2_lib.baseboard_fab2(sch_1):p3e_cpu0_pe1_pch_r_rxp(8)" )
				( signalRef "@baseboard_fab2_lib.baseboard_fab2(sch_1):p3e_cpu0_pe1_pch_rxp(8)" )
				( pinPairRef "@baseboard_fab2_lib.baseboard_fab2(sch_1):\PP5836\" )
				( objectStatus "P3E_CPU0_PE1_PCH_RXP<8>" )
			)
			( electricalNet "@crescent_city_bb_fab1_lib.crescent_city_bb_fab1(sch_1):p3e_cpu0_pe1_pch_rxn(9)"
				( signalRef "@baseboard_fab2_lib.baseboard_fab2(sch_1):p3e_cpu0_pe1_pch_r_rxn(9)" )
				( signalRef "@baseboard_fab2_lib.baseboard_fab2(sch_1):p3e_cpu0_pe1_pch_rxn(9)" )
				( pinPairRef "@baseboard_fab2_lib.baseboard_fab2(sch_1):\PP5835\" )
				( objectStatus "P3E_CPU0_PE1_PCH_RXN<9>" )
			)
			( electricalNet "@crescent_city_bb_fab1_lib.crescent_city_bb_fab1(sch_1):p3e_cpu0_pe1_pch_rxp(9)"
				( signalRef "@baseboard_fab2_lib.baseboard_fab2(sch_1):p3e_cpu0_pe1_pch_r_rxp(9)" )
				( signalRef "@baseboard_fab2_lib.baseboard_fab2(sch_1):p3e_cpu0_pe1_pch_rxp(9)" )
				( pinPairRef "@baseboard_fab2_lib.baseboard_fab2(sch_1):\PP5837\" )
				( objectStatus "P3E_CPU0_PE1_PCH_RXP<9>" )
			)
			( electricalNet "@crescent_city_bb_fab1_lib.crescent_city_bb_fab1(sch_1):p3e_cpu1_pe3_mp_c_txn(2)"
				( signalRef "@baseboard_fab2_lib.baseboard_fab2(sch_1):p3e_cpu1_pe3_mp_txn(2)" )
				( signalRef "@baseboard_fab2_lib.baseboard_fab2(sch_1):p3e_cpu1_pe3_mp_c_txn(2)" )
				( pinPairRef "@baseboard_fab2_lib.baseboard_fab2(sch_1):\PP5963\" )
				( objectStatus "P3E_CPU1_PE3_MP_C_TXN<2>" )
			)
			( electricalNet "@crescent_city_bb_fab1_lib.crescent_city_bb_fab1(sch_1):p3e_cpu1_pe3_mp_c_txp(2)"
				( signalRef "@baseboard_fab2_lib.baseboard_fab2(sch_1):p3e_cpu1_pe3_mp_txp(2)" )
				( signalRef "@baseboard_fab2_lib.baseboard_fab2(sch_1):p3e_cpu1_pe3_mp_c_txp(2)" )
				( pinPairRef "@baseboard_fab2_lib.baseboard_fab2(sch_1):\PP5960\" )
				( objectStatus "P3E_CPU1_PE3_MP_C_TXP<2>" )
			)
			( electricalNet "@crescent_city_bb_fab1_lib.crescent_city_bb_fab1(sch_1):p3e_cpu1_pe3_mp_c_txn(3)"
				( signalRef "@baseboard_fab2_lib.baseboard_fab2(sch_1):p3e_cpu1_pe3_mp_txn(3)" )
				( signalRef "@baseboard_fab2_lib.baseboard_fab2(sch_1):p3e_cpu1_pe3_mp_c_txn(3)" )
				( pinPairRef "@baseboard_fab2_lib.baseboard_fab2(sch_1):\PP5965\" )
				( objectStatus "P3E_CPU1_PE3_MP_C_TXN<3>" )
			)
			( electricalNet "@crescent_city_bb_fab1_lib.crescent_city_bb_fab1(sch_1):p3e_cpu1_pe3_mp_c_txp(3)"
				( signalRef "@baseboard_fab2_lib.baseboard_fab2(sch_1):p3e_cpu1_pe3_mp_txp(3)" )
				( signalRef "@baseboard_fab2_lib.baseboard_fab2(sch_1):p3e_cpu1_pe3_mp_c_txp(3)" )
				( pinPairRef "@baseboard_fab2_lib.baseboard_fab2(sch_1):\PP5964\" )
				( objectStatus "P3E_CPU1_PE3_MP_C_TXP<3>" )
			)
			( electricalNet "@crescent_city_bb_fab1_lib.crescent_city_bb_fab1(sch_1):p3e_cpu1_pe3_mp_c_txn(4)"
				( signalRef "@baseboard_fab2_lib.baseboard_fab2(sch_1):p3e_cpu1_pe3_mp_txn(4)" )
				( signalRef "@baseboard_fab2_lib.baseboard_fab2(sch_1):p3e_cpu1_pe3_mp_c_txn(4)" )
				( pinPairRef "@baseboard_fab2_lib.baseboard_fab2(sch_1):\PP5967\" )
				( objectStatus "P3E_CPU1_PE3_MP_C_TXN<4>" )
			)
			( electricalNet "@crescent_city_bb_fab1_lib.crescent_city_bb_fab1(sch_1):p3e_cpu1_pe3_mp_c_txp(4)"
				( signalRef "@baseboard_fab2_lib.baseboard_fab2(sch_1):p3e_cpu1_pe3_mp_txp(4)" )
				( signalRef "@baseboard_fab2_lib.baseboard_fab2(sch_1):p3e_cpu1_pe3_mp_c_txp(4)" )
				( pinPairRef "@baseboard_fab2_lib.baseboard_fab2(sch_1):\PP5966\" )
				( objectStatus "P3E_CPU1_PE3_MP_C_TXP<4>" )
			)
			( electricalNet "@crescent_city_bb_fab1_lib.crescent_city_bb_fab1(sch_1):p3e_cpu1_pe3_mp_c_txn(5)"
				( signalRef "@baseboard_fab2_lib.baseboard_fab2(sch_1):p3e_cpu1_pe3_mp_txn(5)" )
				( signalRef "@baseboard_fab2_lib.baseboard_fab2(sch_1):p3e_cpu1_pe3_mp_c_txn(5)" )
				( pinPairRef "@baseboard_fab2_lib.baseboard_fab2(sch_1):\PP5968\" )
				( objectStatus "P3E_CPU1_PE3_MP_C_TXN<5>" )
			)
			( electricalNet "@crescent_city_bb_fab1_lib.crescent_city_bb_fab1(sch_1):p3e_cpu1_pe3_mp_c_txp(5)"
				( signalRef "@baseboard_fab2_lib.baseboard_fab2(sch_1):p3e_cpu1_pe3_mp_txp(5)" )
				( signalRef "@baseboard_fab2_lib.baseboard_fab2(sch_1):p3e_cpu1_pe3_mp_c_txp(5)" )
				( pinPairRef "@baseboard_fab2_lib.baseboard_fab2(sch_1):\PP5962\" )
				( objectStatus "P3E_CPU1_PE3_MP_C_TXP<5>" )
			)
			( electricalNet "@crescent_city_bb_fab1_lib.crescent_city_bb_fab1(sch_1):p3e_cpu1_pe3_mp_c_txn(6)"
				( signalRef "@baseboard_fab2_lib.baseboard_fab2(sch_1):p3e_cpu1_pe3_mp_txn(6)" )
				( signalRef "@baseboard_fab2_lib.baseboard_fab2(sch_1):p3e_cpu1_pe3_mp_c_txn(6)" )
				( pinPairRef "@baseboard_fab2_lib.baseboard_fab2(sch_1):\PP5971\" )
				( objectStatus "P3E_CPU1_PE3_MP_C_TXN<6>" )
			)
			( electricalNet "@crescent_city_bb_fab1_lib.crescent_city_bb_fab1(sch_1):p3e_cpu1_pe3_mp_c_txp(6)"
				( signalRef "@baseboard_fab2_lib.baseboard_fab2(sch_1):p3e_cpu1_pe3_mp_txp(6)" )
				( signalRef "@baseboard_fab2_lib.baseboard_fab2(sch_1):p3e_cpu1_pe3_mp_c_txp(6)" )
				( pinPairRef "@baseboard_fab2_lib.baseboard_fab2(sch_1):\PP5970\" )
				( objectStatus "P3E_CPU1_PE3_MP_C_TXP<6>" )
			)
			( electricalNet "@crescent_city_bb_fab1_lib.crescent_city_bb_fab1(sch_1):p3e_cpu1_pe3_mp_c_txn(11)"
				( signalRef "@baseboard_fab2_lib.baseboard_fab2(sch_1):p3e_cpu1_pe3_mp_txn(11)" )
				( signalRef "@baseboard_fab2_lib.baseboard_fab2(sch_1):p3e_cpu1_pe3_mp_c_txn(11)" )
				( pinPairRef "@baseboard_fab2_lib.baseboard_fab2(sch_1):\PP5974\" )
				( objectStatus "P3E_CPU1_PE3_MP_C_TXN<11>" )
			)
			( electricalNet "@crescent_city_bb_fab1_lib.crescent_city_bb_fab1(sch_1):p3e_cpu1_pe3_mp_c_txp(11)"
				( signalRef "@baseboard_fab2_lib.baseboard_fab2(sch_1):p3e_cpu1_pe3_mp_c_txp(11)" )
				( signalRef "@baseboard_fab2_lib.baseboard_fab2(sch_1):p3e_cpu1_pe3_mp_txp(11)" )
				( pinPairRef "@baseboard_fab2_lib.baseboard_fab2(sch_1):\PP5972\" )
				( objectStatus "P3E_CPU1_PE3_MP_C_TXP<11>" )
			)
			( electricalNet "@crescent_city_bb_fab1_lib.crescent_city_bb_fab1(sch_1):p3e_cpu1_pe3_mp_c_txn(12)"
				( signalRef "@baseboard_fab2_lib.baseboard_fab2(sch_1):p3e_cpu1_pe3_mp_txn(12)" )
				( signalRef "@baseboard_fab2_lib.baseboard_fab2(sch_1):p3e_cpu1_pe3_mp_c_txn(12)" )
				( pinPairRef "@baseboard_fab2_lib.baseboard_fab2(sch_1):\PP5973\" )
				( objectStatus "P3E_CPU1_PE3_MP_C_TXN<12>" )
			)
			( electricalNet "@crescent_city_bb_fab1_lib.crescent_city_bb_fab1(sch_1):p3e_cpu1_pe3_mp_c_txp(12)"
				( signalRef "@baseboard_fab2_lib.baseboard_fab2(sch_1):p3e_cpu1_pe3_mp_c_txp(12)" )
				( signalRef "@baseboard_fab2_lib.baseboard_fab2(sch_1):p3e_cpu1_pe3_mp_txp(12)" )
				( pinPairRef "@baseboard_fab2_lib.baseboard_fab2(sch_1):\PP5975\" )
				( objectStatus "P3E_CPU1_PE3_MP_C_TXP<12>" )
			)
			( electricalNet "@crescent_city_bb_fab1_lib.crescent_city_bb_fab1(sch_1):p3e_cpu1_pe3_mp_c_txn(13)"
				( signalRef "@baseboard_fab2_lib.baseboard_fab2(sch_1):p3e_cpu1_pe3_mp_txn(13)" )
				( signalRef "@baseboard_fab2_lib.baseboard_fab2(sch_1):p3e_cpu1_pe3_mp_c_txn(13)" )
				( pinPairRef "@baseboard_fab2_lib.baseboard_fab2(sch_1):\PP5976\" )
				( objectStatus "P3E_CPU1_PE3_MP_C_TXN<13>" )
			)
			( electricalNet "@crescent_city_bb_fab1_lib.crescent_city_bb_fab1(sch_1):p3e_cpu1_pe3_mp_c_txp(13)"
				( signalRef "@baseboard_fab2_lib.baseboard_fab2(sch_1):p3e_cpu1_pe3_mp_c_txp(13)" )
				( signalRef "@baseboard_fab2_lib.baseboard_fab2(sch_1):p3e_cpu1_pe3_mp_txp(13)" )
				( pinPairRef "@baseboard_fab2_lib.baseboard_fab2(sch_1):\PP5969\" )
				( objectStatus "P3E_CPU1_PE3_MP_C_TXP<13>" )
			)
			( electricalNet "@crescent_city_bb_fab1_lib.crescent_city_bb_fab1(sch_1):p3e_cpu1_pe3_mp_c_txn(14)"
				( signalRef "@baseboard_fab2_lib.baseboard_fab2(sch_1):p3e_cpu1_pe3_mp_txn(14)" )
				( signalRef "@baseboard_fab2_lib.baseboard_fab2(sch_1):p3e_cpu1_pe3_mp_c_txn(14)" )
				( pinPairRef "@baseboard_fab2_lib.baseboard_fab2(sch_1):\PP5979\" )
				( objectStatus "P3E_CPU1_PE3_MP_C_TXN<14>" )
			)
			( electricalNet "@crescent_city_bb_fab1_lib.crescent_city_bb_fab1(sch_1):p3e_cpu1_pe3_mp_c_txp(14)"
				( signalRef "@baseboard_fab2_lib.baseboard_fab2(sch_1):p3e_cpu1_pe3_mp_c_txp(14)" )
				( signalRef "@baseboard_fab2_lib.baseboard_fab2(sch_1):p3e_cpu1_pe3_mp_txp(14)" )
				( pinPairRef "@baseboard_fab2_lib.baseboard_fab2(sch_1):\PP5977\" )
				( objectStatus "P3E_CPU1_PE3_MP_C_TXP<14>" )
			)
			( electricalNet "@crescent_city_bb_fab1_lib.crescent_city_bb_fab1(sch_1):p3e_cpu1_pe3_mp_c_txn(15)"
				( signalRef "@baseboard_fab2_lib.baseboard_fab2(sch_1):p3e_cpu1_pe3_mp_txn(15)" )
				( signalRef "@baseboard_fab2_lib.baseboard_fab2(sch_1):p3e_cpu1_pe3_mp_c_txn(15)" )
				( pinPairRef "@baseboard_fab2_lib.baseboard_fab2(sch_1):\PP5987\" )
				( objectStatus "P3E_CPU1_PE3_MP_C_TXN<15>" )
			)
			( electricalNet "@crescent_city_bb_fab1_lib.crescent_city_bb_fab1(sch_1):p3e_cpu1_pe3_mp_c_txp(15)"
				( signalRef "@baseboard_fab2_lib.baseboard_fab2(sch_1):p3e_cpu1_pe3_mp_c_txp(15)" )
				( signalRef "@baseboard_fab2_lib.baseboard_fab2(sch_1):p3e_cpu1_pe3_mp_txp(15)" )
				( pinPairRef "@baseboard_fab2_lib.baseboard_fab2(sch_1):\PP5978\" )
				( objectStatus "P3E_CPU1_PE3_MP_C_TXP<15>" )
			)
			( electricalNet "@crescent_city_bb_fab1_lib.crescent_city_bb_fab1(sch_1):p3e_cpu1_pe3_mp_c_txn(7)"
				( signalRef "@baseboard_fab2_lib.baseboard_fab2(sch_1):p3e_cpu1_pe3_mp_txn(7)" )
				( signalRef "@baseboard_fab2_lib.baseboard_fab2(sch_1):p3e_cpu1_pe3_mp_c_txn(7)" )
				( pinPairRef "@baseboard_fab2_lib.baseboard_fab2(sch_1):\PP5981\" )
				( objectStatus "P3E_CPU1_PE3_MP_C_TXN<7>" )
			)
			( electricalNet "@crescent_city_bb_fab1_lib.crescent_city_bb_fab1(sch_1):p3e_cpu1_pe3_mp_c_txp(7)"
				( signalRef "@baseboard_fab2_lib.baseboard_fab2(sch_1):p3e_cpu1_pe3_mp_txp(7)" )
				( signalRef "@baseboard_fab2_lib.baseboard_fab2(sch_1):p3e_cpu1_pe3_mp_c_txp(7)" )
				( pinPairRef "@baseboard_fab2_lib.baseboard_fab2(sch_1):\PP5980\" )
				( objectStatus "P3E_CPU1_PE3_MP_C_TXP<7>" )
			)
			( electricalNet "@crescent_city_bb_fab1_lib.crescent_city_bb_fab1(sch_1):p3e_cpu1_pe3_mp_c_txn(9)"
				( signalRef "@baseboard_fab2_lib.baseboard_fab2(sch_1):p3e_cpu1_pe3_mp_txn(9)" )
				( signalRef "@baseboard_fab2_lib.baseboard_fab2(sch_1):p3e_cpu1_pe3_mp_c_txn(9)" )
				( pinPairRef "@baseboard_fab2_lib.baseboard_fab2(sch_1):\PP5983\" )
				( objectStatus "P3E_CPU1_PE3_MP_C_TXN<9>" )
			)
			( electricalNet "@crescent_city_bb_fab1_lib.crescent_city_bb_fab1(sch_1):p3e_cpu1_pe3_mp_c_txp(9)"
				( signalRef "@baseboard_fab2_lib.baseboard_fab2(sch_1):p3e_cpu1_pe3_mp_c_txp(9)" )
				( signalRef "@baseboard_fab2_lib.baseboard_fab2(sch_1):p3e_cpu1_pe3_mp_txp(9)" )
				( pinPairRef "@baseboard_fab2_lib.baseboard_fab2(sch_1):\PP5982\" )
				( objectStatus "P3E_CPU1_PE3_MP_C_TXP<9>" )
			)
			( electricalNet "@crescent_city_bb_fab1_lib.crescent_city_bb_fab1(sch_1):dmi_cpu0_pch_rx_c_dn(0)"
				( signalRef "@baseboard_fab2_lib.baseboard_fab2(sch_1):dmi_cpu0_pch_rx_dn(0)" )
				( signalRef "@baseboard_fab2_lib.baseboard_fab2(sch_1):dmi_cpu0_pch_rx_c_dn(0)" )
				( electricalCSetRef "@crescent_city_bb_fab1_lib.crescent_city_bb_fab1(sch_1):\DMI_CPU0_PCH_RX_C_DN_0_\" )
				( pinPairRef "@baseboard_fab2_lib.baseboard_fab2(sch_1):\PP6088\" )
				( objectStatus "DMI_CPU0_PCH_RX_C_DN<0>" )
			)
			( electricalNet "@crescent_city_bb_fab1_lib.crescent_city_bb_fab1(sch_1):dmi_cpu0_pch_rx_c_dp(0)"
				( signalRef "@baseboard_fab2_lib.baseboard_fab2(sch_1):dmi_cpu0_pch_rx_dp(0)" )
				( signalRef "@baseboard_fab2_lib.baseboard_fab2(sch_1):dmi_cpu0_pch_rx_c_dp(0)" )
				( electricalCSetRef "@crescent_city_bb_fab1_lib.crescent_city_bb_fab1(sch_1):\DMI_CPU0_PCH_RX_C_DN_0_\" )
				( pinPairRef "@baseboard_fab2_lib.baseboard_fab2(sch_1):\PP6089\" )
				( objectStatus "DMI_CPU0_PCH_RX_C_DP<0>" )
			)
			( electricalNet "@crescent_city_bb_fab1_lib.crescent_city_bb_fab1(sch_1):dmi_cpu0_pch_rx_c_dn(1)"
				( signalRef "@baseboard_fab2_lib.baseboard_fab2(sch_1):dmi_cpu0_pch_rx_dn(1)" )
				( signalRef "@baseboard_fab2_lib.baseboard_fab2(sch_1):dmi_cpu0_pch_rx_c_dn(1)" )
				( electricalCSetRef "@crescent_city_bb_fab1_lib.crescent_city_bb_fab1(sch_1):\DMI_CPU0_PCH_RX_C_DN_0_\" )
				( pinPairRef "@baseboard_fab2_lib.baseboard_fab2(sch_1):\PP6085\" )
				( objectStatus "DMI_CPU0_PCH_RX_C_DN<1>" )
			)
			( electricalNet "@crescent_city_bb_fab1_lib.crescent_city_bb_fab1(sch_1):dmi_cpu0_pch_rx_c_dp(1)"
				( signalRef "@baseboard_fab2_lib.baseboard_fab2(sch_1):dmi_cpu0_pch_rx_dp(1)" )
				( signalRef "@baseboard_fab2_lib.baseboard_fab2(sch_1):dmi_cpu0_pch_rx_c_dp(1)" )
				( electricalCSetRef "@crescent_city_bb_fab1_lib.crescent_city_bb_fab1(sch_1):\DMI_CPU0_PCH_RX_C_DN_0_\" )
				( pinPairRef "@baseboard_fab2_lib.baseboard_fab2(sch_1):\PP6087\" )
				( objectStatus "DMI_CPU0_PCH_RX_C_DP<1>" )
			)
			( electricalNet "@crescent_city_bb_fab1_lib.crescent_city_bb_fab1(sch_1):dmi_cpu0_pch_rx_c_dn(2)"
				( signalRef "@baseboard_fab2_lib.baseboard_fab2(sch_1):dmi_cpu0_pch_rx_dn(2)" )
				( signalRef "@baseboard_fab2_lib.baseboard_fab2(sch_1):dmi_cpu0_pch_rx_c_dn(2)" )
				( electricalCSetRef "@crescent_city_bb_fab1_lib.crescent_city_bb_fab1(sch_1):\DMI_CPU0_PCH_RX_C_DN_0_\" )
				( pinPairRef "@baseboard_fab2_lib.baseboard_fab2(sch_1):\PP6077\" )
				( objectStatus "DMI_CPU0_PCH_RX_C_DN<2>" )
			)
			( electricalNet "@crescent_city_bb_fab1_lib.crescent_city_bb_fab1(sch_1):dmi_cpu0_pch_rx_c_dp(2)"
				( signalRef "@baseboard_fab2_lib.baseboard_fab2(sch_1):dmi_cpu0_pch_rx_dp(2)" )
				( signalRef "@baseboard_fab2_lib.baseboard_fab2(sch_1):dmi_cpu0_pch_rx_c_dp(2)" )
				( electricalCSetRef "@crescent_city_bb_fab1_lib.crescent_city_bb_fab1(sch_1):\DMI_CPU0_PCH_RX_C_DN_0_\" )
				( pinPairRef "@baseboard_fab2_lib.baseboard_fab2(sch_1):\PP6084\" )
				( objectStatus "DMI_CPU0_PCH_RX_C_DP<2>" )
			)
			( electricalNet "@crescent_city_bb_fab1_lib.crescent_city_bb_fab1(sch_1):dmi_cpu0_pch_rx_c_dn(3)"
				( signalRef "@baseboard_fab2_lib.baseboard_fab2(sch_1):dmi_cpu0_pch_rx_dn(3)" )
				( signalRef "@baseboard_fab2_lib.baseboard_fab2(sch_1):dmi_cpu0_pch_rx_c_dn(3)" )
				( electricalCSetRef "@crescent_city_bb_fab1_lib.crescent_city_bb_fab1(sch_1):\DMI_CPU0_PCH_RX_C_DN_0_\" )
				( pinPairRef "@baseboard_fab2_lib.baseboard_fab2(sch_1):\PP6083\" )
				( objectStatus "DMI_CPU0_PCH_RX_C_DN<3>" )
			)
			( electricalNet "@crescent_city_bb_fab1_lib.crescent_city_bb_fab1(sch_1):dmi_cpu0_pch_rx_c_dp(3)"
				( signalRef "@baseboard_fab2_lib.baseboard_fab2(sch_1):dmi_cpu0_pch_rx_dp(3)" )
				( signalRef "@baseboard_fab2_lib.baseboard_fab2(sch_1):dmi_cpu0_pch_rx_c_dp(3)" )
				( electricalCSetRef "@crescent_city_bb_fab1_lib.crescent_city_bb_fab1(sch_1):\DMI_CPU0_PCH_RX_C_DN_0_\" )
				( pinPairRef "@baseboard_fab2_lib.baseboard_fab2(sch_1):\PP6081\" )
				( objectStatus "DMI_CPU0_PCH_RX_C_DP<3>" )
			)
			( signal "@baseboard_fab2_lib.baseboard_fab2(sch_1):pu_bios_spi_wp0_n"
				( objectStatus "PU_BIOS_SPI_WP0_N" )
			)
			( signal "@baseboard_fab2_lib.baseboard_fab2(sch_1):spi_bios_socket_io2"
				( attribute "CDS_XNET_NAME" "SELECT"
					( Origin gBackEnd )
				)
				( objectStatus "SPI_BIOS_SOCKET_IO2" )
			)
			( signal "@baseboard_fab2_lib.baseboard_fab2(sch_1):clk_100m_cpu1_rc_refclk1_r_dn"
				( objectStatus "CLK_100M_CPU1_RC_REFCLK1_R_DN" )
			)
			( signal "@baseboard_fab2_lib.baseboard_fab2(sch_1):clk_100m_cpu1_rc_refclk1_dn"
				( objectStatus "CLK_100M_CPU1_RC_REFCLK1_DN" )
			)
			( signal "@baseboard_fab2_lib.baseboard_fab2(sch_1):clk_100m_cpu1_rc_refclk1_dp"
				( objectStatus "CLK_100M_CPU1_RC_REFCLK1_DP" )
			)
			( signal "@baseboard_fab2_lib.baseboard_fab2(sch_1):clk_100m_cpu1_rc_refclk1_r_dp"
				( objectStatus "CLK_100M_CPU1_RC_REFCLK1_R_DP" )
			)
			( signal "@baseboard_fab2_lib.baseboard_fab2(sch_1):pu_bios_spi_wp1_n"
				( electricalCSetRef "@crescent_city_bb_fab1_lib.crescent_city_bb_fab1(sch_1):\SPI_PCH_IO2\" )
				( objectStatus "PU_BIOS_SPI_WP1_N" )
			)
			( signal "@baseboard_fab2_lib.baseboard_fab2(sch_1):pu_bios_spi_hold1_n"
				( electricalCSetRef "@crescent_city_bb_fab1_lib.crescent_city_bb_fab1(sch_1):\SPI_PCH_IO3\" )
				( objectStatus "PU_BIOS_SPI_HOLD1_N" )
			)
			( signal "@baseboard_fab2_lib.baseboard_fab2(sch_1):pu_bios_spi_hold0_n"
				( electricalCSetRef "@crescent_city_bb_fab1_lib.crescent_city_bb_fab1(sch_1):\SPI_PCH_IO3\" )
				( objectStatus "PU_BIOS_SPI_HOLD0_N" )
			)
			( signal "@baseboard_fab2_lib.baseboard_fab2(sch_1):spi_bios_socket_io3"
				( electricalCSetRef "@crescent_city_bb_fab1_lib.crescent_city_bb_fab1(sch_1):\SPI_PCH_IO3\" )
				( objectStatus "SPI_BIOS_SOCKET_IO3" )
			)
			( signal "@baseboard_fab2_lib.baseboard_fab2(sch_1):isense_tmp421_1_dxn"
				( objectStatus "ISENSE_TMP421_1_DXN" )
			)
			( signal "@baseboard_fab2_lib.baseboard_fab2(sch_1):isense_tmp421_1_bc"
				( objectStatus "ISENSE_TMP421_1_BC" )
			)
			( signal "@baseboard_fab2_lib.baseboard_fab2(sch_1):isense_tmp421_1_e"
				( objectStatus "ISENSE_TMP421_1_E" )
			)
			( signal "@baseboard_fab2_lib.baseboard_fab2(sch_1):isense_tmp421_1_dxp"
				( objectStatus "ISENSE_TMP421_1_DXP" )
			)
			( signal "@baseboard_fab2_lib.baseboard_fab2(sch_1):isense_tmp421_2_dxn"
				( objectStatus "ISENSE_TMP421_2_DXN" )
			)
			( signal "@baseboard_fab2_lib.baseboard_fab2(sch_1):isense_tmp421_2_bc"
				( objectStatus "ISENSE_TMP421_2_BC" )
			)
			( signal "@baseboard_fab2_lib.baseboard_fab2(sch_1):isense_tmp421_2_e"
				( objectStatus "ISENSE_TMP421_2_E" )
			)
			( signal "@baseboard_fab2_lib.baseboard_fab2(sch_1):isense_tmp421_2_dxp"
				( objectStatus "ISENSE_TMP421_2_DXP" )
			)
			( signal "@baseboard_fab2_lib.baseboard_fab2(sch_1):a_tsense_pvccin_cpu0"
				( objectStatus "A_TSENSE_PVCCIN_CPU0" )
			)
			( signal "@baseboard_fab2_lib.baseboard_fab2(sch_1):a_tsense_pvccin_cpu1"
				( attribute "VOLTAGE" "3.6"
					( Units "uVoltage" "V" 1.000000)
					( Origin gFrontEnd )
				)
				( objectStatus "A_TSENSE_PVCCIN_CPU1" )
			)
			( signal "@baseboard_fab2_lib.baseboard_fab2(sch_1):a_tsense_pvccio_cpu0"
				( attribute "VOLTAGE" "3.6"
					( Units "uVoltage" "V" 1.000000)
					( Origin gFrontEnd )
				)
				( objectStatus "A_TSENSE_PVCCIO_CPU0" )
			)
			( signal "@baseboard_fab2_lib.baseboard_fab2(sch_1):a_tsense_pvccio_cpu1"
				( objectStatus "A_TSENSE_PVCCIO_CPU1" )
			)
			( signal "@baseboard_fab2_lib.baseboard_fab2(sch_1):a_tsense_pvddq_abc"
				( objectStatus "A_TSENSE_PVDDQ_ABC" )
			)
			( signal "@baseboard_fab2_lib.baseboard_fab2(sch_1):a_tsense_pvddq_def"
				( objectStatus "A_TSENSE_PVDDQ_DEF" )
			)
			( signal "@baseboard_fab2_lib.baseboard_fab2(sch_1):a_tsense_pvddq_ghj"
				( objectStatus "A_TSENSE_PVDDQ_GHJ" )
			)
			( signal "@baseboard_fab2_lib.baseboard_fab2(sch_1):a_tsense_pvddq_klm"
				( objectStatus "A_TSENSE_PVDDQ_KLM" )
			)
			( signal "@baseboard_fab2_lib.baseboard_fab2(sch_1):a_tsense_pvnn_pch_tmon"
				( objectStatus "A_TSENSE_PVNN_PCH_TMON" )
			)
			( signal "@baseboard_fab2_lib.baseboard_fab2(sch_1):a_tsense_pvsa_cpu0"
				( objectStatus "A_TSENSE_PVSA_CPU0" )
			)
			( signal "@baseboard_fab2_lib.baseboard_fab2(sch_1):a_tsense_pvsa_cpu1"
				( objectStatus "A_TSENSE_PVSA_CPU1" )
			)
			( signal "@baseboard_fab2_lib.baseboard_fab2(sch_1):a_tsense_p1v05_pch_stby_tmon"
				( objectStatus "A_TSENSE_P1V05_PCH_STBY_TMON" )
			)
			( signal "@baseboard_fab2_lib.baseboard_fab2(sch_1):vsense_pmax_cpu0"
				( objectStatus "VSENSE_PMAX_CPU0" )
			)
			( signal "@baseboard_fab2_lib.baseboard_fab2(sch_1):vsense_pmax_cpu1"
				( objectStatus "VSENSE_PMAX_CPU1" )
			)
			( signal "@baseboard_fab2_lib.baseboard_fab2(sch_1):vsense_p12v_adm1085"
				( objectStatus "VSENSE_P12V_ADM1085" )
			)
			( signal "@baseboard_fab2_lib.baseboard_fab2(sch_1):vsense_pvddq_abc_vtt"
				( objectStatus "VSENSE_PVDDQ_ABC_VTT" )
			)
			( signal "@baseboard_fab2_lib.baseboard_fab2(sch_1):vsense_pvddq_def_vtt"
				( objectStatus "VSENSE_PVDDQ_DEF_VTT" )
			)
			( signal "@baseboard_fab2_lib.baseboard_fab2(sch_1):vsense_pvddq_ghj_vtt"
				( objectStatus "VSENSE_PVDDQ_GHJ_VTT" )
			)
			( signal "@baseboard_fab2_lib.baseboard_fab2(sch_1):vsense_pvddq_klm_vtt"
				( objectStatus "VSENSE_PVDDQ_KLM_VTT" )
			)
			( signal "@baseboard_fab2_lib.baseboard_fab2(sch_1):vsense_pvpp_abc"
				( objectStatus "VSENSE_PVPP_ABC" )
			)
			( signal "@baseboard_fab2_lib.baseboard_fab2(sch_1):vsense_pvpp_def"
				( objectStatus "VSENSE_PVPP_DEF" )
			)
			( signal "@baseboard_fab2_lib.baseboard_fab2(sch_1):vsense_pvpp_ghj"
				( objectStatus "VSENSE_PVPP_GHJ" )
			)
			( signal "@baseboard_fab2_lib.baseboard_fab2(sch_1):vsense_pvpp_klm"
				( objectStatus "VSENSE_PVPP_KLM" )
			)
			( signal "@baseboard_fab2_lib.baseboard_fab2(sch_1):vsense_pvsa_cpu1_bvsp"
				( objectStatus "VSENSE_PVSA_CPU1_BVSP" )
			)
			( signal "@baseboard_fab2_lib.baseboard_fab2(sch_1):vsense_vccinr2pmax_cpu0"
				( objectStatus "VSENSE_VCCINR2PMAX_CPU0" )
			)
			( signal "@baseboard_fab2_lib.baseboard_fab2(sch_1):vsense_vccinr2pmax_cpu1"
				( objectStatus "VSENSE_VCCINR2PMAX_CPU1" )
			)
			( signal "@baseboard_fab2_lib.baseboard_fab2(sch_1):vsense_vout_p3v3_stby"
				( objectStatus "VSENSE_VOUT_P3V3_STBY" )
			)
			( signal "@baseboard_fab2_lib.baseboard_fab2(sch_1):vsense_p3v3_stby"
				( objectStatus "VSENSE_P3V3_STBY" )
			)
			( signal "@baseboard_fab2_lib.baseboard_fab2(sch_1):kr_p0_ocp_tx_dp"
				( objectStatus "KR_P0_OCP_TX_DP" )
			)
			( signal "@baseboard_fab2_lib.baseboard_fab2(sch_1):kr_p0_ocp_tx_dn"
				( objectStatus "KR_P0_OCP_TX_DN" )
			)
			( signal "@baseboard_fab2_lib.baseboard_fab2(sch_1):kr_p1_ocp_tx_dp"
				( objectStatus "KR_P1_OCP_TX_DP" )
			)
			( signal "@baseboard_fab2_lib.baseboard_fab2(sch_1):kr_p1_ocp_tx_dn"
				( objectStatus "KR_P1_OCP_TX_DN" )
			)
			( signal "@baseboard_fab2_lib.baseboard_fab2(sch_1):kr_p2_ocp_tx_dp"
				( objectStatus "KR_P2_OCP_TX_DP" )
			)
			( signal "@baseboard_fab2_lib.baseboard_fab2(sch_1):kr_p2_ocp_tx_dn"
				( objectStatus "KR_P2_OCP_TX_DN" )
			)
			( signal "@baseboard_fab2_lib.baseboard_fab2(sch_1):kr_p3_ocp_tx_dp"
				( objectStatus "KR_P3_OCP_TX_DP" )
			)
			( signal "@baseboard_fab2_lib.baseboard_fab2(sch_1):kr_p3_ocp_tx_dn"
				( objectStatus "KR_P3_OCP_TX_DN" )
			)
			( signal "@baseboard_fab2_lib.baseboard_fab2(sch_1):kr_p0_ocp_rx_c_dp"
				( pinPairRef "@baseboard_fab2_lib.baseboard_fab2(sch_1):\PP6\" )
				( objectStatus "KR_P0_OCP_RX_C_DP" )
			)
			( signal "@baseboard_fab2_lib.baseboard_fab2(sch_1):kr_p0_ocp_rx_dp"
				( objectStatus "KR_P0_OCP_RX_DP" )
			)
			( signal "@baseboard_fab2_lib.baseboard_fab2(sch_1):kr_p0_ocp_rx_dn"
				( objectStatus "KR_P0_OCP_RX_DN" )
			)
			( signal "@baseboard_fab2_lib.baseboard_fab2(sch_1):kr_p0_ocp_rx_c_dn"
				( pinPairRef "@baseboard_fab2_lib.baseboard_fab2(sch_1):\PP5\" )
				( objectStatus "KR_P0_OCP_RX_C_DN" )
			)
			( signal "@baseboard_fab2_lib.baseboard_fab2(sch_1):kr_p1_ocp_rx_c_dp"
				( pinPairRef "@baseboard_fab2_lib.baseboard_fab2(sch_1):\PP8\" )
				( objectStatus "KR_P1_OCP_RX_C_DP" )
			)
			( signal "@baseboard_fab2_lib.baseboard_fab2(sch_1):kr_p1_ocp_rx_dp"
				( objectStatus "KR_P1_OCP_RX_DP" )
			)
			( signal "@baseboard_fab2_lib.baseboard_fab2(sch_1):kr_p1_ocp_rx_dn"
				( objectStatus "KR_P1_OCP_RX_DN" )
			)
			( signal "@baseboard_fab2_lib.baseboard_fab2(sch_1):kr_p1_ocp_rx_c_dn"
				( pinPairRef "@baseboard_fab2_lib.baseboard_fab2(sch_1):\PP7\" )
				( objectStatus "KR_P1_OCP_RX_C_DN" )
			)
			( signal "@baseboard_fab2_lib.baseboard_fab2(sch_1):kr_p2_ocp_rx_c_dp"
				( pinPairRef "@baseboard_fab2_lib.baseboard_fab2(sch_1):\PP10\" )
				( objectStatus "KR_P2_OCP_RX_C_DP" )
			)
			( signal "@baseboard_fab2_lib.baseboard_fab2(sch_1):kr_p2_ocp_rx_dp"
				( objectStatus "KR_P2_OCP_RX_DP" )
			)
			( signal "@baseboard_fab2_lib.baseboard_fab2(sch_1):kr_p2_ocp_rx_dn"
				( objectStatus "KR_P2_OCP_RX_DN" )
			)
			( signal "@baseboard_fab2_lib.baseboard_fab2(sch_1):kr_p2_ocp_rx_c_dn"
				( pinPairRef "@baseboard_fab2_lib.baseboard_fab2(sch_1):\PP9\" )
				( objectStatus "KR_P2_OCP_RX_C_DN" )
			)
			( signal "@baseboard_fab2_lib.baseboard_fab2(sch_1):kr_p3_ocp_rx_c_dp"
				( pinPairRef "@baseboard_fab2_lib.baseboard_fab2(sch_1):\PP12\" )
				( objectStatus "KR_P3_OCP_RX_C_DP" )
			)
			( signal "@baseboard_fab2_lib.baseboard_fab2(sch_1):kr_p3_ocp_rx_dp"
				( objectStatus "KR_P3_OCP_RX_DP" )
			)
			( signal "@baseboard_fab2_lib.baseboard_fab2(sch_1):kr_p3_ocp_rx_dn"
				( objectStatus "KR_P3_OCP_RX_DN" )
			)
			( signal "@baseboard_fab2_lib.baseboard_fab2(sch_1):kr_p3_ocp_rx_c_dn"
				( pinPairRef "@baseboard_fab2_lib.baseboard_fab2(sch_1):\PP11\" )
				( objectStatus "KR_P3_OCP_RX_C_DN" )
			)
			( signal "@baseboard_fab2_lib.baseboard_fab2(sch_1):isense_pvccin_cpu1_ph1_imon"
				( attribute "NO_TEST" "1"
					( Origin gBackEnd )
				)
				( objectStatus "ISENSE_PVCCIN_CPU1_PH1_IMON" )
			)
			( signal "@baseboard_fab2_lib.baseboard_fab2(sch_1):vr_pvccin_cpu1_airef1"
				( objectStatus "VR_PVCCIN_CPU1_AIREF1" )
			)
			( signal "@baseboard_fab2_lib.baseboard_fab2(sch_1):isense_pvccin_cpu1_ph2_imon"
				( objectStatus "ISENSE_PVCCIN_CPU1_PH2_IMON" )
			)
			( signal "@baseboard_fab2_lib.baseboard_fab2(sch_1):vr_pvccin_cpu1_airef2"
				( objectStatus "VR_PVCCIN_CPU1_AIREF2" )
			)
			( signal "@baseboard_fab2_lib.baseboard_fab2(sch_1):isense_pvccin_cpu1_ph4_imon"
				( objectStatus "ISENSE_PVCCIN_CPU1_PH4_IMON" )
			)
			( signal "@baseboard_fab2_lib.baseboard_fab2(sch_1):vr_pvccin_cpu1_airef4"
				( objectStatus "VR_PVCCIN_CPU1_AIREF4" )
			)
			( signal "@baseboard_fab2_lib.baseboard_fab2(sch_1):isense_pvccin_cpu1_ph5_imon"
				( objectStatus "ISENSE_PVCCIN_CPU1_PH5_IMON" )
			)
			( signal "@baseboard_fab2_lib.baseboard_fab2(sch_1):vr_pvccin_cpu1_airef5"
				( objectStatus "VR_PVCCIN_CPU1_AIREF5" )
			)
			( signal "@baseboard_fab2_lib.baseboard_fab2(sch_1):isense_pvsa_cpu1_imon"
				( objectStatus "ISENSE_PVSA_CPU1_IMON" )
			)
			( signal "@baseboard_fab2_lib.baseboard_fab2(sch_1):vr_pvsa_cpu1_biref1"
				( objectStatus "VR_PVSA_CPU1_BIREF1" )
			)
			( signal "@baseboard_fab2_lib.baseboard_fab2(sch_1):isense_pvccin_cpu1_ph3_imon"
				( objectStatus "ISENSE_PVCCIN_CPU1_PH3_IMON" )
			)
			( signal "@baseboard_fab2_lib.baseboard_fab2(sch_1):vr_pvccin_cpu1_airef3"
				( objectStatus "VR_PVCCIN_CPU1_AIREF3" )
			)
			( signal "@baseboard_fab2_lib.baseboard_fab2(sch_1):vr_pvddq_ghj_airef2"
				( physicalCSetRef "@baseboard_fab2_lib.baseboard_fab2(sch_1):\5-5-5_DIFF\" )
				( objectStatus "VR_PVDDQ_GHJ_AIREF2" )
			)
			( signal "@baseboard_fab2_lib.baseboard_fab2(sch_1):isense_pvddq_ghj_ph2_imon"
				( objectStatus "ISENSE_PVDDQ_GHJ_PH2_IMON" )
			)
			( signal "@baseboard_fab2_lib.baseboard_fab2(sch_1):vr_pvddq_ghj_airef1"
				( physicalCSetRef "@baseboard_fab2_lib.baseboard_fab2(sch_1):\5-5-5_DIFF\" )
				( objectStatus "VR_PVDDQ_GHJ_AIREF1" )
			)
			( signal "@baseboard_fab2_lib.baseboard_fab2(sch_1):isense_pvddq_ghj_ph1_imon"
				( physicalCSetRef "@baseboard_fab2_lib.baseboard_fab2(sch_1):\5-5-5_DIFF\" )
				( objectStatus "ISENSE_PVDDQ_GHJ_PH1_IMON" )
			)
			( signal "@baseboard_fab2_lib.baseboard_fab2(sch_1):isense_pvddq_klm_ph2_imon"
				( objectStatus "ISENSE_PVDDQ_KLM_PH2_IMON" )
			)
			( signal "@baseboard_fab2_lib.baseboard_fab2(sch_1):vr_pvddq_klm_airef2"
				( physicalCSetRef "@baseboard_fab2_lib.baseboard_fab2(sch_1):\5-5-5_DIFF\" )
				( objectStatus "VR_PVDDQ_KLM_AIREF2" )
			)
			( signal "@baseboard_fab2_lib.baseboard_fab2(sch_1):isense_pvddq_klm_ph1_imon"
				( objectStatus "ISENSE_PVDDQ_KLM_PH1_IMON" )
			)
			( signal "@baseboard_fab2_lib.baseboard_fab2(sch_1):vr_pvddq_klm_airef1"
				( physicalCSetRef "@baseboard_fab2_lib.baseboard_fab2(sch_1):\5-5-5_DIFF\" )
				( objectStatus "VR_PVDDQ_KLM_AIREF1" )
			)
			( signal "@baseboard_fab2_lib.baseboard_fab2(sch_1):vr_pvddq_def_airef2"
				( physicalCSetRef "@baseboard_fab2_lib.baseboard_fab2(sch_1):\5-5-5_DIFF\" )
				( objectStatus "VR_PVDDQ_DEF_AIREF2" )
			)
			( signal "@baseboard_fab2_lib.baseboard_fab2(sch_1):isense_pvddq_def_ph2_imon"
				( objectStatus "ISENSE_PVDDQ_DEF_PH2_IMON" )
			)
			( signal "@baseboard_fab2_lib.baseboard_fab2(sch_1):isense_pvddq_def_ph1_imon"
				( objectStatus "ISENSE_PVDDQ_DEF_PH1_IMON" )
			)
			( signal "@baseboard_fab2_lib.baseboard_fab2(sch_1):vr_pvddq_def_airef1"
				( physicalCSetRef "@baseboard_fab2_lib.baseboard_fab2(sch_1):\5-5-5_DIFF\" )
				( objectStatus "VR_PVDDQ_DEF_AIREF1" )
			)
			( signal "@baseboard_fab2_lib.baseboard_fab2(sch_1):isense_pvnn_pch_ph1_imon"
				( objectStatus "ISENSE_PVNN_PCH_PH1_IMON" )
			)
			( signal "@baseboard_fab2_lib.baseboard_fab2(sch_1):vr_pvnn_pch_airef1"
				( physicalCSetRef "@baseboard_fab2_lib.baseboard_fab2(sch_1):\5-5-5_DIFF\" )
				( objectStatus "VR_PVNN_PCH_AIREF1" )
			)
			( signal "@baseboard_fab2_lib.baseboard_fab2(sch_1):isense_p1v05_pch_stby_ph1_imon"
				( objectStatus "ISENSE_P1V05_PCH_STBY_PH1_IMON" )
			)
			( signal "@baseboard_fab2_lib.baseboard_fab2(sch_1):vr_p1v05_pch_biref1"
				( physicalCSetRef "@baseboard_fab2_lib.baseboard_fab2(sch_1):\5-5-5_DIFF\" )
				( objectStatus "VR_P1V05_PCH_BIREF1" )
			)
			( signal "@baseboard_fab2_lib.baseboard_fab2(sch_1):vr_pvddq_abc_airef2"
				( physicalCSetRef "@baseboard_fab2_lib.baseboard_fab2(sch_1):\5-5-5_DIFF\" )
				( objectStatus "VR_PVDDQ_ABC_AIREF2" )
			)
			( signal "@baseboard_fab2_lib.baseboard_fab2(sch_1):isense_pvddq_abc_ph2_imon"
				( objectStatus "ISENSE_PVDDQ_ABC_PH2_IMON" )
			)
			( signal "@baseboard_fab2_lib.baseboard_fab2(sch_1):isense_pvddq_abc_ph1_imon"
				( objectStatus "ISENSE_PVDDQ_ABC_PH1_IMON" )
			)
			( signal "@baseboard_fab2_lib.baseboard_fab2(sch_1):vr_pvddq_abc_airef1"
				( physicalCSetRef "@baseboard_fab2_lib.baseboard_fab2(sch_1):\5-5-5_DIFF\" )
				( objectStatus "VR_PVDDQ_ABC_AIREF1" )
			)
			( signal "@baseboard_fab2_lib.baseboard_fab2(sch_1):isense_pvccin_cpu0_ph1_imon"
				( objectStatus "ISENSE_PVCCIN_CPU0_PH1_IMON" )
			)
			( signal "@baseboard_fab2_lib.baseboard_fab2(sch_1):vr_pvccin_cpu0_airef1"
				( objectStatus "VR_PVCCIN_CPU0_AIREF1" )
			)
			( signal "@baseboard_fab2_lib.baseboard_fab2(sch_1):isense_pvccin_cpu0_ph2_imon"
				( objectStatus "ISENSE_PVCCIN_CPU0_PH2_IMON" )
			)
			( signal "@baseboard_fab2_lib.baseboard_fab2(sch_1):vr_pvccin_cpu0_airef2"
				( objectStatus "VR_PVCCIN_CPU0_AIREF2" )
			)
			( signal "@baseboard_fab2_lib.baseboard_fab2(sch_1):vr_pvccin_cpu0_airef3"
				( objectStatus "VR_PVCCIN_CPU0_AIREF3" )
			)
			( signal "@baseboard_fab2_lib.baseboard_fab2(sch_1):isense_pvccin_cpu0_ph3_imon"
				( objectStatus "ISENSE_PVCCIN_CPU0_PH3_IMON" )
			)
			( signal "@baseboard_fab2_lib.baseboard_fab2(sch_1):isense_pvccin_cpu0_ph4_imon"
				( objectStatus "ISENSE_PVCCIN_CPU0_PH4_IMON" )
			)
			( signal "@baseboard_fab2_lib.baseboard_fab2(sch_1):vr_pvccin_cpu0_airef4"
				( objectStatus "VR_PVCCIN_CPU0_AIREF4" )
			)
			( signal "@baseboard_fab2_lib.baseboard_fab2(sch_1):vr_pvccin_cpu0_airef5"
				( objectStatus "VR_PVCCIN_CPU0_AIREF5" )
			)
			( signal "@baseboard_fab2_lib.baseboard_fab2(sch_1):isense_pvccin_cpu0_ph5_imon"
				( objectStatus "ISENSE_PVCCIN_CPU0_PH5_IMON" )
			)
			( signal "@baseboard_fab2_lib.baseboard_fab2(sch_1):vr_pvsa_cpu0_biref1"
				( objectStatus "VR_PVSA_CPU0_BIREF1" )
			)
			( signal "@baseboard_fab2_lib.baseboard_fab2(sch_1):isense_pvsa_cpu0_imon"
				( objectStatus "ISENSE_PVSA_CPU0_IMON" )
			)
			( signal "@baseboard_fab2_lib.baseboard_fab2(sch_1):vr_pvccio_cpu1_airef1"
				( physicalCSetRef "@baseboard_fab2_lib.baseboard_fab2(sch_1):\5-5-5_DIFF\" )
				( objectStatus "VR_PVCCIO_CPU1_AIREF1" )
			)
			( signal "@baseboard_fab2_lib.baseboard_fab2(sch_1):isense_pvccio_cpu1_ph1_imon"
				( objectStatus "ISENSE_PVCCIO_CPU1_PH1_IMON" )
			)
			( signal "@baseboard_fab2_lib.baseboard_fab2(sch_1):vr_pvccio_cpu0_airef1"
				( physicalCSetRef "@baseboard_fab2_lib.baseboard_fab2(sch_1):\5-5-5_DIFF\" )
				( objectStatus "VR_PVCCIO_CPU0_AIREF1" )
			)
			( signal "@baseboard_fab2_lib.baseboard_fab2(sch_1):isense_pvccio_cpu0_ph1_imon"
				( objectStatus "ISENSE_PVCCIO_CPU0_PH1_IMON" )
			)
			( signal "@baseboard_fab2_lib.baseboard_fab2(sch_1):vr_pvddq_abc_avsp"
				( objectStatus "VR_PVDDQ_ABC_AVSP" )
			)
			( signal "@baseboard_fab2_lib.baseboard_fab2(sch_1):vr_pvddq_abc_ph1_vcin"
				( attribute "VOLTAGE" "1 V"
					( Units "uVoltage" "V" 1.000000)
					( Origin gBackEnd )
				)
				( objectStatus "VR_PVDDQ_ABC_PH1_VCIN" )
			)
			( signal "@baseboard_fab2_lib.baseboard_fab2(sch_1):vr_pvddq_abc_ph2_vcin"
				( attribute "VOLTAGE" "2 V"
					( Units "uVoltage" "V" 1.000000)
					( Origin gBackEnd )
				)
				( objectStatus "VR_PVDDQ_ABC_PH2_VCIN" )
			)
			( signal "@baseboard_fab2_lib.baseboard_fab2(sch_1):vr_pvddq_abc_vdd"
				( objectStatus "VR_PVDDQ_ABC_VDD" )
			)
			( signal "@baseboard_fab2_lib.baseboard_fab2(sch_1):vr_pvddq_abc_vd12"
				( objectStatus "VR_PVDDQ_ABC_VD12" )
			)
			( signal "@baseboard_fab2_lib.baseboard_fab2(sch_1):vr_pvddq_abc_vinsen"
				( objectStatus "VR_PVDDQ_ABC_VINSEN" )
			)
			( signal "@baseboard_fab2_lib.baseboard_fab2(sch_1):vr_pvddq_abc_xaddr1"
				( objectStatus "VR_PVDDQ_ABC_XADDR1" )
			)
			( signal "@baseboard_fab2_lib.baseboard_fab2(sch_1):vr_pvddq_abc_xaddr2"
				( objectStatus "VR_PVDDQ_ABC_XADDR2" )
			)
			( signal "@baseboard_fab2_lib.baseboard_fab2(sch_1):vr_pvddq_def_avsp"
				( objectStatus "VR_PVDDQ_DEF_AVSP" )
			)
			( signal "@baseboard_fab2_lib.baseboard_fab2(sch_1):vr_pvddq_def_ph1_vcin"
				( attribute "VOLTAGE" "1 V"
					( Units "uVoltage" "V" 1.000000)
					( Origin gBackEnd )
				)
				( objectStatus "VR_PVDDQ_DEF_PH1_VCIN" )
			)
			( signal "@baseboard_fab2_lib.baseboard_fab2(sch_1):vr_pvddq_def_ph2_vcin"
				( attribute "VOLTAGE" "2 V"
					( Units "uVoltage" "V" 1.000000)
					( Origin gBackEnd )
				)
				( objectStatus "VR_PVDDQ_DEF_PH2_VCIN" )
			)
			( signal "@baseboard_fab2_lib.baseboard_fab2(sch_1):vr_pvddq_def_vdd"
				( objectStatus "VR_PVDDQ_DEF_VDD" )
			)
			( signal "@baseboard_fab2_lib.baseboard_fab2(sch_1):vr_pvddq_def_vd12"
				( objectStatus "VR_PVDDQ_DEF_VD12" )
			)
			( signal "@baseboard_fab2_lib.baseboard_fab2(sch_1):vr_pvddq_def_vinsen"
				( objectStatus "VR_PVDDQ_DEF_VINSEN" )
			)
			( signal "@baseboard_fab2_lib.baseboard_fab2(sch_1):vr_pvddq_def_xaddr1"
				( objectStatus "VR_PVDDQ_DEF_XADDR1" )
			)
			( signal "@baseboard_fab2_lib.baseboard_fab2(sch_1):vr_pvddq_def_xaddr2"
				( objectStatus "VR_PVDDQ_DEF_XADDR2" )
			)
			( signal "@baseboard_fab2_lib.baseboard_fab2(sch_1):vr_pvddq_ghj_avsp"
				( objectStatus "VR_PVDDQ_GHJ_AVSP" )
			)
			( signal "@baseboard_fab2_lib.baseboard_fab2(sch_1):vr_pvddq_ghj_ph1_vcin"
				( attribute "VOLTAGE" "1 V"
					( Units "uVoltage" "V" 1.000000)
					( Origin gBackEnd )
				)
				( objectStatus "VR_PVDDQ_GHJ_PH1_VCIN" )
			)
			( signal "@baseboard_fab2_lib.baseboard_fab2(sch_1):vr_pvddq_ghj_ph2_vcin"
				( attribute "VOLTAGE" "2 V"
					( Units "uVoltage" "V" 1.000000)
					( Origin gBackEnd )
				)
				( objectStatus "VR_PVDDQ_GHJ_PH2_VCIN" )
			)
			( signal "@baseboard_fab2_lib.baseboard_fab2(sch_1):vr_pvddq_ghj_vdd"
				( objectStatus "VR_PVDDQ_GHJ_VDD" )
			)
			( signal "@baseboard_fab2_lib.baseboard_fab2(sch_1):vr_pvddq_ghj_vd12"
				( objectStatus "VR_PVDDQ_GHJ_VD12" )
			)
			( signal "@baseboard_fab2_lib.baseboard_fab2(sch_1):vr_pvddq_ghj_vinsen"
				( objectStatus "VR_PVDDQ_GHJ_VINSEN" )
			)
			( signal "@baseboard_fab2_lib.baseboard_fab2(sch_1):vr_pvddq_ghj_xaddr1"
				( objectStatus "VR_PVDDQ_GHJ_XADDR1" )
			)
			( signal "@baseboard_fab2_lib.baseboard_fab2(sch_1):vr_pvddq_ghj_xaddr2"
				( objectStatus "VR_PVDDQ_GHJ_XADDR2" )
			)
			( signal "@baseboard_fab2_lib.baseboard_fab2(sch_1):vr_pvddq_klm_avsp"
				( objectStatus "VR_PVDDQ_KLM_AVSP" )
			)
			( signal "@baseboard_fab2_lib.baseboard_fab2(sch_1):vr_pvddq_klm_ph1_vcin"
				( attribute "VOLTAGE" "1 V"
					( Units "uVoltage" "V" 1.000000)
					( Origin gBackEnd )
				)
				( objectStatus "VR_PVDDQ_KLM_PH1_VCIN" )
			)
			( signal "@baseboard_fab2_lib.baseboard_fab2(sch_1):vr_pvddq_klm_ph2_vcin"
				( attribute "VOLTAGE" "2 V"
					( Units "uVoltage" "V" 1.000000)
					( Origin gBackEnd )
				)
				( objectStatus "VR_PVDDQ_KLM_PH2_VCIN" )
			)
			( signal "@baseboard_fab2_lib.baseboard_fab2(sch_1):vr_pvddq_klm_vdd"
				( objectStatus "VR_PVDDQ_KLM_VDD" )
			)
			( signal "@baseboard_fab2_lib.baseboard_fab2(sch_1):vr_pvddq_klm_vd12"
				( objectStatus "VR_PVDDQ_KLM_VD12" )
			)
			( signal "@baseboard_fab2_lib.baseboard_fab2(sch_1):vr_pvddq_klm_vinsen"
				( objectStatus "VR_PVDDQ_KLM_VINSEN" )
			)
			( signal "@baseboard_fab2_lib.baseboard_fab2(sch_1):vr_pvddq_klm_xaddr1"
				( objectStatus "VR_PVDDQ_KLM_XADDR1" )
			)
			( signal "@baseboard_fab2_lib.baseboard_fab2(sch_1):vr_pvddq_klm_xaddr2"
				( objectStatus "VR_PVDDQ_KLM_XADDR2" )
			)
			( signal "@baseboard_fab2_lib.baseboard_fab2(sch_1):vr_pvddq_abc_aiinsen_r"
				( objectStatus "VR_PVDDQ_ABC_AIINSEN_R" )
			)
			( signal "@baseboard_fab2_lib.baseboard_fab2(sch_1):vr_pvddq_abc_aiinsen"
				( objectStatus "VR_PVDDQ_ABC_AIINSEN" )
			)
			( signal "@baseboard_fab2_lib.baseboard_fab2(sch_1):vr_pvddq_abc_ph1_phase"
				( objectStatus "VR_PVDDQ_ABC_PH1_PHASE" )
			)
			( signal "@baseboard_fab2_lib.baseboard_fab2(sch_1):vr_pvddq_abc_ph1_boot"
				( objectStatus "VR_PVDDQ_ABC_PH1_BOOT" )
			)
			( signal "@baseboard_fab2_lib.baseboard_fab2(sch_1):vr_pvddq_abc_ph2_phase"
				( objectStatus "VR_PVDDQ_ABC_PH2_PHASE" )
			)
			( signal "@baseboard_fab2_lib.baseboard_fab2(sch_1):vr_pvddq_abc_ph2_boot"
				( objectStatus "VR_PVDDQ_ABC_PH2_BOOT" )
			)
			( signal "@baseboard_fab2_lib.baseboard_fab2(sch_1):vr_pvddq_def_aiinsen_r"
				( objectStatus "VR_PVDDQ_DEF_AIINSEN_R" )
			)
			( signal "@baseboard_fab2_lib.baseboard_fab2(sch_1):vr_pvddq_def_aiinsen"
				( objectStatus "VR_PVDDQ_DEF_AIINSEN" )
			)
			( signal "@baseboard_fab2_lib.baseboard_fab2(sch_1):vr_pvddq_def_ph1_phase"
				( objectStatus "VR_PVDDQ_DEF_PH1_PHASE" )
			)
			( signal "@baseboard_fab2_lib.baseboard_fab2(sch_1):vr_pvddq_def_ph1_boot"
				( objectStatus "VR_PVDDQ_DEF_PH1_BOOT" )
			)
			( signal "@baseboard_fab2_lib.baseboard_fab2(sch_1):vr_pvddq_def_ph2_phase"
				( objectStatus "VR_PVDDQ_DEF_PH2_PHASE" )
			)
			( signal "@baseboard_fab2_lib.baseboard_fab2(sch_1):vr_pvddq_def_ph2_boot"
				( objectStatus "VR_PVDDQ_DEF_PH2_BOOT" )
			)
			( signal "@baseboard_fab2_lib.baseboard_fab2(sch_1):vr_pvddq_ghj_aiinsen_r"
				( objectStatus "VR_PVDDQ_GHJ_AIINSEN_R" )
			)
			( signal "@baseboard_fab2_lib.baseboard_fab2(sch_1):vr_pvddq_ghj_aiinsen"
				( objectStatus "VR_PVDDQ_GHJ_AIINSEN" )
			)
			( signal "@baseboard_fab2_lib.baseboard_fab2(sch_1):vr_pvddq_ghj_ph1_phase"
				( objectStatus "VR_PVDDQ_GHJ_PH1_PHASE" )
			)
			( signal "@baseboard_fab2_lib.baseboard_fab2(sch_1):vr_pvddq_ghj_ph1_boot"
				( objectStatus "VR_PVDDQ_GHJ_PH1_BOOT" )
			)
			( signal "@baseboard_fab2_lib.baseboard_fab2(sch_1):vr_pvddq_ghj_ph2_phase"
				( objectStatus "VR_PVDDQ_GHJ_PH2_PHASE" )
			)
			( signal "@baseboard_fab2_lib.baseboard_fab2(sch_1):vr_pvddq_ghj_ph2_boot"
				( objectStatus "VR_PVDDQ_GHJ_PH2_BOOT" )
			)
			( signal "@baseboard_fab2_lib.baseboard_fab2(sch_1):vr_pvddq_klm_aiinsen_r"
				( objectStatus "VR_PVDDQ_KLM_AIINSEN_R" )
			)
			( signal "@baseboard_fab2_lib.baseboard_fab2(sch_1):vr_pvddq_klm_aiinsen"
				( objectStatus "VR_PVDDQ_KLM_AIINSEN" )
			)
			( signal "@baseboard_fab2_lib.baseboard_fab2(sch_1):vr_pvddq_klm_ph1_phase"
				( objectStatus "VR_PVDDQ_KLM_PH1_PHASE" )
			)
			( signal "@baseboard_fab2_lib.baseboard_fab2(sch_1):vr_pvddq_klm_ph1_boot"
				( objectStatus "VR_PVDDQ_KLM_PH1_BOOT" )
			)
			( signal "@baseboard_fab2_lib.baseboard_fab2(sch_1):vr_pvddq_klm_ph2_phase"
				( objectStatus "VR_PVDDQ_KLM_PH2_PHASE" )
			)
			( signal "@baseboard_fab2_lib.baseboard_fab2(sch_1):vr_pvddq_klm_ph2_boot"
				( objectStatus "VR_PVDDQ_KLM_PH2_BOOT" )
			)
			( signal "@baseboard_fab2_lib.baseboard_fab2(sch_1):clk_100m_airmax8_pe1_dp"
				( electricalCSetRef "@crescent_city_bb_fab1_lib.crescent_city_bb_fab1(sch_1):\CLK_100M_PCH_SLOT\" )
				( pinPairRef "@baseboard_fab2_lib.baseboard_fab2(sch_1):\PP5379\" )
				( objectStatus "CLK_100M_AIRMAX8_PE1_DP" )
			)
			( signal "@baseboard_fab2_lib.baseboard_fab2(sch_1):clk_100m_airmax8_pe1_dn"
				( electricalCSetRef "@crescent_city_bb_fab1_lib.crescent_city_bb_fab1(sch_1):\CLK_100M_PCH_SLOT\" )
				( pinPairRef "@baseboard_fab2_lib.baseboard_fab2(sch_1):\PP5380\" )
				( objectStatus "CLK_100M_AIRMAX8_PE1_DN" )
			)
			( signal "@baseboard_fab2_lib.baseboard_fab2(sch_1):clk_100m_bmc_pe_dn"
				( objectStatus "CLK_100M_BMC_PE_DN" )
			)
			( signal "@baseboard_fab2_lib.baseboard_fab2(sch_1):clk_100m_bmc_pe_r_dn"
				( objectStatus "CLK_100M_BMC_PE_R_DN" )
			)
			( signal "@baseboard_fab2_lib.baseboard_fab2(sch_1):clk_100m_bmc_pe_r_dp"
				( objectStatus "CLK_100M_BMC_PE_R_DP" )
			)
			( signal "@baseboard_fab2_lib.baseboard_fab2(sch_1):clk_100m_bmc_pe_dp"
				( objectStatus "CLK_100M_BMC_PE_DP" )
			)
			( signal "@baseboard_fab2_lib.baseboard_fab2(sch_1):clk_100m_cpu0_bclk0_r_dn"
				( objectStatus "CLK_100M_CPU0_BCLK0_R_DN" )
			)
			( signal "@baseboard_fab2_lib.baseboard_fab2(sch_1):clk_100m_cpu0_bclk0_dn"
				( objectStatus "CLK_100M_CPU0_BCLK0_DN" )
			)
			( signal "@baseboard_fab2_lib.baseboard_fab2(sch_1):clk_100m_cpu0_bclk0_r_dp"
				( objectStatus "CLK_100M_CPU0_BCLK0_R_DP" )
			)
			( signal "@baseboard_fab2_lib.baseboard_fab2(sch_1):clk_100m_cpu0_bclk0_dp"
				( objectStatus "CLK_100M_CPU0_BCLK0_DP" )
			)
			( signal "@baseboard_fab2_lib.baseboard_fab2(sch_1):clk_100m_cpu0_bclk1_r_dn"
				( objectStatus "CLK_100M_CPU0_BCLK1_R_DN" )
			)
			( signal "@baseboard_fab2_lib.baseboard_fab2(sch_1):clk_100m_cpu0_bclk1_dn"
				( objectStatus "CLK_100M_CPU0_BCLK1_DN" )
			)
			( signal "@baseboard_fab2_lib.baseboard_fab2(sch_1):clk_100m_cpu0_bclk1_r_dp"
				( objectStatus "CLK_100M_CPU0_BCLK1_R_DP" )
			)
			( signal "@baseboard_fab2_lib.baseboard_fab2(sch_1):clk_100m_cpu0_bclk1_dp"
				( objectStatus "CLK_100M_CPU0_BCLK1_DP" )
			)
			( signal "@baseboard_fab2_lib.baseboard_fab2(sch_1):clk_100m_cpu0_bclk2_r_dn"
				( objectStatus "CLK_100M_CPU0_BCLK2_R_DN" )
			)
			( signal "@baseboard_fab2_lib.baseboard_fab2(sch_1):clk_100m_cpu0_bclk2_dn"
				( objectStatus "CLK_100M_CPU0_BCLK2_DN" )
			)
			( signal "@baseboard_fab2_lib.baseboard_fab2(sch_1):clk_100m_cpu0_bclk2_r_dp"
				( objectStatus "CLK_100M_CPU0_BCLK2_R_DP" )
			)
			( signal "@baseboard_fab2_lib.baseboard_fab2(sch_1):clk_100m_cpu0_bclk2_dp"
				( objectStatus "CLK_100M_CPU0_BCLK2_DP" )
			)
			( signal "@baseboard_fab2_lib.baseboard_fab2(sch_1):clk_100m_cpu0_rc_refclk0_r_dn"
				( objectStatus "CLK_100M_CPU0_RC_REFCLK0_R_DN" )
			)
			( signal "@baseboard_fab2_lib.baseboard_fab2(sch_1):clk_100m_cpu0_rc_refclk0_dn"
				( objectStatus "CLK_100M_CPU0_RC_REFCLK0_DN" )
			)
			( signal "@baseboard_fab2_lib.baseboard_fab2(sch_1):clk_100m_cpu0_rc_refclk0_dp"
				( objectStatus "CLK_100M_CPU0_RC_REFCLK0_DP" )
			)
			( signal "@baseboard_fab2_lib.baseboard_fab2(sch_1):clk_100m_cpu0_rc_refclk0_r_dp"
				( objectStatus "CLK_100M_CPU0_RC_REFCLK0_R_DP" )
			)
			( signal "@baseboard_fab2_lib.baseboard_fab2(sch_1):clk_100m_cpu0_rc_refclk1_r_dn"
				( objectStatus "CLK_100M_CPU0_RC_REFCLK1_R_DN" )
			)
			( signal "@baseboard_fab2_lib.baseboard_fab2(sch_1):clk_100m_cpu0_rc_refclk1_dn"
				( objectStatus "CLK_100M_CPU0_RC_REFCLK1_DN" )
			)
			( signal "@baseboard_fab2_lib.baseboard_fab2(sch_1):clk_100m_cpu0_rc_refclk1_dp"
				( objectStatus "CLK_100M_CPU0_RC_REFCLK1_DP" )
			)
			( signal "@baseboard_fab2_lib.baseboard_fab2(sch_1):clk_100m_cpu0_rc_refclk1_r_dp"
				( objectStatus "CLK_100M_CPU0_RC_REFCLK1_R_DP" )
			)
			( signal "@baseboard_fab2_lib.baseboard_fab2(sch_1):clk_100m_cpu0_pe_refclk_r_dn"
				( objectStatus "CLK_100M_CPU0_PE_REFCLK_R_DN" )
			)
			( signal "@baseboard_fab2_lib.baseboard_fab2(sch_1):clk_100m_cpu0_pe_refclk_dn"
				( objectStatus "CLK_100M_CPU0_PE_REFCLK_DN" )
			)
			( signal "@baseboard_fab2_lib.baseboard_fab2(sch_1):clk_100m_cpu0_pe_refclk_dp"
				( objectStatus "CLK_100M_CPU0_PE_REFCLK_DP" )
			)
			( signal "@baseboard_fab2_lib.baseboard_fab2(sch_1):clk_100m_cpu0_pe_refclk_r_dp"
				( objectStatus "CLK_100M_CPU0_PE_REFCLK_R_DP" )
			)
			( signal "@baseboard_fab2_lib.baseboard_fab2(sch_1):clk_100m_cpu1_bclk0_r_dn"
				( objectStatus "CLK_100M_CPU1_BCLK0_R_DN" )
			)
			( signal "@baseboard_fab2_lib.baseboard_fab2(sch_1):clk_100m_cpu1_bclk0_dn"
				( objectStatus "CLK_100M_CPU1_BCLK0_DN" )
			)
			( signal "@baseboard_fab2_lib.baseboard_fab2(sch_1):clk_100m_cpu1_bclk0_r_dp"
				( objectStatus "CLK_100M_CPU1_BCLK0_R_DP" )
			)
			( signal "@baseboard_fab2_lib.baseboard_fab2(sch_1):clk_100m_cpu1_bclk0_dp"
				( objectStatus "CLK_100M_CPU1_BCLK0_DP" )
			)
			( signal "@baseboard_fab2_lib.baseboard_fab2(sch_1):clk_100m_cpu1_bclk1_r_dn"
				( objectStatus "CLK_100M_CPU1_BCLK1_R_DN" )
			)
			( signal "@baseboard_fab2_lib.baseboard_fab2(sch_1):clk_100m_cpu1_bclk1_dn"
				( objectStatus "CLK_100M_CPU1_BCLK1_DN" )
			)
			( signal "@baseboard_fab2_lib.baseboard_fab2(sch_1):clk_100m_cpu1_bclk1_r_dp"
				( objectStatus "CLK_100M_CPU1_BCLK1_R_DP" )
			)
			( signal "@baseboard_fab2_lib.baseboard_fab2(sch_1):clk_100m_cpu1_bclk1_dp"
				( objectStatus "CLK_100M_CPU1_BCLK1_DP" )
			)
			( signal "@baseboard_fab2_lib.baseboard_fab2(sch_1):clk_100m_cpu1_bclk2_r_dn"
				( objectStatus "CLK_100M_CPU1_BCLK2_R_DN" )
			)
			( signal "@baseboard_fab2_lib.baseboard_fab2(sch_1):clk_100m_cpu1_bclk2_dn"
				( objectStatus "CLK_100M_CPU1_BCLK2_DN" )
			)
			( signal "@baseboard_fab2_lib.baseboard_fab2(sch_1):clk_100m_cpu1_bclk2_r_dp"
				( objectStatus "CLK_100M_CPU1_BCLK2_R_DP" )
			)
			( signal "@baseboard_fab2_lib.baseboard_fab2(sch_1):clk_100m_cpu1_bclk2_dp"
				( objectStatus "CLK_100M_CPU1_BCLK2_DP" )
			)
			( signal "@baseboard_fab2_lib.baseboard_fab2(sch_1):clk_100m_cpu1_rc_refclk0_r_dn"
				( objectStatus "CLK_100M_CPU1_RC_REFCLK0_R_DN" )
			)
			( signal "@baseboard_fab2_lib.baseboard_fab2(sch_1):clk_100m_cpu1_rc_refclk0_dn"
				( objectStatus "CLK_100M_CPU1_RC_REFCLK0_DN" )
			)
			( signal "@baseboard_fab2_lib.baseboard_fab2(sch_1):clk_100m_cpu1_rc_refclk0_dp"
				( objectStatus "CLK_100M_CPU1_RC_REFCLK0_DP" )
			)
			( signal "@baseboard_fab2_lib.baseboard_fab2(sch_1):clk_100m_cpu1_rc_refclk0_r_dp"
				( objectStatus "CLK_100M_CPU1_RC_REFCLK0_R_DP" )
			)
			( signal "@baseboard_fab2_lib.baseboard_fab2(sch_1):clk_100m_cpu1_pe_refclk_r_dn"
				( objectStatus "CLK_100M_CPU1_PE_REFCLK_R_DN" )
			)
			( signal "@baseboard_fab2_lib.baseboard_fab2(sch_1):clk_100m_cpu1_pe_refclk_dn"
				( objectStatus "CLK_100M_CPU1_PE_REFCLK_DN" )
			)
			( signal "@baseboard_fab2_lib.baseboard_fab2(sch_1):clk_100m_cpu1_pe_refclk_dp"
				( objectStatus "CLK_100M_CPU1_PE_REFCLK_DP" )
			)
			( signal "@baseboard_fab2_lib.baseboard_fab2(sch_1):clk_100m_cpu1_pe_refclk_r_dp"
				( objectStatus "CLK_100M_CPU1_PE_REFCLK_R_DP" )
			)
			( signal "@baseboard_fab2_lib.baseboard_fab2(sch_1):clk_100m_db1200_dp"
				( electricalCSetRef "@crescent_city_bb_fab1_lib.crescent_city_bb_fab1(sch_1):\CLK_100M_OTHERS\" )
				( objectStatus "CLK_100M_DB1200_DP" )
			)
			( signal "@baseboard_fab2_lib.baseboard_fab2(sch_1):clk_100m_db1200_dn"
				( electricalCSetRef "@crescent_city_bb_fab1_lib.crescent_city_bb_fab1(sch_1):\CLK_100M_OTHERS\" )
				( objectStatus "CLK_100M_DB1200_DN" )
			)
			( signal "@baseboard_fab2_lib.baseboard_fab2(sch_1):clk_100m_mezz1_dp"
				( electricalCSetRef "@crescent_city_bb_fab1_lib.crescent_city_bb_fab1(sch_1):\CLK_100M_PCH_SLOT\" )
				( pinPairRef "@baseboard_fab2_lib.baseboard_fab2(sch_1):\PP5399\" )
				( objectStatus "CLK_100M_MEZZ1_DP" )
			)
			( signal "@baseboard_fab2_lib.baseboard_fab2(sch_1):clk_100m_mezz1_dn"
				( electricalCSetRef "@crescent_city_bb_fab1_lib.crescent_city_bb_fab1(sch_1):\CLK_100M_PCH_SLOT\" )
				( pinPairRef "@baseboard_fab2_lib.baseboard_fab2(sch_1):\PP5400\" )
				( objectStatus "CLK_100M_MEZZ1_DN" )
			)
			( signal "@baseboard_fab2_lib.baseboard_fab2(sch_1):clk_100m_mezz2_dp"
				( electricalCSetRef "@crescent_city_bb_fab1_lib.crescent_city_bb_fab1(sch_1):\CLK_100M_PCH_SLOT\" )
				( pinPairRef "@baseboard_fab2_lib.baseboard_fab2(sch_1):\PP5397\" )
				( objectStatus "CLK_100M_MEZZ2_DP" )
			)
			( signal "@baseboard_fab2_lib.baseboard_fab2(sch_1):clk_100m_mezz2_dn"
				( electricalCSetRef "@crescent_city_bb_fab1_lib.crescent_city_bb_fab1(sch_1):\CLK_100M_PCH_SLOT\" )
				( pinPairRef "@baseboard_fab2_lib.baseboard_fab2(sch_1):\PP5398\" )
				( objectStatus "CLK_100M_MEZZ2_DN" )
			)
			( signal "@baseboard_fab2_lib.baseboard_fab2(sch_1):clk_100m_mezz3_dp"
				( electricalCSetRef "@crescent_city_bb_fab1_lib.crescent_city_bb_fab1(sch_1):\CLK_100M_PCH_SLOT\" )
				( pinPairRef "@baseboard_fab2_lib.baseboard_fab2(sch_1):\PP5385\" )
				( objectStatus "CLK_100M_MEZZ3_DP" )
			)
			( signal "@baseboard_fab2_lib.baseboard_fab2(sch_1):clk_100m_mezz3_dn"
				( electricalCSetRef "@crescent_city_bb_fab1_lib.crescent_city_bb_fab1(sch_1):\CLK_100M_PCH_SLOT\" )
				( pinPairRef "@baseboard_fab2_lib.baseboard_fab2(sch_1):\PP5386\" )
				( objectStatus "CLK_100M_MEZZ3_DN" )
			)
			( signal "@baseboard_fab2_lib.baseboard_fab2(sch_1):clk_100m_mezz4_dp"
				( electricalCSetRef "@crescent_city_bb_fab1_lib.crescent_city_bb_fab1(sch_1):\CLK_100M_PCH_SLOT\" )
				( pinPairRef "@baseboard_fab2_lib.baseboard_fab2(sch_1):\PP5383\" )
				( objectStatus "CLK_100M_MEZZ4_DP" )
			)
			( signal "@baseboard_fab2_lib.baseboard_fab2(sch_1):clk_100m_mezz4_dn"
				( electricalCSetRef "@crescent_city_bb_fab1_lib.crescent_city_bb_fab1(sch_1):\CLK_100M_PCH_SLOT\" )
				( pinPairRef "@baseboard_fab2_lib.baseboard_fab2(sch_1):\PP5384\" )
				( objectStatus "CLK_100M_MEZZ4_DN" )
			)
			( signal "@baseboard_fab2_lib.baseboard_fab2(sch_1):clk_100m_m2_dp"
				( electricalCSetRef "@crescent_city_bb_fab1_lib.crescent_city_bb_fab1(sch_1):\CLK_100M_OTHERS\" )
				( objectStatus "CLK_100M_M2_DP" )
			)
			( signal "@baseboard_fab2_lib.baseboard_fab2(sch_1):clk_100m_m2_dn"
				( electricalCSetRef "@crescent_city_bb_fab1_lib.crescent_city_bb_fab1(sch_1):\CLK_100M_OTHERS\" )
				( objectStatus "CLK_100M_M2_DN" )
			)
			( signal "@baseboard_fab2_lib.baseboard_fab2(sch_1):clk_100m_pch_slotx24_s0_dp"
				( electricalCSetRef "@crescent_city_bb_fab1_lib.crescent_city_bb_fab1(sch_1):\CLK_100M_PCH_SLOT\" )
				( pinPairRef "@baseboard_fab2_lib.baseboard_fab2(sch_1):\PP5377\" )
				( objectStatus "CLK_100M_PCH_SLOTX24_S0_DP" )
			)
			( signal "@baseboard_fab2_lib.baseboard_fab2(sch_1):clk_100m_pch_slotx24_s0_dn"
				( electricalCSetRef "@crescent_city_bb_fab1_lib.crescent_city_bb_fab1(sch_1):\CLK_100M_PCH_SLOT\" )
				( pinPairRef "@baseboard_fab2_lib.baseboard_fab2(sch_1):\PP5378\" )
				( objectStatus "CLK_100M_PCH_SLOTX24_S0_DN" )
			)
			( signal "@baseboard_fab2_lib.baseboard_fab2(sch_1):clk_100m_pch_slotx24_s1_dp"
				( electricalCSetRef "@crescent_city_bb_fab1_lib.crescent_city_bb_fab1(sch_1):\CLK_100M_PCH_SLOT\" )
				( pinPairRef "@baseboard_fab2_lib.baseboard_fab2(sch_1):\PP5395\" )
				( objectStatus "CLK_100M_PCH_SLOTX24_S1_DP" )
			)
			( signal "@baseboard_fab2_lib.baseboard_fab2(sch_1):clk_100m_pch_slotx24_s1_dn"
				( electricalCSetRef "@crescent_city_bb_fab1_lib.crescent_city_bb_fab1(sch_1):\CLK_100M_PCH_SLOT\" )
				( pinPairRef "@baseboard_fab2_lib.baseboard_fab2(sch_1):\PP5396\" )
				( objectStatus "CLK_100M_PCH_SLOTX24_S1_DN" )
			)
			( signal "@baseboard_fab2_lib.baseboard_fab2(sch_1):clk_100m_pch_slotx24_s2_dp"
				( electricalCSetRef "@crescent_city_bb_fab1_lib.crescent_city_bb_fab1(sch_1):\CLK_100M_PCH_SLOT\" )
				( pinPairRef "@baseboard_fab2_lib.baseboard_fab2(sch_1):\PP5393\" )
				( objectStatus "CLK_100M_PCH_SLOTX24_S2_DP" )
			)
			( signal "@baseboard_fab2_lib.baseboard_fab2(sch_1):clk_100m_pch_slotx24_s2_dn"
				( electricalCSetRef "@crescent_city_bb_fab1_lib.crescent_city_bb_fab1(sch_1):\CLK_100M_PCH_SLOT\" )
				( pinPairRef "@baseboard_fab2_lib.baseboard_fab2(sch_1):\PP5394\" )
				( objectStatus "CLK_100M_PCH_SLOTX24_S2_DN" )
			)
			( signal "@baseboard_fab2_lib.baseboard_fab2(sch_1):clk_100m_pch_slotx24_s3_dp"
				( electricalCSetRef "@crescent_city_bb_fab1_lib.crescent_city_bb_fab1(sch_1):\CLK_100M_PCH_SLOT\" )
				( pinPairRef "@baseboard_fab2_lib.baseboard_fab2(sch_1):\PP5391\" )
				( objectStatus "CLK_100M_PCH_SLOTX24_S3_DP" )
			)
			( signal "@baseboard_fab2_lib.baseboard_fab2(sch_1):clk_100m_pch_slotx24_s3_dn"
				( electricalCSetRef "@crescent_city_bb_fab1_lib.crescent_city_bb_fab1(sch_1):\CLK_100M_PCH_SLOT\" )
				( pinPairRef "@baseboard_fab2_lib.baseboard_fab2(sch_1):\PP5392\" )
				( objectStatus "CLK_100M_PCH_SLOTX24_S3_DN" )
			)
			( signal "@baseboard_fab2_lib.baseboard_fab2(sch_1):clk_100m_pch_slotx24_s4_dp"
				( electricalCSetRef "@crescent_city_bb_fab1_lib.crescent_city_bb_fab1(sch_1):\CLK_100M_PCH_SLOT\" )
				( pinPairRef "@baseboard_fab2_lib.baseboard_fab2(sch_1):\PP5375\" )
				( objectStatus "CLK_100M_PCH_SLOTX24_S4_DP" )
			)
			( signal "@baseboard_fab2_lib.baseboard_fab2(sch_1):clk_100m_pch_slotx24_s4_dn"
				( electricalCSetRef "@crescent_city_bb_fab1_lib.crescent_city_bb_fab1(sch_1):\CLK_100M_PCH_SLOT\" )
				( pinPairRef "@baseboard_fab2_lib.baseboard_fab2(sch_1):\PP5376\" )
				( objectStatus "CLK_100M_PCH_SLOTX24_S4_DN" )
			)
			( signal "@baseboard_fab2_lib.baseboard_fab2(sch_1):clk_100m_pch_slotx24_s5_dp"
				( electricalCSetRef "@crescent_city_bb_fab1_lib.crescent_city_bb_fab1(sch_1):\CLK_100M_PCH_SLOT\" )
				( pinPairRef "@baseboard_fab2_lib.baseboard_fab2(sch_1):\PP5373\" )
				( objectStatus "CLK_100M_PCH_SLOTX24_S5_DP" )
			)
			( signal "@baseboard_fab2_lib.baseboard_fab2(sch_1):clk_100m_pch_slotx24_s5_dn"
				( electricalCSetRef "@crescent_city_bb_fab1_lib.crescent_city_bb_fab1(sch_1):\CLK_100M_PCH_SLOT\" )
				( pinPairRef "@baseboard_fab2_lib.baseboard_fab2(sch_1):\PP5374\" )
				( objectStatus "CLK_100M_PCH_SLOTX24_S5_DN" )
			)
			( signal "@baseboard_fab2_lib.baseboard_fab2(sch_1):clk_100m_pch_xdp_dn"
				( electricalCSetRef "@crescent_city_bb_fab1_lib.crescent_city_bb_fab1(sch_1):\CLK_100M_OTHERS\" )
				( objectStatus "CLK_100M_PCH_XDP_DN" )
			)
			( signal "@baseboard_fab2_lib.baseboard_fab2(sch_1):clk_100m_pch_xdp_dp"
				( electricalCSetRef "@crescent_city_bb_fab1_lib.crescent_city_bb_fab1(sch_1):\CLK_100M_OTHERS\" )
				( objectStatus "CLK_100M_PCH_XDP_DP" )
			)
			( signal "@baseboard_fab2_lib.baseboard_fab2(sch_1):clk_100m_sprv_dp"
				( electricalCSetRef "@crescent_city_bb_fab1_lib.crescent_city_bb_fab1(sch_1):\CLK_100M_OTHERS\" )
				( objectStatus "CLK_100M_SPRV_DP" )
			)
			( signal "@baseboard_fab2_lib.baseboard_fab2(sch_1):clk_100m_sprv_dn"
				( electricalCSetRef "@crescent_city_bb_fab1_lib.crescent_city_bb_fab1(sch_1):\CLK_100M_OTHERS\" )
				( objectStatus "CLK_100M_SPRV_DN" )
			)
			( signal "@baseboard_fab2_lib.baseboard_fab2(sch_1):clk_322m_osc_cpu0_rc_dn"
				( objectStatus "CLK_322M_OSC_CPU0_RC_DN" )
			)
			( signal "@baseboard_fab2_lib.baseboard_fab2(sch_1):clk_322m_osc_cpu0_rc_dp"
				( objectStatus "CLK_322M_OSC_CPU0_RC_DP" )
			)
			( signal "@baseboard_fab2_lib.baseboard_fab2(sch_1):clk_322m_osc_cpu1_rc_dn"
				( objectStatus "CLK_322M_OSC_CPU1_RC_DN" )
			)
			( signal "@baseboard_fab2_lib.baseboard_fab2(sch_1):clk_322m_osc_cpu1_rc_dp"
				( objectStatus "CLK_322M_OSC_CPU1_RC_DP" )
			)
			( signal "@baseboard_fab2_lib.baseboard_fab2(sch_1):clk_156m_osc_brd_cpu0_dp"
				( objectStatus "CLK_156M_OSC_BRD_CPU0_DP" )
			)
			( signal "@baseboard_fab2_lib.baseboard_fab2(sch_1):clk_156m_osc_brd_cpu0_dn"
				( objectStatus "CLK_156M_OSC_BRD_CPU0_DN" )
			)
			( signal "@baseboard_fab2_lib.baseboard_fab2(sch_1):clk_156m_osc_brd_cpu1_dp"
				( objectStatus "CLK_156M_OSC_BRD_CPU1_DP" )
			)
			( signal "@baseboard_fab2_lib.baseboard_fab2(sch_1):clk_156m_osc_brd_cpu1_dn"
				( objectStatus "CLK_156M_OSC_BRD_CPU1_DN" )
			)
			( signal "@baseboard_fab2_lib.baseboard_fab2(sch_1):clk_156m_osc_cpu0_hfi_dp"
				( objectStatus "CLK_156M_OSC_CPU0_HFI_DP" )
			)
			( signal "@baseboard_fab2_lib.baseboard_fab2(sch_1):clk_156m_osc_cpu0_hfi_dn"
				( objectStatus "CLK_156M_OSC_CPU0_HFI_DN" )
			)
			( signal "@baseboard_fab2_lib.baseboard_fab2(sch_1):clk_156m_osc_cpu1_hfi_dp"
				( objectStatus "CLK_156M_OSC_CPU1_HFI_DP" )
			)
			( signal "@baseboard_fab2_lib.baseboard_fab2(sch_1):clk_156m_osc_cpu1_hfi_dn"
				( objectStatus "CLK_156M_OSC_CPU1_HFI_DN" )
			)
			( signal "@baseboard_fab2_lib.baseboard_fab2(sch_1):clk_322m_156m_cpu0_osc_vrm_dp"
				( objectStatus "CLK_322M_156M_CPU0_OSC_VRM_DP" )
			)
			( signal "@baseboard_fab2_lib.baseboard_fab2(sch_1):clk_322m_156m_cpu0_osc_vrm_dn"
				( objectStatus "CLK_322M_156M_CPU0_OSC_VRM_DN" )
			)
			( signal "@baseboard_fab2_lib.baseboard_fab2(sch_1):clk_322m_156m_cpu1_osc_vrm_dp"
				( objectStatus "CLK_322M_156M_CPU1_OSC_VRM_DP" )
			)
			( signal "@baseboard_fab2_lib.baseboard_fab2(sch_1):clk_322m_156m_cpu1_osc_vrm_dn"
				( objectStatus "CLK_322M_156M_CPU1_OSC_VRM_DN" )
			)
			( signal "@baseboard_fab2_lib.baseboard_fab2(sch_1):vr_comp_pvpp_ghj"
				( objectStatus "VR_COMP_PVPP_GHJ" )
			)
			( signal "@baseboard_fab2_lib.baseboard_fab2(sch_1):vr_comp_pvpp_ghj_3"
				( objectStatus "VR_COMP_PVPP_GHJ_3" )
			)
			( signal "@baseboard_fab2_lib.baseboard_fab2(sch_1):vr_comp_pvpp_klm"
				( objectStatus "VR_COMP_PVPP_KLM" )
			)
			( signal "@baseboard_fab2_lib.baseboard_fab2(sch_1):vr_comp_pvpp_klm_3"
				( objectStatus "VR_COMP_PVPP_KLM_3" )
			)
			( signal "@baseboard_fab2_lib.baseboard_fab2(sch_1):vr_comp_rc_pvpp_ghj"
				( objectStatus "VR_COMP_RC_PVPP_GHJ" )
			)
			( signal "@baseboard_fab2_lib.baseboard_fab2(sch_1):vr_comp_rc_pvpp_klm"
				( objectStatus "VR_COMP_RC_PVPP_KLM" )
			)
			( signal "@baseboard_fab2_lib.baseboard_fab2(sch_1):vr_fb_pvpp_ghj"
				( objectStatus "VR_FB_PVPP_GHJ" )
			)
			( signal "@baseboard_fab2_lib.baseboard_fab2(sch_1):vr_fb_pvpp_klm"
				( objectStatus "VR_FB_PVPP_KLM" )
			)
			( signal "@baseboard_fab2_lib.baseboard_fab2(sch_1):vr_p1v8_pch_stby_fb"
				( objectStatus "VR_P1V8_PCH_STBY_FB" )
			)
			( signal "@baseboard_fab2_lib.baseboard_fab2(sch_1):vr_p1v26_bmc_stby_fb"
				( objectStatus "VR_P1V26_BMC_STBY_FB" )
			)
			( signal "@baseboard_fab2_lib.baseboard_fab2(sch_1):vr_p1v538_bmc_stby_fb"
				( objectStatus "VR_P1V538_BMC_STBY_FB" )
			)
			( signal "@baseboard_fab2_lib.baseboard_fab2(sch_1):vr_comp_pvpp_abc"
				( objectStatus "VR_COMP_PVPP_ABC" )
			)
			( signal "@baseboard_fab2_lib.baseboard_fab2(sch_1):vr_comp_pvpp_abc_3"
				( objectStatus "VR_COMP_PVPP_ABC_3" )
			)
			( signal "@baseboard_fab2_lib.baseboard_fab2(sch_1):vr_comp_pvpp_def"
				( objectStatus "VR_COMP_PVPP_DEF" )
			)
			( signal "@baseboard_fab2_lib.baseboard_fab2(sch_1):vr_comp_pvpp_def_3"
				( objectStatus "VR_COMP_PVPP_DEF_3" )
			)
			( signal "@baseboard_fab2_lib.baseboard_fab2(sch_1):vr_comp_rc_pvpp_abc"
				( objectStatus "VR_COMP_RC_PVPP_ABC" )
			)
			( signal "@baseboard_fab2_lib.baseboard_fab2(sch_1):vr_comp_rc_pvpp_def"
				( objectStatus "VR_COMP_RC_PVPP_DEF" )
			)
			( signal "@baseboard_fab2_lib.baseboard_fab2(sch_1):vr_fb_pvpp_abc"
				( objectStatus "VR_FB_PVPP_ABC" )
			)
			( signal "@baseboard_fab2_lib.baseboard_fab2(sch_1):vr_fb_pvpp_def"
				( objectStatus "VR_FB_PVPP_DEF" )
			)
			( signal "@baseboard_fab2_lib.baseboard_fab2(sch_1):vsense_pvccin_cpu0_avsp"
				( objectStatus "VSENSE_PVCCIN_CPU0_AVSP" )
			)
			( signal "@baseboard_fab2_lib.baseboard_fab2(sch_1):vsense_pvccin_cpu1_avsp"
				( objectStatus "VSENSE_PVCCIN_CPU1_AVSP" )
			)
			( signal "@baseboard_fab2_lib.baseboard_fab2(sch_1):vsense_pvccio_cpu1_avsn"
				( objectStatus "VSENSE_PVCCIO_CPU1_AVSN" )
			)
			( signal "@baseboard_fab2_lib.baseboard_fab2(sch_1):vsense_pvccio_cpu1_avsp"
				( objectStatus "VSENSE_PVCCIO_CPU1_AVSP" )
			)
			( signal "@baseboard_fab2_lib.baseboard_fab2(sch_1):vsense_pvsa_cpu0_bvsp"
				( objectStatus "VSENSE_PVSA_CPU0_BVSP" )
			)
			( signal "@baseboard_fab2_lib.baseboard_fab2(sch_1):rmii_sprngvlle_bmc_pch_rxd1_r1"
				( objectStatus "RMII_SPRNGVLLE_BMC_PCH_RXD1_R1" )
			)
			( signal "@baseboard_fab2_lib.baseboard_fab2(sch_1):rmii_sprngvlle_bmc_pch_rxd0_r1"
				( objectStatus "RMII_SPRNGVLLE_BMC_PCH_RXD0_R1" )
			)
			( signal "@baseboard_fab2_lib.baseboard_fab2(sch_1):rmii_bmc_ocp_rxd0_r"
				( objectStatus "RMII_BMC_OCP_RXD0_R" )
			)
			( signal "@baseboard_fab2_lib.baseboard_fab2(sch_1):rmii_bmc_ocp_rxd1_r"
				( objectStatus "RMII_BMC_OCP_RXD1_R" )
			)
			( signal "@baseboard_fab2_lib.baseboard_fab2(sch_1):rmii_bmc_ocp_rxer_r"
				( objectStatus "RMII_BMC_OCP_RXER_R" )
			)
			( signal "@baseboard_fab2_lib.baseboard_fab2(sch_1):rmii_bmc_pch_sprngvlle_rxer_r"
				( objectStatus "RMII_BMC_PCH_SPRNGVLLE_RXER_R" )
			)
			( signal "@baseboard_fab2_lib.baseboard_fab2(sch_1):rmii_bmc_ocp_rxd0"
				( objectStatus "RMII_BMC_OCP_RXD0" )
			)
			( signal "@baseboard_fab2_lib.baseboard_fab2(sch_1):rmii_bmc_ocp_rxd1"
				( objectStatus "RMII_BMC_OCP_RXD1" )
			)
			( signal "@baseboard_fab2_lib.baseboard_fab2(sch_1):rmii_sprngvlle_bmc_pch_rxd1"
				( objectStatus "RMII_SPRNGVLLE_BMC_PCH_RXD1" )
			)
			( signal "@baseboard_fab2_lib.baseboard_fab2(sch_1):rmii_sprngvlle_bmc_pch_rxd1_r"
				( objectStatus "RMII_SPRNGVLLE_BMC_PCH_RXD1_R" )
			)
			( signal "@baseboard_fab2_lib.baseboard_fab2(sch_1):rmii_sprngvlle_bmc_pch_rxd0"
				( objectStatus "RMII_SPRNGVLLE_BMC_PCH_RXD0" )
			)
			( signal "@baseboard_fab2_lib.baseboard_fab2(sch_1):rmii_sprngvlle_bmc_pch_rxd0_r"
				( objectStatus "RMII_SPRNGVLLE_BMC_PCH_RXD0_R" )
			)
			( signal "@baseboard_fab2_lib.baseboard_fab2(sch_1):rmii_bmc_ocp_rxer"
				( objectStatus "RMII_BMC_OCP_RXER" )
			)
			( signal "@baseboard_fab2_lib.baseboard_fab2(sch_1):rmii_bmc_pch_sprngvlle_rxer"
				( objectStatus "RMII_BMC_PCH_SPRNGVLLE_RXER" )
			)
			( signal "@baseboard_fab2_lib.baseboard_fab2(sch_1):rmii_bmc_pch_sprngvlle_txd0"
				( objectStatus "RMII_BMC_PCH_SPRNGVLLE_TXD0" )
			)
			( signal "@baseboard_fab2_lib.baseboard_fab2(sch_1):rmii_bmc_pch_sprngvlle_txd0_r"
				( objectStatus "RMII_BMC_PCH_SPRNGVLLE_TXD0_R" )
			)
			( signal "@baseboard_fab2_lib.baseboard_fab2(sch_1):rmii_bmc_pch_sprngvlle_txd1"
				( objectStatus "RMII_BMC_PCH_SPRNGVLLE_TXD1" )
			)
			( signal "@baseboard_fab2_lib.baseboard_fab2(sch_1):rmii_bmc_pch_sprngvlle_txd1_r"
				( objectStatus "RMII_BMC_PCH_SPRNGVLLE_TXD1_R" )
			)
			( signal "@baseboard_fab2_lib.baseboard_fab2(sch_1):rmii_bmc_pch_sprngvlle_txen"
				( objectStatus "RMII_BMC_PCH_SPRNGVLLE_TXEN" )
			)
			( signal "@baseboard_fab2_lib.baseboard_fab2(sch_1):rmii_bmc_sprngvlle_txen_r"
				( pinPairRef "@baseboard_fab2_lib.baseboard_fab2(sch_1):\PP39\" )
				( objectStatus "RMII_BMC_SPRNGVLLE_TXEN_R" )
			)
			( signal "@baseboard_fab2_lib.baseboard_fab2(sch_1):rmii_bmc_ocp_txen"
				( objectStatus "RMII_BMC_OCP_TXEN" )
			)
			( signal "@baseboard_fab2_lib.baseboard_fab2(sch_1):rmii_bmc_ocp_txen_r"
				( objectStatus "RMII_BMC_OCP_TXEN_R" )
			)
			( signal "@baseboard_fab2_lib.baseboard_fab2(sch_1):rmii_bmc_ocp_txd0"
				( objectStatus "RMII_BMC_OCP_TXD0" )
			)
			( signal "@baseboard_fab2_lib.baseboard_fab2(sch_1):rmii_bmc_ocp_txd0_r"
				( objectStatus "RMII_BMC_OCP_TXD0_R" )
			)
			( signal "@baseboard_fab2_lib.baseboard_fab2(sch_1):rmii_bmc_ocp_txd1"
				( objectStatus "RMII_BMC_OCP_TXD1" )
			)
			( signal "@baseboard_fab2_lib.baseboard_fab2(sch_1):rmii_bmc_ocp_txd1_r"
				( objectStatus "RMII_BMC_OCP_TXD1_R" )
			)
			( signal "@baseboard_fab2_lib.baseboard_fab2(sch_1):m_a_cpu_vref"
				( objectStatus "M_A_CPU_VREF" )
			)
			( signal "@baseboard_fab2_lib.baseboard_fab2(sch_1):m_b_cpu_vref"
				( objectStatus "M_B_CPU_VREF" )
			)
			( signal "@baseboard_fab2_lib.baseboard_fab2(sch_1):m_c_cpu_vref"
				( objectStatus "M_C_CPU_VREF" )
			)
			( signal "@baseboard_fab2_lib.baseboard_fab2(sch_1):m_d_cpu_vref"
				( objectStatus "M_D_CPU_VREF" )
			)
			( signal "@baseboard_fab2_lib.baseboard_fab2(sch_1):m_e_cpu_vref"
				( attribute "NO_TEST" "1"
					( Origin gBackEnd )
				)
				( objectStatus "M_E_CPU_VREF" )
			)
			( signal "@baseboard_fab2_lib.baseboard_fab2(sch_1):m_f_cpu_vref"
				( attribute "NO_TEST" "1"
					( Origin gBackEnd )
				)
				( objectStatus "M_F_CPU_VREF" )
			)
			( signal "@baseboard_fab2_lib.baseboard_fab2(sch_1):m_g_cpu_vref"
				( objectStatus "M_G_CPU_VREF" )
			)
			( signal "@baseboard_fab2_lib.baseboard_fab2(sch_1):m_h_cpu_vref"
				( attribute "NO_TEST" "1"
					( Origin gBackEnd )
				)
				( objectStatus "M_H_CPU_VREF" )
			)
			( signal "@baseboard_fab2_lib.baseboard_fab2(sch_1):m_j_cpu_vref"
				( attribute "NO_TEST" "1"
					( Origin gBackEnd )
				)
				( objectStatus "M_J_CPU_VREF" )
			)
			( signal "@baseboard_fab2_lib.baseboard_fab2(sch_1):m_k_cpu_vref"
				( objectStatus "M_K_CPU_VREF" )
			)
			( signal "@baseboard_fab2_lib.baseboard_fab2(sch_1):m_l_cpu_vref"
				( objectStatus "M_L_CPU_VREF" )
			)
			( signal "@baseboard_fab2_lib.baseboard_fab2(sch_1):m_m_cpu_vref"
				( objectStatus "M_M_CPU_VREF" )
			)
			( signal "@baseboard_fab2_lib.baseboard_fab2(sch_1):m_bmc_ddr3_mvref"
				( spacingCSetRef "@sapphirecity_baseboard_lib.sapphirecity_baseboard(sch_1):\20_MILS\" )
				( objectStatus "M_BMC_DDR3_MVREF" )
			)
			( signal "@baseboard_fab2_lib.baseboard_fab2(sch_1):m_b_vref"
				( attribute "NO_TEST" "1"
					( Origin gBackEnd )
				)
				( objectStatus "M_B_VREF" )
			)
			( signal "@baseboard_fab2_lib.baseboard_fab2(sch_1):m_c_vref"
				( attribute "NO_TEST" "1"
					( Origin gBackEnd )
				)
				( objectStatus "M_C_VREF" )
			)
			( signal "@baseboard_fab2_lib.baseboard_fab2(sch_1):m_d_vref"
				( attribute "NO_TEST" "1"
					( Origin gBackEnd )
				)
				( objectStatus "M_D_VREF" )
			)
			( signal "@baseboard_fab2_lib.baseboard_fab2(sch_1):m_e_vref"
				( attribute "NO_TEST" "1"
					( Origin gBackEnd )
				)
				( objectStatus "M_E_VREF" )
			)
			( signal "@baseboard_fab2_lib.baseboard_fab2(sch_1):m_f_vref"
				( attribute "NO_TEST" "1"
					( Origin gBackEnd )
				)
				( objectStatus "M_F_VREF" )
			)
			( signal "@baseboard_fab2_lib.baseboard_fab2(sch_1):m_g_vref"
				( attribute "NO_TEST" "1"
					( Origin gBackEnd )
				)
				( objectStatus "M_G_VREF" )
			)
			( signal "@baseboard_fab2_lib.baseboard_fab2(sch_1):m_h_vref"
				( attribute "NO_TEST" "1"
					( Origin gBackEnd )
				)
				( objectStatus "M_H_VREF" )
			)
			( signal "@baseboard_fab2_lib.baseboard_fab2(sch_1):m_j_vref"
				( attribute "NO_TEST" "1"
					( Origin gBackEnd )
				)
				( objectStatus "M_J_VREF" )
			)
			( signal "@baseboard_fab2_lib.baseboard_fab2(sch_1):m_k_vref"
				( attribute "NO_TEST" "1"
					( Origin gBackEnd )
				)
				( objectStatus "M_K_VREF" )
			)
			( signal "@baseboard_fab2_lib.baseboard_fab2(sch_1):m_l_vref"
				( attribute "NO_TEST" "1"
					( Origin gBackEnd )
				)
				( objectStatus "M_L_VREF" )
			)
			( signal "@baseboard_fab2_lib.baseboard_fab2(sch_1):m_m_vref"
				( attribute "NO_TEST" "1"
					( Origin gBackEnd )
				)
				( objectStatus "M_M_VREF" )
			)
			( signal "@baseboard_fab2_lib.baseboard_fab2(sch_1):m_a_vref"
				( objectStatus "M_A_VREF" )
			)
			( signal "@baseboard_fab2_lib.baseboard_fab2(sch_1):vr_pvcciomcp_cpu0_xaddr1"
				( objectStatus "VR_PVCCIOMCP_CPU0_XADDR1" )
			)
			( signal "@baseboard_fab2_lib.baseboard_fab2(sch_1):vr_pvcciomcp_cpu1_xaddr1"
				( objectStatus "VR_PVCCIOMCP_CPU1_XADDR1" )
			)
			( signal "@baseboard_fab2_lib.baseboard_fab2(sch_1):vr_pvccmcp_cpu0_xaddr2"
				( objectStatus "VR_PVCCMCP_CPU0_XADDR2" )
			)
			( signal "@baseboard_fab2_lib.baseboard_fab2(sch_1):vr_pvccmcp_cpu1_xaddr2"
				( objectStatus "VR_PVCCMCP_CPU1_XADDR2" )
			)
			( signal "@baseboard_fab2_lib.baseboard_fab2(sch_1):vr_pvccin_cpu0_xaddr1"
				( attribute "VOLTAGE" "3.3"
					( Units "uVoltage" "V" 1.000000)
					( Origin gFrontEnd )
				)
				( objectStatus "VR_PVCCIN_CPU0_XADDR1" )
			)
			( signal "@baseboard_fab2_lib.baseboard_fab2(sch_1):vr_pvccin_cpu0_xaddr2"
				( attribute "VOLTAGE" "3.3"
					( Units "uVoltage" "V" 1.000000)
					( Origin gFrontEnd )
				)
				( objectStatus "VR_PVCCIN_CPU0_XADDR2" )
			)
			( signal "@baseboard_fab2_lib.baseboard_fab2(sch_1):vr_pvccin_cpu1_xaddr1"
				( attribute "VOLTAGE" "3.3"
					( Units "uVoltage" "V" 1.000000)
					( Origin gFrontEnd )
				)
				( objectStatus "VR_PVCCIN_CPU1_XADDR1" )
			)
			( signal "@baseboard_fab2_lib.baseboard_fab2(sch_1):vr_pvccin_cpu1_xaddr2"
				( attribute "VOLTAGE" "3.3"
					( Units "uVoltage" "V" 1.000000)
					( Origin gFrontEnd )
				)
				( objectStatus "VR_PVCCIN_CPU1_XADDR2" )
			)
			( signal "@baseboard_fab2_lib.baseboard_fab2(sch_1):vr_pvnn_pch_avsp"
				( objectStatus "VR_PVNN_PCH_AVSP" )
			)
			( signal "@baseboard_fab2_lib.baseboard_fab2(sch_1):vr_pvnn_pch_ph1_vcin"
				( objectStatus "VR_PVNN_PCH_PH1_VCIN" )
			)
			( signal "@baseboard_fab2_lib.baseboard_fab2(sch_1):vr_pvnn_pch_vdd"
				( objectStatus "VR_PVNN_PCH_VDD" )
			)
			( signal "@baseboard_fab2_lib.baseboard_fab2(sch_1):vr_pvnn_pch_vinsen"
				( objectStatus "VR_PVNN_PCH_VINSEN" )
			)
			( signal "@baseboard_fab2_lib.baseboard_fab2(sch_1):vr_pvnn_pch_xaddr1"
				( objectStatus "VR_PVNN_PCH_XADDR1" )
			)
			( signal "@baseboard_fab2_lib.baseboard_fab2(sch_1):vr_pvnn_pch_xaddr2"
				( objectStatus "VR_PVNN_PCH_XADDR2" )
			)
			( signal "@baseboard_fab2_lib.baseboard_fab2(sch_1):vr_pvnn_p1v05_pch_vd12"
				( objectStatus "VR_PVNN_P1V05_PCH_VD12" )
			)
			( signal "@baseboard_fab2_lib.baseboard_fab2(sch_1):vr_pvpp_abc_iset"
				( objectStatus "VR_PVPP_ABC_ISET" )
			)
			( signal "@baseboard_fab2_lib.baseboard_fab2(sch_1):vr_pvpp_abc_ss"
				( objectStatus "VR_PVPP_ABC_SS" )
			)
			( signal "@baseboard_fab2_lib.baseboard_fab2(sch_1):vr_pvpp_def_iset"
				( objectStatus "VR_PVPP_DEF_ISET" )
			)
			( signal "@baseboard_fab2_lib.baseboard_fab2(sch_1):vr_pvpp_def_ss"
				( objectStatus "VR_PVPP_DEF_SS" )
			)
			( signal "@baseboard_fab2_lib.baseboard_fab2(sch_1):vr_pvpp_ghj_iset"
				( objectStatus "VR_PVPP_GHJ_ISET" )
			)
			( signal "@baseboard_fab2_lib.baseboard_fab2(sch_1):vr_pvpp_ghj_ss"
				( objectStatus "VR_PVPP_GHJ_SS" )
			)
			( signal "@baseboard_fab2_lib.baseboard_fab2(sch_1):vr_pvpp_klm_iset"
				( objectStatus "VR_PVPP_KLM_ISET" )
			)
			( signal "@baseboard_fab2_lib.baseboard_fab2(sch_1):vr_pvpp_klm_ss"
				( objectStatus "VR_PVPP_KLM_SS" )
			)
			( signal "@baseboard_fab2_lib.baseboard_fab2(sch_1):vr_pvsa_cpu0_vcin"
				( attribute "VOLTAGE" "5"
					( Units "uVoltage" "V" 1.000000)
					( Origin gFrontEnd )
				)
				( objectStatus "VR_PVSA_CPU0_VCIN" )
			)
			( signal "@baseboard_fab2_lib.baseboard_fab2(sch_1):vr_pvsa_cpu1_vcin"
				( attribute "VOLTAGE" "5"
					( Units "uVoltage" "V" 1.000000)
					( Origin gFrontEnd )
				)
				( objectStatus "VR_PVSA_CPU1_VCIN" )
			)
			( signal "@baseboard_fab2_lib.baseboard_fab2(sch_1):vr_pvtt_abc_bias"
				( objectStatus "VR_PVTT_ABC_BIAS" )
			)
			( signal "@baseboard_fab2_lib.baseboard_fab2(sch_1):vr_pvtt_abc_sns"
				( objectStatus "VR_PVTT_ABC_SNS" )
			)
			( signal "@baseboard_fab2_lib.baseboard_fab2(sch_1):vr_pvtt_abc_vref"
				( objectStatus "VR_PVTT_ABC_VREF" )
			)
			( signal "@baseboard_fab2_lib.baseboard_fab2(sch_1):vr_pvtt_def_bias"
				( objectStatus "VR_PVTT_DEF_BIAS" )
			)
			( signal "@baseboard_fab2_lib.baseboard_fab2(sch_1):vr_pvtt_def_sns"
				( objectStatus "VR_PVTT_DEF_SNS" )
			)
			( signal "@baseboard_fab2_lib.baseboard_fab2(sch_1):vr_pvtt_def_vref"
				( objectStatus "VR_PVTT_DEF_VREF" )
			)
			( signal "@baseboard_fab2_lib.baseboard_fab2(sch_1):vr_pvtt_ghj_bias"
				( objectStatus "VR_PVTT_GHJ_BIAS" )
			)
			( signal "@baseboard_fab2_lib.baseboard_fab2(sch_1):vr_pvtt_ghj_sns"
				( objectStatus "VR_PVTT_GHJ_SNS" )
			)
			( signal "@baseboard_fab2_lib.baseboard_fab2(sch_1):vr_pvtt_ghj_vref"
				( objectStatus "VR_PVTT_GHJ_VREF" )
			)
			( signal "@baseboard_fab2_lib.baseboard_fab2(sch_1):vr_pvtt_klm_bias"
				( objectStatus "VR_PVTT_KLM_BIAS" )
			)
			( signal "@baseboard_fab2_lib.baseboard_fab2(sch_1):vr_pvtt_klm_sns"
				( objectStatus "VR_PVTT_KLM_SNS" )
			)
			( signal "@baseboard_fab2_lib.baseboard_fab2(sch_1):vr_pvtt_klm_vref"
				( objectStatus "VR_PVTT_KLM_VREF" )
			)
			( signal "@baseboard_fab2_lib.baseboard_fab2(sch_1):vr_p1v05_pch_stby_ph1_vcin"
				( objectStatus "VR_P1V05_PCH_STBY_PH1_VCIN" )
			)
			( signal "@baseboard_fab2_lib.baseboard_fab2(sch_1):vr_p3v3_stby_ocselect"
				( objectStatus "VR_P3V3_STBY_OCSELECT" )
			)
			( signal "@baseboard_fab2_lib.baseboard_fab2(sch_1):vr_p5v_stby_rt"
				( objectStatus "VR_P5V_STBY_RT" )
			)
			( signal "@baseboard_fab2_lib.baseboard_fab2(sch_1):vr_p5v_stby_ss"
				( objectStatus "VR_P5V_STBY_SS" )
			)
			( signal "@baseboard_fab2_lib.baseboard_fab2(sch_1):vr_p5v_stby_vin"
				( objectStatus "VR_P5V_STBY_VIN" )
			)
			( signal "@baseboard_fab2_lib.baseboard_fab2(sch_1):vr_p5v_stby_vsense"
				( objectStatus "VR_P5V_STBY_VSENSE" )
			)
			( signal "@baseboard_fab2_lib.baseboard_fab2(sch_1):vr_p5v_stby_vsense_r"
				( objectStatus "VR_P5V_STBY_VSENSE_R" )
			)
			( signal "@baseboard_fab2_lib.baseboard_fab2(sch_1):vr_vb_pvpp_abc"
				( objectStatus "VR_VB_PVPP_ABC" )
			)
			( signal "@baseboard_fab2_lib.baseboard_fab2(sch_1):vr_vb_pvpp_def"
				( objectStatus "VR_VB_PVPP_DEF" )
			)
			( signal "@baseboard_fab2_lib.baseboard_fab2(sch_1):vr_vb_pvpp_ghj"
				( objectStatus "VR_VB_PVPP_GHJ" )
			)
			( signal "@baseboard_fab2_lib.baseboard_fab2(sch_1):vr_vb_pvpp_klm"
				( objectStatus "VR_VB_PVPP_KLM" )
			)
			( signal "@baseboard_fab2_lib.baseboard_fab2(sch_1):vr_pvccio_cpu0_ph1_sw"
				( attribute "VOLTAGE" "5"
					( Units "uVoltage" "V" 1.000000)
					( Origin gFrontEnd )
				)
				( objectStatus "VR_PVCCIO_CPU0_PH1_SW" )
			)
			( signal "@baseboard_fab2_lib.baseboard_fab2(sch_1):vr_pvccio_cpu1_ph1_sw"
				( objectStatus "VR_PVCCIO_CPU1_PH1_SW" )
			)
			( signal "@baseboard_fab2_lib.baseboard_fab2(sch_1):vr_pvddq_abc_ph1_sw"
				( objectStatus "VR_PVDDQ_ABC_PH1_SW" )
			)
			( signal "@baseboard_fab2_lib.baseboard_fab2(sch_1):vr_pvddq_abc_ph2_sw"
				( objectStatus "VR_PVDDQ_ABC_PH2_SW" )
			)
			( signal "@baseboard_fab2_lib.baseboard_fab2(sch_1):vr_pvddq_def_ph1_sw"
				( objectStatus "VR_PVDDQ_DEF_PH1_SW" )
			)
			( signal "@baseboard_fab2_lib.baseboard_fab2(sch_1):vr_pvddq_def_ph2_sw"
				( objectStatus "VR_PVDDQ_DEF_PH2_SW" )
			)
			( signal "@baseboard_fab2_lib.baseboard_fab2(sch_1):vr_pvddq_ghj_ph1_sw"
				( objectStatus "VR_PVDDQ_GHJ_PH1_SW" )
			)
			( signal "@baseboard_fab2_lib.baseboard_fab2(sch_1):vr_pvddq_ghj_ph2_sw"
				( objectStatus "VR_PVDDQ_GHJ_PH2_SW" )
			)
			( signal "@baseboard_fab2_lib.baseboard_fab2(sch_1):vr_pvddq_klm_ph1_sw"
				( objectStatus "VR_PVDDQ_KLM_PH1_SW" )
			)
			( signal "@baseboard_fab2_lib.baseboard_fab2(sch_1):vr_pvddq_klm_ph2_sw"
				( objectStatus "VR_PVDDQ_KLM_PH2_SW" )
			)
			( signal "@baseboard_fab2_lib.baseboard_fab2(sch_1):vr_pvccin_cpu1_vren"
				( attribute "VOLTAGE" "3.3"
					( Units "uVoltage" "V" 1.000000)
					( Origin gFrontEnd )
				)
				( objectStatus "VR_PVCCIN_CPU1_VREN" )
			)
			( signal "@baseboard_fab2_lib.baseboard_fab2(sch_1):vr_pvccio_cpu0_ph1_vcin"
				( attribute "VOLTAGE" "5"
					( Units "uVoltage" "V" 1.000000)
					( Origin gFrontEnd )
				)
				( objectStatus "VR_PVCCIO_CPU0_PH1_VCIN" )
			)
			( signal "@baseboard_fab2_lib.baseboard_fab2(sch_1):vr_pvccio_cpu0_vdd"
				( objectStatus "VR_PVCCIO_CPU0_VDD" )
			)
			( signal "@baseboard_fab2_lib.baseboard_fab2(sch_1):vr_pvccio_cpu0_vd12"
				( objectStatus "VR_PVCCIO_CPU0_VD12" )
			)
			( signal "@baseboard_fab2_lib.baseboard_fab2(sch_1):vr_pvccio_cpu0_vinsen"
				( attribute "VOLTAGE" "0.8"
					( Units "uVoltage" "V" 1.000000)
					( Origin gFrontEnd )
				)
				( objectStatus "VR_PVCCIO_CPU0_VINSEN" )
			)
			( signal "@baseboard_fab2_lib.baseboard_fab2(sch_1):vr_pvccio_cpu0_xaddr1"
				( attribute "VOLTAGE" "3.3"
					( Units "uVoltage" "V" 1.000000)
					( Origin gFrontEnd )
				)
				( objectStatus "VR_PVCCIO_CPU0_XADDR1" )
			)
			( signal "@baseboard_fab2_lib.baseboard_fab2(sch_1):vr_pvccio_cpu0_xaddr2"
				( attribute "VOLTAGE" "3.3V"
					( Units "uVoltage" "V" 1.000000)
					( Origin gFrontEnd )
				)
				( objectStatus "VR_PVCCIO_CPU0_XADDR2" )
			)
			( signal "@baseboard_fab2_lib.baseboard_fab2(sch_1):vr_pvccio_cpu1_avsp"
				( attribute "VOLTAGE" "1.05"
					( Units "uVoltage" "V" 1.000000)
					( Origin gFrontEnd )
				)
				( objectStatus "VR_PVCCIO_CPU1_AVSP" )
			)
			( signal "@baseboard_fab2_lib.baseboard_fab2(sch_1):vr_pvccio_cpu1_en"
				( attribute "VOLTAGE" "3.3"
					( Units "uVoltage" "V" 1.000000)
					( Origin gFrontEnd )
				)
				( objectStatus "VR_PVCCIO_CPU1_EN" )
			)
			( signal "@baseboard_fab2_lib.baseboard_fab2(sch_1):vr_pvccio_cpu1_ph1_vcin"
				( objectStatus "VR_PVCCIO_CPU1_PH1_VCIN" )
			)
			( signal "@baseboard_fab2_lib.baseboard_fab2(sch_1):vr_pvccio_cpu1_vdd"
				( attribute "VOLTAGE" "3.3"
					( Units "uVoltage" "V" 1.000000)
					( Origin gFrontEnd )
				)
				( objectStatus "VR_PVCCIO_CPU1_VDD" )
			)
			( signal "@baseboard_fab2_lib.baseboard_fab2(sch_1):vr_pvccio_cpu1_vd12"
				( objectStatus "VR_PVCCIO_CPU1_VD12" )
			)
			( signal "@baseboard_fab2_lib.baseboard_fab2(sch_1):vr_pvccio_cpu1_vinsen"
				( attribute "VOLTAGE" "1 V"
					( Units "uVoltage" "V" 1.000000)
					( Origin gBackEnd )
				)
				( objectStatus "VR_PVCCIO_CPU1_VINSEN" )
			)
			( signal "@baseboard_fab2_lib.baseboard_fab2(sch_1):vr_pvccio_cpu1_xaddr1"
				( attribute "VOLTAGE" "3.3"
					( Units "uVoltage" "V" 1.000000)
					( Origin gFrontEnd )
				)
				( objectStatus "VR_PVCCIO_CPU1_XADDR1" )
			)
			( signal "@baseboard_fab2_lib.baseboard_fab2(sch_1):vr_pvccio_cpu1_xaddr2"
				( attribute "VOLTAGE" "3.3"
					( Units "uVoltage" "V" 1.000000)
					( Origin gFrontEnd )
				)
				( objectStatus "VR_PVCCIO_CPU1_XADDR2" )
			)
			( signal "@baseboard_fab2_lib.baseboard_fab2(sch_1):m_abc_rst_n"
				( attribute "NO_TEST" "1"
					( Origin gBackEnd )
				)
				( objectStatus "M_ABC_RST_N" )
			)
			( signal "@baseboard_fab2_lib.baseboard_fab2(sch_1):m_def_rst_n"
				( objectStatus "M_DEF_RST_N" )
			)
			( signal "@baseboard_fab2_lib.baseboard_fab2(sch_1):m_ghj_rst_n"
				( objectStatus "M_GHJ_RST_N" )
			)
			( signal "@baseboard_fab2_lib.baseboard_fab2(sch_1):m_klm_rst_n"
				( attribute "NO_TEST" "1"
					( Origin gBackEnd )
				)
				( objectStatus "M_KLM_RST_N" )
			)
			( signal "@baseboard_fab2_lib.baseboard_fab2(sch_1):spi_bmc_clk"
				( pinPairRef "@baseboard_fab2_lib.baseboard_fab2(sch_1):\PP6131\" )
				( objectStatus "SPI_BMC_CLK" )
			)
			( signal "@baseboard_fab2_lib.baseboard_fab2(sch_1):spi_bmc_cs0_n"
				( pinPairRef "@baseboard_fab2_lib.baseboard_fab2(sch_1):\PP6132\" )
				( objectStatus "SPI_BMC_CS0_N" )
			)
			( signal "@baseboard_fab2_lib.baseboard_fab2(sch_1):spi_bmc_di"
				( pinPairRef "@baseboard_fab2_lib.baseboard_fab2(sch_1):\PP6129\" )
				( objectStatus "SPI_BMC_DI" )
			)
			( signal "@baseboard_fab2_lib.baseboard_fab2(sch_1):spi_bmc_do"
				( pinPairRef "@baseboard_fab2_lib.baseboard_fab2(sch_1):\PP6130\" )
				( objectStatus "SPI_BMC_DO" )
			)
			( signal "@baseboard_fab2_lib.baseboard_fab2(sch_1):spi_cs0_secondary_r_n"
				( objectStatus "SPI_CS0_SECONDARY_R_N" )
			)
			( signal "@baseboard_fab2_lib.baseboard_fab2(sch_1):spi_cs0_secondary_n"
				( objectStatus "SPI_CS0_SECONDARY_N" )
			)
			( signal "@baseboard_fab2_lib.baseboard_fab2(sch_1):spi_switch_cs0_n"
				( attribute "CDS_XNET_NAME" "SELECT"
					( Origin gBackEnd )
				)
				( objectStatus "SPI_SWITCH_CS0_N" )
			)
			( signal "@baseboard_fab2_lib.baseboard_fab2(sch_1):spi_cs0_primary_n"
				( objectStatus "SPI_CS0_PRIMARY_N" )
			)
			( signal "@baseboard_fab2_lib.baseboard_fab2(sch_1):spi_cs0_primary_r_n"
				( objectStatus "SPI_CS0_PRIMARY_R_N" )
			)
			( signal "@baseboard_fab2_lib.baseboard_fab2(sch_1):xdp_spi_pch_mosi_boot_halt_n"
				( objectStatus "XDP_SPI_PCH_MOSI_BOOT_HALT_N" )
			)
			( signal "@baseboard_fab2_lib.baseboard_fab2(sch_1):spi_pch_mosi"
				( attribute "CDS_XNET_NAME" "SELECT"
					( Origin gBackEnd )
				)
				( objectStatus "SPI_PCH_MOSI" )
			)
			( signal "@baseboard_fab2_lib.baseboard_fab2(sch_1):spi_pch_mosi_r"
				( objectStatus "SPI_PCH_MOSI_R" )
			)
			( signal "@baseboard_fab2_lib.baseboard_fab2(sch_1):spi_pch_tpm_mosi_r"
				( objectStatus "SPI_PCH_TPM_MOSI_R" )
			)
			( signal "@baseboard_fab2_lib.baseboard_fab2(sch_1):xdp_debug_consent_n"
				( objectStatus "XDP_DEBUG_CONSENT_N" )
			)
			( signal "@baseboard_fab2_lib.baseboard_fab2(sch_1):spi_pch_io2"
				( attribute "CDS_XNET_NAME" "SELECT"
					( Origin gBackEnd )
				)
				( objectStatus "SPI_PCH_IO2" )
			)
			( signal "@baseboard_fab2_lib.baseboard_fab2(sch_1):spi_pch_io2_r1"
				( objectStatus "SPI_PCH_IO2_R1" )
			)
			( signal "@baseboard_fab2_lib.baseboard_fab2(sch_1):spi_switch_mosi_r1"
				( objectStatus "SPI_SWITCH_MOSI_R1" )
			)
			( signal "@baseboard_fab2_lib.baseboard_fab2(sch_1):spi_switch_mosi"
				( objectStatus "SPI_SWITCH_MOSI" )
			)
			( signal "@baseboard_fab2_lib.baseboard_fab2(sch_1):spi_switch_mosi_r0"
				( objectStatus "SPI_SWITCH_MOSI_R0" )
			)
			( signal "@baseboard_fab2_lib.baseboard_fab2(sch_1):spi_pch_tpm_cs_n"
				( objectStatus "SPI_PCH_TPM_CS_N" )
			)
			( signal "@baseboard_fab2_lib.baseboard_fab2(sch_1):spi_pch_tpm_cs_r_n"
				( objectStatus "SPI_PCH_TPM_CS_R_N" )
			)
			( signal "@baseboard_fab2_lib.baseboard_fab2(sch_1):spi_clk_r1"
				( pinPairRef "@baseboard_fab2_lib.baseboard_fab2(sch_1):\PP34\" )
				( objectStatus "SPI_CLK_R1" )
			)
			( signal "@baseboard_fab2_lib.baseboard_fab2(sch_1):spi_switch_clk"
				( pinPairRef "@baseboard_fab2_lib.baseboard_fab2(sch_1):\PP35\" )
				( pinPairRef "@baseboard_fab2_lib.baseboard_fab2(sch_1):\PP36\" )
				( attribute "CDS_XNET_NAME" "SELECT"
					( Origin gBackEnd )
				)
				( objectStatus "SPI_SWITCH_CLK" )
			)
			( signal "@baseboard_fab2_lib.baseboard_fab2(sch_1):spi_clk_r0"
				( pinPairRef "@baseboard_fab2_lib.baseboard_fab2(sch_1):\PP38\" )
				( objectStatus "SPI_CLK_R0" )
			)
			( signal "@baseboard_fab2_lib.baseboard_fab2(sch_1):spi_pch_tpm_miso_r"
				( objectStatus "SPI_PCH_TPM_MISO_R" )
			)
			( signal "@baseboard_fab2_lib.baseboard_fab2(sch_1):spi_pch_miso"
				( objectStatus "SPI_PCH_MISO" )
			)
			( signal "@baseboard_fab2_lib.baseboard_fab2(sch_1):spi_pch_miso_r"
				( objectStatus "SPI_PCH_MISO_R" )
			)
			( signal "@baseboard_fab2_lib.baseboard_fab2(sch_1):spi_pch_clk"
				( pinPairRef "@baseboard_fab2_lib.baseboard_fab2(sch_1):\PP26\" )
				( pinPairRef "@baseboard_fab2_lib.baseboard_fab2(sch_1):\PP29\" )
				( objectStatus "SPI_PCH_CLK" )
			)
			( signal "@baseboard_fab2_lib.baseboard_fab2(sch_1):spi_pch_tpm_clk_r"
				( pinPairRef "@baseboard_fab2_lib.baseboard_fab2(sch_1):\PP30\" )
				( objectStatus "SPI_PCH_TPM_CLK_R" )
			)
			( signal "@baseboard_fab2_lib.baseboard_fab2(sch_1):spi_bmc_bt_di_r"
				( objectStatus "SPI_BMC_BT_DI_R" )
			)
			( signal "@baseboard_fab2_lib.baseboard_fab2(sch_1):spi_bmc_bt_di"
				( objectStatus "SPI_BMC_BT_DI" )
			)
			( signal "@baseboard_fab2_lib.baseboard_fab2(sch_1):spi_bmc_bt_do_r"
				( objectStatus "SPI_BMC_BT_DO_R" )
			)
			( signal "@baseboard_fab2_lib.baseboard_fab2(sch_1):spi_bmc_bt_do"
				( objectStatus "SPI_BMC_BT_DO" )
			)
			( signal "@baseboard_fab2_lib.baseboard_fab2(sch_1):spi_bmc_bt_clk_r"
				( objectStatus "SPI_BMC_BT_CLK_R" )
			)
			( signal "@baseboard_fab2_lib.baseboard_fab2(sch_1):spi_bmc_bt_clk"
				( objectStatus "SPI_BMC_BT_CLK" )
			)
			( signal "@baseboard_fab2_lib.baseboard_fab2(sch_1):spi_bmc_bt_cs_r_n"
				( objectStatus "SPI_BMC_BT_CS_R_N" )
			)
			( signal "@baseboard_fab2_lib.baseboard_fab2(sch_1):spi_bmc_bt_cs_n"
				( objectStatus "SPI_BMC_BT_CS_N" )
			)
			( signal "@baseboard_fab2_lib.baseboard_fab2(sch_1):spi_pch_io3"
				( objectStatus "SPI_PCH_IO3" )
			)
			( signal "@baseboard_fab2_lib.baseboard_fab2(sch_1):spi_pch_io3_r1"
				( objectStatus "SPI_PCH_IO3_R1" )
			)
			( signal "@baseboard_fab2_lib.baseboard_fab2(sch_1):spi_switch_miso"
				( pinPairRef "@baseboard_fab2_lib.baseboard_fab2(sch_1):\PP22\" )
				( pinPairRef "@baseboard_fab2_lib.baseboard_fab2(sch_1):\PP23\" )
				( attribute "CDS_XNET_NAME" "SELECT"
					( Origin gBackEnd )
				)
				( objectStatus "SPI_SWITCH_MISO" )
			)
			( signal "@baseboard_fab2_lib.baseboard_fab2(sch_1):spi_miso_r0"
				( pinPairRef "@baseboard_fab2_lib.baseboard_fab2(sch_1):\PP24\" )
				( objectStatus "SPI_MISO_R0" )
			)
			( signal "@baseboard_fab2_lib.baseboard_fab2(sch_1):spi_miso_r1"
				( pinPairRef "@baseboard_fab2_lib.baseboard_fab2(sch_1):\PP25\" )
				( objectStatus "SPI_MISO_R1" )
			)
			( signal "@baseboard_fab2_lib.baseboard_fab2(sch_1):spi_nic_cs_n"
				( objectStatus "SPI_NIC_CS_N" )
			)
			( signal "@baseboard_fab2_lib.baseboard_fab2(sch_1):spi_nic_cs_r_n"
				( objectStatus "SPI_NIC_CS_R_N" )
			)
			( signal "@baseboard_fab2_lib.baseboard_fab2(sch_1):spi_nic_miso_r"
				( objectStatus "SPI_NIC_MISO_R" )
			)
			( signal "@baseboard_fab2_lib.baseboard_fab2(sch_1):spi_nic_miso"
				( objectStatus "SPI_NIC_MISO" )
			)
			( signal "@baseboard_fab2_lib.baseboard_fab2(sch_1):spi_nic_mosi"
				( objectStatus "SPI_NIC_MOSI" )
			)
			( signal "@baseboard_fab2_lib.baseboard_fab2(sch_1):spi_nic_mosi_r"
				( objectStatus "SPI_NIC_MOSI_R" )
			)
			( signal "@baseboard_fab2_lib.baseboard_fab2(sch_1):spi_nic_sclk"
				( objectStatus "SPI_NIC_SCLK" )
			)
			( signal "@baseboard_fab2_lib.baseboard_fab2(sch_1):spi_nic_sclk_r"
				( objectStatus "SPI_NIC_SCLK_R" )
			)
			( signal "@baseboard_fab2_lib.baseboard_fab2(sch_1):spi_pch_cs0_n"
				( objectStatus "SPI_PCH_CS0_N" )
			)
			( signal "@baseboard_fab2_lib.baseboard_fab2(sch_1):spi_pch_cs0_r_n"
				( objectStatus "SPI_PCH_CS0_R_N" )
			)
			( signal "@baseboard_fab2_lib.baseboard_fab2(sch_1):svid_vdio_pvccio_cpu1"
				( pinPairRef "@baseboard_fab2_lib.baseboard_fab2(sch_1):\PP5575\" )
				( objectStatus "SVID_VDIO_PVCCIO_CPU1" )
			)
			( signal "@baseboard_fab2_lib.baseboard_fab2(sch_1):svid_dio0_cpu1_r"
				( pinPairRef "@baseboard_fab2_lib.baseboard_fab2(sch_1):\PP5577\" )
				( pinPairRef "@baseboard_fab2_lib.baseboard_fab2(sch_1):\PP5578\" )
				( pinPairRef "@baseboard_fab2_lib.baseboard_fab2(sch_1):\PP5579\" )
				( objectStatus "SVID_DIO0_CPU1_R" )
			)
			( signal "@baseboard_fab2_lib.baseboard_fab2(sch_1):svid_dio0_cpu1"
				( pinPairRef "@baseboard_fab2_lib.baseboard_fab2(sch_1):\PP5580\" )
				( objectStatus "SVID_DIO0_CPU1" )
			)
			( signal "@baseboard_fab2_lib.baseboard_fab2(sch_1):svid_vdio_pvccin_cpu1"
				( pinPairRef "@baseboard_fab2_lib.baseboard_fab2(sch_1):\PP5581\" )
				( objectStatus "SVID_VDIO_PVCCIN_CPU1" )
			)
			( signal "@baseboard_fab2_lib.baseboard_fab2(sch_1):svid_vdio_pvccio_cpu0"
				( pinPairRef "@baseboard_fab2_lib.baseboard_fab2(sch_1):\PP5568\" )
				( objectStatus "SVID_VDIO_PVCCIO_CPU0" )
			)
			( signal "@baseboard_fab2_lib.baseboard_fab2(sch_1):svid_dio0_cpu0_r"
				( pinPairRef "@baseboard_fab2_lib.baseboard_fab2(sch_1):\PP5570\" )
				( pinPairRef "@baseboard_fab2_lib.baseboard_fab2(sch_1):\PP5571\" )
				( pinPairRef "@baseboard_fab2_lib.baseboard_fab2(sch_1):\PP5572\" )
				( objectStatus "SVID_DIO0_CPU0_R" )
			)
			( signal "@baseboard_fab2_lib.baseboard_fab2(sch_1):svid_vdio_pvccin_cpu0"
				( pinPairRef "@baseboard_fab2_lib.baseboard_fab2(sch_1):\PP5573\" )
				( objectStatus "SVID_VDIO_PVCCIN_CPU0" )
			)
			( signal "@baseboard_fab2_lib.baseboard_fab2(sch_1):svid_dio0_cpu0"
				( pinPairRef "@baseboard_fab2_lib.baseboard_fab2(sch_1):\PP5574\" )
				( objectStatus "SVID_DIO0_CPU0" )
			)
			( signal "@baseboard_fab2_lib.baseboard_fab2(sch_1):svid_clk_pvddq_klm"
				( pinPairRef "@baseboard_fab2_lib.baseboard_fab2(sch_1):\PP5477\" )
				( objectStatus "SVID_CLK_PVDDQ_KLM" )
			)
			( signal "@baseboard_fab2_lib.baseboard_fab2(sch_1):svid_clk1_cpu1_r"
				( pinPairRef "@baseboard_fab2_lib.baseboard_fab2(sch_1):\PP5479\" )
				( pinPairRef "@baseboard_fab2_lib.baseboard_fab2(sch_1):\PP5480\" )
				( objectStatus "SVID_CLK1_CPU1_R" )
			)
			( signal "@baseboard_fab2_lib.baseboard_fab2(sch_1):svid_clk1_cpu1"
				( pinPairRef "@baseboard_fab2_lib.baseboard_fab2(sch_1):\PP5481\" )
				( objectStatus "SVID_CLK1_CPU1" )
			)
			( signal "@baseboard_fab2_lib.baseboard_fab2(sch_1):svid_clk_pvddq_ghj"
				( pinPairRef "@baseboard_fab2_lib.baseboard_fab2(sch_1):\PP5482\" )
				( objectStatus "SVID_CLK_PVDDQ_GHJ" )
			)
			( signal "@baseboard_fab2_lib.baseboard_fab2(sch_1):svid_clk_pvddq_def"
				( objectStatus "SVID_CLK_PVDDQ_DEF" )
			)
			( signal "@baseboard_fab2_lib.baseboard_fab2(sch_1):svid_clk1_cpu0_r"
				( objectStatus "SVID_CLK1_CPU0_R" )
			)
			( signal "@baseboard_fab2_lib.baseboard_fab2(sch_1):svid_clk1_cpu0"
				( pinPairRef "@baseboard_fab2_lib.baseboard_fab2(sch_1):\PP5475\" )
				( objectStatus "SVID_CLK1_CPU0" )
			)
			( signal "@baseboard_fab2_lib.baseboard_fab2(sch_1):svid_clk_pvddq_abc"
				( pinPairRef "@baseboard_fab2_lib.baseboard_fab2(sch_1):\PP5476\" )
				( objectStatus "SVID_CLK_PVDDQ_ABC" )
			)
			( signal "@baseboard_fab2_lib.baseboard_fab2(sch_1):svid_clk_pvccio_cpu1"
				( pinPairRef "@baseboard_fab2_lib.baseboard_fab2(sch_1):\PP5562\" )
				( objectStatus "SVID_CLK_PVCCIO_CPU1" )
			)
			( signal "@baseboard_fab2_lib.baseboard_fab2(sch_1):svid_clk0_cpu1_r"
				( pinPairRef "@baseboard_fab2_lib.baseboard_fab2(sch_1):\PP5563\" )
				( pinPairRef "@baseboard_fab2_lib.baseboard_fab2(sch_1):\PP5565\" )
				( objectStatus "SVID_CLK0_CPU1_R" )
			)
			( signal "@baseboard_fab2_lib.baseboard_fab2(sch_1):svid_vclk_pvccin_cpu1"
				( pinPairRef "@baseboard_fab2_lib.baseboard_fab2(sch_1):\PP5566\" )
				( objectStatus "SVID_VCLK_PVCCIN_CPU1" )
			)
			( signal "@baseboard_fab2_lib.baseboard_fab2(sch_1):svid_clk0_cpu1"
				( pinPairRef "@baseboard_fab2_lib.baseboard_fab2(sch_1):\PP5567\" )
				( objectStatus "SVID_CLK0_CPU1" )
			)
			( signal "@baseboard_fab2_lib.baseboard_fab2(sch_1):svid_clk_pvccio_cpu0"
				( pinPairRef "@baseboard_fab2_lib.baseboard_fab2(sch_1):\PP5556\" )
				( objectStatus "SVID_CLK_PVCCIO_CPU0" )
			)
			( signal "@baseboard_fab2_lib.baseboard_fab2(sch_1):svid_clk0_cpu0_r"
				( pinPairRef "@baseboard_fab2_lib.baseboard_fab2(sch_1):\PP5558\" )
				( pinPairRef "@baseboard_fab2_lib.baseboard_fab2(sch_1):\PP5559\" )
				( objectStatus "SVID_CLK0_CPU0_R" )
			)
			( signal "@baseboard_fab2_lib.baseboard_fab2(sch_1):svid_vclk_pvccin_cpu0"
				( pinPairRef "@baseboard_fab2_lib.baseboard_fab2(sch_1):\PP5560\" )
				( objectStatus "SVID_VCLK_PVCCIN_CPU0" )
			)
			( signal "@baseboard_fab2_lib.baseboard_fab2(sch_1):svid_clk0_cpu0"
				( pinPairRef "@baseboard_fab2_lib.baseboard_fab2(sch_1):\PP5561\" )
				( objectStatus "SVID_CLK0_CPU0" )
			)
			( signal "@baseboard_fab2_lib.baseboard_fab2(sch_1):svid_alert_pvccio_cpu1"
				( pinPairRef "@baseboard_fab2_lib.baseboard_fab2(sch_1):\PP5550\" )
				( objectStatus "SVID_ALERT_PVCCIO_CPU1" )
			)
			( signal "@baseboard_fab2_lib.baseboard_fab2(sch_1):svid_alert0_cpu1_r_n"
				( pinPairRef "@baseboard_fab2_lib.baseboard_fab2(sch_1):\PP5552\" )
				( pinPairRef "@baseboard_fab2_lib.baseboard_fab2(sch_1):\PP5553\" )
				( objectStatus "SVID_ALERT0_CPU1_R_N" )
			)
			( signal "@baseboard_fab2_lib.baseboard_fab2(sch_1):svid_alert0_cpu1_n"
				( objectStatus "SVID_ALERT0_CPU1_N" )
			)
			( signal "@baseboard_fab2_lib.baseboard_fab2(sch_1):svid_valert_vccin_cpu1"
				( pinPairRef "@baseboard_fab2_lib.baseboard_fab2(sch_1):\PP5555\" )
				( objectStatus "SVID_VALERT_VCCIN_CPU1" )
			)
			( signal "@baseboard_fab2_lib.baseboard_fab2(sch_1):svid_alert_pvccio_cpu0"
				( pinPairRef "@baseboard_fab2_lib.baseboard_fab2(sch_1):\PP5544\" )
				( objectStatus "SVID_ALERT_PVCCIO_CPU0" )
			)
			( signal "@baseboard_fab2_lib.baseboard_fab2(sch_1):svid_alert0_cpu0_r_n"
				( pinPairRef "@baseboard_fab2_lib.baseboard_fab2(sch_1):\PP5546\" )
				( pinPairRef "@baseboard_fab2_lib.baseboard_fab2(sch_1):\PP5547\" )
				( objectStatus "SVID_ALERT0_CPU0_R_N" )
			)
			( signal "@baseboard_fab2_lib.baseboard_fab2(sch_1):svid_valert_vccin_cpu0"
				( pinPairRef "@baseboard_fab2_lib.baseboard_fab2(sch_1):\PP5548\" )
				( objectStatus "SVID_VALERT_VCCIN_CPU0" )
			)
			( signal "@baseboard_fab2_lib.baseboard_fab2(sch_1):svid_alert0_cpu0_n"
				( pinPairRef "@baseboard_fab2_lib.baseboard_fab2(sch_1):\PP5549\" )
				( objectStatus "SVID_ALERT0_CPU0_N" )
			)
			( signal "@baseboard_fab2_lib.baseboard_fab2(sch_1):svid_vdio_pvddq_klm"
				( pinPairRef "@baseboard_fab2_lib.baseboard_fab2(sch_1):\PP5491\" )
				( objectStatus "SVID_VDIO_PVDDQ_KLM" )
			)
			( signal "@baseboard_fab2_lib.baseboard_fab2(sch_1):svid_dio1_cpu1_r"
				( pinPairRef "@baseboard_fab2_lib.baseboard_fab2(sch_1):\PP5493\" )
				( pinPairRef "@baseboard_fab2_lib.baseboard_fab2(sch_1):\PP5494\" )
				( pinPairRef "@baseboard_fab2_lib.baseboard_fab2(sch_1):\PP5495\" )
				( pinPairRef "@baseboard_fab2_lib.baseboard_fab2(sch_1):\PP5496\" )
				( objectStatus "SVID_DIO1_CPU1_R" )
			)
			( signal "@baseboard_fab2_lib.baseboard_fab2(sch_1):svid_vdio_pvddq_ghj"
				( pinPairRef "@baseboard_fab2_lib.baseboard_fab2(sch_1):\PP5497\" )
				( objectStatus "SVID_VDIO_PVDDQ_GHJ" )
			)
			( signal "@baseboard_fab2_lib.baseboard_fab2(sch_1):svid_dio1_cpu1"
				( pinPairRef "@baseboard_fab2_lib.baseboard_fab2(sch_1):\PP5498\" )
				( objectStatus "SVID_DIO1_CPU1" )
			)
			( signal "@baseboard_fab2_lib.baseboard_fab2(sch_1):svid_vdio_pvddq_def"
				( pinPairRef "@baseboard_fab2_lib.baseboard_fab2(sch_1):\PP5483\" )
				( objectStatus "SVID_VDIO_PVDDQ_DEF" )
			)
			( signal "@baseboard_fab2_lib.baseboard_fab2(sch_1):svid_dio1_cpu0_r"
				( pinPairRef "@baseboard_fab2_lib.baseboard_fab2(sch_1):\PP5486\" )
				( pinPairRef "@baseboard_fab2_lib.baseboard_fab2(sch_1):\PP5487\" )
				( pinPairRef "@baseboard_fab2_lib.baseboard_fab2(sch_1):\PP5488\" )
				( objectStatus "SVID_DIO1_CPU0_R" )
			)
			( signal "@baseboard_fab2_lib.baseboard_fab2(sch_1):svid_vdio_pvddq_abc"
				( pinPairRef "@baseboard_fab2_lib.baseboard_fab2(sch_1):\PP5489\" )
				( objectStatus "SVID_VDIO_PVDDQ_ABC" )
			)
			( signal "@baseboard_fab2_lib.baseboard_fab2(sch_1):svid_dio1_cpu0"
				( pinPairRef "@baseboard_fab2_lib.baseboard_fab2(sch_1):\PP5490\" )
				( objectStatus "SVID_DIO1_CPU0" )
			)
			( signal "@baseboard_fab2_lib.baseboard_fab2(sch_1):svid_alert_pvddq_klm"
				( pinPairRef "@baseboard_fab2_lib.baseboard_fab2(sch_1):\PP5465\" )
				( objectStatus "SVID_ALERT_PVDDQ_KLM" )
			)
			( signal "@baseboard_fab2_lib.baseboard_fab2(sch_1):svid_alert1_cpu1_r_n"
				( pinPairRef "@baseboard_fab2_lib.baseboard_fab2(sch_1):\PP5467\" )
				( pinPairRef "@baseboard_fab2_lib.baseboard_fab2(sch_1):\PP5468\" )
				( objectStatus "SVID_ALERT1_CPU1_R_N" )
			)
			( signal "@baseboard_fab2_lib.baseboard_fab2(sch_1):svid_alert_pvddq_ghj"
				( pinPairRef "@baseboard_fab2_lib.baseboard_fab2(sch_1):\PP5469\" )
				( objectStatus "SVID_ALERT_PVDDQ_GHJ" )
			)
			( signal "@baseboard_fab2_lib.baseboard_fab2(sch_1):svid_alert1_cpu1_n"
				( pinPairRef "@baseboard_fab2_lib.baseboard_fab2(sch_1):\PP5470\" )
				( objectStatus "SVID_ALERT1_CPU1_N" )
			)
			( signal "@baseboard_fab2_lib.baseboard_fab2(sch_1):svid_alert_pvddq_def"
				( pinPairRef "@baseboard_fab2_lib.baseboard_fab2(sch_1):\PP5457\" )
				( objectStatus "SVID_ALERT_PVDDQ_DEF" )
			)
			( signal "@baseboard_fab2_lib.baseboard_fab2(sch_1):svid_alert1_cpu0_r_n"
				( pinPairRef "@baseboard_fab2_lib.baseboard_fab2(sch_1):\PP5461\" )
				( pinPairRef "@baseboard_fab2_lib.baseboard_fab2(sch_1):\PP5462\" )
				( objectStatus "SVID_ALERT1_CPU0_R_N" )
			)
			( signal "@baseboard_fab2_lib.baseboard_fab2(sch_1):svid_alert_pvddq_abc"
				( pinPairRef "@baseboard_fab2_lib.baseboard_fab2(sch_1):\PP5463\" )
				( objectStatus "SVID_ALERT_PVDDQ_ABC" )
			)
			( signal "@baseboard_fab2_lib.baseboard_fab2(sch_1):svid_alert1_cpu0_n"
				( pinPairRef "@baseboard_fab2_lib.baseboard_fab2(sch_1):\PP5464\" )
				( objectStatus "SVID_ALERT1_CPU0_N" )
			)
			( signal "@baseboard_fab2_lib.baseboard_fab2(sch_1):sgpio_pch_ssata_clock"
				( objectStatus "SGPIO_PCH_SSATA_CLOCK" )
			)
			( signal "@baseboard_fab2_lib.baseboard_fab2(sch_1):sgpio_pch_ssata_clock_r"
				( objectStatus "SGPIO_PCH_SSATA_CLOCK_R" )
			)
			( signal "@baseboard_fab2_lib.baseboard_fab2(sch_1):sgpio_pch_ssata_dout0"
				( objectStatus "SGPIO_PCH_SSATA_DOUT0" )
			)
			( signal "@baseboard_fab2_lib.baseboard_fab2(sch_1):sgpio_pch_ssata_dout0_r"
				( objectStatus "SGPIO_PCH_SSATA_DOUT0_R" )
			)
			( signal "@baseboard_fab2_lib.baseboard_fab2(sch_1):sgpio_pch_ssata_load"
				( objectStatus "SGPIO_PCH_SSATA_LOAD" )
			)
			( signal "@baseboard_fab2_lib.baseboard_fab2(sch_1):sgpio_pch_ssata_load_r"
				( objectStatus "SGPIO_PCH_SSATA_LOAD_R" )
			)
			( signal "@baseboard_fab2_lib.baseboard_fab2(sch_1):vr_pvpp_klm_boot"
				( objectStatus "VR_PVPP_KLM_BOOT" )
			)
			( signal "@baseboard_fab2_lib.baseboard_fab2(sch_1):vr_pvpp_klm_boot_r"
				( objectStatus "VR_PVPP_KLM_BOOT_R" )
			)
			( signal "@baseboard_fab2_lib.baseboard_fab2(sch_1):vr_pvnn_pch_ph1_boot"
				( objectStatus "VR_PVNN_PCH_PH1_BOOT" )
			)
			( signal "@baseboard_fab2_lib.baseboard_fab2(sch_1):vr_pvnn_pch_ph1_phase"
				( objectStatus "VR_PVNN_PCH_PH1_PHASE" )
			)
			( signal "@baseboard_fab2_lib.baseboard_fab2(sch_1):vr_pvsa_cpu0_boot"
				( attribute "VOLTAGE" "5"
					( Units "uVoltage" "V" 1.000000)
					( Origin gFrontEnd )
				)
				( objectStatus "VR_PVSA_CPU0_BOOT" )
			)
			( signal "@baseboard_fab2_lib.baseboard_fab2(sch_1):vr_pvsa_cpu0_phase"
				( attribute "VOLTAGE" "5"
					( Units "uVoltage" "V" 1.000000)
					( Origin gFrontEnd )
				)
				( objectStatus "VR_PVSA_CPU0_PHASE" )
			)
			( signal "@baseboard_fab2_lib.baseboard_fab2(sch_1):vr_pvsa_cpu1_boot"
				( attribute "VOLTAGE" "5"
					( Units "uVoltage" "V" 1.000000)
					( Origin gFrontEnd )
				)
				( objectStatus "VR_PVSA_CPU1_BOOT" )
			)
			( signal "@baseboard_fab2_lib.baseboard_fab2(sch_1):vr_pvsa_cpu1_phase"
				( attribute "VOLTAGE" "5"
					( Units "uVoltage" "V" 1.000000)
					( Origin gFrontEnd )
				)
				( objectStatus "VR_PVSA_CPU1_PHASE" )
			)
			( signal "@baseboard_fab2_lib.baseboard_fab2(sch_1):vr_p1v05_pch_stby_ph1_boot"
				( objectStatus "VR_P1V05_PCH_STBY_PH1_BOOT" )
			)
			( signal "@baseboard_fab2_lib.baseboard_fab2(sch_1):vr_p1v05_pch_stby_ph1_phase"
				( objectStatus "VR_P1V05_PCH_STBY_PH1_PHASE" )
			)
			( signal "@baseboard_fab2_lib.baseboard_fab2(sch_1):vr_p3v3_stby_boot"
				( objectStatus "VR_P3V3_STBY_BOOT" )
			)
			( signal "@baseboard_fab2_lib.baseboard_fab2(sch_1):vr_p3v3_stby_boot_r"
				( objectStatus "VR_P3V3_STBY_BOOT_R" )
			)
			( signal "@baseboard_fab2_lib.baseboard_fab2(sch_1):vr_p3v3_stby_phase"
				( objectStatus "VR_P3V3_STBY_PHASE" )
			)
			( signal "@baseboard_fab2_lib.baseboard_fab2(sch_1):vr_p3v3_stby_ugate"
				( objectStatus "VR_P3V3_STBY_UGATE" )
			)
			( signal "@baseboard_fab2_lib.baseboard_fab2(sch_1):vr_p5v_stby_boot"
				( objectStatus "VR_P5V_STBY_BOOT" )
			)
			( signal "@baseboard_fab2_lib.baseboard_fab2(sch_1):vr_p5v_stby_phase"
				( objectStatus "VR_P5V_STBY_PHASE" )
			)
			( signal "@baseboard_fab2_lib.baseboard_fab2(sch_1):vr_pvnn_pch_ph1_phase_sw"
				( objectStatus "VR_PVNN_PCH_PH1_PHASE_SW" )
			)
			( signal "@baseboard_fab2_lib.baseboard_fab2(sch_1):vr_pvsa_cpu0_phase_sw"
				( attribute "VOLTAGE" "5"
					( Units "uVoltage" "V" 1.000000)
					( Origin gFrontEnd )
				)
				( objectStatus "VR_PVSA_CPU0_PHASE_SW" )
			)
			( signal "@baseboard_fab2_lib.baseboard_fab2(sch_1):vr_pvsa_cpu1_phase_sw"
				( attribute "VOLTAGE" "5"
					( Units "uVoltage" "V" 1.000000)
					( Origin gFrontEnd )
				)
				( objectStatus "VR_PVSA_CPU1_PHASE_SW" )
			)
			( signal "@baseboard_fab2_lib.baseboard_fab2(sch_1):vr_p1v05_pch_stby_ph1_phase_sw"
				( objectStatus "VR_P1V05_PCH_STBY_PH1_PHASE_SW" )
			)
			( signal "@baseboard_fab2_lib.baseboard_fab2(sch_1):vr_pvccio_cpu0_ph1_boot"
				( attribute "VOLTAGE" "5"
					( Units "uVoltage" "V" 1.000000)
					( Origin gFrontEnd )
				)
				( objectStatus "VR_PVCCIO_CPU0_PH1_BOOT" )
			)
			( signal "@baseboard_fab2_lib.baseboard_fab2(sch_1):vr_pvccio_cpu0_ph1_phase"
				( attribute "VOLTAGE" "5"
					( Units "uVoltage" "V" 1.000000)
					( Origin gFrontEnd )
				)
				( objectStatus "VR_PVCCIO_CPU0_PH1_PHASE" )
			)
			( signal "@baseboard_fab2_lib.baseboard_fab2(sch_1):vr_pvccio_cpu1_ph1_boot"
				( objectStatus "VR_PVCCIO_CPU1_PH1_BOOT" )
			)
			( signal "@baseboard_fab2_lib.baseboard_fab2(sch_1):vr_pvccio_cpu1_ph1_phase"
				( objectStatus "VR_PVCCIO_CPU1_PH1_PHASE" )
			)
			( signal "@baseboard_fab2_lib.baseboard_fab2(sch_1):vr_pvpp_abc_boot"
				( objectStatus "VR_PVPP_ABC_BOOT" )
			)
			( signal "@baseboard_fab2_lib.baseboard_fab2(sch_1):vr_pvpp_abc_boot_r"
				( objectStatus "VR_PVPP_ABC_BOOT_R" )
			)
			( signal "@baseboard_fab2_lib.baseboard_fab2(sch_1):vr_pvpp_abc_phase"
				( objectStatus "VR_PVPP_ABC_PHASE" )
			)
			( signal "@baseboard_fab2_lib.baseboard_fab2(sch_1):vr_pvpp_def_boot"
				( objectStatus "VR_PVPP_DEF_BOOT" )
			)
			( signal "@baseboard_fab2_lib.baseboard_fab2(sch_1):vr_fet_sw_p12v_stby_pvddq_abc"
				( attribute "VOLTAGE" "12 V"
					( Units "uVoltage" "V" 1.000000)
					( Origin gBackEnd )
				)
				( objectStatus "VR_FET_SW_P12V_STBY_PVDDQ_ABC" )
			)
			( signal "@baseboard_fab2_lib.baseboard_fab2(sch_1):vr_fet_sw_p12v_stby_pvddq_def"
				( attribute "RATSNEST_SCHEDULE" "MIN_TREE"
					( Origin gBackEnd )
				)
				( attribute "VOLTAGE" "12 V"
					( Units "uVoltage" "V" 1.000000)
					( Origin gBackEnd )
				)
				( objectStatus "VR_FET_SW_P12V_STBY_PVDDQ_DEF" )
			)
			( signal "@baseboard_fab2_lib.baseboard_fab2(sch_1):vr_fet_sw_p12v_stby_pvddq_ghj"
				( attribute "RATSNEST_SCHEDULE" "MIN_TREE"
					( Origin gBackEnd )
				)
				( attribute "VOLTAGE" "12 V"
					( Units "uVoltage" "V" 1.000000)
					( Origin gBackEnd )
				)
				( objectStatus "VR_FET_SW_P12V_STBY_PVDDQ_GHJ" )
			)
			( signal "@baseboard_fab2_lib.baseboard_fab2(sch_1):vr_fet_sw_p12v_stby_pvddq_klm"
				( attribute "VOLTAGE" "12 V"
					( Units "uVoltage" "V" 1.000000)
					( Origin gBackEnd )
				)
				( objectStatus "VR_FET_SW_P12V_STBY_PVDDQ_KLM" )
			)
			( signal "@baseboard_fab2_lib.baseboard_fab2(sch_1):vr_fet_sw_p12v_pvccin_cpu0_r"
				( attribute "VOLTAGE" "12 V"
					( Units "uVoltage" "V" 1.000000)
					( Origin gBackEnd )
				)
				( objectStatus "VR_FET_SW_P12V_PVCCIN_CPU0_R" )
			)
			( signal "@baseboard_fab2_lib.baseboard_fab2(sch_1):vr_fet_sw_p12v_pvccin_cpu1_r"
				( objectStatus "VR_FET_SW_P12V_PVCCIN_CPU1_R" )
			)
			( signal "@baseboard_fab2_lib.baseboard_fab2(sch_1):vr_fet_sw_p12v_stby_pvccin_cpu0"
				( attribute "VOLTAGE" "12 V"
					( Units "uVoltage" "V" 1.000000)
					( Origin gBackEnd )
				)
				( objectStatus "VR_FET_SW_P12V_STBY_PVCCIN_CPU0" )
			)
			( signal "@baseboard_fab2_lib.baseboard_fab2(sch_1):vr_fet_sw_p12v_stby_pvccin_cpu1"
				( attribute "VOLTAGE" "12"
					( Units "uVoltage" "V" 1.000000)
					( Origin gFrontEnd )
				)
				( objectStatus "VR_FET_SW_P12V_STBY_PVCCIN_CPU1" )
			)
			( signal "@baseboard_fab2_lib.baseboard_fab2(sch_1):vr_fet_sw_p12v_stby_pvpp_abc"
				( objectStatus "VR_FET_SW_P12V_STBY_PVPP_ABC" )
			)
			( signal "@baseboard_fab2_lib.baseboard_fab2(sch_1):vr_fet_sw_p12v_stby_pvpp_def"
				( attribute "VOLTAGE" "12 V"
					( Units "uVoltage" "V" 1.000000)
					( Origin gBackEnd )
				)
				( objectStatus "VR_FET_SW_P12V_STBY_PVPP_DEF" )
			)
			( signal "@baseboard_fab2_lib.baseboard_fab2(sch_1):vr_fet_sw_p12v_stby_pvpp_ghj"
				( attribute "VOLTAGE" "12 V"
					( Units "uVoltage" "V" 1.000000)
					( Origin gBackEnd )
				)
				( objectStatus "VR_FET_SW_P12V_STBY_PVPP_GHJ" )
			)
			( signal "@baseboard_fab2_lib.baseboard_fab2(sch_1):vr_fet_sw_p12v_stby_pvpp_klm"
				( attribute "VOLTAGE" "12 V"
					( Units "uVoltage" "V" 1.000000)
					( Origin gBackEnd )
				)
				( objectStatus "VR_FET_SW_P12V_STBY_PVPP_KLM" )
			)
			( signal "@baseboard_fab2_lib.baseboard_fab2(sch_1):vr_fet_sw_p12v_stby_p3v3_stby"
				( objectStatus "VR_FET_SW_P12V_STBY_P3V3_STBY" )
			)
			( signal "@baseboard_fab2_lib.baseboard_fab2(sch_1):vr_pvccin_cpu0_phase1"
				( attribute "VOLTAGE" "5"
					( Units "uVoltage" "V" 1.000000)
					( Origin gFrontEnd )
				)
				( objectStatus "VR_PVCCIN_CPU0_PHASE1" )
			)
			( signal "@baseboard_fab2_lib.baseboard_fab2(sch_1):vr_pvccin_cpu0_phase2"
				( attribute "VOLTAGE" "5"
					( Units "uVoltage" "V" 1.000000)
					( Origin gFrontEnd )
				)
				( objectStatus "VR_PVCCIN_CPU0_PHASE2" )
			)
			( signal "@baseboard_fab2_lib.baseboard_fab2(sch_1):vr_pvccin_cpu0_phase3"
				( attribute "VOLTAGE" "5"
					( Units "uVoltage" "V" 1.000000)
					( Origin gFrontEnd )
				)
				( objectStatus "VR_PVCCIN_CPU0_PHASE3" )
			)
			( signal "@baseboard_fab2_lib.baseboard_fab2(sch_1):vr_pvccin_cpu0_phase4"
				( attribute "VOLTAGE" "5"
					( Units "uVoltage" "V" 1.000000)
					( Origin gFrontEnd )
				)
				( objectStatus "VR_PVCCIN_CPU0_PHASE4" )
			)
			( signal "@baseboard_fab2_lib.baseboard_fab2(sch_1):vr_pvccin_cpu0_phase5"
				( attribute "VOLTAGE" "5"
					( Units "uVoltage" "V" 1.000000)
					( Origin gFrontEnd )
				)
				( objectStatus "VR_PVCCIN_CPU0_PHASE5" )
			)
			( signal "@baseboard_fab2_lib.baseboard_fab2(sch_1):vr_pvccin_cpu0_ph1_phase"
				( attribute "VOLTAGE" "5"
					( Units "uVoltage" "V" 1.000000)
					( Origin gFrontEnd )
				)
				( objectStatus "VR_PVCCIN_CPU0_PH1_PHASE" )
			)
			( signal "@baseboard_fab2_lib.baseboard_fab2(sch_1):vr_pvccin_cpu0_ph2_phase"
				( attribute "VOLTAGE" "5"
					( Units "uVoltage" "V" 1.000000)
					( Origin gFrontEnd )
				)
				( objectStatus "VR_PVCCIN_CPU0_PH2_PHASE" )
			)
			( signal "@baseboard_fab2_lib.baseboard_fab2(sch_1):vr_pvccin_cpu0_ph3_phase"
				( attribute "VOLTAGE" "5"
					( Units "uVoltage" "V" 1.000000)
					( Origin gFrontEnd )
				)
				( objectStatus "VR_PVCCIN_CPU0_PH3_PHASE" )
			)
			( signal "@baseboard_fab2_lib.baseboard_fab2(sch_1):vr_pvccin_cpu0_ph4_phase"
				( attribute "VOLTAGE" "5"
					( Units "uVoltage" "V" 1.000000)
					( Origin gFrontEnd )
				)
				( objectStatus "VR_PVCCIN_CPU0_PH4_PHASE" )
			)
			( signal "@baseboard_fab2_lib.baseboard_fab2(sch_1):vr_pvccin_cpu0_ph5_phase"
				( attribute "VOLTAGE" "5"
					( Units "uVoltage" "V" 1.000000)
					( Origin gFrontEnd )
				)
				( objectStatus "VR_PVCCIN_CPU0_PH5_PHASE" )
			)
			( signal "@baseboard_fab2_lib.baseboard_fab2(sch_1):vr_pvccin_cpu1_phase1"
				( attribute "VOLTAGE" "5"
					( Units "uVoltage" "V" 1.000000)
					( Origin gFrontEnd )
				)
				( objectStatus "VR_PVCCIN_CPU1_PHASE1" )
			)
			( signal "@baseboard_fab2_lib.baseboard_fab2(sch_1):vr_pvccin_cpu1_phase2"
				( attribute "VOLTAGE" "5"
					( Units "uVoltage" "V" 1.000000)
					( Origin gFrontEnd )
				)
				( objectStatus "VR_PVCCIN_CPU1_PHASE2" )
			)
			( signal "@baseboard_fab2_lib.baseboard_fab2(sch_1):vr_pvccin_cpu1_phase3"
				( attribute "VOLTAGE" "5"
					( Units "uVoltage" "V" 1.000000)
					( Origin gFrontEnd )
				)
				( objectStatus "VR_PVCCIN_CPU1_PHASE3" )
			)
			( signal "@baseboard_fab2_lib.baseboard_fab2(sch_1):vr_pvccin_cpu1_phase4"
				( attribute "VOLTAGE" "5"
					( Units "uVoltage" "V" 1.000000)
					( Origin gFrontEnd )
				)
				( objectStatus "VR_PVCCIN_CPU1_PHASE4" )
			)
			( signal "@baseboard_fab2_lib.baseboard_fab2(sch_1):vr_pvccin_cpu1_phase5"
				( attribute "VOLTAGE" "5"
					( Units "uVoltage" "V" 1.000000)
					( Origin gFrontEnd )
				)
				( objectStatus "VR_PVCCIN_CPU1_PHASE5" )
			)
			( signal "@baseboard_fab2_lib.baseboard_fab2(sch_1):vr_pvccin_cpu1_ph1_phase"
				( attribute "VOLTAGE" "5"
					( Units "uVoltage" "V" 1.000000)
					( Origin gFrontEnd )
				)
				( objectStatus "VR_PVCCIN_CPU1_PH1_PHASE" )
			)
			( signal "@baseboard_fab2_lib.baseboard_fab2(sch_1):vr_pvccin_cpu1_ph2_phase"
				( attribute "VOLTAGE" "5"
					( Units "uVoltage" "V" 1.000000)
					( Origin gFrontEnd )
				)
				( objectStatus "VR_PVCCIN_CPU1_PH2_PHASE" )
			)
			( signal "@baseboard_fab2_lib.baseboard_fab2(sch_1):vr_pvccin_cpu1_ph3_phase"
				( objectStatus "VR_PVCCIN_CPU1_PH3_PHASE" )
			)
			( signal "@baseboard_fab2_lib.baseboard_fab2(sch_1):vr_pvccin_cpu1_ph4_phase"
				( attribute "VOLTAGE" "5"
					( Units "uVoltage" "V" 1.000000)
					( Origin gFrontEnd )
				)
				( objectStatus "VR_PVCCIN_CPU1_PH4_PHASE" )
			)
			( signal "@baseboard_fab2_lib.baseboard_fab2(sch_1):vr_pvccin_cpu1_ph5_phase"
				( attribute "VOLTAGE" "5"
					( Units "uVoltage" "V" 1.000000)
					( Origin gFrontEnd )
				)
				( objectStatus "VR_PVCCIN_CPU1_PH5_PHASE" )
			)
			( signal "@baseboard_fab2_lib.baseboard_fab2(sch_1):vr_pvpp_def_phase"
				( objectStatus "VR_PVPP_DEF_PHASE" )
			)
			( signal "@baseboard_fab2_lib.baseboard_fab2(sch_1):vr_pvpp_ghj_phase"
				( objectStatus "VR_PVPP_GHJ_PHASE" )
			)
			( signal "@baseboard_fab2_lib.baseboard_fab2(sch_1):vr_pvpp_klm_phase"
				( objectStatus "VR_PVPP_KLM_PHASE" )
			)
			( signal "@baseboard_fab2_lib.baseboard_fab2(sch_1):vr_pvccin_cpu0_ph1_boot"
				( attribute "VOLTAGE" "5"
					( Units "uVoltage" "V" 1.000000)
					( Origin gFrontEnd )
				)
				( objectStatus "VR_PVCCIN_CPU0_PH1_BOOT" )
			)
			( signal "@baseboard_fab2_lib.baseboard_fab2(sch_1):vr_pvccin_cpu0_ph1_vcin"
				( attribute "VOLTAGE" "5"
					( Units "uVoltage" "V" 1.000000)
					( Origin gFrontEnd )
				)
				( objectStatus "VR_PVCCIN_CPU0_PH1_VCIN" )
			)
			( signal "@baseboard_fab2_lib.baseboard_fab2(sch_1):vr_pvccin_cpu0_ph2_boot"
				( attribute "VOLTAGE" "5"
					( Units "uVoltage" "V" 1.000000)
					( Origin gFrontEnd )
				)
				( objectStatus "VR_PVCCIN_CPU0_PH2_BOOT" )
			)
			( signal "@baseboard_fab2_lib.baseboard_fab2(sch_1):vr_pvccin_cpu0_ph2_vcin"
				( attribute "VOLTAGE" "5"
					( Units "uVoltage" "V" 1.000000)
					( Origin gFrontEnd )
				)
				( objectStatus "VR_PVCCIN_CPU0_PH2_VCIN" )
			)
			( signal "@baseboard_fab2_lib.baseboard_fab2(sch_1):vr_pvccin_cpu0_ph3_boot"
				( attribute "VOLTAGE" "5"
					( Units "uVoltage" "V" 1.000000)
					( Origin gFrontEnd )
				)
				( objectStatus "VR_PVCCIN_CPU0_PH3_BOOT" )
			)
			( signal "@baseboard_fab2_lib.baseboard_fab2(sch_1):vr_pvccin_cpu0_ph3_vcin"
				( objectStatus "VR_PVCCIN_CPU0_PH3_VCIN" )
			)
			( signal "@baseboard_fab2_lib.baseboard_fab2(sch_1):vr_pvccin_cpu0_ph4_boot"
				( attribute "VOLTAGE" "5"
					( Units "uVoltage" "V" 1.000000)
					( Origin gFrontEnd )
				)
				( objectStatus "VR_PVCCIN_CPU0_PH4_BOOT" )
			)
			( signal "@baseboard_fab2_lib.baseboard_fab2(sch_1):vr_pvccin_cpu0_ph4_vcin"
				( attribute "VOLTAGE" "5"
					( Units "uVoltage" "V" 1.000000)
					( Origin gFrontEnd )
				)
				( objectStatus "VR_PVCCIN_CPU0_PH4_VCIN" )
			)
			( signal "@baseboard_fab2_lib.baseboard_fab2(sch_1):vr_pvccin_cpu0_ph5_boot"
				( attribute "VOLTAGE" "5"
					( Units "uVoltage" "V" 1.000000)
					( Origin gFrontEnd )
				)
				( objectStatus "VR_PVCCIN_CPU0_PH5_BOOT" )
			)
			( signal "@baseboard_fab2_lib.baseboard_fab2(sch_1):vr_pvccin_cpu0_ph5_vcin"
				( attribute "VOLTAGE" "5"
					( Units "uVoltage" "V" 1.000000)
					( Origin gFrontEnd )
				)
				( objectStatus "VR_PVCCIN_CPU0_PH5_VCIN" )
			)
			( signal "@baseboard_fab2_lib.baseboard_fab2(sch_1):vr_pvccin_cpu1_ph1_boot"
				( attribute "VOLTAGE" "5"
					( Units "uVoltage" "V" 1.000000)
					( Origin gFrontEnd )
				)
				( objectStatus "VR_PVCCIN_CPU1_PH1_BOOT" )
			)
			( signal "@baseboard_fab2_lib.baseboard_fab2(sch_1):vr_pvccin_cpu1_ph1_vcin"
				( attribute "VOLTAGE" "5"
					( Units "uVoltage" "V" 1.000000)
					( Origin gFrontEnd )
				)
				( objectStatus "VR_PVCCIN_CPU1_PH1_VCIN" )
			)
			( signal "@baseboard_fab2_lib.baseboard_fab2(sch_1):vr_pvccin_cpu1_ph2_boot"
				( attribute "VOLTAGE" "5"
					( Units "uVoltage" "V" 1.000000)
					( Origin gFrontEnd )
				)
				( objectStatus "VR_PVCCIN_CPU1_PH2_BOOT" )
			)
			( signal "@baseboard_fab2_lib.baseboard_fab2(sch_1):vr_pvccin_cpu1_ph2_vcin"
				( attribute "VOLTAGE" "5"
					( Units "uVoltage" "V" 1.000000)
					( Origin gFrontEnd )
				)
				( objectStatus "VR_PVCCIN_CPU1_PH2_VCIN" )
			)
			( signal "@baseboard_fab2_lib.baseboard_fab2(sch_1):vr_pvccin_cpu1_ph3_boot"
				( objectStatus "VR_PVCCIN_CPU1_PH3_BOOT" )
			)
			( signal "@baseboard_fab2_lib.baseboard_fab2(sch_1):vr_pvccin_cpu1_ph3_vcin"
				( attribute "VOLTAGE" "5"
					( Units "uVoltage" "V" 1.000000)
					( Origin gFrontEnd )
				)
				( objectStatus "VR_PVCCIN_CPU1_PH3_VCIN" )
			)
			( signal "@baseboard_fab2_lib.baseboard_fab2(sch_1):vr_pvccin_cpu1_ph4_boot"
				( objectStatus "VR_PVCCIN_CPU1_PH4_BOOT" )
			)
			( signal "@baseboard_fab2_lib.baseboard_fab2(sch_1):vr_pvccin_cpu1_ph4_vcin"
				( attribute "VOLTAGE" "5"
					( Units "uVoltage" "V" 1.000000)
					( Origin gFrontEnd )
				)
				( objectStatus "VR_PVCCIN_CPU1_PH4_VCIN" )
			)
			( signal "@baseboard_fab2_lib.baseboard_fab2(sch_1):vr_pvccin_cpu1_ph5_boot"
				( attribute "VOLTAGE" "5"
					( Units "uVoltage" "V" 1.000000)
					( Origin gFrontEnd )
				)
				( objectStatus "VR_PVCCIN_CPU1_PH5_BOOT" )
			)
			( signal "@baseboard_fab2_lib.baseboard_fab2(sch_1):vr_pvccin_cpu1_ph5_vcin"
				( attribute "VOLTAGE" "5"
					( Units "uVoltage" "V" 1.000000)
					( Origin gFrontEnd )
				)
				( objectStatus "VR_PVCCIN_CPU1_PH5_VCIN" )
			)
			( signal "@baseboard_fab2_lib.baseboard_fab2(sch_1):vr_fet_sw_p5v_stby_pvin"
				( objectStatus "VR_FET_SW_P5V_STBY_PVIN" )
			)
			( signal "@baseboard_fab2_lib.baseboard_fab2(sch_1):vr_fet_sw_p12v_stby_pvccio_cpu0"
				( attribute "VOLTAGE" "12"
					( Units "uVoltage" "V" 1.000000)
					( Origin gFrontEnd )
				)
				( objectStatus "VR_FET_SW_P12V_STBY_PVCCIO_CPU0" )
			)
			( signal "@baseboard_fab2_lib.baseboard_fab2(sch_1):vr_pvpp_def_boot_r"
				( objectStatus "VR_PVPP_DEF_BOOT_R" )
			)
			( signal "@baseboard_fab2_lib.baseboard_fab2(sch_1):vr_pvpp_ghj_boot"
				( objectStatus "VR_PVPP_GHJ_BOOT" )
			)
			( signal "@baseboard_fab2_lib.baseboard_fab2(sch_1):vr_pvpp_ghj_boot_r"
				( objectStatus "VR_PVPP_GHJ_BOOT_R" )
			)
			( signal "@baseboard_fab2_lib.baseboard_fab2(sch_1):fan_tach0"
				( pinPairRef "@baseboard_fab2_lib.baseboard_fab2(sch_1):\PP6133\" )
				( objectStatus "FAN_TACH0" )
			)
			( signal "@baseboard_fab2_lib.baseboard_fab2(sch_1):fan_tach0_cpu0_d1"
				( pinPairRef "@baseboard_fab2_lib.baseboard_fab2(sch_1):\PP6128\" )
				( objectStatus "FAN_TACH0_CPU0_D1" )
			)
			( signal "@baseboard_fab2_lib.baseboard_fab2(sch_1):fan_tach0_cpu0_d2"
				( pinPairRef "@baseboard_fab2_lib.baseboard_fab2(sch_1):\PP6127\" )
				( objectStatus "FAN_TACH0_CPU0_D2" )
			)
			( signal "@baseboard_fab2_lib.baseboard_fab2(sch_1):fan_tach2_cpu1_d1"
				( pinPairRef "@baseboard_fab2_lib.baseboard_fab2(sch_1):\PP6126\" )
				( objectStatus "FAN_TACH2_CPU1_D1" )
			)
			( signal "@baseboard_fab2_lib.baseboard_fab2(sch_1):fan_tach2_cpu1_d2"
				( pinPairRef "@baseboard_fab2_lib.baseboard_fab2(sch_1):\PP6125\" )
				( objectStatus "FAN_TACH2_CPU1_D2" )
			)
			( signal "@baseboard_fab2_lib.baseboard_fab2(sch_1):fan_tach3_r"
				( objectStatus "FAN_TACH3_R" )
			)
			( signal "@baseboard_fab2_lib.baseboard_fab2(sch_1):fan_tach3"
				( objectStatus "FAN_TACH3" )
			)
			( signal "@baseboard_fab2_lib.baseboard_fab2(sch_1):fan_tach2_r"
				( objectStatus "FAN_TACH2_R" )
			)
			( signal "@baseboard_fab2_lib.baseboard_fab2(sch_1):fan_tach2"
				( objectStatus "FAN_TACH2" )
			)
			( signal "@baseboard_fab2_lib.baseboard_fab2(sch_1):fan_tach1_r"
				( objectStatus "FAN_TACH1_R" )
			)
			( signal "@baseboard_fab2_lib.baseboard_fab2(sch_1):fan_tach1"
				( objectStatus "FAN_TACH1" )
			)
			( signal "@baseboard_fab2_lib.baseboard_fab2(sch_1):fan_pwm_out_sys0_r1"
				( pinPairRef "@baseboard_fab2_lib.baseboard_fab2(sch_1):\PP5796\" )
				( objectStatus "FAN_PWM_OUT_SYS0_R1" )
			)
			( signal "@baseboard_fab2_lib.baseboard_fab2(sch_1):fan_pwm_out_sys0_r"
				( objectStatus "FAN_PWM_OUT_SYS0_R" )
			)
			( signal "@baseboard_fab2_lib.baseboard_fab2(sch_1):fan_pwm_out_sys0_buf"
				( objectStatus "FAN_PWM_OUT_SYS0_BUF" )
			)
			( signal "@baseboard_fab2_lib.baseboard_fab2(sch_1):fan_pwm_out_sys1_buf"
				( objectStatus "FAN_PWM_OUT_SYS1_BUF" )
			)
			( signal "@baseboard_fab2_lib.baseboard_fab2(sch_1):fan_pwm_out_sys1_r"
				( pinPairRef "@baseboard_fab2_lib.baseboard_fab2(sch_1):\PP5542\" )
				( pinPairRef "@baseboard_fab2_lib.baseboard_fab2(sch_1):\PP5543\" )
				( objectStatus "FAN_PWM_OUT_SYS1_R" )
			)
			( signal "@baseboard_fab2_lib.baseboard_fab2(sch_1):tp_clk_100m_nsscc1_dn"
				( objectStatus "TP_CLK_100M_NSSCC1_DN" )
			)
			( signal "@baseboard_fab2_lib.baseboard_fab2(sch_1):tp_clk_100m_nsscc1_dp"
				( objectStatus "TP_CLK_100M_NSSCC1_DP" )
			)
			( signal "@baseboard_fab2_lib.baseboard_fab2(sch_1):tp_clk_100m_r_dn"
				( objectStatus "TP_CLK_100M_R_DN" )
			)
			( signal "@baseboard_fab2_lib.baseboard_fab2(sch_1):tp_clk_100m_r_dp"
				( objectStatus "TP_CLK_100M_R_DP" )
			)
			( signal "@baseboard_fab2_lib.baseboard_fab2(sch_1):tp_clk_100m_src12_dn"
				( objectStatus "TP_CLK_100M_SRC12_DN" )
			)
			( signal "@baseboard_fab2_lib.baseboard_fab2(sch_1):tp_clk_100m_src12_dp"
				( objectStatus "TP_CLK_100M_SRC12_DP" )
			)
			( signal "@baseboard_fab2_lib.baseboard_fab2(sch_1):tp_clk_100m_src13_dn"
				( objectStatus "TP_CLK_100M_SRC13_DN" )
			)
			( signal "@baseboard_fab2_lib.baseboard_fab2(sch_1):tp_clk_100m_src13_dp"
				( objectStatus "TP_CLK_100M_SRC13_DP" )
			)
			( signal "@baseboard_fab2_lib.baseboard_fab2(sch_1):tp_cpu0_rsvd_247"
				( objectStatus "TP_CPU0_RSVD_247" )
			)
			( signal "@baseboard_fab2_lib.baseboard_fab2(sch_1):tp_cpu0_rsvd_248"
				( objectStatus "TP_CPU0_RSVD_248" )
			)
			( signal "@baseboard_fab2_lib.baseboard_fab2(sch_1):tp_cpu0_rsvd_249"
				( objectStatus "TP_CPU0_RSVD_249" )
			)
			( signal "@baseboard_fab2_lib.baseboard_fab2(sch_1):tp_cpu0_rsvd_250"
				( objectStatus "TP_CPU0_RSVD_250" )
			)
			( signal "@baseboard_fab2_lib.baseboard_fab2(sch_1):tp_cpu0_rsvd_251"
				( objectStatus "TP_CPU0_RSVD_251" )
			)
			( signal "@baseboard_fab2_lib.baseboard_fab2(sch_1):tp_cpu0_rsvd_252"
				( objectStatus "TP_CPU0_RSVD_252" )
			)
			( signal "@baseboard_fab2_lib.baseboard_fab2(sch_1):tp_cpu0_rsvd_253"
				( objectStatus "TP_CPU0_RSVD_253" )
			)
			( signal "@baseboard_fab2_lib.baseboard_fab2(sch_1):tp_cpu0_rsvd_254"
				( objectStatus "TP_CPU0_RSVD_254" )
			)
			( signal "@baseboard_fab2_lib.baseboard_fab2(sch_1):tp_cpu0_rsvd_255"
				( objectStatus "TP_CPU0_RSVD_255" )
			)
			( signal "@baseboard_fab2_lib.baseboard_fab2(sch_1):tp_cpu0_rsvd_256"
				( objectStatus "TP_CPU0_RSVD_256" )
			)
			( signal "@baseboard_fab2_lib.baseboard_fab2(sch_1):tp_cpu0_rsvd_258"
				( objectStatus "TP_CPU0_RSVD_258" )
			)
			( signal "@baseboard_fab2_lib.baseboard_fab2(sch_1):tp_bios_recover_boot"
				( objectStatus "TP_BIOS_RECOVER_BOOT" )
			)
			( signal "@baseboard_fab2_lib.baseboard_fab2(sch_1):tp_cd_hfi1_cpu1_int_n"
				( objectStatus "TP_CD_HFI1_CPU1_INT_N" )
			)
			( signal "@baseboard_fab2_lib.baseboard_fab2(sch_1):tp_cd_hfi1_cpu1_i2cdat"
				( objectStatus "TP_CD_HFI1_CPU1_I2CDAT" )
			)
			( signal "@baseboard_fab2_lib.baseboard_fab2(sch_1):tp_cd_hfi1_cpu1_i2clk"
				( objectStatus "TP_CD_HFI1_CPU1_I2CLK" )
			)
			( signal "@baseboard_fab2_lib.baseboard_fab2(sch_1):tp_cd_hfi1_cpu1_led_n"
				( objectStatus "TP_CD_HFI1_CPU1_LED_N" )
			)
			( signal "@baseboard_fab2_lib.baseboard_fab2(sch_1):tp_cd_hfi1_cpu1_modprst_n"
				( objectStatus "TP_CD_HFI1_CPU1_MODPRST_N" )
			)
			( signal "@baseboard_fab2_lib.baseboard_fab2(sch_1):tp_cd_hfi1_cpu1_reset_n"
				( objectStatus "TP_CD_HFI1_CPU1_RESET_N" )
			)
			( signal "@baseboard_fab2_lib.baseboard_fab2(sch_1):tp_ch_a_dimm_a0_rfu_0"
				( attribute "NO_TEST" "1"
					( Origin gBackEnd )
				)
				( objectStatus "TP_CH_A_DIMM_A0_RFU_0" )
			)
			( signal "@baseboard_fab2_lib.baseboard_fab2(sch_1):tp_ch_a_dimm_a0_rfu_1"
				( attribute "NO_TEST" "1"
					( Origin gBackEnd )
				)
				( objectStatus "TP_CH_A_DIMM_A0_RFU_1" )
			)
			( signal "@baseboard_fab2_lib.baseboard_fab2(sch_1):tp_ch_a_dimm_a0_rfu_2"
				( attribute "NO_TEST" "1"
					( Origin gBackEnd )
				)
				( objectStatus "TP_CH_A_DIMM_A0_RFU_2" )
			)
			( signal "@baseboard_fab2_lib.baseboard_fab2(sch_1):tp_ch_a_dimm_a1_rfu_0"
				( attribute "NO_TEST" "1"
					( Origin gBackEnd )
				)
				( objectStatus "TP_CH_A_DIMM_A1_RFU_0" )
			)
			( signal "@baseboard_fab2_lib.baseboard_fab2(sch_1):tp_ch_a_dimm_a1_rfu_1"
				( attribute "NO_TEST" "1"
					( Origin gBackEnd )
				)
				( objectStatus "TP_CH_A_DIMM_A1_RFU_1" )
			)
			( signal "@baseboard_fab2_lib.baseboard_fab2(sch_1):tp_ch_a_dimm_a1_rfu_2"
				( attribute "NO_TEST" "1"
					( Origin gBackEnd )
				)
				( objectStatus "TP_CH_A_DIMM_A1_RFU_2" )
			)
			( signal "@baseboard_fab2_lib.baseboard_fab2(sch_1):tp_ch_b_dimm_b0_rfu_0"
				( attribute "NO_TEST" "1"
					( Origin gBackEnd )
				)
				( objectStatus "TP_CH_B_DIMM_B0_RFU_0" )
			)
			( signal "@baseboard_fab2_lib.baseboard_fab2(sch_1):tp_ch_b_dimm_b0_rfu_1"
				( attribute "NO_TEST" "1"
					( Origin gBackEnd )
				)
				( objectStatus "TP_CH_B_DIMM_B0_RFU_1" )
			)
			( signal "@baseboard_fab2_lib.baseboard_fab2(sch_1):tp_ch_b_dimm_b0_rfu_2"
				( attribute "NO_TEST" "1"
					( Origin gBackEnd )
				)
				( objectStatus "TP_CH_B_DIMM_B0_RFU_2" )
			)
			( signal "@baseboard_fab2_lib.baseboard_fab2(sch_1):tp_ch_b_dimm_b1_rfu_0"
				( attribute "NO_TEST" "1"
					( Origin gBackEnd )
				)
				( objectStatus "TP_CH_B_DIMM_B1_RFU_0" )
			)
			( signal "@baseboard_fab2_lib.baseboard_fab2(sch_1):tp_ch_b_dimm_b1_rfu_1"
				( attribute "NO_TEST" "1"
					( Origin gBackEnd )
				)
				( objectStatus "TP_CH_B_DIMM_B1_RFU_1" )
			)
			( signal "@baseboard_fab2_lib.baseboard_fab2(sch_1):tp_ch_b_dimm_b1_rfu_2"
				( attribute "NO_TEST" "1"
					( Origin gBackEnd )
				)
				( objectStatus "TP_CH_B_DIMM_B1_RFU_2" )
			)
			( signal "@baseboard_fab2_lib.baseboard_fab2(sch_1):tp_ch_c_dimm_c0_rfu_0"
				( attribute "NO_TEST" "1"
					( Origin gBackEnd )
				)
				( objectStatus "TP_CH_C_DIMM_C0_RFU_0" )
			)
			( signal "@baseboard_fab2_lib.baseboard_fab2(sch_1):tp_ch_c_dimm_c0_rfu_1"
				( attribute "NO_TEST" "1"
					( Origin gBackEnd )
				)
				( objectStatus "TP_CH_C_DIMM_C0_RFU_1" )
			)
			( signal "@baseboard_fab2_lib.baseboard_fab2(sch_1):tp_ch_c_dimm_c0_rfu_2"
				( attribute "NO_TEST" "1"
					( Origin gBackEnd )
				)
				( objectStatus "TP_CH_C_DIMM_C0_RFU_2" )
			)
			( signal "@baseboard_fab2_lib.baseboard_fab2(sch_1):tp_ch_c_dimm_c1_rfu_0"
				( attribute "NO_TEST" "1"
					( Origin gBackEnd )
				)
				( objectStatus "TP_CH_C_DIMM_C1_RFU_0" )
			)
			( signal "@baseboard_fab2_lib.baseboard_fab2(sch_1):tp_ch_c_dimm_c1_rfu_1"
				( attribute "NO_TEST" "1"
					( Origin gBackEnd )
				)
				( objectStatus "TP_CH_C_DIMM_C1_RFU_1" )
			)
			( signal "@baseboard_fab2_lib.baseboard_fab2(sch_1):tp_ch_c_dimm_c1_rfu_2"
				( attribute "NO_TEST" "1"
					( Origin gBackEnd )
				)
				( objectStatus "TP_CH_C_DIMM_C1_RFU_2" )
			)
			( signal "@baseboard_fab2_lib.baseboard_fab2(sch_1):tp_ch_d_dimm_d0_rfu_0"
				( objectStatus "TP_CH_D_DIMM_D0_RFU_0" )
			)
			( signal "@baseboard_fab2_lib.baseboard_fab2(sch_1):tp_ch_d_dimm_d0_rfu_1"
				( objectStatus "TP_CH_D_DIMM_D0_RFU_1" )
			)
			( signal "@baseboard_fab2_lib.baseboard_fab2(sch_1):tp_ch_d_dimm_d0_rfu_2"
				( attribute "NO_TEST" "1"
					( Origin gBackEnd )
				)
				( objectStatus "TP_CH_D_DIMM_D0_RFU_2" )
			)
			( signal "@baseboard_fab2_lib.baseboard_fab2(sch_1):tp_ch_d_dimm_d1_rfu_0"
				( objectStatus "TP_CH_D_DIMM_D1_RFU_0" )
			)
			( signal "@baseboard_fab2_lib.baseboard_fab2(sch_1):tp_ch_d_dimm_d1_rfu_1"
				( objectStatus "TP_CH_D_DIMM_D1_RFU_1" )
			)
			( signal "@baseboard_fab2_lib.baseboard_fab2(sch_1):tp_ch_d_dimm_d1_rfu_2"
				( attribute "NO_TEST" "1"
					( Origin gBackEnd )
				)
				( objectStatus "TP_CH_D_DIMM_D1_RFU_2" )
			)
			( signal "@baseboard_fab2_lib.baseboard_fab2(sch_1):tp_ch_e_dimm_e0_rfu_0"
				( objectStatus "TP_CH_E_DIMM_E0_RFU_0" )
			)
			( signal "@baseboard_fab2_lib.baseboard_fab2(sch_1):tp_ch_e_dimm_e0_rfu_1"
				( objectStatus "TP_CH_E_DIMM_E0_RFU_1" )
			)
			( signal "@baseboard_fab2_lib.baseboard_fab2(sch_1):tp_ch_e_dimm_e0_rfu_2"
				( attribute "NO_TEST" "1"
					( Origin gBackEnd )
				)
				( objectStatus "TP_CH_E_DIMM_E0_RFU_2" )
			)
			( signal "@baseboard_fab2_lib.baseboard_fab2(sch_1):tp_ch_e_dimm_e1_rfu_0"
				( objectStatus "TP_CH_E_DIMM_E1_RFU_0" )
			)
			( signal "@baseboard_fab2_lib.baseboard_fab2(sch_1):tp_ch_e_dimm_e1_rfu_1"
				( objectStatus "TP_CH_E_DIMM_E1_RFU_1" )
			)
			( signal "@baseboard_fab2_lib.baseboard_fab2(sch_1):tp_ch_e_dimm_e1_rfu_2"
				( attribute "NO_TEST" "1"
					( Origin gBackEnd )
				)
				( objectStatus "TP_CH_E_DIMM_E1_RFU_2" )
			)
			( signal "@baseboard_fab2_lib.baseboard_fab2(sch_1):tp_ch_f_dimm_f0_rfu_0"
				( objectStatus "TP_CH_F_DIMM_F0_RFU_0" )
			)
			( signal "@baseboard_fab2_lib.baseboard_fab2(sch_1):tp_ch_f_dimm_f0_rfu_1"
				( objectStatus "TP_CH_F_DIMM_F0_RFU_1" )
			)
			( signal "@baseboard_fab2_lib.baseboard_fab2(sch_1):tp_ch_f_dimm_f0_rfu_2"
				( attribute "NO_TEST" "1"
					( Origin gBackEnd )
				)
				( objectStatus "TP_CH_F_DIMM_F0_RFU_2" )
			)
			( signal "@baseboard_fab2_lib.baseboard_fab2(sch_1):tp_ch_f_dimm_f1_rfu_0"
				( objectStatus "TP_CH_F_DIMM_F1_RFU_0" )
			)
			( signal "@baseboard_fab2_lib.baseboard_fab2(sch_1):tp_ch_f_dimm_f1_rfu_1"
				( objectStatus "TP_CH_F_DIMM_F1_RFU_1" )
			)
			( signal "@baseboard_fab2_lib.baseboard_fab2(sch_1):tp_ch_f_dimm_f1_rfu_2"
				( attribute "NO_TEST" "1"
					( Origin gBackEnd )
				)
				( objectStatus "TP_CH_F_DIMM_F1_RFU_2" )
			)
			( signal "@baseboard_fab2_lib.baseboard_fab2(sch_1):tp_ch_g_dimm_g0_rfu_0"
				( attribute "NO_TEST" "1"
					( Origin gBackEnd )
				)
				( objectStatus "TP_CH_G_DIMM_G0_RFU_0" )
			)
			( signal "@baseboard_fab2_lib.baseboard_fab2(sch_1):tp_ch_g_dimm_g0_rfu_1"
				( attribute "NO_TEST" "1"
					( Origin gBackEnd )
				)
				( objectStatus "TP_CH_G_DIMM_G0_RFU_1" )
			)
			( signal "@baseboard_fab2_lib.baseboard_fab2(sch_1):tp_ch_g_dimm_g0_rfu_2"
				( attribute "NO_TEST" "1"
					( Origin gBackEnd )
				)
				( objectStatus "TP_CH_G_DIMM_G0_RFU_2" )
			)
			( signal "@baseboard_fab2_lib.baseboard_fab2(sch_1):tp_ch_g_dimm0_rfu_0"
				( attribute "NO_TEST" "1"
					( Origin gBackEnd )
				)
				( objectStatus "TP_CH_G_DIMM0_RFU_0" )
			)
			( signal "@baseboard_fab2_lib.baseboard_fab2(sch_1):tp_ch_g_dimm0_rfu_1"
				( attribute "NO_TEST" "1"
					( Origin gBackEnd )
				)
				( objectStatus "TP_CH_G_DIMM0_RFU_1" )
			)
			( signal "@baseboard_fab2_lib.baseboard_fab2(sch_1):tp_ch_g_dimm0_rfu_2"
				( attribute "NO_TEST" "1"
					( Origin gBackEnd )
				)
				( objectStatus "TP_CH_G_DIMM0_RFU_2" )
			)
			( signal "@baseboard_fab2_lib.baseboard_fab2(sch_1):tp_ch_h_dimm_h0_rfu_0"
				( attribute "NO_TEST" "1"
					( Origin gBackEnd )
				)
				( objectStatus "TP_CH_H_DIMM_H0_RFU_0" )
			)
			( signal "@baseboard_fab2_lib.baseboard_fab2(sch_1):tp_ch_h_dimm_h0_rfu_1"
				( attribute "NO_TEST" "1"
					( Origin gBackEnd )
				)
				( objectStatus "TP_CH_H_DIMM_H0_RFU_1" )
			)
			( signal "@baseboard_fab2_lib.baseboard_fab2(sch_1):tp_ch_h_dimm_h0_rfu_2"
				( attribute "NO_TEST" "1"
					( Origin gBackEnd )
				)
				( objectStatus "TP_CH_H_DIMM_H0_RFU_2" )
			)
			( signal "@baseboard_fab2_lib.baseboard_fab2(sch_1):tp_ch_h_dimm0_rfu_0"
				( attribute "NO_TEST" "1"
					( Origin gBackEnd )
				)
				( objectStatus "TP_CH_H_DIMM0_RFU_0" )
			)
			( signal "@baseboard_fab2_lib.baseboard_fab2(sch_1):tp_ch_h_dimm0_rfu_1"
				( attribute "NO_TEST" "1"
					( Origin gBackEnd )
				)
				( objectStatus "TP_CH_H_DIMM0_RFU_1" )
			)
			( signal "@baseboard_fab2_lib.baseboard_fab2(sch_1):tp_ch_h_dimm0_rfu_2"
				( attribute "NO_TEST" "1"
					( Origin gBackEnd )
				)
				( objectStatus "TP_CH_H_DIMM0_RFU_2" )
			)
			( signal "@baseboard_fab2_lib.baseboard_fab2(sch_1):tp_ch_j_dimm_j0_rfu_0"
				( attribute "NO_TEST" "1"
					( Origin gBackEnd )
				)
				( objectStatus "TP_CH_J_DIMM_J0_RFU_0" )
			)
			( signal "@baseboard_fab2_lib.baseboard_fab2(sch_1):tp_ch_j_dimm_j0_rfu_1"
				( attribute "NO_TEST" "1"
					( Origin gBackEnd )
				)
				( objectStatus "TP_CH_J_DIMM_J0_RFU_1" )
			)
			( signal "@baseboard_fab2_lib.baseboard_fab2(sch_1):tp_ch_j_dimm_j0_rfu_2"
				( attribute "NO_TEST" "1"
					( Origin gBackEnd )
				)
				( objectStatus "TP_CH_J_DIMM_J0_RFU_2" )
			)
			( signal "@baseboard_fab2_lib.baseboard_fab2(sch_1):tp_ch_j_dimm_j1_rfu_0"
				( attribute "NO_TEST" "1"
					( Origin gBackEnd )
				)
				( objectStatus "TP_CH_J_DIMM_J1_RFU_0" )
			)
			( signal "@baseboard_fab2_lib.baseboard_fab2(sch_1):tp_ch_j_dimm_j1_rfu_1"
				( attribute "NO_TEST" "1"
					( Origin gBackEnd )
				)
				( objectStatus "TP_CH_J_DIMM_J1_RFU_1" )
			)
			( signal "@baseboard_fab2_lib.baseboard_fab2(sch_1):tp_ch_j_dimm_j1_rfu_2"
				( attribute "NO_TEST" "1"
					( Origin gBackEnd )
				)
				( objectStatus "TP_CH_J_DIMM_J1_RFU_2" )
			)
			( signal "@baseboard_fab2_lib.baseboard_fab2(sch_1):tp_ch_k_dimm_k0_rfu_0"
				( attribute "NO_TEST" "1"
					( Origin gBackEnd )
				)
				( objectStatus "TP_CH_K_DIMM_K0_RFU_0" )
			)
			( signal "@baseboard_fab2_lib.baseboard_fab2(sch_1):tp_ch_k_dimm_k0_rfu_1"
				( attribute "NO_TEST" "1"
					( Origin gBackEnd )
				)
				( objectStatus "TP_CH_K_DIMM_K0_RFU_1" )
			)
			( signal "@baseboard_fab2_lib.baseboard_fab2(sch_1):tp_ch_k_dimm_k0_rfu_2"
				( attribute "NO_TEST" "1"
					( Origin gBackEnd )
				)
				( objectStatus "TP_CH_K_DIMM_K0_RFU_2" )
			)
			( signal "@baseboard_fab2_lib.baseboard_fab2(sch_1):tp_ch_k_dimm0_rfu_0"
				( attribute "NO_TEST" "1"
					( Origin gBackEnd )
				)
				( objectStatus "TP_CH_K_DIMM0_RFU_0" )
			)
			( signal "@baseboard_fab2_lib.baseboard_fab2(sch_1):tp_ch_k_dimm0_rfu_1"
				( attribute "NO_TEST" "1"
					( Origin gBackEnd )
				)
				( objectStatus "TP_CH_K_DIMM0_RFU_1" )
			)
			( signal "@baseboard_fab2_lib.baseboard_fab2(sch_1):tp_ch_k_dimm0_rfu_2"
				( attribute "NO_TEST" "1"
					( Origin gBackEnd )
				)
				( objectStatus "TP_CH_K_DIMM0_RFU_2" )
			)
			( signal "@baseboard_fab2_lib.baseboard_fab2(sch_1):tp_ch_l_dimm_l0_rfu_0"
				( attribute "NO_TEST" "1"
					( Origin gBackEnd )
				)
				( objectStatus "TP_CH_L_DIMM_L0_RFU_0" )
			)
			( signal "@baseboard_fab2_lib.baseboard_fab2(sch_1):tp_ch_l_dimm_l0_rfu_1"
				( attribute "NO_TEST" "1"
					( Origin gBackEnd )
				)
				( objectStatus "TP_CH_L_DIMM_L0_RFU_1" )
			)
			( signal "@baseboard_fab2_lib.baseboard_fab2(sch_1):tp_ch_l_dimm_l0_rfu_2"
				( attribute "NO_TEST" "1"
					( Origin gBackEnd )
				)
				( objectStatus "TP_CH_L_DIMM_L0_RFU_2" )
			)
			( signal "@baseboard_fab2_lib.baseboard_fab2(sch_1):tp_ch_l_dimm0_rfu_0"
				( attribute "NO_TEST" "1"
					( Origin gBackEnd )
				)
				( objectStatus "TP_CH_L_DIMM0_RFU_0" )
			)
			( signal "@baseboard_fab2_lib.baseboard_fab2(sch_1):tp_ch_l_dimm0_rfu_1"
				( attribute "NO_TEST" "1"
					( Origin gBackEnd )
				)
				( objectStatus "TP_CH_L_DIMM0_RFU_1" )
			)
			( signal "@baseboard_fab2_lib.baseboard_fab2(sch_1):tp_ch_l_dimm0_rfu_2"
				( attribute "NO_TEST" "1"
					( Origin gBackEnd )
				)
				( objectStatus "TP_CH_L_DIMM0_RFU_2" )
			)
			( signal "@baseboard_fab2_lib.baseboard_fab2(sch_1):tp_ch_m_dimm_m0_rfu_0"
				( attribute "NO_TEST" "1"
					( Origin gBackEnd )
				)
				( objectStatus "TP_CH_M_DIMM_M0_RFU_0" )
			)
			( signal "@baseboard_fab2_lib.baseboard_fab2(sch_1):tp_ch_m_dimm_m0_rfu_1"
				( attribute "NO_TEST" "1"
					( Origin gBackEnd )
				)
				( objectStatus "TP_CH_M_DIMM_M0_RFU_1" )
			)
			( signal "@baseboard_fab2_lib.baseboard_fab2(sch_1):tp_ch_m_dimm_m0_rfu_2"
				( attribute "NO_TEST" "1"
					( Origin gBackEnd )
				)
				( objectStatus "TP_CH_M_DIMM_M0_RFU_2" )
			)
			( signal "@baseboard_fab2_lib.baseboard_fab2(sch_1):tp_ch_m_dimm_m1_rfu_0"
				( attribute "NO_TEST" "1"
					( Origin gBackEnd )
				)
				( objectStatus "TP_CH_M_DIMM_M1_RFU_0" )
			)
			( signal "@baseboard_fab2_lib.baseboard_fab2(sch_1):tp_ch_m_dimm_m1_rfu_1"
				( attribute "NO_TEST" "1"
					( Origin gBackEnd )
				)
				( objectStatus "TP_CH_M_DIMM_M1_RFU_1" )
			)
			( signal "@baseboard_fab2_lib.baseboard_fab2(sch_1):tp_ch_m_dimm_m1_rfu_2"
				( attribute "NO_TEST" "1"
					( Origin gBackEnd )
				)
				( objectStatus "TP_CH_M_DIMM_M1_RFU_2" )
			)
			( signal "@baseboard_fab2_lib.baseboard_fab2(sch_1):tp_clk_24m_pmsync2"
				( objectStatus "TP_CLK_24M_PMSYNC2" )
			)
			( signal "@baseboard_fab2_lib.baseboard_fab2(sch_1):tp_clk_96m_ckmng_n"
				( objectStatus "TP_CLK_96M_CKMNG_N" )
			)
			( signal "@baseboard_fab2_lib.baseboard_fab2(sch_1):tp_clk_96m_ckmng_p"
				( objectStatus "TP_CLK_96M_CKMNG_P" )
			)
			( signal "@baseboard_fab2_lib.baseboard_fab2(sch_1):tp_cpu0_upi2_rsvd_cw14"
				( objectStatus "TP_CPU0_UPI2_RSVD_CW14" )
			)
			( signal "@baseboard_fab2_lib.baseboard_fab2(sch_1):tp_cpu0_upi2_rsvd_cw16"
				( objectStatus "TP_CPU0_UPI2_RSVD_CW16" )
			)
			( signal "@baseboard_fab2_lib.baseboard_fab2(sch_1):tp_cpu0_upi2_rsvd_da16"
				( objectStatus "TP_CPU0_UPI2_RSVD_DA16" )
			)
			( signal "@baseboard_fab2_lib.baseboard_fab2(sch_1):tp_cpu0_upi2_rsvd_db15"
				( objectStatus "TP_CPU0_UPI2_RSVD_DB15" )
			)
			( signal "@baseboard_fab2_lib.baseboard_fab2(sch_1):tp_cpu0_upi2_rsvd_dc16"
				( objectStatus "TP_CPU0_UPI2_RSVD_DC16" )
			)
			( signal "@baseboard_fab2_lib.baseboard_fab2(sch_1):tp_clk_125m"
				( objectStatus "TP_CLK_125M" )
			)
			( signal "@baseboard_fab2_lib.baseboard_fab2(sch_1):tp_clk_125m_bmca"
				( objectStatus "TP_CLK_125M_BMCA" )
			)
			( signal "@baseboard_fab2_lib.baseboard_fab2(sch_1):tp_clk5_50m_ckmng"
				( objectStatus "TP_CLK5_50M_CKMNG" )
			)
			( signal "@baseboard_fab2_lib.baseboard_fab2(sch_1):tp_cpld1_pr9c"
				( objectStatus "TP_CPLD1_PR9C" )
			)
			( signal "@baseboard_fab2_lib.baseboard_fab2(sch_1):tp_cpld1_pr9d"
				( objectStatus "TP_CPLD1_PR9D" )
			)
			( signal "@baseboard_fab2_lib.baseboard_fab2(sch_1):tp_cpld1_pr7c"
				( objectStatus "TP_CPLD1_PR7C" )
			)
			( signal "@baseboard_fab2_lib.baseboard_fab2(sch_1):tp_cpld1_pr9a"
				( objectStatus "TP_CPLD1_PR9A" )
			)
			( signal "@baseboard_fab2_lib.baseboard_fab2(sch_1):tp_cpld1_pr7d"
				( objectStatus "TP_CPLD1_PR7D" )
			)
			( signal "@baseboard_fab2_lib.baseboard_fab2(sch_1):tp_cpld1_pr7a_pclkt1_0"
				( objectStatus "TP_CPLD1_PR7A_PCLKT1_0" )
			)
			( signal "@baseboard_fab2_lib.baseboard_fab2(sch_1):tp_cpld1_pr7b_pclkc1_0"
				( objectStatus "TP_CPLD1_PR7B_PCLKC1_0" )
			)
			( signal "@baseboard_fab2_lib.baseboard_fab2(sch_1):tp_cpld1_pt20d_programn"
				( objectStatus "TP_CPLD1_PT20D_PROGRAMN" )
			)
			( signal "@baseboard_fab2_lib.baseboard_fab2(sch_1):tp_cpld1_pt24c_initn"
				( objectStatus "TP_CPLD1_PT24C_INITN" )
			)
			( signal "@baseboard_fab2_lib.baseboard_fab2(sch_1):tp_cpld1_pt24d_done"
				( objectStatus "TP_CPLD1_PT24D_DONE" )
			)
			( signal "@baseboard_fab2_lib.baseboard_fab2(sch_1):tp_cpu_pch_trigger_in"
				( objectStatus "TP_CPU_PCH_TRIGGER_IN" )
			)
			( signal "@baseboard_fab2_lib.baseboard_fab2(sch_1):tp_cpu_pch_trigger_out"
				( objectStatus "TP_CPU_PCH_TRIGGER_OUT" )
			)
			( signal "@baseboard_fab2_lib.baseboard_fab2(sch_1):tp_cpu0_pe_hp_scl"
				( objectStatus "TP_CPU0_PE_HP_SCL" )
			)
			( signal "@baseboard_fab2_lib.baseboard_fab2(sch_1):tp_cpu0_pe_hp_sda"
				( objectStatus "TP_CPU0_PE_HP_SDA" )
			)
			( signal "@baseboard_fab2_lib.baseboard_fab2(sch_1):tp_cpu0_procdis_g_n"
				( objectStatus "TP_CPU0_PROCDIS_G_N" )
			)
			( signal "@baseboard_fab2_lib.baseboard_fab2(sch_1):tp_cpu0_test_6"
				( objectStatus "TP_CPU0_TEST_6" )
			)
			( signal "@baseboard_fab2_lib.baseboard_fab2(sch_1):tp_cpu0_rsvd_184"
				( objectStatus "TP_CPU0_RSVD_184" )
			)
			( signal "@baseboard_fab2_lib.baseboard_fab2(sch_1):tp_cpu0_rsvd_186"
				( objectStatus "TP_CPU0_RSVD_186" )
			)
			( signal "@baseboard_fab2_lib.baseboard_fab2(sch_1):tp_cpu0_rsvd_189"
				( objectStatus "TP_CPU0_RSVD_189" )
			)
			( signal "@baseboard_fab2_lib.baseboard_fab2(sch_1):tp_cpu0_rsvd_190"
				( objectStatus "TP_CPU0_RSVD_190" )
			)
			( signal "@baseboard_fab2_lib.baseboard_fab2(sch_1):tp_cpu0_rsvd_194"
				( objectStatus "TP_CPU0_RSVD_194" )
			)
			( signal "@baseboard_fab2_lib.baseboard_fab2(sch_1):tp_cpu0_rsvd_198"
				( objectStatus "TP_CPU0_RSVD_198" )
			)
			( signal "@baseboard_fab2_lib.baseboard_fab2(sch_1):tp_cpu0_rsvd_199"
				( objectStatus "TP_CPU0_RSVD_199" )
			)
			( signal "@baseboard_fab2_lib.baseboard_fab2(sch_1):tp_cpu0_rsvd_204"
				( objectStatus "TP_CPU0_RSVD_204" )
			)
			( signal "@baseboard_fab2_lib.baseboard_fab2(sch_1):tp_cpu0_rsvd_205"
				( objectStatus "TP_CPU0_RSVD_205" )
			)
			( signal "@baseboard_fab2_lib.baseboard_fab2(sch_1):tp_cpu0_rsvd_208"
				( objectStatus "TP_CPU0_RSVD_208" )
			)
			( signal "@baseboard_fab2_lib.baseboard_fab2(sch_1):tp_cpu0_rsvd_210"
				( objectStatus "TP_CPU0_RSVD_210" )
			)
			( signal "@baseboard_fab2_lib.baseboard_fab2(sch_1):tp_cpu0_rsvd_211"
				( objectStatus "TP_CPU0_RSVD_211" )
			)
			( signal "@baseboard_fab2_lib.baseboard_fab2(sch_1):tp_cpu0_rsvd_212"
				( objectStatus "TP_CPU0_RSVD_212" )
			)
			( signal "@baseboard_fab2_lib.baseboard_fab2(sch_1):tp_cpu0_rsvd_214"
				( objectStatus "TP_CPU0_RSVD_214" )
			)
			( signal "@baseboard_fab2_lib.baseboard_fab2(sch_1):tp_cpu0_rsvd_216"
				( objectStatus "TP_CPU0_RSVD_216" )
			)
			( signal "@baseboard_fab2_lib.baseboard_fab2(sch_1):tp_cpu0_rsvd_217"
				( objectStatus "TP_CPU0_RSVD_217" )
			)
			( signal "@baseboard_fab2_lib.baseboard_fab2(sch_1):tp_cpu0_rsvd_218"
				( objectStatus "TP_CPU0_RSVD_218" )
			)
			( signal "@baseboard_fab2_lib.baseboard_fab2(sch_1):tp_cpu0_rsvd_219"
				( objectStatus "TP_CPU0_RSVD_219" )
			)
			( signal "@baseboard_fab2_lib.baseboard_fab2(sch_1):tp_cpu0_rsvd_222"
				( objectStatus "TP_CPU0_RSVD_222" )
			)
			( signal "@baseboard_fab2_lib.baseboard_fab2(sch_1):tp_cpu0_rsvd_223"
				( objectStatus "TP_CPU0_RSVD_223" )
			)
			( signal "@baseboard_fab2_lib.baseboard_fab2(sch_1):tp_cpu0_rsvd_224"
				( objectStatus "TP_CPU0_RSVD_224" )
			)
			( signal "@baseboard_fab2_lib.baseboard_fab2(sch_1):tp_cpu0_rsvd_225"
				( objectStatus "TP_CPU0_RSVD_225" )
			)
			( signal "@baseboard_fab2_lib.baseboard_fab2(sch_1):tp_cpu0_rsvd_226"
				( objectStatus "TP_CPU0_RSVD_226" )
			)
			( signal "@baseboard_fab2_lib.baseboard_fab2(sch_1):tp_cpu0_rsvd_227"
				( objectStatus "TP_CPU0_RSVD_227" )
			)
			( signal "@baseboard_fab2_lib.baseboard_fab2(sch_1):tp_cpu0_rsvd_228"
				( objectStatus "TP_CPU0_RSVD_228" )
			)
			( signal "@baseboard_fab2_lib.baseboard_fab2(sch_1):tp_cpu0_rsvd_229"
				( objectStatus "TP_CPU0_RSVD_229" )
			)
			( signal "@baseboard_fab2_lib.baseboard_fab2(sch_1):tp_cpu0_rsvd_230"
				( objectStatus "TP_CPU0_RSVD_230" )
			)
			( signal "@baseboard_fab2_lib.baseboard_fab2(sch_1):tp_cpu0_rsvd_231"
				( objectStatus "TP_CPU0_RSVD_231" )
			)
			( signal "@baseboard_fab2_lib.baseboard_fab2(sch_1):tp_cpu0_rsvd_232"
				( objectStatus "TP_CPU0_RSVD_232" )
			)
			( signal "@baseboard_fab2_lib.baseboard_fab2(sch_1):tp_cpu0_rsvd_233"
				( objectStatus "TP_CPU0_RSVD_233" )
			)
			( signal "@baseboard_fab2_lib.baseboard_fab2(sch_1):tp_cpu0_rsvd_234"
				( objectStatus "TP_CPU0_RSVD_234" )
			)
			( signal "@baseboard_fab2_lib.baseboard_fab2(sch_1):tp_cpu0_rsvd_235"
				( objectStatus "TP_CPU0_RSVD_235" )
			)
			( signal "@baseboard_fab2_lib.baseboard_fab2(sch_1):tp_cpu0_rsvd_236"
				( objectStatus "TP_CPU0_RSVD_236" )
			)
			( signal "@baseboard_fab2_lib.baseboard_fab2(sch_1):tp_cpu0_rsvd_237"
				( objectStatus "TP_CPU0_RSVD_237" )
			)
			( signal "@baseboard_fab2_lib.baseboard_fab2(sch_1):tp_cpu0_rsvd_238"
				( objectStatus "TP_CPU0_RSVD_238" )
			)
			( signal "@baseboard_fab2_lib.baseboard_fab2(sch_1):tp_cpu0_rsvd_239"
				( objectStatus "TP_CPU0_RSVD_239" )
			)
			( signal "@baseboard_fab2_lib.baseboard_fab2(sch_1):tp_cpu0_rsvd_240"
				( objectStatus "TP_CPU0_RSVD_240" )
			)
			( signal "@baseboard_fab2_lib.baseboard_fab2(sch_1):tp_cpu0_rsvd_241"
				( objectStatus "TP_CPU0_RSVD_241" )
			)
			( signal "@baseboard_fab2_lib.baseboard_fab2(sch_1):tp_cpu0_rsvd_242"
				( objectStatus "TP_CPU0_RSVD_242" )
			)
			( signal "@baseboard_fab2_lib.baseboard_fab2(sch_1):tp_cpu0_rsvd_243"
				( objectStatus "TP_CPU0_RSVD_243" )
			)
			( signal "@baseboard_fab2_lib.baseboard_fab2(sch_1):tp_cpu0_rsvd_244"
				( objectStatus "TP_CPU0_RSVD_244" )
			)
			( signal "@baseboard_fab2_lib.baseboard_fab2(sch_1):tp_cpu0_rsvd_245"
				( objectStatus "TP_CPU0_RSVD_245" )
			)
			( signal "@baseboard_fab2_lib.baseboard_fab2(sch_1):tp_cpu0_rsvd_246"
				( objectStatus "TP_CPU0_RSVD_246" )
			)
			( signal "@baseboard_fab2_lib.baseboard_fab2(sch_1):tp_cpu1_rsvd_223"
				( objectStatus "TP_CPU1_RSVD_223" )
			)
			( signal "@baseboard_fab2_lib.baseboard_fab2(sch_1):tp_cpu1_rsvd_224"
				( objectStatus "TP_CPU1_RSVD_224" )
			)
			( signal "@baseboard_fab2_lib.baseboard_fab2(sch_1):tp_cpu1_rsvd_225"
				( objectStatus "TP_CPU1_RSVD_225" )
			)
			( signal "@baseboard_fab2_lib.baseboard_fab2(sch_1):tp_cpu1_rsvd_226"
				( objectStatus "TP_CPU1_RSVD_226" )
			)
			( signal "@baseboard_fab2_lib.baseboard_fab2(sch_1):tp_cpu1_rsvd_227"
				( objectStatus "TP_CPU1_RSVD_227" )
			)
			( signal "@baseboard_fab2_lib.baseboard_fab2(sch_1):tp_cpu1_rsvd_228"
				( objectStatus "TP_CPU1_RSVD_228" )
			)
			( signal "@baseboard_fab2_lib.baseboard_fab2(sch_1):tp_cpu1_rsvd_229"
				( objectStatus "TP_CPU1_RSVD_229" )
			)
			( signal "@baseboard_fab2_lib.baseboard_fab2(sch_1):tp_cpu1_rsvd_230"
				( objectStatus "TP_CPU1_RSVD_230" )
			)
			( signal "@baseboard_fab2_lib.baseboard_fab2(sch_1):tp_cpu1_rsvd_231"
				( objectStatus "TP_CPU1_RSVD_231" )
			)
			( signal "@baseboard_fab2_lib.baseboard_fab2(sch_1):tp_cpu1_rsvd_232"
				( objectStatus "TP_CPU1_RSVD_232" )
			)
			( signal "@baseboard_fab2_lib.baseboard_fab2(sch_1):tp_cpu1_rsvd_233"
				( objectStatus "TP_CPU1_RSVD_233" )
			)
			( signal "@baseboard_fab2_lib.baseboard_fab2(sch_1):tp_cpu1_rsvd_234"
				( objectStatus "TP_CPU1_RSVD_234" )
			)
			( signal "@baseboard_fab2_lib.baseboard_fab2(sch_1):tp_cpu0_rsvd_259"
				( objectStatus "TP_CPU0_RSVD_259" )
			)
			( signal "@baseboard_fab2_lib.baseboard_fab2(sch_1):tp_cpu0_rsvd_260"
				( objectStatus "TP_CPU0_RSVD_260" )
			)
			( signal "@baseboard_fab2_lib.baseboard_fab2(sch_1):tp_cpu0_rsvd_261"
				( objectStatus "TP_CPU0_RSVD_261" )
			)
			( signal "@baseboard_fab2_lib.baseboard_fab2(sch_1):tp_cpu0_rsvd_262"
				( objectStatus "TP_CPU0_RSVD_262" )
			)
			( signal "@baseboard_fab2_lib.baseboard_fab2(sch_1):tp_cpu0_rsvd_263"
				( objectStatus "TP_CPU0_RSVD_263" )
			)
			( signal "@baseboard_fab2_lib.baseboard_fab2(sch_1):tp_cpu0_rsvd_264"
				( objectStatus "TP_CPU0_RSVD_264" )
			)
			( signal "@baseboard_fab2_lib.baseboard_fab2(sch_1):tp_cpu0_rsvd_265"
				( objectStatus "TP_CPU0_RSVD_265" )
			)
			( signal "@baseboard_fab2_lib.baseboard_fab2(sch_1):tp_cpu0_rsvd_266"
				( objectStatus "TP_CPU0_RSVD_266" )
			)
			( signal "@baseboard_fab2_lib.baseboard_fab2(sch_1):tp_cpu0_rsvd_267"
				( objectStatus "TP_CPU0_RSVD_267" )
			)
			( signal "@baseboard_fab2_lib.baseboard_fab2(sch_1):tp_cpu0_rsvd_268"
				( objectStatus "TP_CPU0_RSVD_268" )
			)
			( signal "@baseboard_fab2_lib.baseboard_fab2(sch_1):tp_cpu0_rsvd_269"
				( objectStatus "TP_CPU0_RSVD_269" )
			)
			( signal "@baseboard_fab2_lib.baseboard_fab2(sch_1):tp_cpu0_rsvd_270"
				( objectStatus "TP_CPU0_RSVD_270" )
			)
			( signal "@baseboard_fab2_lib.baseboard_fab2(sch_1):tp_cpu0_rsvd_271"
				( objectStatus "TP_CPU0_RSVD_271" )
			)
			( signal "@baseboard_fab2_lib.baseboard_fab2(sch_1):tp_cpu0_rsvd_272"
				( objectStatus "TP_CPU0_RSVD_272" )
			)
			( signal "@baseboard_fab2_lib.baseboard_fab2(sch_1):tp_cpu0_rsvd_273"
				( objectStatus "TP_CPU0_RSVD_273" )
			)
			( signal "@baseboard_fab2_lib.baseboard_fab2(sch_1):tp_cpu0_rsvd_274"
				( objectStatus "TP_CPU0_RSVD_274" )
			)
			( signal "@baseboard_fab2_lib.baseboard_fab2(sch_1):tp_cpu0_rsvd_276"
				( objectStatus "TP_CPU0_RSVD_276" )
			)
			( signal "@baseboard_fab2_lib.baseboard_fab2(sch_1):tp_cpu0_rsvd_277"
				( objectStatus "TP_CPU0_RSVD_277" )
			)
			( signal "@baseboard_fab2_lib.baseboard_fab2(sch_1):tp_cpu0_rsvd_278"
				( objectStatus "TP_CPU0_RSVD_278" )
			)
			( signal "@baseboard_fab2_lib.baseboard_fab2(sch_1):tp_cpu0_rsvd_279"
				( objectStatus "TP_CPU0_RSVD_279" )
			)
			( signal "@baseboard_fab2_lib.baseboard_fab2(sch_1):tp_cpu0_rsvd_280"
				( objectStatus "TP_CPU0_RSVD_280" )
			)
			( signal "@baseboard_fab2_lib.baseboard_fab2(sch_1):tp_cpu0_rsvd_281"
				( objectStatus "TP_CPU0_RSVD_281" )
			)
			( signal "@baseboard_fab2_lib.baseboard_fab2(sch_1):tp_cpu0_rsvd_284"
				( objectStatus "TP_CPU0_RSVD_284" )
			)
			( signal "@baseboard_fab2_lib.baseboard_fab2(sch_1):tp_cpu0_rsvd_285"
				( objectStatus "TP_CPU0_RSVD_285" )
			)
			( signal "@baseboard_fab2_lib.baseboard_fab2(sch_1):tp_cpu0_rsvd_286"
				( objectStatus "TP_CPU0_RSVD_286" )
			)
			( signal "@baseboard_fab2_lib.baseboard_fab2(sch_1):tp_cpu0_rsvd_288"
				( objectStatus "TP_CPU0_RSVD_288" )
			)
			( signal "@baseboard_fab2_lib.baseboard_fab2(sch_1):tp_cpu0_rsvd_289"
				( objectStatus "TP_CPU0_RSVD_289" )
			)
			( signal "@baseboard_fab2_lib.baseboard_fab2(sch_1):tp_cpu0_rsvd_290"
				( objectStatus "TP_CPU0_RSVD_290" )
			)
			( signal "@baseboard_fab2_lib.baseboard_fab2(sch_1):tp_cpu0_rsvd_291"
				( objectStatus "TP_CPU0_RSVD_291" )
			)
			( signal "@baseboard_fab2_lib.baseboard_fab2(sch_1):tp_cpu0_rsvd_292"
				( objectStatus "TP_CPU0_RSVD_292" )
			)
			( signal "@baseboard_fab2_lib.baseboard_fab2(sch_1):tp_cpu0_rsvd_293"
				( objectStatus "TP_CPU0_RSVD_293" )
			)
			( signal "@baseboard_fab2_lib.baseboard_fab2(sch_1):tp_cpu0_rsvd_300"
				( objectStatus "TP_CPU0_RSVD_300" )
			)
			( signal "@baseboard_fab2_lib.baseboard_fab2(sch_1):tp_cpu0_socket_id_2"
				( objectStatus "TP_CPU0_SOCKET_ID_2" )
			)
			( signal "@baseboard_fab2_lib.baseboard_fab2(sch_1):tp_cpu0_rsvd_test_5"
				( objectStatus "TP_CPU0_RSVD_TEST_5" )
			)
			( signal "@baseboard_fab2_lib.baseboard_fab2(sch_1):tp_cpu0_upi2_rsvd_ca12"
				( objectStatus "TP_CPU0_UPI2_RSVD_CA12" )
			)
			( signal "@baseboard_fab2_lib.baseboard_fab2(sch_1):tp_cpu0_upi2_rsvd_cb11"
				( objectStatus "TP_CPU0_UPI2_RSVD_CB11" )
			)
			( signal "@baseboard_fab2_lib.baseboard_fab2(sch_1):tp_cpu0_upi2_rsvd_cc10"
				( objectStatus "TP_CPU0_UPI2_RSVD_CC10" )
			)
			( signal "@baseboard_fab2_lib.baseboard_fab2(sch_1):tp_cpu0_upi2_rsvd_cc12"
				( objectStatus "TP_CPU0_UPI2_RSVD_CC12" )
			)
			( signal "@baseboard_fab2_lib.baseboard_fab2(sch_1):tp_cpu0_upi2_rsvd_cd11"
				( objectStatus "TP_CPU0_UPI2_RSVD_CD11" )
			)
			( signal "@baseboard_fab2_lib.baseboard_fab2(sch_1):tp_cpu0_upi2_rsvd_ce12"
				( objectStatus "TP_CPU0_UPI2_RSVD_CE12" )
			)
			( signal "@baseboard_fab2_lib.baseboard_fab2(sch_1):tp_cpu0_upi2_rsvd_cf11"
				( objectStatus "TP_CPU0_UPI2_RSVD_CF11" )
			)
			( signal "@baseboard_fab2_lib.baseboard_fab2(sch_1):tp_cpu0_upi2_rsvd_cf13"
				( objectStatus "TP_CPU0_UPI2_RSVD_CF13" )
			)
			( signal "@baseboard_fab2_lib.baseboard_fab2(sch_1):tp_cpu0_upi2_rsvd_cg12"
				( objectStatus "TP_CPU0_UPI2_RSVD_CG12" )
			)
			( signal "@baseboard_fab2_lib.baseboard_fab2(sch_1):tp_cpu0_upi2_rsvd_ch11"
				( objectStatus "TP_CPU0_UPI2_RSVD_CH11" )
			)
			( signal "@baseboard_fab2_lib.baseboard_fab2(sch_1):tp_cpu0_upi2_rsvd_ch13"
				( objectStatus "TP_CPU0_UPI2_RSVD_CH13" )
			)
			( signal "@baseboard_fab2_lib.baseboard_fab2(sch_1):tp_cpu0_upi2_rsvd_cj14"
				( objectStatus "TP_CPU0_UPI2_RSVD_CJ14" )
			)
			( signal "@baseboard_fab2_lib.baseboard_fab2(sch_1):tp_cpu0_upi2_rsvd_ck13"
				( objectStatus "TP_CPU0_UPI2_RSVD_CK13" )
			)
			( signal "@baseboard_fab2_lib.baseboard_fab2(sch_1):tp_cpu0_upi2_rsvd_cm13"
				( objectStatus "TP_CPU0_UPI2_RSVD_CM13" )
			)
			( signal "@baseboard_fab2_lib.baseboard_fab2(sch_1):tp_cpu0_upi2_rsvd_cr14"
				( objectStatus "TP_CPU0_UPI2_RSVD_CR14" )
			)
			( signal "@baseboard_fab2_lib.baseboard_fab2(sch_1):tp_cpu0_upi2_rsvd_cu14"
				( objectStatus "TP_CPU0_UPI2_RSVD_CU14" )
			)
			( signal "@baseboard_fab2_lib.baseboard_fab2(sch_1):tp_cpu0_upi2_rsvd_cv13"
				( objectStatus "TP_CPU0_UPI2_RSVD_CV13" )
			)
			( signal "@baseboard_fab2_lib.baseboard_fab2(sch_1):tp_cpu1_upi2_rsvd_cg12"
				( objectStatus "TP_CPU1_UPI2_RSVD_CG12" )
			)
			( signal "@baseboard_fab2_lib.baseboard_fab2(sch_1):tp_cpu1_upi2_rsvd_ch11"
				( objectStatus "TP_CPU1_UPI2_RSVD_CH11" )
			)
			( signal "@baseboard_fab2_lib.baseboard_fab2(sch_1):tp_cpu1_upi2_rsvd_ch13"
				( objectStatus "TP_CPU1_UPI2_RSVD_CH13" )
			)
			( signal "@baseboard_fab2_lib.baseboard_fab2(sch_1):tp_cpu1_upi2_rsvd_cj14"
				( objectStatus "TP_CPU1_UPI2_RSVD_CJ14" )
			)
			( signal "@baseboard_fab2_lib.baseboard_fab2(sch_1):tp_cpu1_upi2_rsvd_ck13"
				( objectStatus "TP_CPU1_UPI2_RSVD_CK13" )
			)
			( signal "@baseboard_fab2_lib.baseboard_fab2(sch_1):tp_cpu1_upi2_rsvd_cm13"
				( objectStatus "TP_CPU1_UPI2_RSVD_CM13" )
			)
			( signal "@baseboard_fab2_lib.baseboard_fab2(sch_1):tp_cpu0_upi2_rsvd_dd15"
				( objectStatus "TP_CPU0_UPI2_RSVD_DD15" )
			)
			( signal "@baseboard_fab2_lib.baseboard_fab2(sch_1):tp_cpu0_upi2_rsvd_dd17"
				( objectStatus "TP_CPU0_UPI2_RSVD_DD17" )
			)
			( signal "@baseboard_fab2_lib.baseboard_fab2(sch_1):tp_cpu0_upi2_rsvd_de16"
				( objectStatus "TP_CPU0_UPI2_RSVD_DE16" )
			)
			( signal "@baseboard_fab2_lib.baseboard_fab2(sch_1):tp_cpu0_upi2_rsvd_df15"
				( objectStatus "TP_CPU0_UPI2_RSVD_DF15" )
			)
			( signal "@baseboard_fab2_lib.baseboard_fab2(sch_1):tp_cpu0_upi2_rsvd_df17"
				( objectStatus "TP_CPU0_UPI2_RSVD_DF17" )
			)
			( signal "@baseboard_fab2_lib.baseboard_fab2(sch_1):tp_cpu0_upi2_rsvd_dg18"
				( objectStatus "TP_CPU0_UPI2_RSVD_DG18" )
			)
			( signal "@baseboard_fab2_lib.baseboard_fab2(sch_1):tp_cpu0_upi2_rsvd_dg20"
				( objectStatus "TP_CPU0_UPI2_RSVD_DG20" )
			)
			( signal "@baseboard_fab2_lib.baseboard_fab2(sch_1):tp_cpu0_upi2_rsvd_dh17"
				( objectStatus "TP_CPU0_UPI2_RSVD_DH17" )
			)
			( signal "@baseboard_fab2_lib.baseboard_fab2(sch_1):tp_cpu0_upi2_rsvd_dh19"
				( objectStatus "TP_CPU0_UPI2_RSVD_DH19" )
			)
			( signal "@baseboard_fab2_lib.baseboard_fab2(sch_1):tp_cpu0_upi2_rsvd_dj18"
				( objectStatus "TP_CPU0_UPI2_RSVD_DJ18" )
			)
			( signal "@baseboard_fab2_lib.baseboard_fab2(sch_1):tp_cpu0_upi2_rsvd_dj20"
				( objectStatus "TP_CPU0_UPI2_RSVD_DJ20" )
			)
			( signal "@baseboard_fab2_lib.baseboard_fab2(sch_1):tp_cpu0_upi2_rsvd_dk17"
				( objectStatus "TP_CPU0_UPI2_RSVD_DK17" )
			)
			( signal "@baseboard_fab2_lib.baseboard_fab2(sch_1):tp_cpu0_upi2_rsvd_dk19"
				( objectStatus "TP_CPU0_UPI2_RSVD_DK19" )
			)
			( signal "@baseboard_fab2_lib.baseboard_fab2(sch_1):tp_cpu0_upi2_rsvd_dl20"
				( objectStatus "TP_CPU0_UPI2_RSVD_DL20" )
			)
			( signal "@baseboard_fab2_lib.baseboard_fab2(sch_1):tp_cpu0_upi2_rsvd_dm21"
				( objectStatus "TP_CPU0_UPI2_RSVD_DM21" )
			)
			( signal "@baseboard_fab2_lib.baseboard_fab2(sch_1):tp_cpu0_upi2_rsvd_dn20"
				( objectStatus "TP_CPU0_UPI2_RSVD_DN20" )
			)
			( signal "@baseboard_fab2_lib.baseboard_fab2(sch_1):tp_cpu0_upi2_rsvd_dp21"
				( objectStatus "TP_CPU0_UPI2_RSVD_DP21" )
			)
			( signal "@baseboard_fab2_lib.baseboard_fab2(sch_1):tp_cpu0_upi2_rsvd_dt21"
				( objectStatus "TP_CPU0_UPI2_RSVD_DT21" )
			)
			( signal "@baseboard_fab2_lib.baseboard_fab2(sch_1):tp_cpu1_dmi_rx_dn0"
				( objectStatus "TP_CPU1_DMI_RX_DN0" )
			)
			( signal "@baseboard_fab2_lib.baseboard_fab2(sch_1):tp_cpu1_dmi_rx_dn1"
				( objectStatus "TP_CPU1_DMI_RX_DN1" )
			)
			( signal "@baseboard_fab2_lib.baseboard_fab2(sch_1):tp_cpu1_dmi_rx_dn2"
				( objectStatus "TP_CPU1_DMI_RX_DN2" )
			)
			( signal "@baseboard_fab2_lib.baseboard_fab2(sch_1):tp_cpu1_dmi_rx_dn3"
				( objectStatus "TP_CPU1_DMI_RX_DN3" )
			)
			( signal "@baseboard_fab2_lib.baseboard_fab2(sch_1):tp_cpu1_dmi_rx_dp0"
				( objectStatus "TP_CPU1_DMI_RX_DP0" )
			)
			( signal "@baseboard_fab2_lib.baseboard_fab2(sch_1):tp_cpu1_dmi_rx_dp1"
				( objectStatus "TP_CPU1_DMI_RX_DP1" )
			)
			( signal "@baseboard_fab2_lib.baseboard_fab2(sch_1):tp_cpu1_dmi_rx_dp2"
				( objectStatus "TP_CPU1_DMI_RX_DP2" )
			)
			( signal "@baseboard_fab2_lib.baseboard_fab2(sch_1):tp_cpu1_dmi_rx_dp3"
				( objectStatus "TP_CPU1_DMI_RX_DP3" )
			)
			( signal "@baseboard_fab2_lib.baseboard_fab2(sch_1):tp_cpu1_dmi_tx_dn0"
				( objectStatus "TP_CPU1_DMI_TX_DN0" )
			)
			( signal "@baseboard_fab2_lib.baseboard_fab2(sch_1):tp_cpu1_dmi_tx_dn1"
				( objectStatus "TP_CPU1_DMI_TX_DN1" )
			)
			( signal "@baseboard_fab2_lib.baseboard_fab2(sch_1):tp_cpu1_dmi_tx_dn2"
				( objectStatus "TP_CPU1_DMI_TX_DN2" )
			)
			( signal "@baseboard_fab2_lib.baseboard_fab2(sch_1):tp_cpu1_dmi_tx_dn3"
				( objectStatus "TP_CPU1_DMI_TX_DN3" )
			)
			( signal "@baseboard_fab2_lib.baseboard_fab2(sch_1):tp_cpu1_dmi_tx_dp0"
				( objectStatus "TP_CPU1_DMI_TX_DP0" )
			)
			( signal "@baseboard_fab2_lib.baseboard_fab2(sch_1):tp_cpu1_dmi_tx_dp1"
				( objectStatus "TP_CPU1_DMI_TX_DP1" )
			)
			( signal "@baseboard_fab2_lib.baseboard_fab2(sch_1):tp_cpu1_dmi_tx_dp2"
				( objectStatus "TP_CPU1_DMI_TX_DP2" )
			)
			( signal "@baseboard_fab2_lib.baseboard_fab2(sch_1):tp_cpu1_dmi_tx_dp3"
				( objectStatus "TP_CPU1_DMI_TX_DP3" )
			)
			( signal "@baseboard_fab2_lib.baseboard_fab2(sch_1):tp_cpu1_nmi"
				( objectStatus "TP_CPU1_NMI" )
			)
			( signal "@baseboard_fab2_lib.baseboard_fab2(sch_1):tp_cpu1_proc_dis_g_n"
				( objectStatus "TP_CPU1_PROC_DIS_G_N" )
			)
			( signal "@baseboard_fab2_lib.baseboard_fab2(sch_1):tp_cpu1_test_6"
				( objectStatus "TP_CPU1_TEST_6" )
			)
			( signal "@baseboard_fab2_lib.baseboard_fab2(sch_1):tp_cpu1_rsvd_174"
				( objectStatus "TP_CPU1_RSVD_174" )
			)
			( signal "@baseboard_fab2_lib.baseboard_fab2(sch_1):tp_cpu1_rsvd_176"
				( objectStatus "TP_CPU1_RSVD_176" )
			)
			( signal "@baseboard_fab2_lib.baseboard_fab2(sch_1):tp_cpu1_rsvd_177"
				( objectStatus "TP_CPU1_RSVD_177" )
			)
			( signal "@baseboard_fab2_lib.baseboard_fab2(sch_1):tp_cpu1_rsvd_178"
				( objectStatus "TP_CPU1_RSVD_178" )
			)
			( signal "@baseboard_fab2_lib.baseboard_fab2(sch_1):tp_cpu1_rsvd_179"
				( objectStatus "TP_CPU1_RSVD_179" )
			)
			( signal "@baseboard_fab2_lib.baseboard_fab2(sch_1):tp_cpu1_rsvd_180"
				( objectStatus "TP_CPU1_RSVD_180" )
			)
			( signal "@baseboard_fab2_lib.baseboard_fab2(sch_1):tp_cpu1_rsvd_181"
				( objectStatus "TP_CPU1_RSVD_181" )
			)
			( signal "@baseboard_fab2_lib.baseboard_fab2(sch_1):tp_cpu1_rsvd_182"
				( objectStatus "TP_CPU1_RSVD_182" )
			)
			( signal "@baseboard_fab2_lib.baseboard_fab2(sch_1):tp_cpu1_rsvd_183"
				( objectStatus "TP_CPU1_RSVD_183" )
			)
			( signal "@baseboard_fab2_lib.baseboard_fab2(sch_1):tp_cpu1_rsvd_184"
				( objectStatus "TP_CPU1_RSVD_184" )
			)
			( signal "@baseboard_fab2_lib.baseboard_fab2(sch_1):tp_cpu1_rsvd_186"
				( objectStatus "TP_CPU1_RSVD_186" )
			)
			( signal "@baseboard_fab2_lib.baseboard_fab2(sch_1):tp_cpu1_rsvd_189"
				( objectStatus "TP_CPU1_RSVD_189" )
			)
			( signal "@baseboard_fab2_lib.baseboard_fab2(sch_1):tp_cpu1_rsvd_190"
				( objectStatus "TP_CPU1_RSVD_190" )
			)
			( signal "@baseboard_fab2_lib.baseboard_fab2(sch_1):tp_cpu1_rsvd_204"
				( objectStatus "TP_CPU1_RSVD_204" )
			)
			( signal "@baseboard_fab2_lib.baseboard_fab2(sch_1):tp_cpu1_rsvd_205"
				( objectStatus "TP_CPU1_RSVD_205" )
			)
			( signal "@baseboard_fab2_lib.baseboard_fab2(sch_1):tp_cpu1_rsvd_208"
				( objectStatus "TP_CPU1_RSVD_208" )
			)
			( signal "@baseboard_fab2_lib.baseboard_fab2(sch_1):tp_cpu1_rsvd_210"
				( objectStatus "TP_CPU1_RSVD_210" )
			)
			( signal "@baseboard_fab2_lib.baseboard_fab2(sch_1):tp_cpu1_rsvd_211"
				( objectStatus "TP_CPU1_RSVD_211" )
			)
			( signal "@baseboard_fab2_lib.baseboard_fab2(sch_1):tp_cpu1_rsvd_212"
				( objectStatus "TP_CPU1_RSVD_212" )
			)
			( signal "@baseboard_fab2_lib.baseboard_fab2(sch_1):tp_cpu1_rsvd_214"
				( objectStatus "TP_CPU1_RSVD_214" )
			)
			( signal "@baseboard_fab2_lib.baseboard_fab2(sch_1):tp_cpu1_rsvd_216"
				( objectStatus "TP_CPU1_RSVD_216" )
			)
			( signal "@baseboard_fab2_lib.baseboard_fab2(sch_1):tp_cpu1_rsvd_217"
				( objectStatus "TP_CPU1_RSVD_217" )
			)
			( signal "@baseboard_fab2_lib.baseboard_fab2(sch_1):tp_cpu1_rsvd_218"
				( objectStatus "TP_CPU1_RSVD_218" )
			)
			( signal "@baseboard_fab2_lib.baseboard_fab2(sch_1):tp_cpu1_rsvd_219"
				( objectStatus "TP_CPU1_RSVD_219" )
			)
			( signal "@baseboard_fab2_lib.baseboard_fab2(sch_1):tp_cpu1_rsvd_222"
				( objectStatus "TP_CPU1_RSVD_222" )
			)
			( signal "@baseboard_fab2_lib.baseboard_fab2(sch_1):tp_ioe4"
				( objectStatus "TP_IOE4" )
			)
			( signal "@baseboard_fab2_lib.baseboard_fab2(sch_1):tp_iof4"
				( objectStatus "TP_IOF4" )
			)
			( signal "@baseboard_fab2_lib.baseboard_fab2(sch_1):tp_iog3"
				( objectStatus "TP_IOG3" )
			)
			( signal "@baseboard_fab2_lib.baseboard_fab2(sch_1):tp_ioh3"
				( objectStatus "TP_IOH3" )
			)
			( signal "@baseboard_fab2_lib.baseboard_fab2(sch_1):tp_ioh4"
				( objectStatus "TP_IOH4" )
			)
			( signal "@baseboard_fab2_lib.baseboard_fab2(sch_1):tp_ioi4"
				( objectStatus "TP_IOI4" )
			)
			( signal "@baseboard_fab2_lib.baseboard_fab2(sch_1):tp_cpld1_pt16b"
				( objectStatus "TP_CPLD1_PT16B" )
			)
			( signal "@baseboard_fab2_lib.baseboard_fab2(sch_1):tp_k4b1g16_bmc_nc0"
				( objectStatus "TP_K4B1G16_BMC_NC0" )
			)
			( signal "@baseboard_fab2_lib.baseboard_fab2(sch_1):tp_k4b1g16_bmc_nc1"
				( objectStatus "TP_K4B1G16_BMC_NC1" )
			)
			( signal "@baseboard_fab2_lib.baseboard_fab2(sch_1):tp_k4b1g16_bmc_nc2"
				( objectStatus "TP_K4B1G16_BMC_NC2" )
			)
			( signal "@baseboard_fab2_lib.baseboard_fab2(sch_1):tp_cpu1_rsvd_235"
				( objectStatus "TP_CPU1_RSVD_235" )
			)
			( signal "@baseboard_fab2_lib.baseboard_fab2(sch_1):tp_cpu1_rsvd_236"
				( objectStatus "TP_CPU1_RSVD_236" )
			)
			( signal "@baseboard_fab2_lib.baseboard_fab2(sch_1):tp_cpu1_rsvd_237"
				( objectStatus "TP_CPU1_RSVD_237" )
			)
			( signal "@baseboard_fab2_lib.baseboard_fab2(sch_1):tp_cpu1_rsvd_238"
				( objectStatus "TP_CPU1_RSVD_238" )
			)
			( signal "@baseboard_fab2_lib.baseboard_fab2(sch_1):tp_cpu1_rsvd_239"
				( objectStatus "TP_CPU1_RSVD_239" )
			)
			( signal "@baseboard_fab2_lib.baseboard_fab2(sch_1):tp_cpu1_rsvd_240"
				( objectStatus "TP_CPU1_RSVD_240" )
			)
			( signal "@baseboard_fab2_lib.baseboard_fab2(sch_1):tp_cpu1_rsvd_241"
				( objectStatus "TP_CPU1_RSVD_241" )
			)
			( signal "@baseboard_fab2_lib.baseboard_fab2(sch_1):tp_cpu1_rsvd_242"
				( objectStatus "TP_CPU1_RSVD_242" )
			)
			( signal "@baseboard_fab2_lib.baseboard_fab2(sch_1):tp_cpu1_rsvd_243"
				( objectStatus "TP_CPU1_RSVD_243" )
			)
			( signal "@baseboard_fab2_lib.baseboard_fab2(sch_1):tp_cpu1_rsvd_244"
				( objectStatus "TP_CPU1_RSVD_244" )
			)
			( signal "@baseboard_fab2_lib.baseboard_fab2(sch_1):tp_cpu1_rsvd_245"
				( objectStatus "TP_CPU1_RSVD_245" )
			)
			( signal "@baseboard_fab2_lib.baseboard_fab2(sch_1):tp_cpu1_rsvd_246"
				( objectStatus "TP_CPU1_RSVD_246" )
			)
			( signal "@baseboard_fab2_lib.baseboard_fab2(sch_1):tp_cpu1_rsvd_247"
				( objectStatus "TP_CPU1_RSVD_247" )
			)
			( signal "@baseboard_fab2_lib.baseboard_fab2(sch_1):tp_cpu1_rsvd_248"
				( objectStatus "TP_CPU1_RSVD_248" )
			)
			( signal "@baseboard_fab2_lib.baseboard_fab2(sch_1):tp_cpu1_rsvd_249"
				( objectStatus "TP_CPU1_RSVD_249" )
			)
			( signal "@baseboard_fab2_lib.baseboard_fab2(sch_1):tp_cpu1_rsvd_250"
				( objectStatus "TP_CPU1_RSVD_250" )
			)
			( signal "@baseboard_fab2_lib.baseboard_fab2(sch_1):tp_cpu1_rsvd_251"
				( objectStatus "TP_CPU1_RSVD_251" )
			)
			( signal "@baseboard_fab2_lib.baseboard_fab2(sch_1):tp_cpu1_rsvd_252"
				( objectStatus "TP_CPU1_RSVD_252" )
			)
			( signal "@baseboard_fab2_lib.baseboard_fab2(sch_1):tp_cpu1_rsvd_253"
				( objectStatus "TP_CPU1_RSVD_253" )
			)
			( signal "@baseboard_fab2_lib.baseboard_fab2(sch_1):tp_cpu1_rsvd_254"
				( objectStatus "TP_CPU1_RSVD_254" )
			)
			( signal "@baseboard_fab2_lib.baseboard_fab2(sch_1):tp_cpu1_rsvd_255"
				( objectStatus "TP_CPU1_RSVD_255" )
			)
			( signal "@baseboard_fab2_lib.baseboard_fab2(sch_1):tp_cpu1_rsvd_256"
				( objectStatus "TP_CPU1_RSVD_256" )
			)
			( signal "@baseboard_fab2_lib.baseboard_fab2(sch_1):tp_cpu1_rsvd_258"
				( objectStatus "TP_CPU1_RSVD_258" )
			)
			( signal "@baseboard_fab2_lib.baseboard_fab2(sch_1):tp_cpu1_rsvd_259"
				( objectStatus "TP_CPU1_RSVD_259" )
			)
			( signal "@baseboard_fab2_lib.baseboard_fab2(sch_1):tp_cpu1_rsvd_260"
				( objectStatus "TP_CPU1_RSVD_260" )
			)
			( signal "@baseboard_fab2_lib.baseboard_fab2(sch_1):tp_cpu1_rsvd_261"
				( objectStatus "TP_CPU1_RSVD_261" )
			)
			( signal "@baseboard_fab2_lib.baseboard_fab2(sch_1):tp_cpu1_rsvd_262"
				( objectStatus "TP_CPU1_RSVD_262" )
			)
			( signal "@baseboard_fab2_lib.baseboard_fab2(sch_1):tp_cpu1_rsvd_263"
				( objectStatus "TP_CPU1_RSVD_263" )
			)
			( signal "@baseboard_fab2_lib.baseboard_fab2(sch_1):tp_cpu1_rsvd_264"
				( objectStatus "TP_CPU1_RSVD_264" )
			)
			( signal "@baseboard_fab2_lib.baseboard_fab2(sch_1):tp_cpu1_rsvd_265"
				( objectStatus "TP_CPU1_RSVD_265" )
			)
			( signal "@baseboard_fab2_lib.baseboard_fab2(sch_1):tp_cpu1_rsvd_266"
				( objectStatus "TP_CPU1_RSVD_266" )
			)
			( signal "@baseboard_fab2_lib.baseboard_fab2(sch_1):tp_cpu1_rsvd_267"
				( objectStatus "TP_CPU1_RSVD_267" )
			)
			( signal "@baseboard_fab2_lib.baseboard_fab2(sch_1):tp_cpu1_rsvd_268"
				( objectStatus "TP_CPU1_RSVD_268" )
			)
			( signal "@baseboard_fab2_lib.baseboard_fab2(sch_1):tp_cpu1_rsvd_269"
				( objectStatus "TP_CPU1_RSVD_269" )
			)
			( signal "@baseboard_fab2_lib.baseboard_fab2(sch_1):tp_cpu1_rsvd_270"
				( objectStatus "TP_CPU1_RSVD_270" )
			)
			( signal "@baseboard_fab2_lib.baseboard_fab2(sch_1):tp_cpu1_rsvd_271"
				( objectStatus "TP_CPU1_RSVD_271" )
			)
			( signal "@baseboard_fab2_lib.baseboard_fab2(sch_1):tp_cpu1_rsvd_272"
				( objectStatus "TP_CPU1_RSVD_272" )
			)
			( signal "@baseboard_fab2_lib.baseboard_fab2(sch_1):tp_cpu1_rsvd_273"
				( objectStatus "TP_CPU1_RSVD_273" )
			)
			( signal "@baseboard_fab2_lib.baseboard_fab2(sch_1):tp_cpu1_rsvd_274"
				( objectStatus "TP_CPU1_RSVD_274" )
			)
			( signal "@baseboard_fab2_lib.baseboard_fab2(sch_1):tp_cpu1_rsvd_276"
				( objectStatus "TP_CPU1_RSVD_276" )
			)
			( signal "@baseboard_fab2_lib.baseboard_fab2(sch_1):tp_cpu1_rsvd_277"
				( objectStatus "TP_CPU1_RSVD_277" )
			)
			( signal "@baseboard_fab2_lib.baseboard_fab2(sch_1):tp_cpu1_rsvd_278"
				( objectStatus "TP_CPU1_RSVD_278" )
			)
			( signal "@baseboard_fab2_lib.baseboard_fab2(sch_1):tp_cpu1_rsvd_279"
				( objectStatus "TP_CPU1_RSVD_279" )
			)
			( signal "@baseboard_fab2_lib.baseboard_fab2(sch_1):tp_cpu1_rsvd_280"
				( objectStatus "TP_CPU1_RSVD_280" )
			)
			( signal "@baseboard_fab2_lib.baseboard_fab2(sch_1):tp_cpu1_rsvd_281"
				( objectStatus "TP_CPU1_RSVD_281" )
			)
			( signal "@baseboard_fab2_lib.baseboard_fab2(sch_1):tp_cpu1_rsvd_284"
				( objectStatus "TP_CPU1_RSVD_284" )
			)
			( signal "@baseboard_fab2_lib.baseboard_fab2(sch_1):tp_cpu1_rsvd_285"
				( objectStatus "TP_CPU1_RSVD_285" )
			)
			( signal "@baseboard_fab2_lib.baseboard_fab2(sch_1):tp_cpu1_rsvd_286"
				( objectStatus "TP_CPU1_RSVD_286" )
			)
			( signal "@baseboard_fab2_lib.baseboard_fab2(sch_1):tp_cpu1_rsvd_288"
				( objectStatus "TP_CPU1_RSVD_288" )
			)
			( signal "@baseboard_fab2_lib.baseboard_fab2(sch_1):tp_cpu1_rsvd_289"
				( objectStatus "TP_CPU1_RSVD_289" )
			)
			( signal "@baseboard_fab2_lib.baseboard_fab2(sch_1):tp_cpu1_rsvd_290"
				( objectStatus "TP_CPU1_RSVD_290" )
			)
			( signal "@baseboard_fab2_lib.baseboard_fab2(sch_1):tp_cpu1_rsvd_291"
				( objectStatus "TP_CPU1_RSVD_291" )
			)
			( signal "@baseboard_fab2_lib.baseboard_fab2(sch_1):tp_cpu1_rsvd_292"
				( objectStatus "TP_CPU1_RSVD_292" )
			)
			( signal "@baseboard_fab2_lib.baseboard_fab2(sch_1):tp_cpu1_rsvd_293"
				( objectStatus "TP_CPU1_RSVD_293" )
			)
			( signal "@baseboard_fab2_lib.baseboard_fab2(sch_1):tp_cpu1_rsvd_300"
				( objectStatus "TP_CPU1_RSVD_300" )
			)
			( signal "@baseboard_fab2_lib.baseboard_fab2(sch_1):fm_cpu1_sm_wp"
				( objectStatus "FM_CPU1_SM_WP" )
			)
			( signal "@baseboard_fab2_lib.baseboard_fab2(sch_1):tp_cpu1_socket_id_2"
				( objectStatus "TP_CPU1_SOCKET_ID_2" )
			)
			( signal "@baseboard_fab2_lib.baseboard_fab2(sch_1):tp_cpu1_rsvd_test_5"
				( objectStatus "TP_CPU1_RSVD_TEST_5" )
			)
			( signal "@baseboard_fab2_lib.baseboard_fab2(sch_1):tp_cpu1_upi2_rsvd_ca12"
				( objectStatus "TP_CPU1_UPI2_RSVD_CA12" )
			)
			( signal "@baseboard_fab2_lib.baseboard_fab2(sch_1):tp_cpu1_upi2_rsvd_cb11"
				( objectStatus "TP_CPU1_UPI2_RSVD_CB11" )
			)
			( signal "@baseboard_fab2_lib.baseboard_fab2(sch_1):tp_cpu1_upi2_rsvd_cc10"
				( objectStatus "TP_CPU1_UPI2_RSVD_CC10" )
			)
			( signal "@baseboard_fab2_lib.baseboard_fab2(sch_1):tp_cpu1_upi2_rsvd_cc12"
				( objectStatus "TP_CPU1_UPI2_RSVD_CC12" )
			)
			( signal "@baseboard_fab2_lib.baseboard_fab2(sch_1):tp_cpu1_upi2_rsvd_cd11"
				( objectStatus "TP_CPU1_UPI2_RSVD_CD11" )
			)
			( signal "@baseboard_fab2_lib.baseboard_fab2(sch_1):tp_cpu1_upi2_rsvd_ce12"
				( objectStatus "TP_CPU1_UPI2_RSVD_CE12" )
			)
			( signal "@baseboard_fab2_lib.baseboard_fab2(sch_1):tp_cpu1_upi2_rsvd_cf11"
				( objectStatus "TP_CPU1_UPI2_RSVD_CF11" )
			)
			( signal "@baseboard_fab2_lib.baseboard_fab2(sch_1):tp_cpu1_upi2_rsvd_cf13"
				( objectStatus "TP_CPU1_UPI2_RSVD_CF13" )
			)
			( signal "@baseboard_fab2_lib.baseboard_fab2(sch_1):tp_pch_rsvd28"
				( objectStatus "TP_PCH_RSVD28" )
			)
			( signal "@baseboard_fab2_lib.baseboard_fab2(sch_1):tp_pch_rsvd29"
				( objectStatus "TP_PCH_RSVD29" )
			)
			( signal "@baseboard_fab2_lib.baseboard_fab2(sch_1):tp_pch_rsvd30"
				( objectStatus "TP_PCH_RSVD30" )
			)
			( signal "@baseboard_fab2_lib.baseboard_fab2(sch_1):tp_pch_rsvd31"
				( objectStatus "TP_PCH_RSVD31" )
			)
			( signal "@baseboard_fab2_lib.baseboard_fab2(sch_1):tp_pch_rsvd32"
				( objectStatus "TP_PCH_RSVD32" )
			)
			( signal "@baseboard_fab2_lib.baseboard_fab2(sch_1):tp_pch_rsvd33"
				( objectStatus "TP_PCH_RSVD33" )
			)
			( signal "@baseboard_fab2_lib.baseboard_fab2(sch_1):tp_pch_rsvd34"
				( objectStatus "TP_PCH_RSVD34" )
			)
			( signal "@baseboard_fab2_lib.baseboard_fab2(sch_1):tp_pch_rsvd35"
				( objectStatus "TP_PCH_RSVD35" )
			)
			( signal "@baseboard_fab2_lib.baseboard_fab2(sch_1):tp_pch_rsvd36"
				( objectStatus "TP_PCH_RSVD36" )
			)
			( signal "@baseboard_fab2_lib.baseboard_fab2(sch_1):tp_pch_rsvd37"
				( objectStatus "TP_PCH_RSVD37" )
			)
			( signal "@baseboard_fab2_lib.baseboard_fab2(sch_1):tp_pch_rsvd38"
				( objectStatus "TP_PCH_RSVD38" )
			)
			( signal "@baseboard_fab2_lib.baseboard_fab2(sch_1):tp_pch_rsvd41"
				( objectStatus "TP_PCH_RSVD41" )
			)
			( signal "@baseboard_fab2_lib.baseboard_fab2(sch_1):tp_cpu1_upi2_rsvd_cr14"
				( objectStatus "TP_CPU1_UPI2_RSVD_CR14" )
			)
			( signal "@baseboard_fab2_lib.baseboard_fab2(sch_1):tp_cpu1_upi2_rsvd_cu14"
				( objectStatus "TP_CPU1_UPI2_RSVD_CU14" )
			)
			( signal "@baseboard_fab2_lib.baseboard_fab2(sch_1):tp_cpu1_upi2_rsvd_cv13"
				( objectStatus "TP_CPU1_UPI2_RSVD_CV13" )
			)
			( signal "@baseboard_fab2_lib.baseboard_fab2(sch_1):tp_cpu1_upi2_rsvd_cw14"
				( objectStatus "TP_CPU1_UPI2_RSVD_CW14" )
			)
			( signal "@baseboard_fab2_lib.baseboard_fab2(sch_1):tp_cpu1_upi2_rsvd_cw16"
				( objectStatus "TP_CPU1_UPI2_RSVD_CW16" )
			)
			( signal "@baseboard_fab2_lib.baseboard_fab2(sch_1):tp_cpu1_upi2_rsvd_da16"
				( objectStatus "TP_CPU1_UPI2_RSVD_DA16" )
			)
			( signal "@baseboard_fab2_lib.baseboard_fab2(sch_1):tp_cpu1_upi2_rsvd_db15"
				( objectStatus "TP_CPU1_UPI2_RSVD_DB15" )
			)
			( signal "@baseboard_fab2_lib.baseboard_fab2(sch_1):tp_cpu1_upi2_rsvd_dc16"
				( objectStatus "TP_CPU1_UPI2_RSVD_DC16" )
			)
			( signal "@baseboard_fab2_lib.baseboard_fab2(sch_1):tp_cpu1_upi2_rsvd_dd15"
				( objectStatus "TP_CPU1_UPI2_RSVD_DD15" )
			)
			( signal "@baseboard_fab2_lib.baseboard_fab2(sch_1):tp_cpu1_upi2_rsvd_dd17"
				( objectStatus "TP_CPU1_UPI2_RSVD_DD17" )
			)
			( signal "@baseboard_fab2_lib.baseboard_fab2(sch_1):tp_cpu1_upi2_rsvd_de16"
				( objectStatus "TP_CPU1_UPI2_RSVD_DE16" )
			)
			( signal "@baseboard_fab2_lib.baseboard_fab2(sch_1):tp_cpu1_upi2_rsvd_df15"
				( objectStatus "TP_CPU1_UPI2_RSVD_DF15" )
			)
			( signal "@baseboard_fab2_lib.baseboard_fab2(sch_1):tp_cpu1_upi2_rsvd_df17"
				( objectStatus "TP_CPU1_UPI2_RSVD_DF17" )
			)
			( signal "@baseboard_fab2_lib.baseboard_fab2(sch_1):tp_cpu1_upi2_rsvd_dg18"
				( objectStatus "TP_CPU1_UPI2_RSVD_DG18" )
			)
			( signal "@baseboard_fab2_lib.baseboard_fab2(sch_1):tp_cpu1_upi2_rsvd_dg20"
				( objectStatus "TP_CPU1_UPI2_RSVD_DG20" )
			)
			( signal "@baseboard_fab2_lib.baseboard_fab2(sch_1):tp_cpu1_upi2_rsvd_dh17"
				( objectStatus "TP_CPU1_UPI2_RSVD_DH17" )
			)
			( signal "@baseboard_fab2_lib.baseboard_fab2(sch_1):tp_cpu1_upi2_rsvd_dh19"
				( objectStatus "TP_CPU1_UPI2_RSVD_DH19" )
			)
			( signal "@baseboard_fab2_lib.baseboard_fab2(sch_1):tp_cpu1_upi2_rsvd_dj18"
				( objectStatus "TP_CPU1_UPI2_RSVD_DJ18" )
			)
			( signal "@baseboard_fab2_lib.baseboard_fab2(sch_1):tp_cpu1_upi2_rsvd_dj20"
				( objectStatus "TP_CPU1_UPI2_RSVD_DJ20" )
			)
			( signal "@baseboard_fab2_lib.baseboard_fab2(sch_1):tp_cpu1_upi2_rsvd_dk17"
				( objectStatus "TP_CPU1_UPI2_RSVD_DK17" )
			)
			( signal "@baseboard_fab2_lib.baseboard_fab2(sch_1):tp_cpu1_upi2_rsvd_dk19"
				( objectStatus "TP_CPU1_UPI2_RSVD_DK19" )
			)
			( signal "@baseboard_fab2_lib.baseboard_fab2(sch_1):tp_cpu1_upi2_rsvd_dl20"
				( objectStatus "TP_CPU1_UPI2_RSVD_DL20" )
			)
			( signal "@baseboard_fab2_lib.baseboard_fab2(sch_1):tp_cpu1_upi2_rsvd_dm21"
				( objectStatus "TP_CPU1_UPI2_RSVD_DM21" )
			)
			( signal "@baseboard_fab2_lib.baseboard_fab2(sch_1):tp_cpu1_upi2_rsvd_dn20"
				( objectStatus "TP_CPU1_UPI2_RSVD_DN20" )
			)
			( signal "@baseboard_fab2_lib.baseboard_fab2(sch_1):tp_cpu1_upi2_rsvd_dp21"
				( objectStatus "TP_CPU1_UPI2_RSVD_DP21" )
			)
			( signal "@baseboard_fab2_lib.baseboard_fab2(sch_1):tp_cpu1_upi2_rsvd_dt21"
				( objectStatus "TP_CPU1_UPI2_RSVD_DT21" )
			)
			( signal "@baseboard_fab2_lib.baseboard_fab2(sch_1):tp_cpld1_pl2b_l_gpllc_in"
				( objectStatus "TP_CPLD1_PL2B_L_GPLLC_IN" )
			)
			( signal "@baseboard_fab2_lib.baseboard_fab2(sch_1):tp_cpld1_pb8a_mclk_cclk"
				( objectStatus "TP_CPLD1_PB8A_MCLK_CCLK" )
			)
			( signal "@baseboard_fab2_lib.baseboard_fab2(sch_1):tp_cpld1_pb5a_csspin"
				( objectStatus "TP_CPLD1_PB5A_CSSPIN" )
			)
			( signal "@baseboard_fab2_lib.baseboard_fab2(sch_1):tp_cpld1_pb8b_so_spiso"
				( objectStatus "TP_CPLD1_PB8B_SO_SPISO" )
			)
			( signal "@baseboard_fab2_lib.baseboard_fab2(sch_1):tp_cpld1_pt20b"
				( objectStatus "TP_CPLD1_PT20B" )
			)
			( signal "@baseboard_fab2_lib.baseboard_fab2(sch_1):tp_cpld1_pt20a"
				( objectStatus "TP_CPLD1_PT20A" )
			)
			( signal "@baseboard_fab2_lib.baseboard_fab2(sch_1):tp_cpld1_pt22c"
				( objectStatus "TP_CPLD1_PT22C" )
			)
			( signal "@baseboard_fab2_lib.baseboard_fab2(sch_1):tp_fm_qat_cbl_prsnt0_r_n"
				( objectStatus "TP_FM_QAT_CBL_PRSNT0_R_N" )
			)
			( signal "@baseboard_fab2_lib.baseboard_fab2(sch_1):tp_fm_qat_cbl_prsnt1_n_r"
				( objectStatus "TP_FM_QAT_CBL_PRSNT1_N_R" )
			)
			( signal "@baseboard_fab2_lib.baseboard_fab2(sch_1):tp_fm_qat_cbl_prsnt2_n"
				( objectStatus "TP_FM_QAT_CBL_PRSNT2_N" )
			)
			( signal "@baseboard_fab2_lib.baseboard_fab2(sch_1):tp_cpld1_pl1a_l_gpllt_fb"
				( objectStatus "TP_CPLD1_PL1A_L_GPLLT_FB" )
			)
			( signal "@baseboard_fab2_lib.baseboard_fab2(sch_1):tp_gpiom5_nrts2_vpib7"
				( objectStatus "TP_GPIOM5_NRTS2_VPIB7" )
			)
			( signal "@baseboard_fab2_lib.baseboard_fab2(sch_1):tp_hfi_io_conn0_rsvd_17"
				( objectStatus "TP_HFI_IO_CONN0_RSVD_17" )
			)
			( signal "@baseboard_fab2_lib.baseboard_fab2(sch_1):tp_hsc_alert2_n"
				( objectStatus "TP_HSC_ALERT2_N" )
			)
			( signal "@baseboard_fab2_lib.baseboard_fab2(sch_1):tp_hsc_mclk"
				( objectStatus "TP_HSC_MCLK" )
			)
			( signal "@baseboard_fab2_lib.baseboard_fab2(sch_1):tp_hsc_mdat"
				( objectStatus "TP_HSC_MDAT" )
			)
			( signal "@baseboard_fab2_lib.baseboard_fab2(sch_1):tp_hsc_spissn"
				( objectStatus "TP_HSC_SPISSN" )
			)
			( signal "@baseboard_fab2_lib.baseboard_fab2(sch_1):tp_ie_debug_mode"
				( objectStatus "TP_IE_DEBUG_MODE" )
			)
			( signal "@baseboard_fab2_lib.baseboard_fab2(sch_1):tp_fm_wake_n"
				( objectStatus "TP_FM_WAKE_N" )
			)
			( signal "@baseboard_fab2_lib.baseboard_fab2(sch_1):tp_pvddq_abc_mp1"
				( objectStatus "TP_PVDDQ_ABC_MP1" )
			)
			( signal "@baseboard_fab2_lib.baseboard_fab2(sch_1):tp_pvddq_abc_ph3_imon"
				( objectStatus "TP_PVDDQ_ABC_PH3_IMON" )
			)
			( signal "@baseboard_fab2_lib.baseboard_fab2(sch_1):tp_pvddq_abc_ph3_imon_ref"
				( objectStatus "TP_PVDDQ_ABC_PH3_IMON_REF" )
			)
			( signal "@baseboard_fab2_lib.baseboard_fab2(sch_1):tp_pvddq_abc_pinalrt_n"
				( objectStatus "TP_PVDDQ_ABC_PINALRT_N" )
			)
			( signal "@baseboard_fab2_lib.baseboard_fab2(sch_1):tp_pvddq_abc_pwm3"
				( objectStatus "TP_PVDDQ_ABC_PWM3" )
			)
			( signal "@baseboard_fab2_lib.baseboard_fab2(sch_1):tp_pvddq_abc_reset_n"
				( objectStatus "TP_PVDDQ_ABC_RESET_N" )
			)
			( signal "@baseboard_fab2_lib.baseboard_fab2(sch_1):tp_pvddq_def_bpwm1"
				( objectStatus "TP_PVDDQ_DEF_BPWM1" )
			)
			( signal "@baseboard_fab2_lib.baseboard_fab2(sch_1):tp_k4b1g16_bmc_nc3"
				( objectStatus "TP_K4B1G16_BMC_NC3" )
			)
			( signal "@baseboard_fab2_lib.baseboard_fab2(sch_1):tp_k4b1g16_bmc_nc4"
				( objectStatus "TP_K4B1G16_BMC_NC4" )
			)
			( signal "@baseboard_fab2_lib.baseboard_fab2(sch_1):tp_cpld1_pb16b_pclkc2_1"
				( objectStatus "TP_CPLD1_PB16B_PCLKC2_1" )
			)
			( signal "@baseboard_fab2_lib.baseboard_fab2(sch_1):tp_pch_gpp_j21"
				( objectStatus "TP_PCH_GPP_J21" )
			)
			( signal "@baseboard_fab2_lib.baseboard_fab2(sch_1):tp_pch_gpp_j23"
				( objectStatus "TP_PCH_GPP_J23" )
			)
			( signal "@baseboard_fab2_lib.baseboard_fab2(sch_1):tp_cpld1_pl1b_l_gpllc_fb"
				( objectStatus "TP_CPLD1_PL1B_L_GPLLC_FB" )
			)
			( signal "@baseboard_fab2_lib.baseboard_fab2(sch_1):tp_cpld1_pb11b_pclkc2_0"
				( objectStatus "TP_CPLD1_PB11B_PCLKC2_0" )
			)
			( signal "@baseboard_fab2_lib.baseboard_fab2(sch_1):tp_me_rcvr_boot"
				( objectStatus "TP_ME_RCVR_BOOT" )
			)
			( signal "@baseboard_fab2_lib.baseboard_fab2(sch_1):tp_nmi_cpu0"
				( objectStatus "TP_NMI_CPU0" )
			)
			( signal "@baseboard_fab2_lib.baseboard_fab2(sch_1):tp_password_clear"
				( objectStatus "TP_PASSWORD_CLEAR" )
			)
			( signal "@baseboard_fab2_lib.baseboard_fab2(sch_1):tp_pch_dispa_bclk"
				( objectStatus "TP_PCH_DISPA_BCLK" )
			)
			( signal "@baseboard_fab2_lib.baseboard_fab2(sch_1):tp_pch_dispa_sdi"
				( objectStatus "TP_PCH_DISPA_SDI" )
			)
			( signal "@baseboard_fab2_lib.baseboard_fab2(sch_1):tp_pch_dispa_sdo"
				( objectStatus "TP_PCH_DISPA_SDO" )
			)
			( signal "@baseboard_fab2_lib.baseboard_fab2(sch_1):tp_pch_hda_bclk"
				( objectStatus "TP_PCH_HDA_BCLK" )
			)
			( signal "@baseboard_fab2_lib.baseboard_fab2(sch_1):tp_pch_hda_sdi_0"
				( objectStatus "TP_PCH_HDA_SDI_0" )
			)
			( signal "@baseboard_fab2_lib.baseboard_fab2(sch_1):tp_pch_hda_sdi_1"
				( objectStatus "TP_PCH_HDA_SDI_1" )
			)
			( signal "@baseboard_fab2_lib.baseboard_fab2(sch_1):tp_pch_hda_sync"
				( objectStatus "TP_PCH_HDA_SYNC" )
			)
			( signal "@baseboard_fab2_lib.baseboard_fab2(sch_1):tp_pch_hsa_rst_n"
				( objectStatus "TP_PCH_HSA_RST_N" )
			)
			( signal "@baseboard_fab2_lib.baseboard_fab2(sch_1):tp_pch_rsvd0"
				( objectStatus "TP_PCH_RSVD0" )
			)
			( signal "@baseboard_fab2_lib.baseboard_fab2(sch_1):tp_pch_rsvd1"
				( objectStatus "TP_PCH_RSVD1" )
			)
			( signal "@baseboard_fab2_lib.baseboard_fab2(sch_1):tp_pch_rsvd2"
				( objectStatus "TP_PCH_RSVD2" )
			)
			( signal "@baseboard_fab2_lib.baseboard_fab2(sch_1):tp_pch_rsvd3"
				( objectStatus "TP_PCH_RSVD3" )
			)
			( signal "@baseboard_fab2_lib.baseboard_fab2(sch_1):tp_pch_rsvd4"
				( objectStatus "TP_PCH_RSVD4" )
			)
			( signal "@baseboard_fab2_lib.baseboard_fab2(sch_1):tp_pch_rsvd5"
				( objectStatus "TP_PCH_RSVD5" )
			)
			( signal "@baseboard_fab2_lib.baseboard_fab2(sch_1):tp_pch_rsvd6"
				( objectStatus "TP_PCH_RSVD6" )
			)
			( signal "@baseboard_fab2_lib.baseboard_fab2(sch_1):tp_pch_rsvd7"
				( objectStatus "TP_PCH_RSVD7" )
			)
			( signal "@baseboard_fab2_lib.baseboard_fab2(sch_1):tp_pch_rsvd8"
				( objectStatus "TP_PCH_RSVD8" )
			)
			( signal "@baseboard_fab2_lib.baseboard_fab2(sch_1):tp_pch_rsvd9"
				( objectStatus "TP_PCH_RSVD9" )
			)
			( signal "@baseboard_fab2_lib.baseboard_fab2(sch_1):tp_pch_rsvd12"
				( objectStatus "TP_PCH_RSVD12" )
			)
			( signal "@baseboard_fab2_lib.baseboard_fab2(sch_1):tp_pch_rsvd13"
				( objectStatus "TP_PCH_RSVD13" )
			)
			( signal "@baseboard_fab2_lib.baseboard_fab2(sch_1):tp_pch_rsvd14"
				( objectStatus "TP_PCH_RSVD14" )
			)
			( signal "@baseboard_fab2_lib.baseboard_fab2(sch_1):tp_pch_rsvd15"
				( objectStatus "TP_PCH_RSVD15" )
			)
			( signal "@baseboard_fab2_lib.baseboard_fab2(sch_1):tp_pch_rsvd16"
				( objectStatus "TP_PCH_RSVD16" )
			)
			( signal "@baseboard_fab2_lib.baseboard_fab2(sch_1):tp_pch_rsvd17"
				( objectStatus "TP_PCH_RSVD17" )
			)
			( signal "@baseboard_fab2_lib.baseboard_fab2(sch_1):tp_pch_rsvd18"
				( objectStatus "TP_PCH_RSVD18" )
			)
			( signal "@baseboard_fab2_lib.baseboard_fab2(sch_1):tp_pch_rsvd19"
				( objectStatus "TP_PCH_RSVD19" )
			)
			( signal "@baseboard_fab2_lib.baseboard_fab2(sch_1):tp_pch_rsvd20"
				( objectStatus "TP_PCH_RSVD20" )
			)
			( signal "@baseboard_fab2_lib.baseboard_fab2(sch_1):tp_pch_rsvd21"
				( objectStatus "TP_PCH_RSVD21" )
			)
			( signal "@baseboard_fab2_lib.baseboard_fab2(sch_1):tp_pch_rsvd22"
				( objectStatus "TP_PCH_RSVD22" )
			)
			( signal "@baseboard_fab2_lib.baseboard_fab2(sch_1):tp_pch_rsvd23"
				( objectStatus "TP_PCH_RSVD23" )
			)
			( signal "@baseboard_fab2_lib.baseboard_fab2(sch_1):tp_pch_rsvd24"
				( objectStatus "TP_PCH_RSVD24" )
			)
			( signal "@baseboard_fab2_lib.baseboard_fab2(sch_1):tp_pch_rsvd25"
				( objectStatus "TP_PCH_RSVD25" )
			)
			( signal "@baseboard_fab2_lib.baseboard_fab2(sch_1):tp_pch_rsvd26"
				( objectStatus "TP_PCH_RSVD26" )
			)
			( signal "@baseboard_fab2_lib.baseboard_fab2(sch_1):tp_pch_rsvd27"
				( objectStatus "TP_PCH_RSVD27" )
			)
			( signal "@baseboard_fab2_lib.baseboard_fab2(sch_1):tp_p3e_cpu1_pe1_mp_txp(6)"
				( objectStatus "TP_P3E_CPU1_PE1_MP_TXP<6>" )
			)
			( signal "@baseboard_fab2_lib.baseboard_fab2(sch_1):tp_p3e_cpu1_pe1_mp_txp(7)"
				( objectStatus "TP_P3E_CPU1_PE1_MP_TXP<7>" )
			)
			( signal "@baseboard_fab2_lib.baseboard_fab2(sch_1):tp_p3e_cpu1_pe1_rsr3_rxn(8)"
				( objectStatus "TP_P3E_CPU1_PE1_RSR3_RXN<8>" )
			)
			( signal "@baseboard_fab2_lib.baseboard_fab2(sch_1):tp_p3e_cpu1_pe1_rsr3_rxn(9)"
				( objectStatus "TP_P3E_CPU1_PE1_RSR3_RXN<9>" )
			)
			( signal "@baseboard_fab2_lib.baseboard_fab2(sch_1):tp_p3e_cpu1_pe1_rsr3_rxn(10)"
				( objectStatus "TP_P3E_CPU1_PE1_RSR3_RXN<10>" )
			)
			( signal "@baseboard_fab2_lib.baseboard_fab2(sch_1):tp_p3e_cpu1_pe1_rsr3_rxn(11)"
				( objectStatus "TP_P3E_CPU1_PE1_RSR3_RXN<11>" )
			)
			( signal "@baseboard_fab2_lib.baseboard_fab2(sch_1):tp_p3e_cpu1_pe1_rsr3_rxn(12)"
				( objectStatus "TP_P3E_CPU1_PE1_RSR3_RXN<12>" )
			)
			( signal "@baseboard_fab2_lib.baseboard_fab2(sch_1):tp_p3e_cpu1_pe1_rsr3_rxn(13)"
				( objectStatus "TP_P3E_CPU1_PE1_RSR3_RXN<13>" )
			)
			( signal "@baseboard_fab2_lib.baseboard_fab2(sch_1):tp_p3e_cpu1_pe1_rsr3_rxn(14)"
				( objectStatus "TP_P3E_CPU1_PE1_RSR3_RXN<14>" )
			)
			( signal "@baseboard_fab2_lib.baseboard_fab2(sch_1):tp_p3e_cpu1_pe1_rsr3_rxn(15)"
				( objectStatus "TP_P3E_CPU1_PE1_RSR3_RXN<15>" )
			)
			( signal "@baseboard_fab2_lib.baseboard_fab2(sch_1):tp_p3e_cpu1_pe1_rsr3_rxp(8)"
				( objectStatus "TP_P3E_CPU1_PE1_RSR3_RXP<8>" )
			)
			( signal "@baseboard_fab2_lib.baseboard_fab2(sch_1):tp_p3e_cpu1_pe1_rsr3_rxp(9)"
				( objectStatus "TP_P3E_CPU1_PE1_RSR3_RXP<9>" )
			)
			( signal "@baseboard_fab2_lib.baseboard_fab2(sch_1):tp_pch_rsvd42"
				( objectStatus "TP_PCH_RSVD42" )
			)
			( signal "@baseboard_fab2_lib.baseboard_fab2(sch_1):tp_pch_rsvd45"
				( objectStatus "TP_PCH_RSVD45" )
			)
			( signal "@baseboard_fab2_lib.baseboard_fab2(sch_1):tp_pch_rsvd46"
				( objectStatus "TP_PCH_RSVD46" )
			)
			( signal "@baseboard_fab2_lib.baseboard_fab2(sch_1):tp_pch_rsvd47"
				( objectStatus "TP_PCH_RSVD47" )
			)
			( signal "@baseboard_fab2_lib.baseboard_fab2(sch_1):tp_pch_rsvd48"
				( objectStatus "TP_PCH_RSVD48" )
			)
			( signal "@baseboard_fab2_lib.baseboard_fab2(sch_1):tp_pch_rsvd49"
				( objectStatus "TP_PCH_RSVD49" )
			)
			( signal "@baseboard_fab2_lib.baseboard_fab2(sch_1):tp_pch_rsvd50"
				( objectStatus "TP_PCH_RSVD50" )
			)
			( signal "@baseboard_fab2_lib.baseboard_fab2(sch_1):tp_pch_rsvd51"
				( objectStatus "TP_PCH_RSVD51" )
			)
			( signal "@baseboard_fab2_lib.baseboard_fab2(sch_1):tp_pch_rsvd52"
				( objectStatus "TP_PCH_RSVD52" )
			)
			( signal "@baseboard_fab2_lib.baseboard_fab2(sch_1):tp_pch_rsvd53"
				( objectStatus "TP_PCH_RSVD53" )
			)
			( signal "@baseboard_fab2_lib.baseboard_fab2(sch_1):tp_pch_rsvd54"
				( objectStatus "TP_PCH_RSVD54" )
			)
			( signal "@baseboard_fab2_lib.baseboard_fab2(sch_1):tp_pch_rsvd55"
				( objectStatus "TP_PCH_RSVD55" )
			)
			( signal "@baseboard_fab2_lib.baseboard_fab2(sch_1):tp_pch_rsvd58"
				( objectStatus "TP_PCH_RSVD58" )
			)
			( signal "@baseboard_fab2_lib.baseboard_fab2(sch_1):tp_pch_rsvd59"
				( objectStatus "TP_PCH_RSVD59" )
			)
			( signal "@baseboard_fab2_lib.baseboard_fab2(sch_1):tp_pch_rsvd64"
				( objectStatus "TP_PCH_RSVD64" )
			)
			( signal "@baseboard_fab2_lib.baseboard_fab2(sch_1):tp_pch_rsvd65"
				( objectStatus "TP_PCH_RSVD65" )
			)
			( signal "@baseboard_fab2_lib.baseboard_fab2(sch_1):tp_cpld1_pr12d"
				( objectStatus "TP_CPLD1_PR12D" )
			)
			( signal "@baseboard_fab2_lib.baseboard_fab2(sch_1):tp_pltrst_cpu_n"
				( objectStatus "TP_PLTRST_CPU_N" )
			)
			( signal "@baseboard_fab2_lib.baseboard_fab2(sch_1):tp_pm_sync_gtl"
				( objectStatus "TP_PM_SYNC_GTL" )
			)
			( signal "@baseboard_fab2_lib.baseboard_fab2(sch_1):tp_pvccin_cpu0_airef6"
				( objectStatus "TP_PVCCIN_CPU0_AIREF6" )
			)
			( signal "@baseboard_fab2_lib.baseboard_fab2(sch_1):tp_pvccin_cpu0_apwm6"
				( objectStatus "TP_PVCCIN_CPU0_APWM6" )
			)
			( signal "@baseboard_fab2_lib.baseboard_fab2(sch_1):tp_pvccin_cpu0_gp1"
				( objectStatus "TP_PVCCIN_CPU0_GP1" )
			)
			( signal "@baseboard_fab2_lib.baseboard_fab2(sch_1):tp_pvccin_cpu0_reset"
				( objectStatus "TP_PVCCIN_CPU0_RESET" )
			)
			( signal "@baseboard_fab2_lib.baseboard_fab2(sch_1):tp_pvccin_cpu1_airef6"
				( objectStatus "TP_PVCCIN_CPU1_AIREF6" )
			)
			( signal "@baseboard_fab2_lib.baseboard_fab2(sch_1):tp_pvccin_cpu1_apwm6"
				( objectStatus "TP_PVCCIN_CPU1_APWM6" )
			)
			( signal "@baseboard_fab2_lib.baseboard_fab2(sch_1):tp_pvccin_cpu1_gp1"
				( objectStatus "TP_PVCCIN_CPU1_GP1" )
			)
			( signal "@baseboard_fab2_lib.baseboard_fab2(sch_1):tp_pvccin_cpu1_reset_n"
				( objectStatus "TP_PVCCIN_CPU1_RESET_N" )
			)
			( signal "@baseboard_fab2_lib.baseboard_fab2(sch_1):tp_pvccio_cpu0_biref1"
				( objectStatus "TP_PVCCIO_CPU0_BIREF1" )
			)
			( signal "@baseboard_fab2_lib.baseboard_fab2(sch_1):tp_pvccio_cpu0_bpwm1"
				( objectStatus "TP_PVCCIO_CPU0_BPWM1" )
			)
			( signal "@baseboard_fab2_lib.baseboard_fab2(sch_1):tp_pvccio_cpu0_btsen"
				( objectStatus "TP_PVCCIO_CPU0_BTSEN" )
			)
			( signal "@baseboard_fab2_lib.baseboard_fab2(sch_1):tp_pvccio_cpu0_bvref"
				( objectStatus "TP_PVCCIO_CPU0_BVREF" )
			)
			( signal "@baseboard_fab2_lib.baseboard_fab2(sch_1):tp_pvccio_cpu0_bvsen"
				( objectStatus "TP_PVCCIO_CPU0_BVSEN" )
			)
			( signal "@baseboard_fab2_lib.baseboard_fab2(sch_1):tp_vr_pvccio_cpu0_mp0"
				( objectStatus "TP_VR_PVCCIO_CPU0_MP0" )
			)
			( signal "@baseboard_fab2_lib.baseboard_fab2(sch_1):tp_vr_pvccio_cpu0_mp1"
				( objectStatus "TP_VR_PVCCIO_CPU0_MP1" )
			)
			( signal "@baseboard_fab2_lib.baseboard_fab2(sch_1):tp_pvccio_cpu0_pinalrt_n"
				( objectStatus "TP_PVCCIO_CPU0_PINALRT_N" )
			)
			( signal "@baseboard_fab2_lib.baseboard_fab2(sch_1):tp_pvccio_cpu0_reset_n"
				( objectStatus "TP_PVCCIO_CPU0_RESET_N" )
			)
			( signal "@baseboard_fab2_lib.baseboard_fab2(sch_1):tp_pvccio_cpu1_biref1"
				( objectStatus "TP_PVCCIO_CPU1_BIREF1" )
			)
			( signal "@baseboard_fab2_lib.baseboard_fab2(sch_1):tp_pvccio_cpu1_bpwm1"
				( objectStatus "TP_PVCCIO_CPU1_BPWM1" )
			)
			( signal "@baseboard_fab2_lib.baseboard_fab2(sch_1):tp_pvccio_cpu1_btsen"
				( objectStatus "TP_PVCCIO_CPU1_BTSEN" )
			)
			( signal "@baseboard_fab2_lib.baseboard_fab2(sch_1):tp_pvccio_cpu1_bvref"
				( objectStatus "TP_PVCCIO_CPU1_BVREF" )
			)
			( signal "@baseboard_fab2_lib.baseboard_fab2(sch_1):tp_pvccio_cpu1_bvsen"
				( objectStatus "TP_PVCCIO_CPU1_BVSEN" )
			)
			( signal "@baseboard_fab2_lib.baseboard_fab2(sch_1):tp_vr_pvccio_cpu1_mp0"
				( objectStatus "TP_VR_PVCCIO_CPU1_MP0" )
			)
			( signal "@baseboard_fab2_lib.baseboard_fab2(sch_1):tp_vr_pvccio_cpu1_mp1"
				( objectStatus "TP_VR_PVCCIO_CPU1_MP1" )
			)
			( signal "@baseboard_fab2_lib.baseboard_fab2(sch_1):tp_pvccio_cpu1_pinalrt_n"
				( objectStatus "TP_PVCCIO_CPU1_PINALRT_N" )
			)
			( signal "@baseboard_fab2_lib.baseboard_fab2(sch_1):tp_pvccio_cpu1_reset_n"
				( objectStatus "TP_PVCCIO_CPU1_RESET_N" )
			)
			( signal "@baseboard_fab2_lib.baseboard_fab2(sch_1):tp_pvddq_abc_bpwm1"
				( objectStatus "TP_PVDDQ_ABC_BPWM1" )
			)
			( signal "@baseboard_fab2_lib.baseboard_fab2(sch_1):tp_pvddq_abc_bref1"
				( objectStatus "TP_PVDDQ_ABC_BREF1" )
			)
			( signal "@baseboard_fab2_lib.baseboard_fab2(sch_1):tp_pvddq_abc_btsen"
				( objectStatus "TP_PVDDQ_ABC_BTSEN" )
			)
			( signal "@baseboard_fab2_lib.baseboard_fab2(sch_1):tp_pvddq_abc_bvref"
				( objectStatus "TP_PVDDQ_ABC_BVREF" )
			)
			( signal "@baseboard_fab2_lib.baseboard_fab2(sch_1):tp_pvddq_abc_bvsen"
				( objectStatus "TP_PVDDQ_ABC_BVSEN" )
			)
			( signal "@baseboard_fab2_lib.baseboard_fab2(sch_1):tp_cpld1_pt13a"
				( objectStatus "TP_CPLD1_PT13A" )
			)
			( signal "@baseboard_fab2_lib.baseboard_fab2(sch_1):tp_cpld1_pt11b"
				( objectStatus "TP_CPLD1_PT11B" )
			)
			( signal "@baseboard_fab2_lib.baseboard_fab2(sch_1):tp_cpld1_pt11a"
				( objectStatus "TP_CPLD1_PT11A" )
			)
			( signal "@baseboard_fab2_lib.baseboard_fab2(sch_1):tp_rst_rtcrst_n"
				( objectStatus "TP_RST_RTCRST_N" )
			)
			( signal "@baseboard_fab2_lib.baseboard_fab2(sch_1):tp_rsvd_b1"
				( objectStatus "TP_RSVD_B1" )
			)
			( signal "@baseboard_fab2_lib.baseboard_fab2(sch_1):tp_sgpio_sata_clock1_r"
				( objectStatus "TP_SGPIO_SATA_CLOCK1_R" )
			)
			( signal "@baseboard_fab2_lib.baseboard_fab2(sch_1):tp_sgpio_sata_data1_r"
				( objectStatus "TP_SGPIO_SATA_DATA1_R" )
			)
			( signal "@baseboard_fab2_lib.baseboard_fab2(sch_1):tp_pvddq_def_bref1"
				( objectStatus "TP_PVDDQ_DEF_BREF1" )
			)
			( signal "@baseboard_fab2_lib.baseboard_fab2(sch_1):tp_pvddq_def_btsen"
				( objectStatus "TP_PVDDQ_DEF_BTSEN" )
			)
			( signal "@baseboard_fab2_lib.baseboard_fab2(sch_1):tp_pvddq_def_bvref"
				( objectStatus "TP_PVDDQ_DEF_BVREF" )
			)
			( signal "@baseboard_fab2_lib.baseboard_fab2(sch_1):tp_pvddq_def_bvsen"
				( objectStatus "TP_PVDDQ_DEF_BVSEN" )
			)
			( signal "@baseboard_fab2_lib.baseboard_fab2(sch_1):tp_pvddq_def_mp1"
				( objectStatus "TP_PVDDQ_DEF_MP1" )
			)
			( signal "@baseboard_fab2_lib.baseboard_fab2(sch_1):tp_pvddq_def_ph3_imon"
				( objectStatus "TP_PVDDQ_DEF_PH3_IMON" )
			)
			( signal "@baseboard_fab2_lib.baseboard_fab2(sch_1):tp_pvddq_def_ph3_imon_ref"
				( objectStatus "TP_PVDDQ_DEF_PH3_IMON_REF" )
			)
			( signal "@baseboard_fab2_lib.baseboard_fab2(sch_1):tp_pvddq_def_pinalrt_n"
				( objectStatus "TP_PVDDQ_DEF_PINALRT_N" )
			)
			( signal "@baseboard_fab2_lib.baseboard_fab2(sch_1):tp_pvddq_def_pwm3"
				( objectStatus "TP_PVDDQ_DEF_PWM3" )
			)
			( signal "@baseboard_fab2_lib.baseboard_fab2(sch_1):tp_pvddq_def_reset_n"
				( objectStatus "TP_PVDDQ_DEF_RESET_N" )
			)
			( signal "@baseboard_fab2_lib.baseboard_fab2(sch_1):tp_pvddq_ghj_bpwm1"
				( objectStatus "TP_PVDDQ_GHJ_BPWM1" )
			)
			( signal "@baseboard_fab2_lib.baseboard_fab2(sch_1):tp_pvddq_ghj_bref1"
				( objectStatus "TP_PVDDQ_GHJ_BREF1" )
			)
			( signal "@baseboard_fab2_lib.baseboard_fab2(sch_1):tp_pvddq_ghj_btsen"
				( objectStatus "TP_PVDDQ_GHJ_BTSEN" )
			)
			( signal "@baseboard_fab2_lib.baseboard_fab2(sch_1):tp_pvddq_ghj_bvref"
				( objectStatus "TP_PVDDQ_GHJ_BVREF" )
			)
			( signal "@baseboard_fab2_lib.baseboard_fab2(sch_1):tp_pvddq_ghj_bvsen"
				( objectStatus "TP_PVDDQ_GHJ_BVSEN" )
			)
			( signal "@baseboard_fab2_lib.baseboard_fab2(sch_1):tp_pvddq_ghj_mp1"
				( objectStatus "TP_PVDDQ_GHJ_MP1" )
			)
			( signal "@baseboard_fab2_lib.baseboard_fab2(sch_1):tp_pvddq_ghj_pwm3"
				( objectStatus "TP_PVDDQ_GHJ_PWM3" )
			)
			( signal "@baseboard_fab2_lib.baseboard_fab2(sch_1):tp_pvddq_ghj_reset_n"
				( objectStatus "TP_PVDDQ_GHJ_RESET_N" )
			)
			( signal "@baseboard_fab2_lib.baseboard_fab2(sch_1):tp_pvddq_klm_bpwm1"
				( objectStatus "TP_PVDDQ_KLM_BPWM1" )
			)
			( signal "@baseboard_fab2_lib.baseboard_fab2(sch_1):tp_pvddq_klm_bref1"
				( objectStatus "TP_PVDDQ_KLM_BREF1" )
			)
			( signal "@baseboard_fab2_lib.baseboard_fab2(sch_1):tp_pvddq_klm_btsen"
				( objectStatus "TP_PVDDQ_KLM_BTSEN" )
			)
			( signal "@baseboard_fab2_lib.baseboard_fab2(sch_1):tp_pvddq_klm_bvref"
				( objectStatus "TP_PVDDQ_KLM_BVREF" )
			)
			( signal "@baseboard_fab2_lib.baseboard_fab2(sch_1):tp_pvddq_klm_bvsen"
				( objectStatus "TP_PVDDQ_KLM_BVSEN" )
			)
			( signal "@baseboard_fab2_lib.baseboard_fab2(sch_1):tp_pvddq_klm_reset_n"
				( objectStatus "TP_PVDDQ_KLM_RESET_N" )
			)
			( signal "@baseboard_fab2_lib.baseboard_fab2(sch_1):tp_pvnn_pch_pinalrt_n"
				( objectStatus "TP_PVNN_PCH_PINALRT_N" )
			)
			( signal "@baseboard_fab2_lib.baseboard_fab2(sch_1):tp_pvnn_pch_reset_n"
				( objectStatus "TP_PVNN_PCH_RESET_N" )
			)
			( signal "@baseboard_fab2_lib.baseboard_fab2(sch_1):tp_pvnn_pch_svid_alert"
				( objectStatus "TP_PVNN_PCH_SVID_ALERT" )
			)
			( signal "@baseboard_fab2_lib.baseboard_fab2(sch_1):tp_pvnn_pch_vclk"
				( objectStatus "TP_PVNN_PCH_VCLK" )
			)
			( signal "@baseboard_fab2_lib.baseboard_fab2(sch_1):tp_pvnn_pch_vdio"
				( objectStatus "TP_PVNN_PCH_VDIO" )
			)
			( signal "@baseboard_fab2_lib.baseboard_fab2(sch_1):tp_cpld1_pt22d"
				( objectStatus "TP_CPLD1_PT22D" )
			)
			( signal "@baseboard_fab2_lib.baseboard_fab2(sch_1):tp_p3e_cpu1_pe1_mp_rxn(0)"
				( objectStatus "TP_P3E_CPU1_PE1_MP_RXN<0>" )
			)
			( signal "@baseboard_fab2_lib.baseboard_fab2(sch_1):tp_p3e_cpu1_pe1_mp_rxn(1)"
				( objectStatus "TP_P3E_CPU1_PE1_MP_RXN<1>" )
			)
			( signal "@baseboard_fab2_lib.baseboard_fab2(sch_1):tp_p3e_cpu1_pe1_mp_rxn(2)"
				( objectStatus "TP_P3E_CPU1_PE1_MP_RXN<2>" )
			)
			( signal "@baseboard_fab2_lib.baseboard_fab2(sch_1):tp_p3e_cpu1_pe1_mp_rxn(3)"
				( objectStatus "TP_P3E_CPU1_PE1_MP_RXN<3>" )
			)
			( signal "@baseboard_fab2_lib.baseboard_fab2(sch_1):tp_p3e_cpu1_pe1_mp_rxn(4)"
				( objectStatus "TP_P3E_CPU1_PE1_MP_RXN<4>" )
			)
			( signal "@baseboard_fab2_lib.baseboard_fab2(sch_1):tp_p3e_cpu1_pe1_mp_rxn(5)"
				( objectStatus "TP_P3E_CPU1_PE1_MP_RXN<5>" )
			)
			( signal "@baseboard_fab2_lib.baseboard_fab2(sch_1):tp_p3e_cpu1_pe1_mp_rxn(6)"
				( objectStatus "TP_P3E_CPU1_PE1_MP_RXN<6>" )
			)
			( signal "@baseboard_fab2_lib.baseboard_fab2(sch_1):tp_p3e_cpu1_pe1_mp_rxn(7)"
				( objectStatus "TP_P3E_CPU1_PE1_MP_RXN<7>" )
			)
			( signal "@baseboard_fab2_lib.baseboard_fab2(sch_1):tp_p3e_cpu1_pe1_mp_rxp(0)"
				( objectStatus "TP_P3E_CPU1_PE1_MP_RXP<0>" )
			)
			( signal "@baseboard_fab2_lib.baseboard_fab2(sch_1):tp_p3e_cpu1_pe1_mp_rxp(1)"
				( objectStatus "TP_P3E_CPU1_PE1_MP_RXP<1>" )
			)
			( signal "@baseboard_fab2_lib.baseboard_fab2(sch_1):tp_p3e_cpu1_pe1_mp_rxp(2)"
				( objectStatus "TP_P3E_CPU1_PE1_MP_RXP<2>" )
			)
			( signal "@baseboard_fab2_lib.baseboard_fab2(sch_1):tp_p3e_cpu1_pe1_mp_rxp(3)"
				( objectStatus "TP_P3E_CPU1_PE1_MP_RXP<3>" )
			)
			( signal "@baseboard_fab2_lib.baseboard_fab2(sch_1):tp_p3e_cpu1_pe1_mp_rxp(4)"
				( objectStatus "TP_P3E_CPU1_PE1_MP_RXP<4>" )
			)
			( signal "@baseboard_fab2_lib.baseboard_fab2(sch_1):tp_p3e_cpu1_pe1_mp_rxp(5)"
				( objectStatus "TP_P3E_CPU1_PE1_MP_RXP<5>" )
			)
			( signal "@baseboard_fab2_lib.baseboard_fab2(sch_1):tp_p3e_cpu1_pe1_mp_rxp(6)"
				( objectStatus "TP_P3E_CPU1_PE1_MP_RXP<6>" )
			)
			( signal "@baseboard_fab2_lib.baseboard_fab2(sch_1):tp_p3e_cpu1_pe1_mp_rxp(7)"
				( objectStatus "TP_P3E_CPU1_PE1_MP_RXP<7>" )
			)
			( signal "@baseboard_fab2_lib.baseboard_fab2(sch_1):tp_p3e_cpu1_pe1_mp_txn(0)"
				( objectStatus "TP_P3E_CPU1_PE1_MP_TXN<0>" )
			)
			( signal "@baseboard_fab2_lib.baseboard_fab2(sch_1):tp_p3e_cpu1_pe1_mp_txn(1)"
				( objectStatus "TP_P3E_CPU1_PE1_MP_TXN<1>" )
			)
			( signal "@baseboard_fab2_lib.baseboard_fab2(sch_1):tp_p3e_cpu1_pe1_mp_txn(2)"
				( objectStatus "TP_P3E_CPU1_PE1_MP_TXN<2>" )
			)
			( signal "@baseboard_fab2_lib.baseboard_fab2(sch_1):tp_p3e_cpu1_pe1_mp_txn(3)"
				( objectStatus "TP_P3E_CPU1_PE1_MP_TXN<3>" )
			)
			( signal "@baseboard_fab2_lib.baseboard_fab2(sch_1):tp_p3e_cpu1_pe1_mp_txn(4)"
				( objectStatus "TP_P3E_CPU1_PE1_MP_TXN<4>" )
			)
			( signal "@baseboard_fab2_lib.baseboard_fab2(sch_1):tp_p3e_cpu1_pe1_mp_txn(5)"
				( objectStatus "TP_P3E_CPU1_PE1_MP_TXN<5>" )
			)
			( signal "@baseboard_fab2_lib.baseboard_fab2(sch_1):tp_p3e_cpu1_pe1_mp_txn(6)"
				( objectStatus "TP_P3E_CPU1_PE1_MP_TXN<6>" )
			)
			( signal "@baseboard_fab2_lib.baseboard_fab2(sch_1):tp_p3e_cpu1_pe1_mp_txn(7)"
				( objectStatus "TP_P3E_CPU1_PE1_MP_TXN<7>" )
			)
			( signal "@baseboard_fab2_lib.baseboard_fab2(sch_1):tp_p3e_cpu1_pe1_mp_txp(0)"
				( objectStatus "TP_P3E_CPU1_PE1_MP_TXP<0>" )
			)
			( signal "@baseboard_fab2_lib.baseboard_fab2(sch_1):tp_p3e_cpu1_pe1_mp_txp(1)"
				( objectStatus "TP_P3E_CPU1_PE1_MP_TXP<1>" )
			)
			( signal "@baseboard_fab2_lib.baseboard_fab2(sch_1):tp_p3e_cpu1_pe1_mp_txp(2)"
				( objectStatus "TP_P3E_CPU1_PE1_MP_TXP<2>" )
			)
			( signal "@baseboard_fab2_lib.baseboard_fab2(sch_1):tp_p3e_cpu1_pe1_mp_txp(3)"
				( objectStatus "TP_P3E_CPU1_PE1_MP_TXP<3>" )
			)
			( signal "@baseboard_fab2_lib.baseboard_fab2(sch_1):tp_p3e_cpu1_pe1_mp_txp(4)"
				( objectStatus "TP_P3E_CPU1_PE1_MP_TXP<4>" )
			)
			( signal "@baseboard_fab2_lib.baseboard_fab2(sch_1):tp_p3e_cpu1_pe1_mp_txp(5)"
				( objectStatus "TP_P3E_CPU1_PE1_MP_TXP<5>" )
			)
			( signal "@baseboard_fab2_lib.baseboard_fab2(sch_1):tp_xdp_cpu_obsfn_c0"
				( objectStatus "TP_XDP_CPU_OBSFN_C0" )
			)
			( signal "@baseboard_fab2_lib.baseboard_fab2(sch_1):tp_xdp_cpu0_obsdata_a0_mbp2_n"
				( objectStatus "TP_XDP_CPU0_OBSDATA_A0_MBP2_N" )
			)
			( signal "@baseboard_fab2_lib.baseboard_fab2(sch_1):tp_p3e_cpu1_pe1_rsr3_rxp(10)"
				( objectStatus "TP_P3E_CPU1_PE1_RSR3_RXP<10>" )
			)
			( signal "@baseboard_fab2_lib.baseboard_fab2(sch_1):tp_p3e_cpu1_pe1_rsr3_rxp(11)"
				( objectStatus "TP_P3E_CPU1_PE1_RSR3_RXP<11>" )
			)
			( signal "@baseboard_fab2_lib.baseboard_fab2(sch_1):tp_p3e_cpu1_pe1_rsr3_rxp(12)"
				( objectStatus "TP_P3E_CPU1_PE1_RSR3_RXP<12>" )
			)
			( signal "@baseboard_fab2_lib.baseboard_fab2(sch_1):tp_p3e_cpu1_pe1_rsr3_rxp(13)"
				( objectStatus "TP_P3E_CPU1_PE1_RSR3_RXP<13>" )
			)
			( signal "@baseboard_fab2_lib.baseboard_fab2(sch_1):tp_p3e_cpu1_pe1_rsr3_rxp(14)"
				( objectStatus "TP_P3E_CPU1_PE1_RSR3_RXP<14>" )
			)
			( signal "@baseboard_fab2_lib.baseboard_fab2(sch_1):tp_p3e_cpu1_pe1_rsr3_rxp(15)"
				( objectStatus "TP_P3E_CPU1_PE1_RSR3_RXP<15>" )
			)
			( signal "@baseboard_fab2_lib.baseboard_fab2(sch_1):tp_p3e_cpu1_pe1_rsr3_txn(8)"
				( objectStatus "TP_P3E_CPU1_PE1_RSR3_TXN<8>" )
			)
			( signal "@baseboard_fab2_lib.baseboard_fab2(sch_1):tp_p3e_cpu1_pe1_rsr3_txn(9)"
				( objectStatus "TP_P3E_CPU1_PE1_RSR3_TXN<9>" )
			)
			( signal "@baseboard_fab2_lib.baseboard_fab2(sch_1):tp_p3e_cpu1_pe1_rsr3_txn(10)"
				( objectStatus "TP_P3E_CPU1_PE1_RSR3_TXN<10>" )
			)
			( signal "@baseboard_fab2_lib.baseboard_fab2(sch_1):tp_p3e_cpu1_pe1_rsr3_txn(11)"
				( objectStatus "TP_P3E_CPU1_PE1_RSR3_TXN<11>" )
			)
			( signal "@baseboard_fab2_lib.baseboard_fab2(sch_1):tp_p3e_cpu1_pe1_rsr3_txn(12)"
				( objectStatus "TP_P3E_CPU1_PE1_RSR3_TXN<12>" )
			)
			( signal "@baseboard_fab2_lib.baseboard_fab2(sch_1):tp_p3e_cpu1_pe1_rsr3_txn(13)"
				( objectStatus "TP_P3E_CPU1_PE1_RSR3_TXN<13>" )
			)
			( signal "@baseboard_fab2_lib.baseboard_fab2(sch_1):tp_p3e_cpu1_pe1_rsr3_txn(14)"
				( objectStatus "TP_P3E_CPU1_PE1_RSR3_TXN<14>" )
			)
			( signal "@baseboard_fab2_lib.baseboard_fab2(sch_1):tp_p3e_cpu1_pe1_rsr3_txn(15)"
				( objectStatus "TP_P3E_CPU1_PE1_RSR3_TXN<15>" )
			)
			( signal "@baseboard_fab2_lib.baseboard_fab2(sch_1):tp_p3e_cpu1_pe1_rsr3_txp(8)"
				( objectStatus "TP_P3E_CPU1_PE1_RSR3_TXP<8>" )
			)
			( signal "@baseboard_fab2_lib.baseboard_fab2(sch_1):tp_p3e_cpu1_pe1_rsr3_txp(9)"
				( objectStatus "TP_P3E_CPU1_PE1_RSR3_TXP<9>" )
			)
			( signal "@baseboard_fab2_lib.baseboard_fab2(sch_1):tp_p3e_cpu1_pe1_rsr3_txp(10)"
				( objectStatus "TP_P3E_CPU1_PE1_RSR3_TXP<10>" )
			)
			( signal "@baseboard_fab2_lib.baseboard_fab2(sch_1):tp_p3e_cpu1_pe1_rsr3_txp(11)"
				( objectStatus "TP_P3E_CPU1_PE1_RSR3_TXP<11>" )
			)
			( signal "@baseboard_fab2_lib.baseboard_fab2(sch_1):tp_p3e_cpu1_pe1_rsr3_txp(12)"
				( objectStatus "TP_P3E_CPU1_PE1_RSR3_TXP<12>" )
			)
			( signal "@baseboard_fab2_lib.baseboard_fab2(sch_1):tp_p3e_cpu1_pe1_rsr3_txp(13)"
				( objectStatus "TP_P3E_CPU1_PE1_RSR3_TXP<13>" )
			)
			( signal "@baseboard_fab2_lib.baseboard_fab2(sch_1):tp_p3e_cpu1_pe1_rsr3_txp(14)"
				( objectStatus "TP_P3E_CPU1_PE1_RSR3_TXP<14>" )
			)
			( signal "@baseboard_fab2_lib.baseboard_fab2(sch_1):tp_p3e_cpu1_pe1_rsr3_txp(15)"
				( objectStatus "TP_P3E_CPU1_PE1_RSR3_TXP<15>" )
			)
			( signal "@baseboard_fab2_lib.baseboard_fab2(sch_1):tp_p3e_cpu1_pe2_rsr_rxn(0)"
				( objectStatus "TP_P3E_CPU1_PE2_RSR_RXN<0>" )
			)
			( signal "@baseboard_fab2_lib.baseboard_fab2(sch_1):tp_p3e_cpu1_pe2_rsr_rxn(1)"
				( objectStatus "TP_P3E_CPU1_PE2_RSR_RXN<1>" )
			)
			( signal "@baseboard_fab2_lib.baseboard_fab2(sch_1):tp_p3e_cpu1_pe2_rsr_rxn(2)"
				( objectStatus "TP_P3E_CPU1_PE2_RSR_RXN<2>" )
			)
			( signal "@baseboard_fab2_lib.baseboard_fab2(sch_1):tp_p3e_cpu1_pe2_rsr_rxn(3)"
				( objectStatus "TP_P3E_CPU1_PE2_RSR_RXN<3>" )
			)
			( signal "@baseboard_fab2_lib.baseboard_fab2(sch_1):tp_p3e_cpu1_pe2_rsr_rxn(4)"
				( objectStatus "TP_P3E_CPU1_PE2_RSR_RXN<4>" )
			)
			( signal "@baseboard_fab2_lib.baseboard_fab2(sch_1):tp_p3e_cpu1_pe2_rsr_rxn(5)"
				( objectStatus "TP_P3E_CPU1_PE2_RSR_RXN<5>" )
			)
			( signal "@baseboard_fab2_lib.baseboard_fab2(sch_1):tp_p3e_cpu1_pe2_rsr_rxn(6)"
				( objectStatus "TP_P3E_CPU1_PE2_RSR_RXN<6>" )
			)
			( signal "@baseboard_fab2_lib.baseboard_fab2(sch_1):tp_p3e_cpu1_pe2_rsr_rxn(7)"
				( objectStatus "TP_P3E_CPU1_PE2_RSR_RXN<7>" )
			)
			( signal "@baseboard_fab2_lib.baseboard_fab2(sch_1):tp_p3e_cpu1_pe2_rsr_rxn(8)"
				( objectStatus "TP_P3E_CPU1_PE2_RSR_RXN<8>" )
			)
			( signal "@baseboard_fab2_lib.baseboard_fab2(sch_1):tp_p3e_cpu1_pe2_rsr_rxn(9)"
				( objectStatus "TP_P3E_CPU1_PE2_RSR_RXN<9>" )
			)
			( signal "@baseboard_fab2_lib.baseboard_fab2(sch_1):tp_p3e_cpu1_pe2_rsr_rxn(10)"
				( objectStatus "TP_P3E_CPU1_PE2_RSR_RXN<10>" )
			)
			( signal "@baseboard_fab2_lib.baseboard_fab2(sch_1):tp_p3e_cpu1_pe2_rsr_rxn(11)"
				( objectStatus "TP_P3E_CPU1_PE2_RSR_RXN<11>" )
			)
			( signal "@baseboard_fab2_lib.baseboard_fab2(sch_1):tp_p3e_cpu1_pe2_rsr_rxn(12)"
				( objectStatus "TP_P3E_CPU1_PE2_RSR_RXN<12>" )
			)
			( signal "@baseboard_fab2_lib.baseboard_fab2(sch_1):tp_p3e_cpu1_pe2_rsr_rxn(13)"
				( objectStatus "TP_P3E_CPU1_PE2_RSR_RXN<13>" )
			)
			( signal "@baseboard_fab2_lib.baseboard_fab2(sch_1):tp_p3e_cpu1_pe2_rsr_rxn(14)"
				( objectStatus "TP_P3E_CPU1_PE2_RSR_RXN<14>" )
			)
			( signal "@baseboard_fab2_lib.baseboard_fab2(sch_1):tp_p3e_cpu1_pe2_rsr_rxn(15)"
				( objectStatus "TP_P3E_CPU1_PE2_RSR_RXN<15>" )
			)
			( signal "@baseboard_fab2_lib.baseboard_fab2(sch_1):tp_p3e_cpu1_pe2_rsr_rxp(0)"
				( objectStatus "TP_P3E_CPU1_PE2_RSR_RXP<0>" )
			)
			( signal "@baseboard_fab2_lib.baseboard_fab2(sch_1):tp_p3e_cpu1_pe2_rsr_rxp(1)"
				( objectStatus "TP_P3E_CPU1_PE2_RSR_RXP<1>" )
			)
			( signal "@baseboard_fab2_lib.baseboard_fab2(sch_1):tp_p3e_cpu1_pe2_rsr_rxp(2)"
				( objectStatus "TP_P3E_CPU1_PE2_RSR_RXP<2>" )
			)
			( signal "@baseboard_fab2_lib.baseboard_fab2(sch_1):tp_p3e_cpu1_pe2_rsr_rxp(3)"
				( objectStatus "TP_P3E_CPU1_PE2_RSR_RXP<3>" )
			)
			( signal "@baseboard_fab2_lib.baseboard_fab2(sch_1):tp_p3e_cpu1_pe2_rsr_rxp(4)"
				( objectStatus "TP_P3E_CPU1_PE2_RSR_RXP<4>" )
			)
			( signal "@baseboard_fab2_lib.baseboard_fab2(sch_1):tp_p3e_cpu1_pe2_rsr_rxp(5)"
				( objectStatus "TP_P3E_CPU1_PE2_RSR_RXP<5>" )
			)
			( signal "@baseboard_fab2_lib.baseboard_fab2(sch_1):tp_p3e_cpu1_pe2_rsr_rxp(6)"
				( objectStatus "TP_P3E_CPU1_PE2_RSR_RXP<6>" )
			)
			( signal "@baseboard_fab2_lib.baseboard_fab2(sch_1):tp_p3e_cpu1_pe2_rsr_rxp(7)"
				( objectStatus "TP_P3E_CPU1_PE2_RSR_RXP<7>" )
			)
			( signal "@baseboard_fab2_lib.baseboard_fab2(sch_1):tp_p3e_cpu1_pe2_rsr_rxp(8)"
				( objectStatus "TP_P3E_CPU1_PE2_RSR_RXP<8>" )
			)
			( signal "@baseboard_fab2_lib.baseboard_fab2(sch_1):tp_p3e_cpu1_pe2_rsr_rxp(9)"
				( objectStatus "TP_P3E_CPU1_PE2_RSR_RXP<9>" )
			)
			( signal "@baseboard_fab2_lib.baseboard_fab2(sch_1):tp_p3e_cpu1_pe2_rsr_rxp(10)"
				( objectStatus "TP_P3E_CPU1_PE2_RSR_RXP<10>" )
			)
			( signal "@baseboard_fab2_lib.baseboard_fab2(sch_1):tp_p3e_cpu1_pe2_rsr_rxp(11)"
				( objectStatus "TP_P3E_CPU1_PE2_RSR_RXP<11>" )
			)
			( signal "@baseboard_fab2_lib.baseboard_fab2(sch_1):tp_p3e_cpu1_pe2_rsr_rxp(12)"
				( objectStatus "TP_P3E_CPU1_PE2_RSR_RXP<12>" )
			)
			( signal "@baseboard_fab2_lib.baseboard_fab2(sch_1):tp_p3e_cpu1_pe2_rsr_rxp(13)"
				( objectStatus "TP_P3E_CPU1_PE2_RSR_RXP<13>" )
			)
			( signal "@baseboard_fab2_lib.baseboard_fab2(sch_1):tp_p3e_cpu1_pe2_rsr_rxp(14)"
				( objectStatus "TP_P3E_CPU1_PE2_RSR_RXP<14>" )
			)
			( signal "@baseboard_fab2_lib.baseboard_fab2(sch_1):tp_p3e_cpu1_pe2_rsr_rxp(15)"
				( objectStatus "TP_P3E_CPU1_PE2_RSR_RXP<15>" )
			)
			( signal "@baseboard_fab2_lib.baseboard_fab2(sch_1):tp_p3e_cpu1_pe2_rsr_txn(0)"
				( objectStatus "TP_P3E_CPU1_PE2_RSR_TXN<0>" )
			)
			( signal "@baseboard_fab2_lib.baseboard_fab2(sch_1):tp_p3e_cpu1_pe2_rsr_txn(1)"
				( objectStatus "TP_P3E_CPU1_PE2_RSR_TXN<1>" )
			)
			( signal "@baseboard_fab2_lib.baseboard_fab2(sch_1):tp_p3e_cpu1_pe2_rsr_txn(2)"
				( objectStatus "TP_P3E_CPU1_PE2_RSR_TXN<2>" )
			)
			( signal "@baseboard_fab2_lib.baseboard_fab2(sch_1):tp_p3e_cpu1_pe2_rsr_txn(3)"
				( objectStatus "TP_P3E_CPU1_PE2_RSR_TXN<3>" )
			)
			( signal "@baseboard_fab2_lib.baseboard_fab2(sch_1):tp_p3e_cpu1_pe2_rsr_txn(4)"
				( objectStatus "TP_P3E_CPU1_PE2_RSR_TXN<4>" )
			)
			( signal "@baseboard_fab2_lib.baseboard_fab2(sch_1):tp_p3e_cpu1_pe2_rsr_txn(5)"
				( objectStatus "TP_P3E_CPU1_PE2_RSR_TXN<5>" )
			)
			( signal "@baseboard_fab2_lib.baseboard_fab2(sch_1):tp_p3e_cpu1_pe2_rsr_txn(6)"
				( objectStatus "TP_P3E_CPU1_PE2_RSR_TXN<6>" )
			)
			( signal "@baseboard_fab2_lib.baseboard_fab2(sch_1):tp_p3e_cpu1_pe2_rsr_txn(7)"
				( objectStatus "TP_P3E_CPU1_PE2_RSR_TXN<7>" )
			)
			( signal "@baseboard_fab2_lib.baseboard_fab2(sch_1):tp_p3e_cpu1_pe2_rsr_txn(8)"
				( objectStatus "TP_P3E_CPU1_PE2_RSR_TXN<8>" )
			)
			( signal "@baseboard_fab2_lib.baseboard_fab2(sch_1):tp_p3e_cpu1_pe2_rsr_txn(9)"
				( objectStatus "TP_P3E_CPU1_PE2_RSR_TXN<9>" )
			)
			( signal "@baseboard_fab2_lib.baseboard_fab2(sch_1):tp_p3e_cpu1_pe2_rsr_txn(10)"
				( objectStatus "TP_P3E_CPU1_PE2_RSR_TXN<10>" )
			)
			( signal "@baseboard_fab2_lib.baseboard_fab2(sch_1):tp_p3e_cpu1_pe2_rsr_txn(11)"
				( objectStatus "TP_P3E_CPU1_PE2_RSR_TXN<11>" )
			)
			( signal "@baseboard_fab2_lib.baseboard_fab2(sch_1):tp_p3e_cpu1_pe2_rsr_txn(12)"
				( objectStatus "TP_P3E_CPU1_PE2_RSR_TXN<12>" )
			)
			( signal "@baseboard_fab2_lib.baseboard_fab2(sch_1):tp_p3e_cpu1_pe2_rsr_txn(13)"
				( objectStatus "TP_P3E_CPU1_PE2_RSR_TXN<13>" )
			)
			( signal "@baseboard_fab2_lib.baseboard_fab2(sch_1):tp_p3e_cpu1_pe2_rsr_txn(14)"
				( objectStatus "TP_P3E_CPU1_PE2_RSR_TXN<14>" )
			)
			( signal "@baseboard_fab2_lib.baseboard_fab2(sch_1):tp_p3e_cpu1_pe2_rsr_txn(15)"
				( objectStatus "TP_P3E_CPU1_PE2_RSR_TXN<15>" )
			)
			( signal "@baseboard_fab2_lib.baseboard_fab2(sch_1):tp_p3e_cpu1_pe2_rsr_txp(0)"
				( objectStatus "TP_P3E_CPU1_PE2_RSR_TXP<0>" )
			)
			( signal "@baseboard_fab2_lib.baseboard_fab2(sch_1):tp_p3e_cpu1_pe2_rsr_txp(1)"
				( objectStatus "TP_P3E_CPU1_PE2_RSR_TXP<1>" )
			)
			( signal "@baseboard_fab2_lib.baseboard_fab2(sch_1):tp_p3e_cpu1_pe2_rsr_txp(2)"
				( objectStatus "TP_P3E_CPU1_PE2_RSR_TXP<2>" )
			)
			( signal "@baseboard_fab2_lib.baseboard_fab2(sch_1):tp_p3e_cpu1_pe2_rsr_txp(3)"
				( objectStatus "TP_P3E_CPU1_PE2_RSR_TXP<3>" )
			)
			( signal "@baseboard_fab2_lib.baseboard_fab2(sch_1):tp_p3e_cpu1_pe2_rsr_txp(4)"
				( objectStatus "TP_P3E_CPU1_PE2_RSR_TXP<4>" )
			)
			( signal "@baseboard_fab2_lib.baseboard_fab2(sch_1):tp_p3e_cpu1_pe2_rsr_txp(5)"
				( objectStatus "TP_P3E_CPU1_PE2_RSR_TXP<5>" )
			)
			( signal "@baseboard_fab2_lib.baseboard_fab2(sch_1):tp_p3e_cpu1_pe2_rsr_txp(6)"
				( objectStatus "TP_P3E_CPU1_PE2_RSR_TXP<6>" )
			)
			( signal "@baseboard_fab2_lib.baseboard_fab2(sch_1):tp_p3e_cpu1_pe2_rsr_txp(7)"
				( objectStatus "TP_P3E_CPU1_PE2_RSR_TXP<7>" )
			)
			( signal "@baseboard_fab2_lib.baseboard_fab2(sch_1):tp_p3e_cpu1_pe2_rsr_txp(8)"
				( objectStatus "TP_P3E_CPU1_PE2_RSR_TXP<8>" )
			)
			( signal "@baseboard_fab2_lib.baseboard_fab2(sch_1):tp_p3e_cpu1_pe2_rsr_txp(9)"
				( objectStatus "TP_P3E_CPU1_PE2_RSR_TXP<9>" )
			)
			( signal "@baseboard_fab2_lib.baseboard_fab2(sch_1):tp_p3e_cpu1_pe2_rsr_txp(10)"
				( objectStatus "TP_P3E_CPU1_PE2_RSR_TXP<10>" )
			)
			( signal "@baseboard_fab2_lib.baseboard_fab2(sch_1):tp_p3e_cpu1_pe2_rsr_txp(11)"
				( objectStatus "TP_P3E_CPU1_PE2_RSR_TXP<11>" )
			)
			( signal "@baseboard_fab2_lib.baseboard_fab2(sch_1):tp_p3e_cpu1_pe2_rsr_txp(12)"
				( objectStatus "TP_P3E_CPU1_PE2_RSR_TXP<12>" )
			)
			( signal "@baseboard_fab2_lib.baseboard_fab2(sch_1):tp_p3e_cpu1_pe2_rsr_txp(13)"
				( objectStatus "TP_P3E_CPU1_PE2_RSR_TXP<13>" )
			)
			( signal "@baseboard_fab2_lib.baseboard_fab2(sch_1):tp_p3e_cpu1_pe2_rsr_txp(14)"
				( objectStatus "TP_P3E_CPU1_PE2_RSR_TXP<14>" )
			)
			( signal "@baseboard_fab2_lib.baseboard_fab2(sch_1):tp_p3e_cpu1_pe2_rsr_txp(15)"
				( objectStatus "TP_P3E_CPU1_PE2_RSR_TXP<15>" )
			)
			( signal "@baseboard_fab2_lib.baseboard_fab2(sch_1):tp_cpld1_pt17b_pclkc0_1"
				( objectStatus "TP_CPLD1_PT17B_PCLKC0_1" )
			)
			( signal "@baseboard_fab2_lib.baseboard_fab2(sch_1):tp_xdp_cpu0_obsdata_a1_mbp3_n"
				( objectStatus "TP_XDP_CPU0_OBSDATA_A1_MBP3_N" )
			)
			( signal "@baseboard_fab2_lib.baseboard_fab2(sch_1):tp_xdp_cpu0_obsdata_a2_mbp4_n"
				( objectStatus "TP_XDP_CPU0_OBSDATA_A2_MBP4_N" )
			)
			( signal "@baseboard_fab2_lib.baseboard_fab2(sch_1):tp_xdp_cpu0_obsdata_a3_mbp5_n"
				( objectStatus "TP_XDP_CPU0_OBSDATA_A3_MBP5_N" )
			)
			( signal "@baseboard_fab2_lib.baseboard_fab2(sch_1):tp_xdp_cpu1_obsdata_b0_mbp2_n"
				( objectStatus "TP_XDP_CPU1_OBSDATA_B0_MBP2_N" )
			)
			( signal "@baseboard_fab2_lib.baseboard_fab2(sch_1):tp_xdp_cpu1_obsdata_b1_mbp3_n"
				( objectStatus "TP_XDP_CPU1_OBSDATA_B1_MBP3_N" )
			)
			( signal "@baseboard_fab2_lib.baseboard_fab2(sch_1):tp_xdp_cpu1_obsdata_b2_mbp4_n"
				( objectStatus "TP_XDP_CPU1_OBSDATA_B2_MBP4_N" )
			)
			( signal "@baseboard_fab2_lib.baseboard_fab2(sch_1):tp_xdp_cpu1_obsdata_b3_mbp5_n"
				( objectStatus "TP_XDP_CPU1_OBSDATA_B3_MBP5_N" )
			)
			( signal "@baseboard_fab2_lib.baseboard_fab2(sch_1):tp_10gbe_kr0_mon_dn"
				( objectStatus "TP_10GBE_KR0_MON_DN" )
			)
			( signal "@baseboard_fab2_lib.baseboard_fab2(sch_1):tp_10gbe_kr0_mon_dp"
				( objectStatus "TP_10GBE_KR0_MON_DP" )
			)
			( signal "@baseboard_fab2_lib.baseboard_fab2(sch_1):tp_10gbe_kr1_mon_dn"
				( objectStatus "TP_10GBE_KR1_MON_DN" )
			)
			( signal "@baseboard_fab2_lib.baseboard_fab2(sch_1):tp_10gbe_kr1_mon_dp"
				( objectStatus "TP_10GBE_KR1_MON_DP" )
			)
			( signal "@baseboard_fab2_lib.baseboard_fab2(sch_1):tp_33p_33m_smbadr"
				( objectStatus "TP_33P_33M_SMBADR" )
			)
			( signal "@baseboard_fab2_lib.baseboard_fab2(sch_1):tp_sgpio_sata_load1_r"
				( objectStatus "TP_SGPIO_SATA_LOAD1_R" )
			)
			( signal "@baseboard_fab2_lib.baseboard_fab2(sch_1):tp_slp_lan_n"
				( objectStatus "TP_SLP_LAN_N" )
			)
			( signal "@baseboard_fab2_lib.baseboard_fab2(sch_1):tp_smb_ddr_abc_en"
				( objectStatus "TP_SMB_DDR_ABC_EN" )
			)
			( signal "@baseboard_fab2_lib.baseboard_fab2(sch_1):tp_smb_ddr_def_en"
				( objectStatus "TP_SMB_DDR_DEF_EN" )
			)
			( signal "@baseboard_fab2_lib.baseboard_fab2(sch_1):tp_smb_ddr_ghj_en"
				( objectStatus "TP_SMB_DDR_GHJ_EN" )
			)
			( signal "@baseboard_fab2_lib.baseboard_fab2(sch_1):tp_smb_ddr_klm_en"
				( objectStatus "TP_SMB_DDR_KLM_EN" )
			)
			( signal "@baseboard_fab2_lib.baseboard_fab2(sch_1):tp_smb_pehpcpu1_en"
				( objectStatus "TP_SMB_PEHPCPU1_EN" )
			)
			( signal "@baseboard_fab2_lib.baseboard_fab2(sch_1):fm_cpu0_sm_wp"
				( objectStatus "FM_CPU0_SM_WP" )
			)
			( signal "@baseboard_fab2_lib.baseboard_fab2(sch_1):tp_spi_bmc_bt_d2"
				( objectStatus "TP_SPI_BMC_BT_D2" )
			)
			( signal "@baseboard_fab2_lib.baseboard_fab2(sch_1):tp_spi_pch_cs1_r1_n"
				( objectStatus "TP_SPI_PCH_CS1_R1_N" )
			)
			( signal "@baseboard_fab2_lib.baseboard_fab2(sch_1):tp_spi_0_0"
				( objectStatus "TP_SPI_0_0" )
			)
			( signal "@baseboard_fab2_lib.baseboard_fab2(sch_1):tp_spi_0_1"
				( objectStatus "TP_SPI_0_1" )
			)
			( signal "@baseboard_fab2_lib.baseboard_fab2(sch_1):tp_spi_0_2"
				( objectStatus "TP_SPI_0_2" )
			)
			( signal "@baseboard_fab2_lib.baseboard_fab2(sch_1):tp_spi_0_3"
				( objectStatus "TP_SPI_0_3" )
			)
			( signal "@baseboard_fab2_lib.baseboard_fab2(sch_1):tp_spi_0_4"
				( objectStatus "TP_SPI_0_4" )
			)
			( signal "@baseboard_fab2_lib.baseboard_fab2(sch_1):tp_spi_0_5"
				( objectStatus "TP_SPI_0_5" )
			)
			( signal "@baseboard_fab2_lib.baseboard_fab2(sch_1):tp_spi_0_6"
				( objectStatus "TP_SPI_0_6" )
			)
			( signal "@baseboard_fab2_lib.baseboard_fab2(sch_1):tp_spi_1_0"
				( objectStatus "TP_SPI_1_0" )
			)
			( signal "@baseboard_fab2_lib.baseboard_fab2(sch_1):tp_spi_1_1"
				( objectStatus "TP_SPI_1_1" )
			)
			( signal "@baseboard_fab2_lib.baseboard_fab2(sch_1):tp_spi_1_2"
				( objectStatus "TP_SPI_1_2" )
			)
			( signal "@baseboard_fab2_lib.baseboard_fab2(sch_1):tp_spi_1_3"
				( objectStatus "TP_SPI_1_3" )
			)
			( signal "@baseboard_fab2_lib.baseboard_fab2(sch_1):tp_spi_1_4"
				( objectStatus "TP_SPI_1_4" )
			)
			( signal "@baseboard_fab2_lib.baseboard_fab2(sch_1):tp_spi_1_5"
				( objectStatus "TP_SPI_1_5" )
			)
			( signal "@baseboard_fab2_lib.baseboard_fab2(sch_1):tp_spi_1_6"
				( objectStatus "TP_SPI_1_6" )
			)
			( signal "@baseboard_fab2_lib.baseboard_fab2(sch_1):tp_spi_2_6"
				( objectStatus "TP_SPI_2_6" )
			)
			( signal "@baseboard_fab2_lib.baseboard_fab2(sch_1):tp_spi_2_5"
				( objectStatus "TP_SPI_2_5" )
			)
			( signal "@baseboard_fab2_lib.baseboard_fab2(sch_1):tp_spi_2_4"
				( objectStatus "TP_SPI_2_4" )
			)
			( signal "@baseboard_fab2_lib.baseboard_fab2(sch_1):tp_spi_2_3"
				( objectStatus "TP_SPI_2_3" )
			)
			( signal "@baseboard_fab2_lib.baseboard_fab2(sch_1):tp_spi_2_2"
				( objectStatus "TP_SPI_2_2" )
			)
			( signal "@baseboard_fab2_lib.baseboard_fab2(sch_1):tp_spi_2_1"
				( objectStatus "TP_SPI_2_1" )
			)
			( signal "@baseboard_fab2_lib.baseboard_fab2(sch_1):tp_spi_2_0"
				( objectStatus "TP_SPI_2_0" )
			)
			( signal "@baseboard_fab2_lib.baseboard_fab2(sch_1):tp_usb2_p8_dn"
				( objectStatus "TP_USB2_P8_DN" )
			)
			( signal "@baseboard_fab2_lib.baseboard_fab2(sch_1):tp_usb2_p8_dp"
				( objectStatus "TP_USB2_P8_DP" )
			)
			( signal "@baseboard_fab2_lib.baseboard_fab2(sch_1):tp_usb2_p9_dn"
				( objectStatus "TP_USB2_P9_DN" )
			)
			( signal "@baseboard_fab2_lib.baseboard_fab2(sch_1):tp_usb2_p9_dp"
				( objectStatus "TP_USB2_P9_DP" )
			)
			( signal "@baseboard_fab2_lib.baseboard_fab2(sch_1):tp_usb2_p02_dn"
				( objectStatus "TP_USB2_P02_DN" )
			)
			( signal "@baseboard_fab2_lib.baseboard_fab2(sch_1):tp_usb2_p02_dp"
				( objectStatus "TP_USB2_P02_DP" )
			)
			( signal "@baseboard_fab2_lib.baseboard_fab2(sch_1):tp_usb2_p03_dn"
				( objectStatus "TP_USB2_P03_DN" )
			)
			( signal "@baseboard_fab2_lib.baseboard_fab2(sch_1):tp_usb2_p03_dp"
				( objectStatus "TP_USB2_P03_DP" )
			)
			( signal "@baseboard_fab2_lib.baseboard_fab2(sch_1):tp_usb2_p06_dn"
				( objectStatus "TP_USB2_P06_DN" )
			)
			( signal "@baseboard_fab2_lib.baseboard_fab2(sch_1):tp_usb2_p06_dp"
				( objectStatus "TP_USB2_P06_DP" )
			)
			( signal "@baseboard_fab2_lib.baseboard_fab2(sch_1):tp_usb2_p07_dn"
				( objectStatus "TP_USB2_P07_DN" )
			)
			( signal "@baseboard_fab2_lib.baseboard_fab2(sch_1):tp_usb2_p07_dp"
				( objectStatus "TP_USB2_P07_DP" )
			)
			( signal "@baseboard_fab2_lib.baseboard_fab2(sch_1):tp_usb2_p10_dn"
				( objectStatus "TP_USB2_P10_DN" )
			)
			( signal "@baseboard_fab2_lib.baseboard_fab2(sch_1):tp_usb2_p10_dp"
				( objectStatus "TP_USB2_P10_DP" )
			)
			( signal "@baseboard_fab2_lib.baseboard_fab2(sch_1):tp_usb2_p11_dn"
				( objectStatus "TP_USB2_P11_DN" )
			)
			( signal "@baseboard_fab2_lib.baseboard_fab2(sch_1):tp_usb2_p11_dp"
				( objectStatus "TP_USB2_P11_DP" )
			)
			( signal "@baseboard_fab2_lib.baseboard_fab2(sch_1):tp_usb2_p12_dn"
				( objectStatus "TP_USB2_P12_DN" )
			)
			( signal "@baseboard_fab2_lib.baseboard_fab2(sch_1):tp_usb2_p12_dp"
				( objectStatus "TP_USB2_P12_DP" )
			)
			( signal "@baseboard_fab2_lib.baseboard_fab2(sch_1):tp_usb2_p13_dn"
				( objectStatus "TP_USB2_P13_DN" )
			)
			( signal "@baseboard_fab2_lib.baseboard_fab2(sch_1):tp_usb2_p13_dp"
				( objectStatus "TP_USB2_P13_DP" )
			)
			( signal "@baseboard_fab2_lib.baseboard_fab2(sch_1):tp_usb2_p14_dn"
				( objectStatus "TP_USB2_P14_DN" )
			)
			( signal "@baseboard_fab2_lib.baseboard_fab2(sch_1):tp_usb2_p14_dp"
				( objectStatus "TP_USB2_P14_DP" )
			)
			( signal "@baseboard_fab2_lib.baseboard_fab2(sch_1):tp_usb3_p04_rxn"
				( objectStatus "TP_USB3_P04_RXN" )
			)
			( signal "@baseboard_fab2_lib.baseboard_fab2(sch_1):tp_usb3_p04_rxp"
				( objectStatus "TP_USB3_P04_RXP" )
			)
			( signal "@baseboard_fab2_lib.baseboard_fab2(sch_1):tp_usb3_p04_txn"
				( objectStatus "TP_USB3_P04_TXN" )
			)
			( signal "@baseboard_fab2_lib.baseboard_fab2(sch_1):tp_usb3_p04_txp"
				( objectStatus "TP_USB3_P04_TXP" )
			)
			( signal "@baseboard_fab2_lib.baseboard_fab2(sch_1):tp_vr_pvccio_cpu0_aiinsen"
				( objectStatus "TP_VR_PVCCIO_CPU0_AIINSEN" )
			)
			( signal "@baseboard_fab2_lib.baseboard_fab2(sch_1):tp_vr_pvccio_cpu1_aiinsen"
				( objectStatus "TP_VR_PVCCIO_CPU1_AIINSEN" )
			)
			( signal "@baseboard_fab2_lib.baseboard_fab2(sch_1):tp_vr_pvnn_pch_aiinsen"
				( objectStatus "TP_VR_PVNN_PCH_AIINSEN" )
			)
			( signal "@baseboard_fab2_lib.baseboard_fab2(sch_1):pu_pi7c9x1172_i2c_spi_n"
				( objectStatus "PU_PI7C9X1172_I2C_SPI_N" )
			)
			( signal "@baseboard_fab2_lib.baseboard_fab2(sch_1):pu_rst_perst_bit0"
				( objectStatus "PU_RST_PERST_BIT0" )
			)
			( signal "@baseboard_fab2_lib.baseboard_fab2(sch_1):pu_rst_perst_bit1"
				( objectStatus "PU_RST_PERST_BIT1" )
			)
			( signal "@baseboard_fab2_lib.baseboard_fab2(sch_1):pu_spi_bmc_bt_hold_n"
				( objectStatus "PU_SPI_BMC_BT_HOLD_N" )
			)
			( signal "@baseboard_fab2_lib.baseboard_fab2(sch_1):pu_spi_bmc_bt_wp_n"
				( objectStatus "PU_SPI_BMC_BT_WP_N" )
			)
			( signal "@baseboard_fab2_lib.baseboard_fab2(sch_1):pu_spi_flash_reset_2_n"
				( objectStatus "PU_SPI_FLASH_RESET_2_N" )
			)
			( signal "@baseboard_fab2_lib.baseboard_fab2(sch_1):pu_spi0_rst"
				( objectStatus "PU_SPI0_RST" )
			)
			( signal "@baseboard_fab2_lib.baseboard_fab2(sch_1):pu_spi1_rst"
				( objectStatus "PU_SPI1_RST" )
			)
			( signal "@baseboard_fab2_lib.baseboard_fab2(sch_1):pu_sprv_lan_pwr_good"
				( objectStatus "PU_SPRV_LAN_PWR_GOOD" )
			)
			( signal "@baseboard_fab2_lib.baseboard_fab2(sch_1):pu_thermtrip_force_n"
				( objectStatus "PU_THERMTRIP_FORCE_N" )
			)
			( signal "@baseboard_fab2_lib.baseboard_fab2(sch_1):pu_tmp421_1_a1"
				( objectStatus "PU_TMP421_1_A1" )
			)
			( signal "@baseboard_fab2_lib.baseboard_fab2(sch_1):pu_tmp421_2_a0"
				( objectStatus "PU_TMP421_2_A0" )
			)
			( signal "@baseboard_fab2_lib.baseboard_fab2(sch_1):pu_tri_state_en"
				( objectStatus "PU_TRI_STATE_EN" )
			)
			( signal "@baseboard_fab2_lib.baseboard_fab2(sch_1):pu_vr_pvccin_cpu0_imon"
				( objectStatus "PU_VR_PVCCIN_CPU0_IMON" )
			)
			( signal "@baseboard_fab2_lib.baseboard_fab2(sch_1):pu_vr_pvccio_cpu0_fault1"
				( objectStatus "PU_VR_PVCCIO_CPU0_FAULT1" )
			)
			( signal "@baseboard_fab2_lib.baseboard_fab2(sch_1):pu_vr_pvccio_cpu1_fault1"
				( objectStatus "PU_VR_PVCCIO_CPU1_FAULT1" )
			)
			( signal "@baseboard_fab2_lib.baseboard_fab2(sch_1):pu_vr_pvddq_abc_fault1"
				( objectStatus "PU_VR_PVDDQ_ABC_FAULT1" )
			)
			( signal "@baseboard_fab2_lib.baseboard_fab2(sch_1):pu_vr_pvddq_def_fault1"
				( objectStatus "PU_VR_PVDDQ_DEF_FAULT1" )
			)
			( signal "@baseboard_fab2_lib.baseboard_fab2(sch_1):pu_vr_pvddq_ghj_fault1"
				( objectStatus "PU_VR_PVDDQ_GHJ_FAULT1" )
			)
			( signal "@baseboard_fab2_lib.baseboard_fab2(sch_1):pu_vr_pvddq_klm_fault1"
				( objectStatus "PU_VR_PVDDQ_KLM_FAULT1" )
			)
			( signal "@baseboard_fab2_lib.baseboard_fab2(sch_1):pu_vr_pvnn_pch_fault1"
				( objectStatus "PU_VR_PVNN_PCH_FAULT1" )
			)
			( signal "@baseboard_fab2_lib.baseboard_fab2(sch_1):pd_adcrext"
				( objectStatus "PD_ADCREXT" )
			)
			( signal "@baseboard_fab2_lib.baseboard_fab2(sch_1):pd_ckmng_oe"
				( objectStatus "PD_CKMNG_OE" )
			)
			( signal "@baseboard_fab2_lib.baseboard_fab2(sch_1):pd_cpu0_bist_enable"
				( objectStatus "PD_CPU0_BIST_ENABLE" )
			)
			( signal "@baseboard_fab2_lib.baseboard_fab2(sch_1):pd_cpu0_dmimode_override"
				( objectStatus "PD_CPU0_DMIMODE_OVERRIDE" )
			)
			( signal "@baseboard_fab2_lib.baseboard_fab2(sch_1):pd_cpu0_ksfc_dis"
				( objectStatus "PD_CPU0_KSFC_DIS" )
			)
			( signal "@baseboard_fab2_lib.baseboard_fab2(sch_1):pd_cpu0_txt_plten"
				( objectStatus "PD_CPU0_TXT_PLTEN" )
			)
			( signal "@baseboard_fab2_lib.baseboard_fab2(sch_1):pd_cpu1_bist_enable"
				( objectStatus "PD_CPU1_BIST_ENABLE" )
			)
			( signal "@baseboard_fab2_lib.baseboard_fab2(sch_1):pd_cpu1_dmimode_override"
				( objectStatus "PD_CPU1_DMIMODE_OVERRIDE" )
			)
			( signal "@baseboard_fab2_lib.baseboard_fab2(sch_1):pd_cpu1_ksfc_dis"
				( objectStatus "PD_CPU1_KSFC_DIS" )
			)
			( signal "@baseboard_fab2_lib.baseboard_fab2(sch_1):pd_cpu1_txt_plten"
				( objectStatus "PD_CPU1_TXT_PLTEN" )
			)
			( signal "@baseboard_fab2_lib.baseboard_fab2(sch_1):pd_dir_2"
				( objectStatus "PD_DIR_2" )
			)
			( signal "@baseboard_fab2_lib.baseboard_fab2(sch_1):pd_fru_wp"
				( objectStatus "PD_FRU_WP" )
			)
			( signal "@baseboard_fab2_lib.baseboard_fab2(sch_1):pd_gtl2014_1_vref"
				( objectStatus "PD_GTL2014_1_VREF" )
			)
			( signal "@baseboard_fab2_lib.baseboard_fab2(sch_1):pd_gtl2014_2_vref"
				( objectStatus "PD_GTL2014_2_VREF" )
			)
			( signal "@baseboard_fab2_lib.baseboard_fab2(sch_1):pd_gtl2104_dir_0"
				( objectStatus "PD_GTL2104_DIR_0" )
			)
			( signal "@baseboard_fab2_lib.baseboard_fab2(sch_1):pd_gtl2104_dir_1"
				( objectStatus "PD_GTL2104_DIR_1" )
			)
			( signal "@baseboard_fab2_lib.baseboard_fab2(sch_1):pd_gtl2104_4_dir"
				( objectStatus "PD_GTL2104_4_DIR" )
			)
			( signal "@baseboard_fab2_lib.baseboard_fab2(sch_1):pd_hsc_retry_n"
				( objectStatus "PD_HSC_RETRY_N" )
			)
			( signal "@baseboard_fab2_lib.baseboard_fab2(sch_1):pd_ie_debug_mode"
				( objectStatus "PD_IE_DEBUG_MODE" )
			)
			( signal "@baseboard_fab2_lib.baseboard_fab2(sch_1):pd_me_rcvr_n"
				( objectStatus "PD_ME_RCVR_N" )
			)
			( signal "@baseboard_fab2_lib.baseboard_fab2(sch_1):a_m_bmc_zq"
				( objectStatus "A_M_BMC_ZQ" )
			)
			( signal "@baseboard_fab2_lib.baseboard_fab2(sch_1):pd_password_clear"
				( objectStatus "PD_PASSWORD_CLEAR" )
			)
			( signal "@baseboard_fab2_lib.baseboard_fab2(sch_1):pd_perext"
				( objectStatus "PD_PEREXT" )
			)
			( signal "@baseboard_fab2_lib.baseboard_fab2(sch_1):pd_rst_rtcrst_n"
				( objectStatus "PD_RST_RTCRST_N" )
			)
			( signal "@baseboard_fab2_lib.baseboard_fab2(sch_1):pd_sata0_controller_type_r"
				( objectStatus "PD_SATA0_CONTROLLER_TYPE_R" )
			)
			( signal "@baseboard_fab2_lib.baseboard_fab2(sch_1):pd_sata1_controller_type_r"
				( objectStatus "PD_SATA1_CONTROLLER_TYPE_R" )
			)
			( signal "@baseboard_fab2_lib.baseboard_fab2(sch_1):pd_sata2_controller_type"
				( objectStatus "PD_SATA2_CONTROLLER_TYPE" )
			)
			( signal "@baseboard_fab2_lib.baseboard_fab2(sch_1):pd_sprv_rset"
				( objectStatus "PD_SPRV_RSET" )
			)
			( signal "@baseboard_fab2_lib.baseboard_fab2(sch_1):pd_sp_entest"
				( objectStatus "PD_SP_ENTEST" )
			)
			( signal "@baseboard_fab2_lib.baseboard_fab2(sch_1):pd_tmp421_1_a0"
				( objectStatus "PD_TMP421_1_A0" )
			)
			( signal "@baseboard_fab2_lib.baseboard_fab2(sch_1):pd_tmp421_2_a1"
				( objectStatus "PD_TMP421_2_A1" )
			)
			( signal "@baseboard_fab2_lib.baseboard_fab2(sch_1):pd_usb_bmc_p1_dn"
				( objectStatus "PD_USB_BMC_P1_DN" )
			)
			( signal "@baseboard_fab2_lib.baseboard_fab2(sch_1):pd_usb_bmc_p1_dp"
				( objectStatus "PD_USB_BMC_P1_DP" )
			)
			( signal "@baseboard_fab2_lib.baseboard_fab2(sch_1):pu_adr_timer_hold_off_n"
				( objectStatus "PU_ADR_TIMER_HOLD_OFF_N" )
			)
			( signal "@baseboard_fab2_lib.baseboard_fab2(sch_1):pu_at24c64_a2"
				( objectStatus "PU_AT24C64_A2" )
			)
			( signal "@baseboard_fab2_lib.baseboard_fab2(sch_1):pu_bios_recover_boot"
				( objectStatus "PU_BIOS_RECOVER_BOOT" )
			)
			( signal "@baseboard_fab2_lib.baseboard_fab2(sch_1):pu_bios_usb_recovery"
				( objectStatus "PU_BIOS_USB_RECOVERY" )
			)
			( signal "@baseboard_fab2_lib.baseboard_fab2(sch_1):h_cpu0_bmcinit"
				( objectStatus "H_CPU0_BMCINIT" )
			)
			( signal "@baseboard_fab2_lib.baseboard_fab2(sch_1):pu_cpu0_ear_n"
				( objectStatus "PU_CPU0_EAR_N" )
			)
			( signal "@baseboard_fab2_lib.baseboard_fab2(sch_1):pu_cpu0_frmagent"
				( objectStatus "PU_CPU0_FRMAGENT" )
			)
			( signal "@baseboard_fab2_lib.baseboard_fab2(sch_1):pu_cpu0_legacy_skt"
				( objectStatus "PU_CPU0_LEGACY_SKT" )
			)
			( signal "@baseboard_fab2_lib.baseboard_fab2(sch_1):pu_cpu0_safe_mode_boot"
				( objectStatus "PU_CPU0_SAFE_MODE_BOOT" )
			)
			( signal "@baseboard_fab2_lib.baseboard_fab2(sch_1):pu_cpu0_socket_id_0"
				( objectStatus "PU_CPU0_SOCKET_ID_0" )
			)
			( signal "@baseboard_fab2_lib.baseboard_fab2(sch_1):pu_cpu0_socket_id_1"
				( objectStatus "PU_CPU0_SOCKET_ID_1" )
			)
			( signal "@baseboard_fab2_lib.baseboard_fab2(sch_1):pu_cpu0_tsc_sync"
				( objectStatus "PU_CPU0_TSC_SYNC" )
			)
			( signal "@baseboard_fab2_lib.baseboard_fab2(sch_1):pu_cpu0_txt_agent"
				( objectStatus "PU_CPU0_TXT_AGENT" )
			)
			( signal "@baseboard_fab2_lib.baseboard_fab2(sch_1):h_cpu1_bmcinit"
				( objectStatus "H_CPU1_BMCINIT" )
			)
			( signal "@baseboard_fab2_lib.baseboard_fab2(sch_1):pu_cpu1_ear_n"
				( objectStatus "PU_CPU1_EAR_N" )
			)
			( signal "@baseboard_fab2_lib.baseboard_fab2(sch_1):pu_cpu1_frmagent"
				( objectStatus "PU_CPU1_FRMAGENT" )
			)
			( signal "@baseboard_fab2_lib.baseboard_fab2(sch_1):pu_cpu1_legacy_skt"
				( objectStatus "PU_CPU1_LEGACY_SKT" )
			)
			( signal "@baseboard_fab2_lib.baseboard_fab2(sch_1):pu_cpu1_safe_mode_boot"
				( objectStatus "PU_CPU1_SAFE_MODE_BOOT" )
			)
			( signal "@baseboard_fab2_lib.baseboard_fab2(sch_1):pu_cpu1_socket_id_0"
				( objectStatus "PU_CPU1_SOCKET_ID_0" )
			)
			( signal "@baseboard_fab2_lib.baseboard_fab2(sch_1):pu_cpu1_socket_id_1"
				( objectStatus "PU_CPU1_SOCKET_ID_1" )
			)
			( signal "@baseboard_fab2_lib.baseboard_fab2(sch_1):pu_cpu1_tsc_sync"
				( objectStatus "PU_CPU1_TSC_SYNC" )
			)
			( signal "@baseboard_fab2_lib.baseboard_fab2(sch_1):pu_cpu1_txt_agent"
				( objectStatus "PU_CPU1_TXT_AGENT" )
			)
			( signal "@baseboard_fab2_lib.baseboard_fab2(sch_1):pu_datain1_sata_0_r"
				( objectStatus "PU_DATAIN1_SATA_0_R" )
			)
			( signal "@baseboard_fab2_lib.baseboard_fab2(sch_1):pu_datain1_sata_1_r"
				( objectStatus "PU_DATAIN1_SATA_1_R" )
			)
			( signal "@baseboard_fab2_lib.baseboard_fab2(sch_1):pu_datain1_sata_2"
				( objectStatus "PU_DATAIN1_SATA_2" )
			)
			( signal "@baseboard_fab2_lib.baseboard_fab2(sch_1):pu_fm_rcin_n"
				( objectStatus "PU_FM_RCIN_N" )
			)
			( signal "@baseboard_fab2_lib.baseboard_fab2(sch_1):pu_gtl2014_1_dir"
				( objectStatus "PU_GTL2014_1_DIR" )
			)
			( signal "@baseboard_fab2_lib.baseboard_fab2(sch_1):pu_gtl2014_2_dir"
				( objectStatus "PU_GTL2014_2_DIR" )
			)
			( signal "@baseboard_fab2_lib.baseboard_fab2(sch_1):pu_irq_pch_sci_whea_n"
				( objectStatus "PU_IRQ_PCH_SCI_WHEA_N" )
			)
			( signal "@baseboard_fab2_lib.baseboard_fab2(sch_1):pu_irq_vralert_n"
				( objectStatus "PU_IRQ_VRALERT_N" )
			)
			( signal "@baseboard_fab2_lib.baseboard_fab2(sch_1):pu_key_conn_pin2_r"
				( objectStatus "PU_KEY_CONN_PIN2_R" )
			)
			( signal "@baseboard_fab2_lib.baseboard_fab2(sch_1):pu_lpc_clkrun_n"
				( objectStatus "PU_LPC_CLKRUN_N" )
			)
			( signal "@baseboard_fab2_lib.baseboard_fab2(sch_1):pu_lpc_pme_n"
				( objectStatus "PU_LPC_PME_N" )
			)
			( signal "@baseboard_fab2_lib.baseboard_fab2(sch_1):pu_nv_hold_n"
				( objectStatus "PU_NV_HOLD_N" )
			)
			( signal "@baseboard_fab2_lib.baseboard_fab2(sch_1):pu_nv_wp_n"
				( objectStatus "PU_NV_WP_N" )
			)
			( signal "@baseboard_fab2_lib.baseboard_fab2(sch_1):pu_pch_tls_enable_strap"
				( objectStatus "PU_PCH_TLS_ENABLE_STRAP" )
			)
			( signal "@baseboard_fab2_lib.baseboard_fab2(sch_1):tp_cpu0_rsvd_101"
				( objectStatus "TP_CPU0_RSVD_101" )
			)
			( signal "@baseboard_fab2_lib.baseboard_fab2(sch_1):tp_cpu0_rsvd_105"
				( objectStatus "TP_CPU0_RSVD_105" )
			)
			( signal "@baseboard_fab2_lib.baseboard_fab2(sch_1):tp_cpu0_rsvd_106"
				( objectStatus "TP_CPU0_RSVD_106" )
			)
			( signal "@baseboard_fab2_lib.baseboard_fab2(sch_1):tp_cpu0_rsvd_108"
				( objectStatus "TP_CPU0_RSVD_108" )
			)
			( signal "@baseboard_fab2_lib.baseboard_fab2(sch_1):tp_cpu0_rsvd_111"
				( objectStatus "TP_CPU0_RSVD_111" )
			)
			( signal "@baseboard_fab2_lib.baseboard_fab2(sch_1):tp_cpu0_rsvd_113"
				( objectStatus "TP_CPU0_RSVD_113" )
			)
			( signal "@baseboard_fab2_lib.baseboard_fab2(sch_1):tp_cpu0_rsvd_114"
				( objectStatus "TP_CPU0_RSVD_114" )
			)
			( signal "@baseboard_fab2_lib.baseboard_fab2(sch_1):tp_cpu0_rsvd_117"
				( objectStatus "TP_CPU0_RSVD_117" )
			)
			( signal "@baseboard_fab2_lib.baseboard_fab2(sch_1):tp_cpu0_rsvd_119"
				( objectStatus "TP_CPU0_RSVD_119" )
			)
			( signal "@baseboard_fab2_lib.baseboard_fab2(sch_1):tp_cpu0_rsvd_121"
				( objectStatus "TP_CPU0_RSVD_121" )
			)
			( signal "@baseboard_fab2_lib.baseboard_fab2(sch_1):tp_cpu0_rsvd_123"
				( objectStatus "TP_CPU0_RSVD_123" )
			)
			( signal "@baseboard_fab2_lib.baseboard_fab2(sch_1):tp_cpu0_rsvd_124"
				( objectStatus "TP_CPU0_RSVD_124" )
			)
			( signal "@baseboard_fab2_lib.baseboard_fab2(sch_1):tp_cpu0_rsvd_144"
				( objectStatus "TP_CPU0_RSVD_144" )
			)
			( signal "@baseboard_fab2_lib.baseboard_fab2(sch_1):tp_cpu0_rsvd_145"
				( objectStatus "TP_CPU0_RSVD_145" )
			)
			( signal "@baseboard_fab2_lib.baseboard_fab2(sch_1):tp_cpu0_rsvd_146"
				( objectStatus "TP_CPU0_RSVD_146" )
			)
			( signal "@baseboard_fab2_lib.baseboard_fab2(sch_1):tp_cpu0_rsvd_147"
				( objectStatus "TP_CPU0_RSVD_147" )
			)
			( signal "@baseboard_fab2_lib.baseboard_fab2(sch_1):tp_cpu0_rsvd_148"
				( objectStatus "TP_CPU0_RSVD_148" )
			)
			( signal "@baseboard_fab2_lib.baseboard_fab2(sch_1):tp_cpu0_rsvd_149"
				( objectStatus "TP_CPU0_RSVD_149" )
			)
			( signal "@baseboard_fab2_lib.baseboard_fab2(sch_1):tp_cpu0_rsvd_150"
				( objectStatus "TP_CPU0_RSVD_150" )
			)
			( signal "@baseboard_fab2_lib.baseboard_fab2(sch_1):tp_cpu0_rsvd_151"
				( objectStatus "TP_CPU0_RSVD_151" )
			)
			( signal "@baseboard_fab2_lib.baseboard_fab2(sch_1):tp_cpu0_rsvd_152"
				( objectStatus "TP_CPU0_RSVD_152" )
			)
			( signal "@baseboard_fab2_lib.baseboard_fab2(sch_1):tp_cpu0_rsvd_154"
				( objectStatus "TP_CPU0_RSVD_154" )
			)
			( signal "@baseboard_fab2_lib.baseboard_fab2(sch_1):tp_cpu0_rsvd_155"
				( objectStatus "TP_CPU0_RSVD_155" )
			)
			( signal "@baseboard_fab2_lib.baseboard_fab2(sch_1):tp_cpu0_rsvd_156"
				( objectStatus "TP_CPU0_RSVD_156" )
			)
			( signal "@baseboard_fab2_lib.baseboard_fab2(sch_1):tp_cpu0_rsvd_157"
				( objectStatus "TP_CPU0_RSVD_157" )
			)
			( signal "@baseboard_fab2_lib.baseboard_fab2(sch_1):tp_cpu0_rsvd_158"
				( objectStatus "TP_CPU0_RSVD_158" )
			)
			( signal "@baseboard_fab2_lib.baseboard_fab2(sch_1):tp_cpu0_rsvd_159"
				( objectStatus "TP_CPU0_RSVD_159" )
			)
			( signal "@baseboard_fab2_lib.baseboard_fab2(sch_1):tp_cpu0_rsvd_160"
				( objectStatus "TP_CPU0_RSVD_160" )
			)
			( signal "@baseboard_fab2_lib.baseboard_fab2(sch_1):tp_cpu0_rsvd_161"
				( objectStatus "TP_CPU0_RSVD_161" )
			)
			( signal "@baseboard_fab2_lib.baseboard_fab2(sch_1):tp_cpu0_rsvd_162"
				( objectStatus "TP_CPU0_RSVD_162" )
			)
			( signal "@baseboard_fab2_lib.baseboard_fab2(sch_1):tp_cpu0_rsvd_163"
				( objectStatus "TP_CPU0_RSVD_163" )
			)
			( signal "@baseboard_fab2_lib.baseboard_fab2(sch_1):tp_cpu0_rsvd_164"
				( objectStatus "TP_CPU0_RSVD_164" )
			)
			( signal "@baseboard_fab2_lib.baseboard_fab2(sch_1):tp_cpu0_rsvd_166"
				( objectStatus "TP_CPU0_RSVD_166" )
			)
			( signal "@baseboard_fab2_lib.baseboard_fab2(sch_1):tp_cpu0_rsvd_167"
				( objectStatus "TP_CPU0_RSVD_167" )
			)
			( signal "@baseboard_fab2_lib.baseboard_fab2(sch_1):tp_cpu0_rsvd_168"
				( objectStatus "TP_CPU0_RSVD_168" )
			)
			( signal "@baseboard_fab2_lib.baseboard_fab2(sch_1):tp_cpu0_rsvd_169"
				( objectStatus "TP_CPU0_RSVD_169" )
			)
			( signal "@baseboard_fab2_lib.baseboard_fab2(sch_1):tp_cpu0_rsvd_170"
				( objectStatus "TP_CPU0_RSVD_170" )
			)
			( signal "@baseboard_fab2_lib.baseboard_fab2(sch_1):tp_cpu0_rsvd_171"
				( objectStatus "TP_CPU0_RSVD_171" )
			)
			( signal "@baseboard_fab2_lib.baseboard_fab2(sch_1):tp_cpu0_rsvd_172"
				( objectStatus "TP_CPU0_RSVD_172" )
			)
			( signal "@baseboard_fab2_lib.baseboard_fab2(sch_1):tp_cpu0_rsvd_173"
				( objectStatus "TP_CPU0_RSVD_173" )
			)
			( signal "@baseboard_fab2_lib.baseboard_fab2(sch_1):tp_cpu0_rsvd_174"
				( objectStatus "TP_CPU0_RSVD_174" )
			)
			( signal "@baseboard_fab2_lib.baseboard_fab2(sch_1):tp_cpu0_rsvd_175"
				( objectStatus "TP_CPU0_RSVD_175" )
			)
			( signal "@baseboard_fab2_lib.baseboard_fab2(sch_1):tp_cpu0_rsvd_176"
				( objectStatus "TP_CPU0_RSVD_176" )
			)
			( signal "@baseboard_fab2_lib.baseboard_fab2(sch_1):tp_cpu1_rsvd_95"
				( objectStatus "TP_CPU1_RSVD_95" )
			)
			( signal "@baseboard_fab2_lib.baseboard_fab2(sch_1):tp_cpu1_rsvd_97"
				( objectStatus "TP_CPU1_RSVD_97" )
			)
			( signal "@baseboard_fab2_lib.baseboard_fab2(sch_1):tp_cpu1_rsvd_99"
				( objectStatus "TP_CPU1_RSVD_99" )
			)
			( signal "@baseboard_fab2_lib.baseboard_fab2(sch_1):tp_cpu1_rsvd_100"
				( objectStatus "TP_CPU1_RSVD_100" )
			)
			( signal "@baseboard_fab2_lib.baseboard_fab2(sch_1):tp_cpu1_rsvd_101"
				( objectStatus "TP_CPU1_RSVD_101" )
			)
			( signal "@baseboard_fab2_lib.baseboard_fab2(sch_1):tp_cpu1_rsvd_105"
				( objectStatus "TP_CPU1_RSVD_105" )
			)
			( signal "@baseboard_fab2_lib.baseboard_fab2(sch_1):tp_cpu1_rsvd_106"
				( objectStatus "TP_CPU1_RSVD_106" )
			)
			( signal "@baseboard_fab2_lib.baseboard_fab2(sch_1):tp_cpu1_rsvd_108"
				( objectStatus "TP_CPU1_RSVD_108" )
			)
			( signal "@baseboard_fab2_lib.baseboard_fab2(sch_1):tp_cpu1_rsvd_111"
				( objectStatus "TP_CPU1_RSVD_111" )
			)
			( signal "@baseboard_fab2_lib.baseboard_fab2(sch_1):tp_cpu1_rsvd_113"
				( objectStatus "TP_CPU1_RSVD_113" )
			)
			( signal "@baseboard_fab2_lib.baseboard_fab2(sch_1):tp_cpu1_rsvd_114"
				( objectStatus "TP_CPU1_RSVD_114" )
			)
			( signal "@baseboard_fab2_lib.baseboard_fab2(sch_1):tp_cpu1_rsvd_117"
				( objectStatus "TP_CPU1_RSVD_117" )
			)
			( signal "@baseboard_fab2_lib.baseboard_fab2(sch_1):tp_cpu1_rsvd_119"
				( objectStatus "TP_CPU1_RSVD_119" )
			)
			( signal "@baseboard_fab2_lib.baseboard_fab2(sch_1):tp_cpu1_rsvd_121"
				( objectStatus "TP_CPU1_RSVD_121" )
			)
			( signal "@baseboard_fab2_lib.baseboard_fab2(sch_1):tp_cpu1_rsvd_123"
				( objectStatus "TP_CPU1_RSVD_123" )
			)
			( signal "@baseboard_fab2_lib.baseboard_fab2(sch_1):tp_cpu1_rsvd_124"
				( objectStatus "TP_CPU1_RSVD_124" )
			)
			( signal "@baseboard_fab2_lib.baseboard_fab2(sch_1):tp_cpu1_rsvd_144"
				( objectStatus "TP_CPU1_RSVD_144" )
			)
			( signal "@baseboard_fab2_lib.baseboard_fab2(sch_1):tp_cpu1_rsvd_145"
				( objectStatus "TP_CPU1_RSVD_145" )
			)
			( signal "@baseboard_fab2_lib.baseboard_fab2(sch_1):tp_cpu1_rsvd_146"
				( objectStatus "TP_CPU1_RSVD_146" )
			)
			( signal "@baseboard_fab2_lib.baseboard_fab2(sch_1):tp_cpu1_rsvd_147"
				( objectStatus "TP_CPU1_RSVD_147" )
			)
			( signal "@baseboard_fab2_lib.baseboard_fab2(sch_1):tp_cpu1_rsvd_148"
				( objectStatus "TP_CPU1_RSVD_148" )
			)
			( signal "@baseboard_fab2_lib.baseboard_fab2(sch_1):tp_cpu1_rsvd_149"
				( objectStatus "TP_CPU1_RSVD_149" )
			)
			( signal "@baseboard_fab2_lib.baseboard_fab2(sch_1):tp_cpu1_rsvd_150"
				( objectStatus "TP_CPU1_RSVD_150" )
			)
			( signal "@baseboard_fab2_lib.baseboard_fab2(sch_1):tp_cpu1_rsvd_151"
				( objectStatus "TP_CPU1_RSVD_151" )
			)
			( signal "@baseboard_fab2_lib.baseboard_fab2(sch_1):tp_cpu1_rsvd_152"
				( objectStatus "TP_CPU1_RSVD_152" )
			)
			( signal "@baseboard_fab2_lib.baseboard_fab2(sch_1):tp_cpu1_rsvd_154"
				( objectStatus "TP_CPU1_RSVD_154" )
			)
			( signal "@baseboard_fab2_lib.baseboard_fab2(sch_1):tp_cpu1_rsvd_155"
				( objectStatus "TP_CPU1_RSVD_155" )
			)
			( signal "@baseboard_fab2_lib.baseboard_fab2(sch_1):tp_cpu1_rsvd_156"
				( objectStatus "TP_CPU1_RSVD_156" )
			)
			( signal "@baseboard_fab2_lib.baseboard_fab2(sch_1):tp_cpu1_rsvd_157"
				( objectStatus "TP_CPU1_RSVD_157" )
			)
			( signal "@baseboard_fab2_lib.baseboard_fab2(sch_1):tp_cpu1_rsvd_158"
				( objectStatus "TP_CPU1_RSVD_158" )
			)
			( signal "@baseboard_fab2_lib.baseboard_fab2(sch_1):tp_cpu1_rsvd_159"
				( objectStatus "TP_CPU1_RSVD_159" )
			)
			( signal "@baseboard_fab2_lib.baseboard_fab2(sch_1):tp_cpu1_rsvd_160"
				( objectStatus "TP_CPU1_RSVD_160" )
			)
			( signal "@baseboard_fab2_lib.baseboard_fab2(sch_1):tp_cpu1_rsvd_161"
				( objectStatus "TP_CPU1_RSVD_161" )
			)
			( signal "@baseboard_fab2_lib.baseboard_fab2(sch_1):tp_cpu1_rsvd_162"
				( objectStatus "TP_CPU1_RSVD_162" )
			)
			( signal "@baseboard_fab2_lib.baseboard_fab2(sch_1):tp_cpu1_rsvd_163"
				( objectStatus "TP_CPU1_RSVD_163" )
			)
			( signal "@baseboard_fab2_lib.baseboard_fab2(sch_1):tp_cpu1_rsvd_164"
				( objectStatus "TP_CPU1_RSVD_164" )
			)
			( signal "@baseboard_fab2_lib.baseboard_fab2(sch_1):tp_cpu1_rsvd_166"
				( objectStatus "TP_CPU1_RSVD_166" )
			)
			( signal "@baseboard_fab2_lib.baseboard_fab2(sch_1):tp_cpu1_rsvd_167"
				( objectStatus "TP_CPU1_RSVD_167" )
			)
			( signal "@baseboard_fab2_lib.baseboard_fab2(sch_1):tp_cpu1_rsvd_168"
				( objectStatus "TP_CPU1_RSVD_168" )
			)
			( signal "@baseboard_fab2_lib.baseboard_fab2(sch_1):tp_cpu1_rsvd_169"
				( objectStatus "TP_CPU1_RSVD_169" )
			)
			( signal "@baseboard_fab2_lib.baseboard_fab2(sch_1):tp_cpu1_rsvd_170"
				( objectStatus "TP_CPU1_RSVD_170" )
			)
			( signal "@baseboard_fab2_lib.baseboard_fab2(sch_1):tp_adc128_vref"
				( objectStatus "TP_ADC128_VREF" )
			)
			( signal "@baseboard_fab2_lib.baseboard_fab2(sch_1):nc_clk_156m_cpu0_osc"
				( objectStatus "NC_CLK_156M_CPU0_OSC" )
			)
			( signal "@baseboard_fab2_lib.baseboard_fab2(sch_1):nc_clk_156m_cpu1_osc"
				( objectStatus "NC_CLK_156M_CPU1_OSC" )
			)
			( signal "@baseboard_fab2_lib.baseboard_fab2(sch_1):nc_cpld1"
				( objectStatus "NC_CPLD1" )
			)
			( signal "@baseboard_fab2_lib.baseboard_fab2(sch_1):tp_cpu0_rsvd_82"
				( objectStatus "TP_CPU0_RSVD_82" )
			)
			( signal "@baseboard_fab2_lib.baseboard_fab2(sch_1):tp_cpu0_rsvd_85"
				( objectStatus "TP_CPU0_RSVD_85" )
			)
			( signal "@baseboard_fab2_lib.baseboard_fab2(sch_1):tp_cpu0_rsvd_90"
				( objectStatus "TP_CPU0_RSVD_90" )
			)
			( signal "@baseboard_fab2_lib.baseboard_fab2(sch_1):tp_cpu0_rsvd_91"
				( objectStatus "TP_CPU0_RSVD_91" )
			)
			( signal "@baseboard_fab2_lib.baseboard_fab2(sch_1):tp_cpu0_rsvd_94"
				( objectStatus "TP_CPU0_RSVD_94" )
			)
			( signal "@baseboard_fab2_lib.baseboard_fab2(sch_1):tp_cpu0_rsvd_95"
				( objectStatus "TP_CPU0_RSVD_95" )
			)
			( signal "@baseboard_fab2_lib.baseboard_fab2(sch_1):tp_cpu0_rsvd_97"
				( objectStatus "TP_CPU0_RSVD_97" )
			)
			( signal "@baseboard_fab2_lib.baseboard_fab2(sch_1):tp_cpu0_rsvd_99"
				( objectStatus "TP_CPU0_RSVD_99" )
			)
			( signal "@baseboard_fab2_lib.baseboard_fab2(sch_1):tp_cpu0_rsvd_100"
				( objectStatus "TP_CPU0_RSVD_100" )
			)
			( signal "@baseboard_fab2_lib.baseboard_fab2(sch_1):tp_fm_cpu1_cd_hfi0_modprst_n"
				( objectStatus "TP_FM_CPU1_CD_HFI0_MODPRST_N" )
			)
			( signal "@baseboard_fab2_lib.baseboard_fab2(sch_1):tp_cpld1_pl7d_pclkt4_0"
				( objectStatus "TP_CPLD1_PL7D_PCLKT4_0" )
			)
			( signal "@baseboard_fab2_lib.baseboard_fab2(sch_1):tp_gpio0_dsrb_n"
				( objectStatus "TP_GPIO0_DSRB_N" )
			)
			( signal "@baseboard_fab2_lib.baseboard_fab2(sch_1):tp_gpio1_dtrb_n"
				( objectStatus "TP_GPIO1_DTRB_N" )
			)
			( signal "@baseboard_fab2_lib.baseboard_fab2(sch_1):tp_gpio2_cdb_n"
				( objectStatus "TP_GPIO2_CDB_N" )
			)
			( signal "@baseboard_fab2_lib.baseboard_fab2(sch_1):tp_gpio3_rib_n"
				( objectStatus "TP_GPIO3_RIB_N" )
			)
			( signal "@baseboard_fab2_lib.baseboard_fab2(sch_1):tp_gpio4_dsra_n"
				( objectStatus "TP_GPIO4_DSRA_N" )
			)
			( signal "@baseboard_fab2_lib.baseboard_fab2(sch_1):tp_gpio5_dtra_n"
				( objectStatus "TP_GPIO5_DTRA_N" )
			)
			( signal "@baseboard_fab2_lib.baseboard_fab2(sch_1):tp_gpio6_cda_n"
				( objectStatus "TP_GPIO6_CDA_N" )
			)
			( signal "@baseboard_fab2_lib.baseboard_fab2(sch_1):tp_gpio7_ria_n"
				( objectStatus "TP_GPIO7_RIA_N" )
			)
			( signal "@baseboard_fab2_lib.baseboard_fab2(sch_1):tp_irq_cpu1_cd_hfi0_n"
				( objectStatus "TP_IRQ_CPU1_CD_HFI0_N" )
			)
			( signal "@baseboard_fab2_lib.baseboard_fab2(sch_1):tp_jtag_bmc_rtck"
				( objectStatus "TP_JTAG_BMC_RTCK" )
			)
			( signal "@baseboard_fab2_lib.baseboard_fab2(sch_1):tp_led_cpu1_cd_hfi0_n"
				( objectStatus "TP_LED_CPU1_CD_HFI0_N" )
			)
			( signal "@baseboard_fab2_lib.baseboard_fab2(sch_1):tp_led_m2_act_n"
				( objectStatus "TP_LED_M2_ACT_N" )
			)
			( signal "@baseboard_fab2_lib.baseboard_fab2(sch_1):tp_m_bmc_ddr3_mioz"
				( objectStatus "TP_M_BMC_DDR3_MIOZ" )
			)
			( signal "@baseboard_fab2_lib.baseboard_fab2(sch_1):tp_m2_devslp"
				( objectStatus "TP_M2_DEVSLP" )
			)
			( signal "@baseboard_fab2_lib.baseboard_fab2(sch_1):tp_m2_32m_susclk"
				( objectStatus "TP_M2_32M_SUSCLK" )
			)
			( signal "@baseboard_fab2_lib.baseboard_fab2(sch_1):tp_pi7c9x1172_enir_n"
				( objectStatus "TP_PI7C9X1172_ENIR_N" )
			)
			( signal "@baseboard_fab2_lib.baseboard_fab2(sch_1):tp_pi7c9x1172_en485_n"
				( objectStatus "TP_PI7C9X1172_EN485_N" )
			)
			( signal "@baseboard_fab2_lib.baseboard_fab2(sch_1):tp_pi7c9x1172_rtsa_n"
				( objectStatus "TP_PI7C9X1172_RTSA_N" )
			)
			( signal "@baseboard_fab2_lib.baseboard_fab2(sch_1):tp_pi7c9x1172_rtsb_n"
				( objectStatus "TP_PI7C9X1172_RTSB_N" )
			)
			( signal "@baseboard_fab2_lib.baseboard_fab2(sch_1):tp_pi7c9x1172_so"
				( objectStatus "TP_PI7C9X1172_SO" )
			)
			( signal "@baseboard_fab2_lib.baseboard_fab2(sch_1):nc_pi7c9x1172_1"
				( objectStatus "NC_PI7C9X1172_1" )
			)
			( signal "@baseboard_fab2_lib.baseboard_fab2(sch_1):nc_pi7c9x1172_8"
				( objectStatus "NC_PI7C9X1172_8" )
			)
			( signal "@baseboard_fab2_lib.baseboard_fab2(sch_1):tp_pvccin_cpu0_ph2_gl_0"
				( objectStatus "TP_PVCCIN_CPU0_PH2_GL_0" )
			)
			( signal "@baseboard_fab2_lib.baseboard_fab2(sch_1):tp_pvccin_cpu0_ph3_gl_0"
				( objectStatus "TP_PVCCIN_CPU0_PH3_GL_0" )
			)
			( signal "@baseboard_fab2_lib.baseboard_fab2(sch_1):tp_pvccin_cpu0_ph4_gl_0"
				( objectStatus "TP_PVCCIN_CPU0_PH4_GL_0" )
			)
			( signal "@baseboard_fab2_lib.baseboard_fab2(sch_1):tp_pvccin_cpu0_ph5_gl_0"
				( objectStatus "TP_PVCCIN_CPU0_PH5_GL_0" )
			)
			( signal "@baseboard_fab2_lib.baseboard_fab2(sch_1):tp_pvccinc_cpu1_ph1_gl_0"
				( objectStatus "TP_PVCCINC_CPU1_PH1_GL_0" )
			)
			( signal "@baseboard_fab2_lib.baseboard_fab2(sch_1):tp_pvccinc_cpu1_ph2_gl_0"
				( objectStatus "TP_PVCCINC_CPU1_PH2_GL_0" )
			)
			( signal "@baseboard_fab2_lib.baseboard_fab2(sch_1):tp_pvccin_cpu1_ph3_gl_0"
				( objectStatus "TP_PVCCIN_CPU1_PH3_GL_0" )
			)
			( signal "@baseboard_fab2_lib.baseboard_fab2(sch_1):tp_pvccin_cpu1_ph4_gl_0"
				( objectStatus "TP_PVCCIN_CPU1_PH4_GL_0" )
			)
			( signal "@baseboard_fab2_lib.baseboard_fab2(sch_1):tp_pvccin_cpu1_ph5_gl_0"
				( objectStatus "TP_PVCCIN_CPU1_PH5_GL_0" )
			)
			( signal "@baseboard_fab2_lib.baseboard_fab2(sch_1):nc_pvccio_cpu0_dnc0"
				( objectStatus "NC_PVCCIO_CPU0_DNC0" )
			)
			( signal "@baseboard_fab2_lib.baseboard_fab2(sch_1):nc_pvccio_cpu0_dnc1"
				( objectStatus "NC_PVCCIO_CPU0_DNC1" )
			)
			( signal "@baseboard_fab2_lib.baseboard_fab2(sch_1):nc_pvccio_cpu0_dnc2"
				( objectStatus "NC_PVCCIO_CPU0_DNC2" )
			)
			( signal "@baseboard_fab2_lib.baseboard_fab2(sch_1):nc_pvccio_cpu0_dnc3"
				( objectStatus "NC_PVCCIO_CPU0_DNC3" )
			)
			( signal "@baseboard_fab2_lib.baseboard_fab2(sch_1):nc_pvccio_cpu0_dnc4"
				( objectStatus "NC_PVCCIO_CPU0_DNC4" )
			)
			( signal "@baseboard_fab2_lib.baseboard_fab2(sch_1):tp_pvccio_cpu0_gl_0"
				( objectStatus "TP_PVCCIO_CPU0_GL_0" )
			)
			( signal "@baseboard_fab2_lib.baseboard_fab2(sch_1):nc_pvccio_cpu1_dnc0"
				( objectStatus "NC_PVCCIO_CPU1_DNC0" )
			)
			( signal "@baseboard_fab2_lib.baseboard_fab2(sch_1):nc_pvccio_cpu1_dnc1"
				( objectStatus "NC_PVCCIO_CPU1_DNC1" )
			)
			( signal "@baseboard_fab2_lib.baseboard_fab2(sch_1):tp_cpu0_rsvd_177"
				( objectStatus "TP_CPU0_RSVD_177" )
			)
			( signal "@baseboard_fab2_lib.baseboard_fab2(sch_1):tp_cpu0_rsvd_178"
				( objectStatus "TP_CPU0_RSVD_178" )
			)
			( signal "@baseboard_fab2_lib.baseboard_fab2(sch_1):tp_cpu0_rsvd_179"
				( objectStatus "TP_CPU0_RSVD_179" )
			)
			( signal "@baseboard_fab2_lib.baseboard_fab2(sch_1):tp_cpu0_rsvd_180"
				( objectStatus "TP_CPU0_RSVD_180" )
			)
			( signal "@baseboard_fab2_lib.baseboard_fab2(sch_1):tp_cpu0_rsvd_181"
				( objectStatus "TP_CPU0_RSVD_181" )
			)
			( signal "@baseboard_fab2_lib.baseboard_fab2(sch_1):tp_cpu0_rsvd_182"
				( objectStatus "TP_CPU0_RSVD_182" )
			)
			( signal "@baseboard_fab2_lib.baseboard_fab2(sch_1):tp_cpu0_rsvd_183"
				( objectStatus "TP_CPU0_RSVD_183" )
			)
			( signal "@baseboard_fab2_lib.baseboard_fab2(sch_1):tp_cpu0_test_7"
				( objectStatus "TP_CPU0_TEST_7" )
			)
			( signal "@baseboard_fab2_lib.baseboard_fab2(sch_1):tp_cpu0_test_8"
				( objectStatus "TP_CPU0_TEST_8" )
			)
			( signal "@baseboard_fab2_lib.baseboard_fab2(sch_1):tp_cpu0_test_10"
				( objectStatus "TP_CPU0_TEST_10" )
			)
			( signal "@baseboard_fab2_lib.baseboard_fab2(sch_1):tp_cpu0_test_9"
				( objectStatus "TP_CPU0_TEST_9" )
			)
			( signal "@baseboard_fab2_lib.baseboard_fab2(sch_1):tp_cpu0_rsvd_test_11"
				( objectStatus "TP_CPU0_RSVD_TEST_11" )
			)
			( signal "@baseboard_fab2_lib.baseboard_fab2(sch_1):tp_cpu1_rsvd_82"
				( objectStatus "TP_CPU1_RSVD_82" )
			)
			( signal "@baseboard_fab2_lib.baseboard_fab2(sch_1):tp_cpu1_rsvd_85"
				( objectStatus "TP_CPU1_RSVD_85" )
			)
			( signal "@baseboard_fab2_lib.baseboard_fab2(sch_1):tp_cpu1_rsvd_90"
				( objectStatus "TP_CPU1_RSVD_90" )
			)
			( signal "@baseboard_fab2_lib.baseboard_fab2(sch_1):tp_cpu1_rsvd_91"
				( objectStatus "TP_CPU1_RSVD_91" )
			)
			( signal "@baseboard_fab2_lib.baseboard_fab2(sch_1):tp_cpu1_rsvd_94"
				( objectStatus "TP_CPU1_RSVD_94" )
			)
			( signal "@baseboard_fab2_lib.baseboard_fab2(sch_1):nc_pvccio_cpu1_dnc2"
				( objectStatus "NC_PVCCIO_CPU1_DNC2" )
			)
			( signal "@baseboard_fab2_lib.baseboard_fab2(sch_1):nc_pvccio_cpu1_dnc3"
				( objectStatus "NC_PVCCIO_CPU1_DNC3" )
			)
			( signal "@baseboard_fab2_lib.baseboard_fab2(sch_1):nc_pvccio_cpu1_dnc4"
				( objectStatus "NC_PVCCIO_CPU1_DNC4" )
			)
			( signal "@baseboard_fab2_lib.baseboard_fab2(sch_1):tp_pvccio_cpu1_gl_0"
				( objectStatus "TP_PVCCIO_CPU1_GL_0" )
			)
			( signal "@baseboard_fab2_lib.baseboard_fab2(sch_1):nc_pvddq_abc_dnc0"
				( objectStatus "NC_PVDDQ_ABC_DNC0" )
			)
			( signal "@baseboard_fab2_lib.baseboard_fab2(sch_1):nc_pvddq_abc_dnc1"
				( objectStatus "NC_PVDDQ_ABC_DNC1" )
			)
			( signal "@baseboard_fab2_lib.baseboard_fab2(sch_1):tp_pvddq_abc_ph1_gl_0"
				( objectStatus "TP_PVDDQ_ABC_PH1_GL_0" )
			)
			( signal "@baseboard_fab2_lib.baseboard_fab2(sch_1):tp_pvddq_abc_ph2_gl_0"
				( objectStatus "TP_PVDDQ_ABC_PH2_GL_0" )
			)
			( signal "@baseboard_fab2_lib.baseboard_fab2(sch_1):nc_pvddq_def_dnc0"
				( objectStatus "NC_PVDDQ_DEF_DNC0" )
			)
			( signal "@baseboard_fab2_lib.baseboard_fab2(sch_1):nc_pvddq_def_dnc1"
				( objectStatus "NC_PVDDQ_DEF_DNC1" )
			)
			( signal "@baseboard_fab2_lib.baseboard_fab2(sch_1):tp_pvddq_def_ph1_gl_0"
				( objectStatus "TP_PVDDQ_DEF_PH1_GL_0" )
			)
			( signal "@baseboard_fab2_lib.baseboard_fab2(sch_1):tp_pvddq_def_ph2_gl_0"
				( objectStatus "TP_PVDDQ_DEF_PH2_GL_0" )
			)
			( signal "@baseboard_fab2_lib.baseboard_fab2(sch_1):nc_pvddq_ghj_dnc0"
				( objectStatus "NC_PVDDQ_GHJ_DNC0" )
			)
			( signal "@baseboard_fab2_lib.baseboard_fab2(sch_1):nc_pvddq_ghj_dnc1"
				( objectStatus "NC_PVDDQ_GHJ_DNC1" )
			)
			( signal "@baseboard_fab2_lib.baseboard_fab2(sch_1):tp_pvddq_ghj_ph1_gl_0"
				( objectStatus "TP_PVDDQ_GHJ_PH1_GL_0" )
			)
			( signal "@baseboard_fab2_lib.baseboard_fab2(sch_1):tp_pvddq_ghj_ph2_gl_0"
				( objectStatus "TP_PVDDQ_GHJ_PH2_GL_0" )
			)
			( signal "@baseboard_fab2_lib.baseboard_fab2(sch_1):tp_pvddq_ghj_ph3_imon"
				( objectStatus "TP_PVDDQ_GHJ_PH3_IMON" )
			)
			( signal "@baseboard_fab2_lib.baseboard_fab2(sch_1):tp_pvddq_ghj_ph3_imon_ref"
				( objectStatus "TP_PVDDQ_GHJ_PH3_IMON_REF" )
			)
			( signal "@baseboard_fab2_lib.baseboard_fab2(sch_1):nc_pvddq_ghj_pinalrt_n"
				( objectStatus "NC_PVDDQ_GHJ_PINALRT_N" )
			)
			( signal "@baseboard_fab2_lib.baseboard_fab2(sch_1):nc_pvddq_klm_dnc0"
				( objectStatus "NC_PVDDQ_KLM_DNC0" )
			)
			( signal "@baseboard_fab2_lib.baseboard_fab2(sch_1):nc_pvddq_klm_dnc1"
				( objectStatus "NC_PVDDQ_KLM_DNC1" )
			)
			( signal "@baseboard_fab2_lib.baseboard_fab2(sch_1):nc_pvddq_klm_gp0"
				( objectStatus "NC_PVDDQ_KLM_GP0" )
			)
			( signal "@baseboard_fab2_lib.baseboard_fab2(sch_1):nc_pvddq_klm_gp1"
				( objectStatus "NC_PVDDQ_KLM_GP1" )
			)
			( signal "@baseboard_fab2_lib.baseboard_fab2(sch_1):tp_pvddq_klm_ph1_gl_0"
				( objectStatus "TP_PVDDQ_KLM_PH1_GL_0" )
			)
			( signal "@baseboard_fab2_lib.baseboard_fab2(sch_1):tp_pvddq_klm_ph2_gl_0"
				( objectStatus "TP_PVDDQ_KLM_PH2_GL_0" )
			)
			( signal "@baseboard_fab2_lib.baseboard_fab2(sch_1):tp_pvddq_klm_ph3_imon"
				( objectStatus "TP_PVDDQ_KLM_PH3_IMON" )
			)
			( signal "@baseboard_fab2_lib.baseboard_fab2(sch_1):tp_pvddq_klm_ph3_imon_ref"
				( objectStatus "TP_PVDDQ_KLM_PH3_IMON_REF" )
			)
			( signal "@baseboard_fab2_lib.baseboard_fab2(sch_1):nc_pvddq_klm_pinalrt_n"
				( objectStatus "NC_PVDDQ_KLM_PINALRT_N" )
			)
			( signal "@baseboard_fab2_lib.baseboard_fab2(sch_1):nc_pvddq_klm_pwm3"
				( objectStatus "NC_PVDDQ_KLM_PWM3" )
			)
			( signal "@baseboard_fab2_lib.baseboard_fab2(sch_1):nc_pvnn_pch_dnc0"
				( objectStatus "NC_PVNN_PCH_DNC0" )
			)
			( signal "@baseboard_fab2_lib.baseboard_fab2(sch_1):nc_pvnn_pch_dnc1"
				( objectStatus "NC_PVNN_PCH_DNC1" )
			)
			( signal "@baseboard_fab2_lib.baseboard_fab2(sch_1):nc_pvnn_pch_dnc2"
				( objectStatus "NC_PVNN_PCH_DNC2" )
			)
			( signal "@baseboard_fab2_lib.baseboard_fab2(sch_1):nc_pvnn_pch_dnc3"
				( objectStatus "NC_PVNN_PCH_DNC3" )
			)
			( signal "@baseboard_fab2_lib.baseboard_fab2(sch_1):nc_pvnn_pch_dnc4"
				( objectStatus "NC_PVNN_PCH_DNC4" )
			)
			( signal "@baseboard_fab2_lib.baseboard_fab2(sch_1):tp_pvnn_pch_gl_0"
				( objectStatus "TP_PVNN_PCH_GL_0" )
			)
			( signal "@baseboard_fab2_lib.baseboard_fab2(sch_1):tp_pvsa_cpu0_gl_0"
				( objectStatus "TP_PVSA_CPU0_GL_0" )
			)
			( signal "@baseboard_fab2_lib.baseboard_fab2(sch_1):tp_pvsa_cpu1_gl_0"
				( objectStatus "TP_PVSA_CPU1_GL_0" )
			)
			( signal "@baseboard_fab2_lib.baseboard_fab2(sch_1):tp_p1v05_pch_gl_0"
				( objectStatus "TP_P1V05_PCH_GL_0" )
			)
			( signal "@baseboard_fab2_lib.baseboard_fab2(sch_1):tp_rgmii1txctl_gpiot1"
				( objectStatus "TP_RGMII1TXCTL_GPIOT1" )
			)
			( signal "@baseboard_fab2_lib.baseboard_fab2(sch_1):tp_rgmii1txd2_gpiot4"
				( objectStatus "TP_RGMII1TXD2_GPIOT4" )
			)
			( signal "@baseboard_fab2_lib.baseboard_fab2(sch_1):tp_rgmii1txd3_gpiot5"
				( objectStatus "TP_RGMII1TXD3_GPIOT5" )
			)
			( signal "@baseboard_fab2_lib.baseboard_fab2(sch_1):tp_rgmii2txctl_gpiot7"
				( objectStatus "TP_RGMII2TXCTL_GPIOT7" )
			)
			( signal "@baseboard_fab2_lib.baseboard_fab2(sch_1):tp_rgmii2txd2_gpiot4"
				( objectStatus "TP_RGMII2TXD2_GPIOT4" )
			)
			( signal "@baseboard_fab2_lib.baseboard_fab2(sch_1):tp_rgmii2txd3_gpiot5"
				( objectStatus "TP_RGMII2TXD3_GPIOT5" )
			)
			( signal "@baseboard_fab2_lib.baseboard_fab2(sch_1):tp_rst_cpu1_cd_hfi0_n"
				( objectStatus "TP_RST_CPU1_CD_HFI0_N" )
			)
			( signal "@baseboard_fab2_lib.baseboard_fab2(sch_1):tp_smb_cpu1_cd_hfi0_i2cclk"
				( objectStatus "TP_SMB_CPU1_CD_HFI0_I2CCLK" )
			)
			( signal "@baseboard_fab2_lib.baseboard_fab2(sch_1):tp_smb_cpu1_cd_hfi0_i2cdat"
				( objectStatus "TP_SMB_CPU1_CD_HFI0_I2CDAT" )
			)
			( signal "@baseboard_fab2_lib.baseboard_fab2(sch_1):tp_spi_pch_bios_clk_r"
				( objectStatus "TP_SPI_PCH_BIOS_CLK_R" )
			)
			( signal "@baseboard_fab2_lib.baseboard_fab2(sch_1):tp_spi_pch_bios_cs0_r_n"
				( objectStatus "TP_SPI_PCH_BIOS_CS0_R_N" )
			)
			( signal "@baseboard_fab2_lib.baseboard_fab2(sch_1):tp_spi_pch_bios_miso_r"
				( objectStatus "TP_SPI_PCH_BIOS_MISO_R" )
			)
			( signal "@baseboard_fab2_lib.baseboard_fab2(sch_1):tp_spi_pch_bios_mosi_r"
				( objectStatus "TP_SPI_PCH_BIOS_MOSI_R" )
			)
			( signal "@baseboard_fab2_lib.baseboard_fab2(sch_1):tp_spi_switch1_3"
				( objectStatus "TP_SPI_SWITCH1_3" )
			)
			( signal "@baseboard_fab2_lib.baseboard_fab2(sch_1):tp_spi_switch1_6"
				( objectStatus "TP_SPI_SWITCH1_6" )
			)
			( signal "@baseboard_fab2_lib.baseboard_fab2(sch_1):tp_spi_switch1_9"
				( objectStatus "TP_SPI_SWITCH1_9" )
			)
			( signal "@baseboard_fab2_lib.baseboard_fab2(sch_1):tp_spi_switch1_10"
				( objectStatus "TP_SPI_SWITCH1_10" )
			)
			( signal "@baseboard_fab2_lib.baseboard_fab2(sch_1):tp_spi_switch1_11"
				( objectStatus "TP_SPI_SWITCH1_11" )
			)
			( signal "@baseboard_fab2_lib.baseboard_fab2(sch_1):tp_spi_switch1_12"
				( objectStatus "TP_SPI_SWITCH1_12" )
			)
			( signal "@baseboard_fab2_lib.baseboard_fab2(sch_1):tp_spi_switch1_13"
				( objectStatus "TP_SPI_SWITCH1_13" )
			)
			( signal "@baseboard_fab2_lib.baseboard_fab2(sch_1):tp_spi_switch1_14"
				( objectStatus "TP_SPI_SWITCH1_14" )
			)
			( signal "@baseboard_fab2_lib.baseboard_fab2(sch_1):nc_sprngvlle_22"
				( objectStatus "NC_SPRNGVLLE_22" )
			)
			( signal "@baseboard_fab2_lib.baseboard_fab2(sch_1):tp_sprv_sdp0"
				( objectStatus "TP_SPRV_SDP0" )
			)
			( signal "@baseboard_fab2_lib.baseboard_fab2(sch_1):tp_sprv_sdp1"
				( objectStatus "TP_SPRV_SDP1" )
			)
			( signal "@baseboard_fab2_lib.baseboard_fab2(sch_1):tp_sprv_sdp2"
				( objectStatus "TP_SPRV_SDP2" )
			)
			( signal "@baseboard_fab2_lib.baseboard_fab2(sch_1):tp_sprv_sdp3"
				( objectStatus "TP_SPRV_SDP3" )
			)
			( signal "@baseboard_fab2_lib.baseboard_fab2(sch_1):tp_usb_esd_ac2"
				( objectStatus "TP_USB_ESD_AC2" )
			)
			( signal "@baseboard_fab2_lib.baseboard_fab2(sch_1):tp_usb_esd_ac3"
				( objectStatus "TP_USB_ESD_AC3" )
			)
			( signal "@baseboard_fab2_lib.baseboard_fab2(sch_1):tp_usb_esd_out2"
				( objectStatus "TP_USB_ESD_OUT2" )
			)
			( signal "@baseboard_fab2_lib.baseboard_fab2(sch_1):tp_usb_esd_out3"
				( objectStatus "TP_USB_ESD_OUT3" )
			)
			( signal "@baseboard_fab2_lib.baseboard_fab2(sch_1):tp_vgahs_gpioj4"
				( objectStatus "TP_VGAHS_GPIOJ4" )
			)
			( signal "@baseboard_fab2_lib.baseboard_fab2(sch_1):tp_vgavs_gpioj5"
				( objectStatus "TP_VGAVS_GPIOJ5" )
			)
			( signal "@baseboard_fab2_lib.baseboard_fab2(sch_1):tp_cpu1_rsvd_171"
				( objectStatus "TP_CPU1_RSVD_171" )
			)
			( signal "@baseboard_fab2_lib.baseboard_fab2(sch_1):tp_cpu1_rsvd_172"
				( objectStatus "TP_CPU1_RSVD_172" )
			)
			( signal "@baseboard_fab2_lib.baseboard_fab2(sch_1):tp_cpu1_rsvd_173"
				( objectStatus "TP_CPU1_RSVD_173" )
			)
			( signal "@baseboard_fab2_lib.baseboard_fab2(sch_1):tp_cpu1_rsvd_175"
				( objectStatus "TP_CPU1_RSVD_175" )
			)
			( signal "@baseboard_fab2_lib.baseboard_fab2(sch_1):tp_cpu1_test_7"
				( objectStatus "TP_CPU1_TEST_7" )
			)
			( signal "@baseboard_fab2_lib.baseboard_fab2(sch_1):tp_cpu1_test_8"
				( objectStatus "TP_CPU1_TEST_8" )
			)
			( signal "@baseboard_fab2_lib.baseboard_fab2(sch_1):tp_cpu1_test_10"
				( objectStatus "TP_CPU1_TEST_10" )
			)
			( signal "@baseboard_fab2_lib.baseboard_fab2(sch_1):tp_cpu1_test_9"
				( objectStatus "TP_CPU1_TEST_9" )
			)
			( signal "@baseboard_fab2_lib.baseboard_fab2(sch_1):tp_cpu1_rsvd_test_11"
				( objectStatus "TP_CPU1_RSVD_TEST_11" )
			)
			( signal "@baseboard_fab2_lib.baseboard_fab2(sch_1):tp_dacb"
				( objectStatus "TP_DACB" )
			)
			( signal "@baseboard_fab2_lib.baseboard_fab2(sch_1):tp_dacg"
				( objectStatus "TP_DACG" )
			)
			( signal "@baseboard_fab2_lib.baseboard_fab2(sch_1):tp_dacr"
				( objectStatus "TP_DACR" )
			)
			( signal "@baseboard_fab2_lib.baseboard_fab2(sch_1):tp_ddcclk_gpioj6"
				( objectStatus "TP_DDCCLK_GPIOJ6" )
			)
			( signal "@baseboard_fab2_lib.baseboard_fab2(sch_1):tp_ddcdat_gpioj7"
				( objectStatus "TP_DDCDAT_GPIOJ7" )
			)
			( signal "@baseboard_fab2_lib.baseboard_fab2(sch_1):sp1_bmc_host_uart_rx"
				( objectStatus "SP1_BMC_HOST_UART_RX" )
			)
			( signal "@baseboard_fab2_lib.baseboard_fab2(sch_1):sp1_bmc_host_uart_tx"
				( objectStatus "SP1_BMC_HOST_UART_TX" )
			)
			( signal "@baseboard_fab2_lib.baseboard_fab2(sch_1):uart_bmc_rxd5"
				( objectStatus "UART_BMC_RXD5" )
			)
			( signal "@baseboard_fab2_lib.baseboard_fab2(sch_1):uart_bmc_txd5"
				( objectStatus "UART_BMC_TXD5" )
			)
			( signal "@baseboard_fab2_lib.baseboard_fab2(sch_1):uart_mux_out_r"
				( objectStatus "UART_MUX_OUT_R" )
			)
			( signal "@baseboard_fab2_lib.baseboard_fab2(sch_1):spa_mid_dbg_tx"
				( objectStatus "SPA_MID_DBG_TX" )
			)
			( signal "@baseboard_fab2_lib.baseboard_fab2(sch_1):sp2_bmc_cm_uart_tx"
				( objectStatus "SP2_BMC_CM_UART_TX" )
			)
			( signal "@baseboard_fab2_lib.baseboard_fab2(sch_1):uart_mux_in_r"
				( objectStatus "UART_MUX_IN_R" )
			)
			( signal "@baseboard_fab2_lib.baseboard_fab2(sch_1):spa_mid_dbg_rx"
				( objectStatus "SPA_MID_DBG_RX" )
			)
			( signal "@baseboard_fab2_lib.baseboard_fab2(sch_1):spa_sin_sw_r"
				( objectStatus "SPA_SIN_SW_R" )
			)
			( signal "@baseboard_fab2_lib.baseboard_fab2(sch_1):sp2_bmc_cm_uart_rx"
				( objectStatus "SP2_BMC_CM_UART_RX" )
			)
			( signal "@baseboard_fab2_lib.baseboard_fab2(sch_1):sp1_host_bridge_uart_rx"
				( objectStatus "SP1_HOST_BRIDGE_UART_RX" )
			)
			( signal "@baseboard_fab2_lib.baseboard_fab2(sch_1):sp1_host_bridge_uart_tx"
				( objectStatus "SP1_HOST_BRIDGE_UART_TX" )
			)
			( signal "@baseboard_fab2_lib.baseboard_fab2(sch_1):uart_bridge_rxd5"
				( objectStatus "UART_BRIDGE_RXD5" )
			)
			( signal "@baseboard_fab2_lib.baseboard_fab2(sch_1):uart_bridge_txd5"
				( objectStatus "UART_BRIDGE_TXD5" )
			)
			( signal "@baseboard_fab2_lib.baseboard_fab2(sch_1):jtag_tms_r"
				( objectStatus "JTAG_TMS_R" )
			)
			( signal "@baseboard_fab2_lib.baseboard_fab2(sch_1):jtag_tms"
				( objectStatus "JTAG_TMS" )
			)
			( signal "@baseboard_fab2_lib.baseboard_fab2(sch_1):jtag_bmc_tms"
				( objectStatus "JTAG_BMC_TMS" )
			)
			( signal "@baseboard_fab2_lib.baseboard_fab2(sch_1):jtag_pld_tms"
				( objectStatus "JTAG_PLD_TMS" )
			)
			( signal "@baseboard_fab2_lib.baseboard_fab2(sch_1):jtag_pch_gbe_tms"
				( objectStatus "JTAG_PCH_GBE_TMS" )
			)
			( signal "@baseboard_fab2_lib.baseboard_fab2(sch_1):jtag_pch_pld_tms"
				( objectStatus "JTAG_PCH_PLD_TMS" )
			)
			( signal "@baseboard_fab2_lib.baseboard_fab2(sch_1):jtag_tck_r"
				( objectStatus "JTAG_TCK_R" )
			)
			( signal "@baseboard_fab2_lib.baseboard_fab2(sch_1):jtag_tck"
				( objectStatus "JTAG_TCK" )
			)
			( signal "@baseboard_fab2_lib.baseboard_fab2(sch_1):jtag_pch_pld_tck"
				( objectStatus "JTAG_PCH_PLD_TCK" )
			)
			( signal "@baseboard_fab2_lib.baseboard_fab2(sch_1):jtag_pch_gbe_clk"
				( objectStatus "JTAG_PCH_GBE_CLK" )
			)
			( signal "@baseboard_fab2_lib.baseboard_fab2(sch_1):jtag_bmc_tck"
				( objectStatus "JTAG_BMC_TCK" )
			)
			( signal "@baseboard_fab2_lib.baseboard_fab2(sch_1):jtag_pld_tck"
				( objectStatus "JTAG_PLD_TCK" )
			)
			( signal "@baseboard_fab2_lib.baseboard_fab2(sch_1):jtag_tdi_r"
				( objectStatus "JTAG_TDI_R" )
			)
			( signal "@baseboard_fab2_lib.baseboard_fab2(sch_1):jtag_tdi"
				( objectStatus "JTAG_TDI" )
			)
			( signal "@baseboard_fab2_lib.baseboard_fab2(sch_1):jtag_pch_pld_tdi"
				( objectStatus "JTAG_PCH_PLD_TDI" )
			)
			( signal "@baseboard_fab2_lib.baseboard_fab2(sch_1):jtag_pch_gbe_tdi"
				( objectStatus "JTAG_PCH_GBE_TDI" )
			)
			( signal "@baseboard_fab2_lib.baseboard_fab2(sch_1):jtag_pld_tdi"
				( objectStatus "JTAG_PLD_TDI" )
			)
			( signal "@baseboard_fab2_lib.baseboard_fab2(sch_1):jtag_bmc_tdi"
				( objectStatus "JTAG_BMC_TDI" )
			)
			( signal "@baseboard_fab2_lib.baseboard_fab2(sch_1):jtag_tdo_r"
				( objectStatus "JTAG_TDO_R" )
			)
			( signal "@baseboard_fab2_lib.baseboard_fab2(sch_1):jtag_tdo"
				( objectStatus "JTAG_TDO" )
			)
			( signal "@baseboard_fab2_lib.baseboard_fab2(sch_1):jtag_bmc_tdo"
				( objectStatus "JTAG_BMC_TDO" )
			)
			( signal "@baseboard_fab2_lib.baseboard_fab2(sch_1):jtag_pch_gbe_tdo"
				( objectStatus "JTAG_PCH_GBE_TDO" )
			)
			( signal "@baseboard_fab2_lib.baseboard_fab2(sch_1):jtag_pch_pld_tdo"
				( objectStatus "JTAG_PCH_PLD_TDO" )
			)
			( signal "@baseboard_fab2_lib.baseboard_fab2(sch_1):jtag_pld_tdo"
				( objectStatus "JTAG_PLD_TDO" )
			)
			( signal "@baseboard_fab2_lib.baseboard_fab2(sch_1):jtag_pch_gbe_trst_n"
				( objectStatus "JTAG_PCH_GBE_TRST_N" )
			)
			( signal "@baseboard_fab2_lib.baseboard_fab2(sch_1):jtag_trst_n"
				( pinPairRef "@baseboard_fab2_lib.baseboard_fab2(sch_1):\PP5608\" )
				( pinPairRef "@baseboard_fab2_lib.baseboard_fab2(sch_1):\PP5609\" )
				( objectStatus "JTAG_TRST_N" )
			)
			( signal "@baseboard_fab2_lib.baseboard_fab2(sch_1):jtag_bmc_trst_n"
				( objectStatus "JTAG_BMC_TRST_N" )
			)
			( signal "@baseboard_fab2_lib.baseboard_fab2(sch_1):jtag_mcp_mux_tdo"
				( objectStatus "JTAG_MCP_MUX_TDO" )
			)
			( signal "@baseboard_fab2_lib.baseboard_fab2(sch_1):jtag_mcp_cpu0_tdo"
				( objectStatus "JTAG_MCP_CPU0_TDO" )
			)
			( signal "@baseboard_fab2_lib.baseboard_fab2(sch_1):jtag_mcp_cpu1_tdi"
				( objectStatus "JTAG_MCP_CPU1_TDI" )
			)
			( signal "@baseboard_fab2_lib.baseboard_fab2(sch_1):jtag_mcp_cpu1_tdi_r"
				( objectStatus "JTAG_MCP_CPU1_TDI_R" )
			)
			( signal "@baseboard_fab2_lib.baseboard_fab2(sch_1):jtag_mcp_cpu1_tdo"
				( objectStatus "JTAG_MCP_CPU1_TDO" )
			)
			( signal "@baseboard_fab2_lib.baseboard_fab2(sch_1):xdp_cpu_mbp0_n"
				( pinPairRef "@baseboard_fab2_lib.baseboard_fab2(sch_1):\PP6138\" )
				( pinPairRef "@baseboard_fab2_lib.baseboard_fab2(sch_1):\PP6139\" )
				( objectStatus "XDP_CPU_MBP0_N" )
			)
			( signal "@baseboard_fab2_lib.baseboard_fab2(sch_1):xdp_cpu_mbp1_n"
				( pinPairRef "@baseboard_fab2_lib.baseboard_fab2(sch_1):\PP6136\" )
				( pinPairRef "@baseboard_fab2_lib.baseboard_fab2(sch_1):\PP6137\" )
				( objectStatus "XDP_CPU_MBP1_N" )
			)
			( signal "@baseboard_fab2_lib.baseboard_fab2(sch_1):xdp_cpu_pwr_debug_n"
				( objectStatus "XDP_CPU_PWR_DEBUG_N" )
			)
			( signal "@baseboard_fab2_lib.baseboard_fab2(sch_1):xdp_itp_pmode"
				( attribute "RATSNEST_SCHEDULE" "MIN_TREE"
					( Origin gBackEnd )
				)
				( objectStatus "XDP_ITP_PMODE" )
			)
			( signal "@baseboard_fab2_lib.baseboard_fab2(sch_1):xdp_pch_tck1"
				( pinPairRef "@baseboard_fab2_lib.baseboard_fab2(sch_1):\PP6134\" )
				( pinPairRef "@baseboard_fab2_lib.baseboard_fab2(sch_1):\PP6135\" )
				( objectStatus "XDP_PCH_TCK1" )
			)
			( signal "@baseboard_fab2_lib.baseboard_fab2(sch_1):xdp_present_n"
				( objectStatus "XDP_PRESENT_N" )
			)
			( signal "@baseboard_fab2_lib.baseboard_fab2(sch_1):xdp_pwrgd_rst_n"
				( objectStatus "XDP_PWRGD_RST_N" )
			)
			( signal "@baseboard_fab2_lib.baseboard_fab2(sch_1):xdp_rst_co_n"
				( objectStatus "XDP_RST_CO_N" )
			)
			( signal "@baseboard_fab2_lib.baseboard_fab2(sch_1):xdp_syspwrok"
				( objectStatus "XDP_SYSPWROK" )
			)
			( signal "@baseboard_fab2_lib.baseboard_fab2(sch_1):xdp_cpu1_tdo"
				( pinPairRef "@baseboard_fab2_lib.baseboard_fab2(sch_1):\PP5610\" )
				( pinPairRef "@baseboard_fab2_lib.baseboard_fab2(sch_1):\PP5611\" )
				( objectStatus "XDP_CPU1_TDO" )
			)
			( signal "@baseboard_fab2_lib.baseboard_fab2(sch_1):xdp_cpu_tdo"
				( pinPairRef "@baseboard_fab2_lib.baseboard_fab2(sch_1):\PP5612\" )
				( objectStatus "XDP_CPU_TDO" )
			)
			( signal "@baseboard_fab2_lib.baseboard_fab2(sch_1):xdp_tdo"
				( pinPairRef "@baseboard_fab2_lib.baseboard_fab2(sch_1):\PP5613\" )
				( pinPairRef "@baseboard_fab2_lib.baseboard_fab2(sch_1):\PP5614\" )
				( pinPairRef "@baseboard_fab2_lib.baseboard_fab2(sch_1):\PP5615\" )
				( pinPairRef "@baseboard_fab2_lib.baseboard_fab2(sch_1):\PP5616\" )
				( objectStatus "XDP_TDO" )
			)
			( signal "@baseboard_fab2_lib.baseboard_fab2(sch_1):xdp_cpu0_tdo"
				( pinPairRef "@baseboard_fab2_lib.baseboard_fab2(sch_1):\PP5617\" )
				( pinPairRef "@baseboard_fab2_lib.baseboard_fab2(sch_1):\PP5618\" )
				( pinPairRef "@baseboard_fab2_lib.baseboard_fab2(sch_1):\PP5619\" )
				( objectStatus "XDP_CPU0_TDO" )
			)
			( signal "@baseboard_fab2_lib.baseboard_fab2(sch_1):xdp_cpu1_tdi"
				( pinPairRef "@baseboard_fab2_lib.baseboard_fab2(sch_1):\PP5620\" )
				( pinPairRef "@baseboard_fab2_lib.baseboard_fab2(sch_1):\PP5621\" )
				( objectStatus "XDP_CPU1_TDI" )
			)
			( signal "@baseboard_fab2_lib.baseboard_fab2(sch_1):xdp_pch_cpu_tck0"
				( pinPairRef "@baseboard_fab2_lib.baseboard_fab2(sch_1):\PP5622\" )
				( pinPairRef "@baseboard_fab2_lib.baseboard_fab2(sch_1):\PP5623\" )
				( objectStatus "XDP_PCH_CPU_TCK0" )
			)
			( signal "@baseboard_fab2_lib.baseboard_fab2(sch_1):xdp_cpu_gtl_tck_r2"
				( pinPairRef "@baseboard_fab2_lib.baseboard_fab2(sch_1):\PP5624\" )
				( objectStatus "XDP_CPU_GTL_TCK_R2" )
			)
			( signal "@baseboard_fab2_lib.baseboard_fab2(sch_1):xdp_cpu_tck0"
				( pinPairRef "@baseboard_fab2_lib.baseboard_fab2(sch_1):\PP5625\" )
				( pinPairRef "@baseboard_fab2_lib.baseboard_fab2(sch_1):\PP5626\" )
				( pinPairRef "@baseboard_fab2_lib.baseboard_fab2(sch_1):\PP5627\" )
				( objectStatus "XDP_CPU_TCK0" )
			)
			( signal "@baseboard_fab2_lib.baseboard_fab2(sch_1):xdp_trst_n"
				( pinPairRef "@baseboard_fab2_lib.baseboard_fab2(sch_1):\PP5525\" )
				( pinPairRef "@baseboard_fab2_lib.baseboard_fab2(sch_1):\PP5526\" )
				( pinPairRef "@baseboard_fab2_lib.baseboard_fab2(sch_1):\PP5527\" )
				( objectStatus "XDP_TRST_N" )
			)
			( signal "@baseboard_fab2_lib.baseboard_fab2(sch_1):xdp_cpu_trst_n"
				( pinPairRef "@baseboard_fab2_lib.baseboard_fab2(sch_1):\PP5528\" )
				( pinPairRef "@baseboard_fab2_lib.baseboard_fab2(sch_1):\PP5529\" )
				( objectStatus "XDP_CPU_TRST_N" )
			)
			( signal "@baseboard_fab2_lib.baseboard_fab2(sch_1):xdp_tms"
				( pinPairRef "@baseboard_fab2_lib.baseboard_fab2(sch_1):\PP5521\" )
				( pinPairRef "@baseboard_fab2_lib.baseboard_fab2(sch_1):\PP5522\" )
				( pinPairRef "@baseboard_fab2_lib.baseboard_fab2(sch_1):\PP5523\" )
				( objectStatus "XDP_TMS" )
			)
			( signal "@baseboard_fab2_lib.baseboard_fab2(sch_1):xdp_cpu_tms"
				( pinPairRef "@baseboard_fab2_lib.baseboard_fab2(sch_1):\PP5524\" )
				( objectStatus "XDP_CPU_TMS" )
			)
			( signal "@baseboard_fab2_lib.baseboard_fab2(sch_1):xdp_tdi"
				( pinPairRef "@baseboard_fab2_lib.baseboard_fab2(sch_1):\PP5515\" )
				( pinPairRef "@baseboard_fab2_lib.baseboard_fab2(sch_1):\PP5516\" )
				( pinPairRef "@baseboard_fab2_lib.baseboard_fab2(sch_1):\PP5517\" )
				( pinPairRef "@baseboard_fab2_lib.baseboard_fab2(sch_1):\PP5518\" )
				( objectStatus "XDP_TDI" )
			)
			( signal "@baseboard_fab2_lib.baseboard_fab2(sch_1):xdp_cpu_tdi"
				( pinPairRef "@baseboard_fab2_lib.baseboard_fab2(sch_1):\PP5519\" )
				( pinPairRef "@baseboard_fab2_lib.baseboard_fab2(sch_1):\PP5520\" )
				( objectStatus "XDP_CPU_TDI" )
			)
			( signal "@baseboard_fab2_lib.baseboard_fab2(sch_1):xdp_rsmrst_n"
				( pinPairRef "@baseboard_fab2_lib.baseboard_fab2(sch_1):\PP5513\" )
				( objectStatus "XDP_RSMRST_N" )
			)
			( signal "@baseboard_fab2_lib.baseboard_fab2(sch_1):rst_rsmrst_n"
				( pinPairRef "@baseboard_fab2_lib.baseboard_fab2(sch_1):\PP5514\" )
				( attribute "CDS_XNET_NAME" "SELECT"
					( Origin gBackEnd )
				)
				( objectStatus "RST_RSMRST_N" )
			)
			( signal "@baseboard_fab2_lib.baseboard_fab2(sch_1):rst_rsmrst_r_n"
				( objectStatus "RST_RSMRST_R_N" )
			)
			( signal "@baseboard_fab2_lib.baseboard_fab2(sch_1):xdp_preq_n"
				( pinPairRef "@baseboard_fab2_lib.baseboard_fab2(sch_1):\PP5510\" )
				( pinPairRef "@baseboard_fab2_lib.baseboard_fab2(sch_1):\PP5511\" )
				( objectStatus "XDP_PREQ_N" )
			)
			( signal "@baseboard_fab2_lib.baseboard_fab2(sch_1):xdp_cpu_preq_n"
				( pinPairRef "@baseboard_fab2_lib.baseboard_fab2(sch_1):\PP5512\" )
				( objectStatus "XDP_CPU_PREQ_N" )
			)
			( signal "@baseboard_fab2_lib.baseboard_fab2(sch_1):xdp_prdy_n"
				( pinPairRef "@baseboard_fab2_lib.baseboard_fab2(sch_1):\PP5507\" )
				( pinPairRef "@baseboard_fab2_lib.baseboard_fab2(sch_1):\PP5508\" )
				( objectStatus "XDP_PRDY_N" )
			)
			( signal "@baseboard_fab2_lib.baseboard_fab2(sch_1):xdp_cpu_prdy_n"
				( pinPairRef "@baseboard_fab2_lib.baseboard_fab2(sch_1):\PP5509\" )
				( objectStatus "XDP_CPU_PRDY_N" )
			)
			( signal "@baseboard_fab2_lib.baseboard_fab2(sch_1):xdp_obsfn_b1_mbp7_n"
				( pinPairRef "@baseboard_fab2_lib.baseboard_fab2(sch_1):\PP5505\" )
				( objectStatus "XDP_OBSFN_B1_MBP7_N" )
			)
			( signal "@baseboard_fab2_lib.baseboard_fab2(sch_1):xdp_cpu_obsfn_b1_mbp7_n"
				( pinPairRef "@baseboard_fab2_lib.baseboard_fab2(sch_1):\PP5506\" )
				( objectStatus "XDP_CPU_OBSFN_B1_MBP7_N" )
			)
			( signal "@baseboard_fab2_lib.baseboard_fab2(sch_1):xdp_obsfn_b0_mbp6_n"
				( pinPairRef "@baseboard_fab2_lib.baseboard_fab2(sch_1):\PP5503\" )
				( objectStatus "XDP_OBSFN_B0_MBP6_N" )
			)
			( signal "@baseboard_fab2_lib.baseboard_fab2(sch_1):xdp_cpu_obsfn_b0_mbp6_n"
				( pinPairRef "@baseboard_fab2_lib.baseboard_fab2(sch_1):\PP5504\" )
				( objectStatus "XDP_CPU_OBSFN_B0_MBP6_N" )
			)
			( signal "@baseboard_fab2_lib.baseboard_fab2(sch_1):smb_hfi0_cpu0_lvc2_scl"
				( objectStatus "SMB_HFI0_CPU0_LVC2_SCL" )
			)
			( signal "@baseboard_fab2_lib.baseboard_fab2(sch_1):smb_hfi0_cpu0_lvc2_sda"
				( objectStatus "SMB_HFI0_CPU0_LVC2_SDA" )
			)
			( signal "@baseboard_fab2_lib.baseboard_fab2(sch_1):smb_hfi1_cpu0_lvc2_scl"
				( objectStatus "SMB_HFI1_CPU0_LVC2_SCL" )
			)
			( signal "@baseboard_fab2_lib.baseboard_fab2(sch_1):smb_hfi1_cpu0_lvc2_sda"
				( objectStatus "SMB_HFI1_CPU0_LVC2_SDA" )
			)
			( signal "@baseboard_fab2_lib.baseboard_fab2(sch_1):smb_pehpcpu1_stby_lvc3_r_scl"
				( pinPairRef "@baseboard_fab2_lib.baseboard_fab2(sch_1):\PP5654\" )
				( objectStatus "SMB_PEHPCPU1_STBY_LVC3_R_SCL" )
			)
			( signal "@baseboard_fab2_lib.baseboard_fab2(sch_1):smb_slotx24_bmc_stby_lvc3_scl"
				( pinPairRef "@baseboard_fab2_lib.baseboard_fab2(sch_1):\PP5655\" )
				( objectStatus "SMB_SLOTX24_BMC_STBY_LVC3_SCL" )
			)
			( signal "@baseboard_fab2_lib.baseboard_fab2(sch_1):smb_slotx24_stby_lvc3_scl_r2"
				( pinPairRef "@baseboard_fab2_lib.baseboard_fab2(sch_1):\PP5656\" )
				( objectStatus "SMB_SLOTX24_STBY_LVC3_SCL_R2" )
			)
			( signal "@baseboard_fab2_lib.baseboard_fab2(sch_1):smb_slotx24_pch_stby_lvc3_scl"
				( pinPairRef "@baseboard_fab2_lib.baseboard_fab2(sch_1):\PP5657\" )
				( objectStatus "SMB_SLOTX24_PCH_STBY_LVC3_SCL" )
			)
			( signal "@baseboard_fab2_lib.baseboard_fab2(sch_1):smb_slotx24_stby_lvc3_scl_r1"
				( pinPairRef "@baseboard_fab2_lib.baseboard_fab2(sch_1):\PP5658\" )
				( objectStatus "SMB_SLOTX24_STBY_LVC3_SCL_R1" )
			)
			( signal "@baseboard_fab2_lib.baseboard_fab2(sch_1):smb_slotx24_stby_lvc3_scl_r"
				( pinPairRef "@baseboard_fab2_lib.baseboard_fab2(sch_1):\PP5659\" )
				( objectStatus "SMB_SLOTX24_STBY_LVC3_SCL_R" )
			)
			( signal "@baseboard_fab2_lib.baseboard_fab2(sch_1):smb_pehpcpu1_stby_lvc3_scl"
				( pinPairRef "@baseboard_fab2_lib.baseboard_fab2(sch_1):\PP5660\" )
				( objectStatus "SMB_PEHPCPU1_STBY_LVC3_SCL" )
			)
			( signal "@baseboard_fab2_lib.baseboard_fab2(sch_1):smb_sensor_stby_lvc3_scl"
				( pinPairRef "@baseboard_fab2_lib.baseboard_fab2(sch_1):\PP5628\" )
				( objectStatus "SMB_SENSOR_STBY_LVC3_SCL" )
			)
			( signal "@baseboard_fab2_lib.baseboard_fab2(sch_1):smb_sensor_tmp421_2_scl"
				( pinPairRef "@baseboard_fab2_lib.baseboard_fab2(sch_1):\PP5629\" )
				( objectStatus "SMB_SENSOR_TMP421_2_SCL" )
			)
			( signal "@baseboard_fab2_lib.baseboard_fab2(sch_1):smb_sensor_tmp421_1_scl"
				( pinPairRef "@baseboard_fab2_lib.baseboard_fab2(sch_1):\PP5630\" )
				( objectStatus "SMB_SENSOR_TMP421_1_SCL" )
			)
			( signal "@baseboard_fab2_lib.baseboard_fab2(sch_1):smb_sensor_bmc_stby_lvc3_scl"
				( pinPairRef "@baseboard_fab2_lib.baseboard_fab2(sch_1):\PP5631\" )
				( objectStatus "SMB_SENSOR_BMC_STBY_LVC3_SCL" )
			)
			( signal "@baseboard_fab2_lib.baseboard_fab2(sch_1):smb_sensor_pch_stby_lvc3_scl"
				( pinPairRef "@baseboard_fab2_lib.baseboard_fab2(sch_1):\PP5632\" )
				( objectStatus "SMB_SENSOR_PCH_STBY_LVC3_SCL" )
			)
			( signal "@baseboard_fab2_lib.baseboard_fab2(sch_1):smb_sensor_stby_lvc3_scl_r1"
				( pinPairRef "@baseboard_fab2_lib.baseboard_fab2(sch_1):\PP5633\" )
				( objectStatus "SMB_SENSOR_STBY_LVC3_SCL_R1" )
			)
			( signal "@baseboard_fab2_lib.baseboard_fab2(sch_1):smb_lan_stby_lvc3_sda"
				( pinPairRef "@baseboard_fab2_lib.baseboard_fab2(sch_1):\PP5678\" )
				( objectStatus "SMB_LAN_STBY_LVC3_SDA" )
			)
			( signal "@baseboard_fab2_lib.baseboard_fab2(sch_1):smb_lan_stby_lvc3_sda_r2"
				( pinPairRef "@baseboard_fab2_lib.baseboard_fab2(sch_1):\PP5679\" )
				( objectStatus "SMB_LAN_STBY_LVC3_SDA_R2" )
			)
			( signal "@baseboard_fab2_lib.baseboard_fab2(sch_1):smb_lan_stby_lvc3_sda_r"
				( pinPairRef "@baseboard_fab2_lib.baseboard_fab2(sch_1):\PP5680\" )
				( objectStatus "SMB_LAN_STBY_LVC3_SDA_R" )
			)
			( signal "@baseboard_fab2_lib.baseboard_fab2(sch_1):smb_ocp_fru_stby_lvc3_sda"
				( pinPairRef "@baseboard_fab2_lib.baseboard_fab2(sch_1):\PP5681\" )
				( objectStatus "SMB_OCP_FRU_STBY_LVC3_SDA" )
			)
			( signal "@baseboard_fab2_lib.baseboard_fab2(sch_1):smb_ocp_fru_stby_lvc3_sda_r"
				( pinPairRef "@baseboard_fab2_lib.baseboard_fab2(sch_1):\PP5682\" )
				( objectStatus "SMB_OCP_FRU_STBY_LVC3_SDA_R" )
			)
			( signal "@baseboard_fab2_lib.baseboard_fab2(sch_1):smb_lan_stby_lvc3_sda_r1"
				( pinPairRef "@baseboard_fab2_lib.baseboard_fab2(sch_1):\PP5683\" )
				( objectStatus "SMB_LAN_STBY_LVC3_SDA_R1" )
			)
			( signal "@baseboard_fab2_lib.baseboard_fab2(sch_1):smb_lan_stby_lvc3_scl"
				( pinPairRef "@baseboard_fab2_lib.baseboard_fab2(sch_1):\PP5672\" )
				( objectStatus "SMB_LAN_STBY_LVC3_SCL" )
			)
			( signal "@baseboard_fab2_lib.baseboard_fab2(sch_1):smb_lan_stby_lvc3_scl_r2"
				( pinPairRef "@baseboard_fab2_lib.baseboard_fab2(sch_1):\PP5673\" )
				( objectStatus "SMB_LAN_STBY_LVC3_SCL_R2" )
			)
			( signal "@baseboard_fab2_lib.baseboard_fab2(sch_1):smb_lan_stby_lvc3_scl_r"
				( pinPairRef "@baseboard_fab2_lib.baseboard_fab2(sch_1):\PP5674\" )
				( objectStatus "SMB_LAN_STBY_LVC3_SCL_R" )
			)
			( signal "@baseboard_fab2_lib.baseboard_fab2(sch_1):smb_ocp_fru_stby_lvc3_scl"
				( pinPairRef "@baseboard_fab2_lib.baseboard_fab2(sch_1):\PP5675\" )
				( objectStatus "SMB_OCP_FRU_STBY_LVC3_SCL" )
			)
			( signal "@baseboard_fab2_lib.baseboard_fab2(sch_1):smb_ocp_fru_stby_lvc3_scl_r"
				( pinPairRef "@baseboard_fab2_lib.baseboard_fab2(sch_1):\PP5676\" )
				( objectStatus "SMB_OCP_FRU_STBY_LVC3_SCL_R" )
			)
			( signal "@baseboard_fab2_lib.baseboard_fab2(sch_1):smb_lan_stby_lvc3_scl_r1"
				( pinPairRef "@baseboard_fab2_lib.baseboard_fab2(sch_1):\PP5677\" )
				( objectStatus "SMB_LAN_STBY_LVC3_SCL_R1" )
			)
			( signal "@baseboard_fab2_lib.baseboard_fab2(sch_1):smb_pmbus_bmc_stby_lvc3_sda_r1"
				( pinPairRef "@baseboard_fab2_lib.baseboard_fab2(sch_1):\PP5538\" )
				( objectStatus "SMB_PMBUS_BMC_STBY_LVC3_SDA_R1" )
			)
			( signal "@baseboard_fab2_lib.baseboard_fab2(sch_1):smb_bmc_pmbus_stby_lvc3_sda"
				( pinPairRef "@baseboard_fab2_lib.baseboard_fab2(sch_1):\PP5539\" )
				( objectStatus "SMB_BMC_PMBUS_STBY_LVC3_SDA" )
			)
			( signal "@baseboard_fab2_lib.baseboard_fab2(sch_1):smb_3v3sb_hsc_sda_r"
				( pinPairRef "@baseboard_fab2_lib.baseboard_fab2(sch_1):\PP5540\" )
				( objectStatus "SMB_3V3SB_HSC_SDA_R" )
			)
			( signal "@baseboard_fab2_lib.baseboard_fab2(sch_1):smb_bmc_pmbus_stby_lvc3_sda_r"
				( pinPairRef "@baseboard_fab2_lib.baseboard_fab2(sch_1):\PP5541\" )
				( objectStatus "SMB_BMC_PMBUS_STBY_LVC3_SDA_R" )
			)
			( signal "@baseboard_fab2_lib.baseboard_fab2(sch_1):smb_pmbus_bmc_stby_lvc3_scl_r1"
				( pinPairRef "@baseboard_fab2_lib.baseboard_fab2(sch_1):\PP5534\" )
				( objectStatus "SMB_PMBUS_BMC_STBY_LVC3_SCL_R1" )
			)
			( signal "@baseboard_fab2_lib.baseboard_fab2(sch_1):smb_bmc_pmbus_stby_lvc3_scl"
				( pinPairRef "@baseboard_fab2_lib.baseboard_fab2(sch_1):\PP5535\" )
				( objectStatus "SMB_BMC_PMBUS_STBY_LVC3_SCL" )
			)
			( signal "@baseboard_fab2_lib.baseboard_fab2(sch_1):smb_3v3sb_hsc_scl_r"
				( pinPairRef "@baseboard_fab2_lib.baseboard_fab2(sch_1):\PP5536\" )
				( objectStatus "SMB_3V3SB_HSC_SCL_R" )
			)
			( signal "@baseboard_fab2_lib.baseboard_fab2(sch_1):smb_bmc_pmbus_stby_lvc3_scl_r"
				( pinPairRef "@baseboard_fab2_lib.baseboard_fab2(sch_1):\PP5537\" )
				( objectStatus "SMB_BMC_PMBUS_STBY_LVC3_SCL_R" )
			)
			( signal "@baseboard_fab2_lib.baseboard_fab2(sch_1):smb_pehpcpu1_stby_lvc3_r_sda"
				( pinPairRef "@baseboard_fab2_lib.baseboard_fab2(sch_1):\PP5661\" )
				( objectStatus "SMB_PEHPCPU1_STBY_LVC3_R_SDA" )
			)
			( signal "@baseboard_fab2_lib.baseboard_fab2(sch_1):smb_slotx24_bmc_stby_lvc3_sda"
				( pinPairRef "@baseboard_fab2_lib.baseboard_fab2(sch_1):\PP5662\" )
				( objectStatus "SMB_SLOTX24_BMC_STBY_LVC3_SDA" )
			)
			( signal "@baseboard_fab2_lib.baseboard_fab2(sch_1):smb_slotx24_stby_lvc3_sda_r"
				( pinPairRef "@baseboard_fab2_lib.baseboard_fab2(sch_1):\PP5663\" )
				( objectStatus "SMB_SLOTX24_STBY_LVC3_SDA_R" )
			)
			( signal "@baseboard_fab2_lib.baseboard_fab2(sch_1):smb_slotx24_stby_lvc3_sda_r2"
				( pinPairRef "@baseboard_fab2_lib.baseboard_fab2(sch_1):\PP5664\" )
				( objectStatus "SMB_SLOTX24_STBY_LVC3_SDA_R2" )
			)
			( signal "@baseboard_fab2_lib.baseboard_fab2(sch_1):smb_slotx24_pch_stby_lvc3_sda"
				( pinPairRef "@baseboard_fab2_lib.baseboard_fab2(sch_1):\PP5665\" )
				( objectStatus "SMB_SLOTX24_PCH_STBY_LVC3_SDA" )
			)
			( signal "@baseboard_fab2_lib.baseboard_fab2(sch_1):smb_slotx24_stby_lvc3_sda_r1"
				( pinPairRef "@baseboard_fab2_lib.baseboard_fab2(sch_1):\PP5666\" )
				( objectStatus "SMB_SLOTX24_STBY_LVC3_SDA_R1" )
			)
			( signal "@baseboard_fab2_lib.baseboard_fab2(sch_1):smb_pehpcpu1_stby_lvc3_sda"
				( pinPairRef "@baseboard_fab2_lib.baseboard_fab2(sch_1):\PP5667\" )
				( objectStatus "SMB_PEHPCPU1_STBY_LVC3_SDA" )
			)
			( signal "@baseboard_fab2_lib.baseboard_fab2(sch_1):smb_springville_stby_lvc3_sda"
				( pinPairRef "@baseboard_fab2_lib.baseboard_fab2(sch_1):\PP5646\" )
				( objectStatus "SMB_SPRINGVILLE_STBY_LVC3_SDA" )
			)
			( signal "@baseboard_fab2_lib.baseboard_fab2(sch_1):smb_smlink0_stby_lvc3_sda"
				( pinPairRef "@baseboard_fab2_lib.baseboard_fab2(sch_1):\PP5647\" )
				( objectStatus "SMB_SMLINK0_STBY_LVC3_SDA" )
			)
			( signal "@baseboard_fab2_lib.baseboard_fab2(sch_1):smb_smlink0_stby_lvc3_sda_r"
				( pinPairRef "@baseboard_fab2_lib.baseboard_fab2(sch_1):\PP5648\" )
				( objectStatus "SMB_SMLINK0_STBY_LVC3_SDA_R" )
			)
			( signal "@baseboard_fab2_lib.baseboard_fab2(sch_1):smb_smlink0_stby_lvc3_sda_r1"
				( pinPairRef "@baseboard_fab2_lib.baseboard_fab2(sch_1):\PP5649\" )
				( objectStatus "SMB_SMLINK0_STBY_LVC3_SDA_R1" )
			)
			( signal "@baseboard_fab2_lib.baseboard_fab2(sch_1):smb_ocp_lan_stby_lvc3_sda"
				( pinPairRef "@baseboard_fab2_lib.baseboard_fab2(sch_1):\PP5650\" )
				( objectStatus "SMB_OCP_LAN_STBY_LVC3_SDA" )
			)
			( signal "@baseboard_fab2_lib.baseboard_fab2(sch_1):smb_ocp_lan_stby_lvc3_sda_r"
				( pinPairRef "@baseboard_fab2_lib.baseboard_fab2(sch_1):\PP5651\" )
				( objectStatus "SMB_OCP_LAN_STBY_LVC3_SDA_R" )
			)
			( signal "@baseboard_fab2_lib.baseboard_fab2(sch_1):smb_springville_stby_lvc3_scl"
				( pinPairRef "@baseboard_fab2_lib.baseboard_fab2(sch_1):\PP5640\" )
				( objectStatus "SMB_SPRINGVILLE_STBY_LVC3_SCL" )
			)
			( signal "@baseboard_fab2_lib.baseboard_fab2(sch_1):smb_ocp_lan_stby_lvc3_scl"
				( pinPairRef "@baseboard_fab2_lib.baseboard_fab2(sch_1):\PP5641\" )
				( objectStatus "SMB_OCP_LAN_STBY_LVC3_SCL" )
			)
			( signal "@baseboard_fab2_lib.baseboard_fab2(sch_1):smb_ocp_lan_stby_lvc3_scl_r"
				( pinPairRef "@baseboard_fab2_lib.baseboard_fab2(sch_1):\PP5642\" )
				( objectStatus "SMB_OCP_LAN_STBY_LVC3_SCL_R" )
			)
			( signal "@baseboard_fab2_lib.baseboard_fab2(sch_1):smb_smlink0_stby_lvc3_scl"
				( pinPairRef "@baseboard_fab2_lib.baseboard_fab2(sch_1):\PP5643\" )
				( objectStatus "SMB_SMLINK0_STBY_LVC3_SCL" )
			)
			( signal "@baseboard_fab2_lib.baseboard_fab2(sch_1):smb_smlink0_stby_lvc3_scl_r"
				( pinPairRef "@baseboard_fab2_lib.baseboard_fab2(sch_1):\PP5644\" )
				( objectStatus "SMB_SMLINK0_STBY_LVC3_SCL_R" )
			)
			( signal "@baseboard_fab2_lib.baseboard_fab2(sch_1):smb_smlink0_stby_lvc3_scl_r1"
				( pinPairRef "@baseboard_fab2_lib.baseboard_fab2(sch_1):\PP5645\" )
				( objectStatus "SMB_SMLINK0_STBY_LVC3_SCL_R1" )
			)
			( signal "@baseboard_fab2_lib.baseboard_fab2(sch_1):smb_sensor_stby_lvc3_sda"
				( pinPairRef "@baseboard_fab2_lib.baseboard_fab2(sch_1):\PP5634\" )
				( objectStatus "SMB_SENSOR_STBY_LVC3_SDA" )
			)
			( signal "@baseboard_fab2_lib.baseboard_fab2(sch_1):smb_sensor_pch_stby_lvc3_sda"
				( pinPairRef "@baseboard_fab2_lib.baseboard_fab2(sch_1):\PP5635\" )
				( objectStatus "SMB_SENSOR_PCH_STBY_LVC3_SDA" )
			)
			( signal "@baseboard_fab2_lib.baseboard_fab2(sch_1):smb_sensor_stby_lvc3_sda_r1"
				( pinPairRef "@baseboard_fab2_lib.baseboard_fab2(sch_1):\PP5636\" )
				( objectStatus "SMB_SENSOR_STBY_LVC3_SDA_R1" )
			)
			( signal "@baseboard_fab2_lib.baseboard_fab2(sch_1):smb_sensor_bmc_stby_lvc3_sda"
				( pinPairRef "@baseboard_fab2_lib.baseboard_fab2(sch_1):\PP5637\" )
				( objectStatus "SMB_SENSOR_BMC_STBY_LVC3_SDA" )
			)
			( signal "@baseboard_fab2_lib.baseboard_fab2(sch_1):smb_sensor_tmp421_2_sda"
				( pinPairRef "@baseboard_fab2_lib.baseboard_fab2(sch_1):\PP5638\" )
				( objectStatus "SMB_SENSOR_TMP421_2_SDA" )
			)
			( signal "@baseboard_fab2_lib.baseboard_fab2(sch_1):smb_sensor_tmp421_1_sda"
				( pinPairRef "@baseboard_fab2_lib.baseboard_fab2(sch_1):\PP5639\" )
				( objectStatus "SMB_SENSOR_TMP421_1_SDA" )
			)
			( signal "@baseboard_fab2_lib.baseboard_fab2(sch_1):smb_vr_sda_pvnn_pch"
				( pinPairRef "@baseboard_fab2_lib.baseboard_fab2(sch_1):\PP5596\" )
				( objectStatus "SMB_VR_SDA_PVNN_PCH" )
			)
			( signal "@baseboard_fab2_lib.baseboard_fab2(sch_1):smb_vr_stby_lvc3_sda"
				( pinPairRef "@baseboard_fab2_lib.baseboard_fab2(sch_1):\PP5597\" )
				( objectStatus "SMB_VR_STBY_LVC3_SDA" )
			)
			( signal "@baseboard_fab2_lib.baseboard_fab2(sch_1):smb_vr_sda_vddq_abc"
				( pinPairRef "@baseboard_fab2_lib.baseboard_fab2(sch_1):\PP5598\" )
				( objectStatus "SMB_VR_SDA_VDDQ_ABC" )
			)
			( signal "@baseboard_fab2_lib.baseboard_fab2(sch_1):smb_vr_sda_vddq_klm"
				( pinPairRef "@baseboard_fab2_lib.baseboard_fab2(sch_1):\PP5599\" )
				( objectStatus "SMB_VR_SDA_VDDQ_KLM" )
			)
			( signal "@baseboard_fab2_lib.baseboard_fab2(sch_1):smb_vr_sda_pvccio_cpu1"
				( pinPairRef "@baseboard_fab2_lib.baseboard_fab2(sch_1):\PP5600\" )
				( objectStatus "SMB_VR_SDA_PVCCIO_CPU1" )
			)
			( signal "@baseboard_fab2_lib.baseboard_fab2(sch_1):smb_vr_sda_pvccio_cpu0"
				( pinPairRef "@baseboard_fab2_lib.baseboard_fab2(sch_1):\PP5601\" )
				( objectStatus "SMB_VR_SDA_PVCCIO_CPU0" )
			)
			( signal "@baseboard_fab2_lib.baseboard_fab2(sch_1):smb_vr_stby_lvc3_sda_r1"
				( pinPairRef "@baseboard_fab2_lib.baseboard_fab2(sch_1):\PP5602\" )
				( objectStatus "SMB_VR_STBY_LVC3_SDA_R1" )
			)
			( signal "@baseboard_fab2_lib.baseboard_fab2(sch_1):smb_vr_sda_r"
				( pinPairRef "@baseboard_fab2_lib.baseboard_fab2(sch_1):\PP5603\" )
				( objectStatus "SMB_VR_SDA_R" )
			)
			( signal "@baseboard_fab2_lib.baseboard_fab2(sch_1):smb_vr_sda_r1"
				( pinPairRef "@baseboard_fab2_lib.baseboard_fab2(sch_1):\PP5604\" )
				( objectStatus "SMB_VR_SDA_R1" )
			)
			( signal "@baseboard_fab2_lib.baseboard_fab2(sch_1):smb_vr_sda_vddq_def"
				( pinPairRef "@baseboard_fab2_lib.baseboard_fab2(sch_1):\PP5605\" )
				( objectStatus "SMB_VR_SDA_VDDQ_DEF" )
			)
			( signal "@baseboard_fab2_lib.baseboard_fab2(sch_1):smb_vr_stby_lvc3_sda_r"
				( pinPairRef "@baseboard_fab2_lib.baseboard_fab2(sch_1):\PP5606\" )
				( objectStatus "SMB_VR_STBY_LVC3_SDA_R" )
			)
			( signal "@baseboard_fab2_lib.baseboard_fab2(sch_1):smb_vr_sda_vddq_ghj"
				( pinPairRef "@baseboard_fab2_lib.baseboard_fab2(sch_1):\PP5607\" )
				( objectStatus "SMB_VR_SDA_VDDQ_GHJ" )
			)
			( signal "@baseboard_fab2_lib.baseboard_fab2(sch_1):smb_vr_scl_pvnn_pch"
				( pinPairRef "@baseboard_fab2_lib.baseboard_fab2(sch_1):\PP5584\" )
				( objectStatus "SMB_VR_SCL_PVNN_PCH" )
			)
			( signal "@baseboard_fab2_lib.baseboard_fab2(sch_1):smb_vr_stby_lvc3_scl"
				( pinPairRef "@baseboard_fab2_lib.baseboard_fab2(sch_1):\PP5585\" )
				( objectStatus "SMB_VR_STBY_LVC3_SCL" )
			)
			( signal "@baseboard_fab2_lib.baseboard_fab2(sch_1):smb_vr_scl_vddq_klm"
				( pinPairRef "@baseboard_fab2_lib.baseboard_fab2(sch_1):\PP5586\" )
				( objectStatus "SMB_VR_SCL_VDDQ_KLM" )
			)
			( signal "@baseboard_fab2_lib.baseboard_fab2(sch_1):smb_vr_scl_pvccio_cpu0"
				( pinPairRef "@baseboard_fab2_lib.baseboard_fab2(sch_1):\PP5587\" )
				( objectStatus "SMB_VR_SCL_PVCCIO_CPU0" )
			)
			( signal "@baseboard_fab2_lib.baseboard_fab2(sch_1):smb_vr_scl_r"
				( pinPairRef "@baseboard_fab2_lib.baseboard_fab2(sch_1):\PP5588\" )
				( objectStatus "SMB_VR_SCL_R" )
			)
			( signal "@baseboard_fab2_lib.baseboard_fab2(sch_1):smb_vr_scl_pvccio_cpu1"
				( pinPairRef "@baseboard_fab2_lib.baseboard_fab2(sch_1):\PP5589\" )
				( objectStatus "SMB_VR_SCL_PVCCIO_CPU1" )
			)
			( signal "@baseboard_fab2_lib.baseboard_fab2(sch_1):smb_vr_scl_r1"
				( pinPairRef "@baseboard_fab2_lib.baseboard_fab2(sch_1):\PP5590\" )
				( objectStatus "SMB_VR_SCL_R1" )
			)
			( signal "@baseboard_fab2_lib.baseboard_fab2(sch_1):smb_vr_scl_vddq_def"
				( pinPairRef "@baseboard_fab2_lib.baseboard_fab2(sch_1):\PP5591\" )
				( objectStatus "SMB_VR_SCL_VDDQ_DEF" )
			)
			( signal "@baseboard_fab2_lib.baseboard_fab2(sch_1):smb_vr_scl_vddq_ghj"
				( pinPairRef "@baseboard_fab2_lib.baseboard_fab2(sch_1):\PP5592\" )
				( objectStatus "SMB_VR_SCL_VDDQ_GHJ" )
			)
			( signal "@baseboard_fab2_lib.baseboard_fab2(sch_1):smb_vr_stby_lvc3_scl_r1"
				( pinPairRef "@baseboard_fab2_lib.baseboard_fab2(sch_1):\PP5593\" )
				( objectStatus "SMB_VR_STBY_LVC3_SCL_R1" )
			)
			( signal "@baseboard_fab2_lib.baseboard_fab2(sch_1):smb_vr_stby_lvc3_scl_r"
				( pinPairRef "@baseboard_fab2_lib.baseboard_fab2(sch_1):\PP5594\" )
				( objectStatus "SMB_VR_STBY_LVC3_SCL_R" )
			)
			( signal "@baseboard_fab2_lib.baseboard_fab2(sch_1):smb_vr_scl_vddq_abc"
				( pinPairRef "@baseboard_fab2_lib.baseboard_fab2(sch_1):\PP5595\" )
				( objectStatus "SMB_VR_SCL_VDDQ_ABC" )
			)
			( signal "@baseboard_fab2_lib.baseboard_fab2(sch_1):smb_ddr_klm_vpp_sda_r"
				( pinPairRef "@baseboard_fab2_lib.baseboard_fab2(sch_1):\PP5449\" )
				( pinPairRef "@baseboard_fab2_lib.baseboard_fab2(sch_1):\PP5450\" )
				( pinPairRef "@baseboard_fab2_lib.baseboard_fab2(sch_1):\PP5451\" )
				( objectStatus "SMB_DDR_KLM_VPP_SDA_R" )
			)
			( signal "@baseboard_fab2_lib.baseboard_fab2(sch_1):smb_ddr_klm_vpp_sda"
				( pinPairRef "@baseboard_fab2_lib.baseboard_fab2(sch_1):\PP5452\" )
				( objectStatus "SMB_DDR_KLM_VPP_SDA" )
			)
			( signal "@baseboard_fab2_lib.baseboard_fab2(sch_1):smb_ddr_klm_vpp_scl_r"
				( pinPairRef "@baseboard_fab2_lib.baseboard_fab2(sch_1):\PP5445\" )
				( pinPairRef "@baseboard_fab2_lib.baseboard_fab2(sch_1):\PP5446\" )
				( pinPairRef "@baseboard_fab2_lib.baseboard_fab2(sch_1):\PP5447\" )
				( objectStatus "SMB_DDR_KLM_VPP_SCL_R" )
			)
			( signal "@baseboard_fab2_lib.baseboard_fab2(sch_1):smb_ddr_klm_vpp_scl"
				( pinPairRef "@baseboard_fab2_lib.baseboard_fab2(sch_1):\PP5448\" )
				( objectStatus "SMB_DDR_KLM_VPP_SCL" )
			)
			( signal "@baseboard_fab2_lib.baseboard_fab2(sch_1):smb_ddr_ghj_vpp_sda_r"
				( pinPairRef "@baseboard_fab2_lib.baseboard_fab2(sch_1):\PP5435\" )
				( pinPairRef "@baseboard_fab2_lib.baseboard_fab2(sch_1):\PP5436\" )
				( pinPairRef "@baseboard_fab2_lib.baseboard_fab2(sch_1):\PP5437\" )
				( objectStatus "SMB_DDR_GHJ_VPP_SDA_R" )
			)
			( signal "@baseboard_fab2_lib.baseboard_fab2(sch_1):smb_ddr_ghj_vpp_sda"
				( pinPairRef "@baseboard_fab2_lib.baseboard_fab2(sch_1):\PP5438\" )
				( objectStatus "SMB_DDR_GHJ_VPP_SDA" )
			)
			( signal "@baseboard_fab2_lib.baseboard_fab2(sch_1):smb_ddr_ghj_vpp_scl_r"
				( pinPairRef "@baseboard_fab2_lib.baseboard_fab2(sch_1):\PP5432\" )
				( pinPairRef "@baseboard_fab2_lib.baseboard_fab2(sch_1):\PP5433\" )
				( objectStatus "SMB_DDR_GHJ_VPP_SCL_R" )
			)
			( signal "@baseboard_fab2_lib.baseboard_fab2(sch_1):smb_ddr_ghj_vpp_scl"
				( pinPairRef "@baseboard_fab2_lib.baseboard_fab2(sch_1):\PP5434\" )
				( objectStatus "SMB_DDR_GHJ_VPP_SCL" )
			)
			( signal "@baseboard_fab2_lib.baseboard_fab2(sch_1):smb_ddr_def_vpp_sda_r"
				( pinPairRef "@baseboard_fab2_lib.baseboard_fab2(sch_1):\PP5428\" )
				( pinPairRef "@baseboard_fab2_lib.baseboard_fab2(sch_1):\PP5429\" )
				( pinPairRef "@baseboard_fab2_lib.baseboard_fab2(sch_1):\PP5430\" )
				( objectStatus "SMB_DDR_DEF_VPP_SDA_R" )
			)
			( signal "@baseboard_fab2_lib.baseboard_fab2(sch_1):smb_ddr_def_vpp_sda"
				( pinPairRef "@baseboard_fab2_lib.baseboard_fab2(sch_1):\PP5431\" )
				( objectStatus "SMB_DDR_DEF_VPP_SDA" )
			)
			( signal "@baseboard_fab2_lib.baseboard_fab2(sch_1):smb_ddr_def_vpp_scl_r"
				( pinPairRef "@baseboard_fab2_lib.baseboard_fab2(sch_1):\PP5424\" )
				( pinPairRef "@baseboard_fab2_lib.baseboard_fab2(sch_1):\PP5425\" )
				( pinPairRef "@baseboard_fab2_lib.baseboard_fab2(sch_1):\PP5426\" )
				( objectStatus "SMB_DDR_DEF_VPP_SCL_R" )
			)
			( signal "@baseboard_fab2_lib.baseboard_fab2(sch_1):smb_ddr_def_vpp_scl"
				( pinPairRef "@baseboard_fab2_lib.baseboard_fab2(sch_1):\PP5427\" )
				( objectStatus "SMB_DDR_DEF_VPP_SCL" )
			)
			( signal "@baseboard_fab2_lib.baseboard_fab2(sch_1):smb_ddr_abc_vpp_sda_r"
				( pinPairRef "@baseboard_fab2_lib.baseboard_fab2(sch_1):\PP5415\" )
				( pinPairRef "@baseboard_fab2_lib.baseboard_fab2(sch_1):\PP5416\" )
				( objectStatus "SMB_DDR_ABC_VPP_SDA_R" )
			)
			( signal "@baseboard_fab2_lib.baseboard_fab2(sch_1):smb_ddr_abc_vpp_sda"
				( pinPairRef "@baseboard_fab2_lib.baseboard_fab2(sch_1):\PP5417\" )
				( objectStatus "SMB_DDR_ABC_VPP_SDA" )
			)
			( signal "@baseboard_fab2_lib.baseboard_fab2(sch_1):smb_ddr_abc_vpp_scl_r"
				( pinPairRef "@baseboard_fab2_lib.baseboard_fab2(sch_1):\PP5412\" )
				( pinPairRef "@baseboard_fab2_lib.baseboard_fab2(sch_1):\PP5413\" )
				( objectStatus "SMB_DDR_ABC_VPP_SCL_R" )
			)
			( signal "@baseboard_fab2_lib.baseboard_fab2(sch_1):smb_ddr_abc_vpp_scl"
				( pinPairRef "@baseboard_fab2_lib.baseboard_fab2(sch_1):\PP5414\" )
				( objectStatus "SMB_DDR_ABC_VPP_SCL" )
			)
			( signal "@baseboard_fab2_lib.baseboard_fab2(sch_1):smb_ddr_klm_sda_g_r"
				( objectStatus "SMB_DDR_KLM_SDA_G_R" )
			)
			( signal "@baseboard_fab2_lib.baseboard_fab2(sch_1):smb_ddr_klm_sda_g"
				( pinPairRef "@baseboard_fab2_lib.baseboard_fab2(sch_1):\PP5456\" )
				( objectStatus "SMB_DDR_KLM_SDA_G" )
			)
			( signal "@baseboard_fab2_lib.baseboard_fab2(sch_1):smb_ddr_klm_scl_g_r"
				( pinPairRef "@baseboard_fab2_lib.baseboard_fab2(sch_1):\PP5453\" )
				( objectStatus "SMB_DDR_KLM_SCL_G_R" )
			)
			( signal "@baseboard_fab2_lib.baseboard_fab2(sch_1):smb_ddr_klm_scl_g"
				( pinPairRef "@baseboard_fab2_lib.baseboard_fab2(sch_1):\PP5454\" )
				( pinPairRef "@baseboard_fab2_lib.baseboard_fab2(sch_1):\PP5455\" )
				( objectStatus "SMB_DDR_KLM_SCL_G" )
			)
			( signal "@baseboard_fab2_lib.baseboard_fab2(sch_1):smb_ddr_ghj_sda_g_r"
				( pinPairRef "@baseboard_fab2_lib.baseboard_fab2(sch_1):\PP5442\" )
				( objectStatus "SMB_DDR_GHJ_SDA_G_R" )
			)
			( signal "@baseboard_fab2_lib.baseboard_fab2(sch_1):smb_ddr_ghj_sda_g"
				( pinPairRef "@baseboard_fab2_lib.baseboard_fab2(sch_1):\PP5443\" )
				( pinPairRef "@baseboard_fab2_lib.baseboard_fab2(sch_1):\PP5444\" )
				( objectStatus "SMB_DDR_GHJ_SDA_G" )
			)
			( signal "@baseboard_fab2_lib.baseboard_fab2(sch_1):smb_ddr_ghj_scl_g_r"
				( pinPairRef "@baseboard_fab2_lib.baseboard_fab2(sch_1):\PP5439\" )
				( objectStatus "SMB_DDR_GHJ_SCL_G_R" )
			)
			( signal "@baseboard_fab2_lib.baseboard_fab2(sch_1):smb_ddr_ghj_scl_g"
				( pinPairRef "@baseboard_fab2_lib.baseboard_fab2(sch_1):\PP5440\" )
				( pinPairRef "@baseboard_fab2_lib.baseboard_fab2(sch_1):\PP5441\" )
				( objectStatus "SMB_DDR_GHJ_SCL_G" )
			)
			( signal "@baseboard_fab2_lib.baseboard_fab2(sch_1):smb_ddr_def_sda_g_r"
				( pinPairRef "@baseboard_fab2_lib.baseboard_fab2(sch_1):\PP5421\" )
				( objectStatus "SMB_DDR_DEF_SDA_G_R" )
			)
			( signal "@baseboard_fab2_lib.baseboard_fab2(sch_1):smb_ddr_def_sda_g"
				( pinPairRef "@baseboard_fab2_lib.baseboard_fab2(sch_1):\PP5422\" )
				( pinPairRef "@baseboard_fab2_lib.baseboard_fab2(sch_1):\PP5423\" )
				( objectStatus "SMB_DDR_DEF_SDA_G" )
			)
			( signal "@baseboard_fab2_lib.baseboard_fab2(sch_1):smb_ddr_def_scl_g_r"
				( pinPairRef "@baseboard_fab2_lib.baseboard_fab2(sch_1):\PP5418\" )
				( objectStatus "SMB_DDR_DEF_SCL_G_R" )
			)
			( signal "@baseboard_fab2_lib.baseboard_fab2(sch_1):smb_ddr_def_scl_g"
				( pinPairRef "@baseboard_fab2_lib.baseboard_fab2(sch_1):\PP5419\" )
				( pinPairRef "@baseboard_fab2_lib.baseboard_fab2(sch_1):\PP5420\" )
				( objectStatus "SMB_DDR_DEF_SCL_G" )
			)
			( signal "@baseboard_fab2_lib.baseboard_fab2(sch_1):smb_ddr_abc_sda_g_r"
				( pinPairRef "@baseboard_fab2_lib.baseboard_fab2(sch_1):\PP5409\" )
				( objectStatus "SMB_DDR_ABC_SDA_G_R" )
			)
			( signal "@baseboard_fab2_lib.baseboard_fab2(sch_1):smb_ddr_abc_sda_g"
				( pinPairRef "@baseboard_fab2_lib.baseboard_fab2(sch_1):\PP5410\" )
				( pinPairRef "@baseboard_fab2_lib.baseboard_fab2(sch_1):\PP5411\" )
				( objectStatus "SMB_DDR_ABC_SDA_G" )
			)
			( signal "@baseboard_fab2_lib.baseboard_fab2(sch_1):smb_ddr_abc_scl_g_r"
				( pinPairRef "@baseboard_fab2_lib.baseboard_fab2(sch_1):\PP5406\" )
				( objectStatus "SMB_DDR_ABC_SCL_G_R" )
			)
			( signal "@baseboard_fab2_lib.baseboard_fab2(sch_1):smb_ddr_abc_scl_g"
				( pinPairRef "@baseboard_fab2_lib.baseboard_fab2(sch_1):\PP5407\" )
				( pinPairRef "@baseboard_fab2_lib.baseboard_fab2(sch_1):\PP5408\" )
				( objectStatus "SMB_DDR_ABC_SCL_G" )
			)
			( signal "@baseboard_fab2_lib.baseboard_fab2(sch_1):pe_pch_sprv_tx_dn"
				( objectStatus "PE_PCH_SPRV_TX_DN" )
			)
			( signal "@baseboard_fab2_lib.baseboard_fab2(sch_1):pe_pch_sprv_tx_c_dn"
				( objectStatus "PE_PCH_SPRV_TX_C_DN" )
			)
			( signal "@baseboard_fab2_lib.baseboard_fab2(sch_1):pe_pch_sprv_tx_dp"
				( objectStatus "PE_PCH_SPRV_TX_DP" )
			)
			( signal "@baseboard_fab2_lib.baseboard_fab2(sch_1):pe_pch_sprv_tx_c_dp"
				( objectStatus "PE_PCH_SPRV_TX_C_DP" )
			)
			( signal "@baseboard_fab2_lib.baseboard_fab2(sch_1):nic_ser_n_mdi_3_dn"
				( attribute "CDS_XNET_NAME" "SELECT"
					( Origin gBackEnd )
				)
				( attribute "NO_TEST" "1"
					( Origin gBackEnd )
				)
				( objectStatus "NIC_SER_N_MDI_3_DN" )
			)
			( signal "@baseboard_fab2_lib.baseboard_fab2(sch_1):nic_mdi_sprv_rj45_3_r_dn"
				( attribute "NO_TEST" "1"
					( Origin gBackEnd )
				)
				( objectStatus "NIC_MDI_SPRV_RJ45_3_R_DN" )
			)
			( signal "@baseboard_fab2_lib.baseboard_fab2(sch_1):nic_ser_p_mdi_3_dp"
				( attribute "CDS_XNET_NAME" "SELECT"
					( Origin gBackEnd )
				)
				( attribute "NO_TEST" "1"
					( Origin gBackEnd )
				)
				( objectStatus "NIC_SER_P_MDI_3_DP" )
			)
			( signal "@baseboard_fab2_lib.baseboard_fab2(sch_1):nic_mdi_sprv_rj45_3_r_dp"
				( attribute "NO_TEST" "1"
					( Origin gBackEnd )
				)
				( objectStatus "NIC_MDI_SPRV_RJ45_3_R_DP" )
			)
			( signal "@baseboard_fab2_lib.baseboard_fab2(sch_1):nic_set_n_mdi_2_dn"
				( attribute "CDS_XNET_NAME" "SELECT"
					( Origin gBackEnd )
				)
				( attribute "NO_TEST" "1"
					( Origin gBackEnd )
				)
				( objectStatus "NIC_SET_N_MDI_2_DN" )
			)
			( signal "@baseboard_fab2_lib.baseboard_fab2(sch_1):nic_mdi_sprv_rj45_2_r_dn"
				( attribute "NO_TEST" "1"
					( Origin gBackEnd )
				)
				( objectStatus "NIC_MDI_SPRV_RJ45_2_R_DN" )
			)
			( signal "@baseboard_fab2_lib.baseboard_fab2(sch_1):nic_set_p_mdi_2_dp"
				( attribute "CDS_XNET_NAME" "SELECT"
					( Origin gBackEnd )
				)
				( attribute "NO_TEST" "1"
					( Origin gBackEnd )
				)
				( objectStatus "NIC_SET_P_MDI_2_DP" )
			)
			( signal "@baseboard_fab2_lib.baseboard_fab2(sch_1):nic_mdi_sprv_rj45_2_r_dp"
				( attribute "NO_TEST" "1"
					( Origin gBackEnd )
				)
				( objectStatus "NIC_MDI_SPRV_RJ45_2_R_DP" )
			)
			( signal "@baseboard_fab2_lib.baseboard_fab2(sch_1):sata6g_p0_rx_c_dn"
				( pinPairRef "@baseboard_fab2_lib.baseboard_fab2(sch_1):\PP5762\" )
				( objectStatus "SATA6G_P0_RX_C_DN" )
			)
			( signal "@baseboard_fab2_lib.baseboard_fab2(sch_1):sata6g_pch_pcie_up_sata_rxn(0)"
				( pinPairRef "@baseboard_fab2_lib.baseboard_fab2(sch_1):\PP5763\" )
				( objectStatus "SATA6G_PCH_PCIE_UP_SATA_RXN<0>" )
			)
			( signal "@baseboard_fab2_lib.baseboard_fab2(sch_1):sata6g_pch_pcie_up_sata_rxp(0)"
				( pinPairRef "@baseboard_fab2_lib.baseboard_fab2(sch_1):\PP5764\" )
				( objectStatus "SATA6G_PCH_PCIE_UP_SATA_RXP<0>" )
			)
			( signal "@baseboard_fab2_lib.baseboard_fab2(sch_1):sata6g_p0_rx_c_dp"
				( pinPairRef "@baseboard_fab2_lib.baseboard_fab2(sch_1):\PP5765\" )
				( objectStatus "SATA6G_P0_RX_C_DP" )
			)
			( signal "@baseboard_fab2_lib.baseboard_fab2(sch_1):sata6g_p1_rx_c_dn"
				( pinPairRef "@baseboard_fab2_lib.baseboard_fab2(sch_1):\PP5766\" )
				( objectStatus "SATA6G_P1_RX_C_DN" )
			)
			( signal "@baseboard_fab2_lib.baseboard_fab2(sch_1):sata6g_pch_pcie_up_sata_rxn(1)"
				( pinPairRef "@baseboard_fab2_lib.baseboard_fab2(sch_1):\PP5767\" )
				( objectStatus "SATA6G_PCH_PCIE_UP_SATA_RXN<1>" )
			)
			( signal "@baseboard_fab2_lib.baseboard_fab2(sch_1):sata6g_pch_pcie_up_sata_rxp(1)"
				( pinPairRef "@baseboard_fab2_lib.baseboard_fab2(sch_1):\PP5768\" )
				( objectStatus "SATA6G_PCH_PCIE_UP_SATA_RXP<1>" )
			)
			( signal "@baseboard_fab2_lib.baseboard_fab2(sch_1):sata6g_p1_rx_c_dp"
				( pinPairRef "@baseboard_fab2_lib.baseboard_fab2(sch_1):\PP5769\" )
				( objectStatus "SATA6G_P1_RX_C_DP" )
			)
			( signal "@baseboard_fab2_lib.baseboard_fab2(sch_1):sata6g_p2_rx_c_dn"
				( pinPairRef "@baseboard_fab2_lib.baseboard_fab2(sch_1):\PP5770\" )
				( objectStatus "SATA6G_P2_RX_C_DN" )
			)
			( signal "@baseboard_fab2_lib.baseboard_fab2(sch_1):sata6g_pch_pcie_up_sata_rxn(2)"
				( pinPairRef "@baseboard_fab2_lib.baseboard_fab2(sch_1):\PP5771\" )
				( objectStatus "SATA6G_PCH_PCIE_UP_SATA_RXN<2>" )
			)
			( signal "@baseboard_fab2_lib.baseboard_fab2(sch_1):sata6g_pch_pcie_up_sata_rxp(2)"
				( pinPairRef "@baseboard_fab2_lib.baseboard_fab2(sch_1):\PP5772\" )
				( objectStatus "SATA6G_PCH_PCIE_UP_SATA_RXP<2>" )
			)
			( signal "@baseboard_fab2_lib.baseboard_fab2(sch_1):sata6g_p2_rx_c_dp"
				( pinPairRef "@baseboard_fab2_lib.baseboard_fab2(sch_1):\PP5773\" )
				( objectStatus "SATA6G_P2_RX_C_DP" )
			)
			( signal "@baseboard_fab2_lib.baseboard_fab2(sch_1):sata6g_p3_rx_c_dn"
				( pinPairRef "@baseboard_fab2_lib.baseboard_fab2(sch_1):\PP5774\" )
				( objectStatus "SATA6G_P3_RX_C_DN" )
			)
			( signal "@baseboard_fab2_lib.baseboard_fab2(sch_1):sata6g_pch_pcie_up_sata_rxn(3)"
				( pinPairRef "@baseboard_fab2_lib.baseboard_fab2(sch_1):\PP5775\" )
				( objectStatus "SATA6G_PCH_PCIE_UP_SATA_RXN<3>" )
			)
			( signal "@baseboard_fab2_lib.baseboard_fab2(sch_1):sata6g_pch_pcie_up_sata_rxp(3)"
				( pinPairRef "@baseboard_fab2_lib.baseboard_fab2(sch_1):\PP5776\" )
				( objectStatus "SATA6G_PCH_PCIE_UP_SATA_RXP<3>" )
			)
			( signal "@baseboard_fab2_lib.baseboard_fab2(sch_1):sata6g_p3_rx_c_dp"
				( pinPairRef "@baseboard_fab2_lib.baseboard_fab2(sch_1):\PP5777\" )
				( objectStatus "SATA6G_P3_RX_C_DP" )
			)
			( signal "@baseboard_fab2_lib.baseboard_fab2(sch_1):sata6g_p4_rx_c_dn"
				( pinPairRef "@baseboard_fab2_lib.baseboard_fab2(sch_1):\PP5778\" )
				( objectStatus "SATA6G_P4_RX_C_DN" )
			)
			( signal "@baseboard_fab2_lib.baseboard_fab2(sch_1):sata6g_pch_pcie_up_sata_rxn(4)"
				( pinPairRef "@baseboard_fab2_lib.baseboard_fab2(sch_1):\PP5779\" )
				( objectStatus "SATA6G_PCH_PCIE_UP_SATA_RXN<4>" )
			)
			( signal "@baseboard_fab2_lib.baseboard_fab2(sch_1):sata6g_pch_pcie_up_sata_rxp(4)"
				( pinPairRef "@baseboard_fab2_lib.baseboard_fab2(sch_1):\PP5780\" )
				( objectStatus "SATA6G_PCH_PCIE_UP_SATA_RXP<4>" )
			)
			( signal "@baseboard_fab2_lib.baseboard_fab2(sch_1):sata6g_p4_rx_c_dp"
				( pinPairRef "@baseboard_fab2_lib.baseboard_fab2(sch_1):\PP5781\" )
				( objectStatus "SATA6G_P4_RX_C_DP" )
			)
			( signal "@baseboard_fab2_lib.baseboard_fab2(sch_1):sata6g_p5_rx_c_dn"
				( pinPairRef "@baseboard_fab2_lib.baseboard_fab2(sch_1):\PP5782\" )
				( objectStatus "SATA6G_P5_RX_C_DN" )
			)
			( signal "@baseboard_fab2_lib.baseboard_fab2(sch_1):sata6g_pch_pcie_up_sata_rxn(5)"
				( pinPairRef "@baseboard_fab2_lib.baseboard_fab2(sch_1):\PP5783\" )
				( objectStatus "SATA6G_PCH_PCIE_UP_SATA_RXN<5>" )
			)
			( signal "@baseboard_fab2_lib.baseboard_fab2(sch_1):sata6g_pch_pcie_up_sata_rxp(5)"
				( pinPairRef "@baseboard_fab2_lib.baseboard_fab2(sch_1):\PP5784\" )
				( objectStatus "SATA6G_PCH_PCIE_UP_SATA_RXP<5>" )
			)
			( signal "@baseboard_fab2_lib.baseboard_fab2(sch_1):sata6g_p5_rx_c_dp"
				( pinPairRef "@baseboard_fab2_lib.baseboard_fab2(sch_1):\PP5785\" )
				( objectStatus "SATA6G_P5_RX_C_DP" )
			)
			( signal "@baseboard_fab2_lib.baseboard_fab2(sch_1):sata6g_p6_rx_c_dn"
				( pinPairRef "@baseboard_fab2_lib.baseboard_fab2(sch_1):\PP5786\" )
				( objectStatus "SATA6G_P6_RX_C_DN" )
			)
			( signal "@baseboard_fab2_lib.baseboard_fab2(sch_1):sata6g_pch_pcie_up_sata_rxn(6)"
				( pinPairRef "@baseboard_fab2_lib.baseboard_fab2(sch_1):\PP5787\" )
				( objectStatus "SATA6G_PCH_PCIE_UP_SATA_RXN<6>" )
			)
			( signal "@baseboard_fab2_lib.baseboard_fab2(sch_1):sata6g_pch_pcie_up_sata_rxp(6)"
				( pinPairRef "@baseboard_fab2_lib.baseboard_fab2(sch_1):\PP5788\" )
				( objectStatus "SATA6G_PCH_PCIE_UP_SATA_RXP<6>" )
			)
			( signal "@baseboard_fab2_lib.baseboard_fab2(sch_1):sata6g_p6_rx_c_dp"
				( pinPairRef "@baseboard_fab2_lib.baseboard_fab2(sch_1):\PP5789\" )
				( objectStatus "SATA6G_P6_RX_C_DP" )
			)
			( signal "@baseboard_fab2_lib.baseboard_fab2(sch_1):sata6g_p7_rx_c_dn"
				( pinPairRef "@baseboard_fab2_lib.baseboard_fab2(sch_1):\PP5790\" )
				( objectStatus "SATA6G_P7_RX_C_DN" )
			)
			( signal "@baseboard_fab2_lib.baseboard_fab2(sch_1):sata6g_pch_pcie_up_sata_rxn(7)"
				( pinPairRef "@baseboard_fab2_lib.baseboard_fab2(sch_1):\PP5791\" )
				( objectStatus "SATA6G_PCH_PCIE_UP_SATA_RXN<7>" )
			)
			( signal "@baseboard_fab2_lib.baseboard_fab2(sch_1):sata6g_pch_pcie_up_sata_rxp(7)"
				( pinPairRef "@baseboard_fab2_lib.baseboard_fab2(sch_1):\PP5792\" )
				( objectStatus "SATA6G_PCH_PCIE_UP_SATA_RXP<7>" )
			)
			( signal "@baseboard_fab2_lib.baseboard_fab2(sch_1):sata6g_p7_rx_c_dp"
				( pinPairRef "@baseboard_fab2_lib.baseboard_fab2(sch_1):\PP5793\" )
				( objectStatus "SATA6G_P7_RX_C_DP" )
			)
			( signal "@baseboard_fab2_lib.baseboard_fab2(sch_1):sata6g_pch_pcie_up_sata_txn(0)"
				( pinPairRef "@baseboard_fab2_lib.baseboard_fab2(sch_1):\PP5730\" )
				( objectStatus "SATA6G_PCH_PCIE_UP_SATA_TXN<0>" )
			)
			( signal "@baseboard_fab2_lib.baseboard_fab2(sch_1):sata6g_p0_tx_c_dn"
				( pinPairRef "@baseboard_fab2_lib.baseboard_fab2(sch_1):\PP5731\" )
				( objectStatus "SATA6G_P0_TX_C_DN" )
			)
			( signal "@baseboard_fab2_lib.baseboard_fab2(sch_1):sata6g_p0_tx_c_dp"
				( pinPairRef "@baseboard_fab2_lib.baseboard_fab2(sch_1):\PP5732\" )
				( objectStatus "SATA6G_P0_TX_C_DP" )
			)
			( signal "@baseboard_fab2_lib.baseboard_fab2(sch_1):sata6g_pch_pcie_up_sata_txp(0)"
				( pinPairRef "@baseboard_fab2_lib.baseboard_fab2(sch_1):\PP5733\" )
				( objectStatus "SATA6G_PCH_PCIE_UP_SATA_TXP<0>" )
			)
			( signal "@baseboard_fab2_lib.baseboard_fab2(sch_1):sata6g_pch_pcie_up_sata_txn(1)"
				( pinPairRef "@baseboard_fab2_lib.baseboard_fab2(sch_1):\PP5734\" )
				( objectStatus "SATA6G_PCH_PCIE_UP_SATA_TXN<1>" )
			)
			( signal "@baseboard_fab2_lib.baseboard_fab2(sch_1):sata6g_p1_tx_c_dn"
				( pinPairRef "@baseboard_fab2_lib.baseboard_fab2(sch_1):\PP5735\" )
				( objectStatus "SATA6G_P1_TX_C_DN" )
			)
			( signal "@baseboard_fab2_lib.baseboard_fab2(sch_1):sata6g_p1_tx_c_dp"
				( pinPairRef "@baseboard_fab2_lib.baseboard_fab2(sch_1):\PP5736\" )
				( objectStatus "SATA6G_P1_TX_C_DP" )
			)
			( signal "@baseboard_fab2_lib.baseboard_fab2(sch_1):sata6g_pch_pcie_up_sata_txp(1)"
				( pinPairRef "@baseboard_fab2_lib.baseboard_fab2(sch_1):\PP5737\" )
				( objectStatus "SATA6G_PCH_PCIE_UP_SATA_TXP<1>" )
			)
			( signal "@baseboard_fab2_lib.baseboard_fab2(sch_1):sata6g_pch_pcie_up_sata_txn(2)"
				( pinPairRef "@baseboard_fab2_lib.baseboard_fab2(sch_1):\PP5738\" )
				( objectStatus "SATA6G_PCH_PCIE_UP_SATA_TXN<2>" )
			)
			( signal "@baseboard_fab2_lib.baseboard_fab2(sch_1):sata6g_p2_tx_c_dn"
				( pinPairRef "@baseboard_fab2_lib.baseboard_fab2(sch_1):\PP5739\" )
				( objectStatus "SATA6G_P2_TX_C_DN" )
			)
			( signal "@baseboard_fab2_lib.baseboard_fab2(sch_1):sata6g_p2_tx_c_dp"
				( pinPairRef "@baseboard_fab2_lib.baseboard_fab2(sch_1):\PP5740\" )
				( objectStatus "SATA6G_P2_TX_C_DP" )
			)
			( signal "@baseboard_fab2_lib.baseboard_fab2(sch_1):sata6g_pch_pcie_up_sata_txp(2)"
				( pinPairRef "@baseboard_fab2_lib.baseboard_fab2(sch_1):\PP5741\" )
				( objectStatus "SATA6G_PCH_PCIE_UP_SATA_TXP<2>" )
			)
			( signal "@baseboard_fab2_lib.baseboard_fab2(sch_1):sata6g_pch_pcie_up_sata_txn(3)"
				( pinPairRef "@baseboard_fab2_lib.baseboard_fab2(sch_1):\PP5742\" )
				( objectStatus "SATA6G_PCH_PCIE_UP_SATA_TXN<3>" )
			)
			( signal "@baseboard_fab2_lib.baseboard_fab2(sch_1):sata6g_p3_tx_c_dn"
				( pinPairRef "@baseboard_fab2_lib.baseboard_fab2(sch_1):\PP5743\" )
				( objectStatus "SATA6G_P3_TX_C_DN" )
			)
			( signal "@baseboard_fab2_lib.baseboard_fab2(sch_1):sata6g_p3_tx_c_dp"
				( pinPairRef "@baseboard_fab2_lib.baseboard_fab2(sch_1):\PP5744\" )
				( objectStatus "SATA6G_P3_TX_C_DP" )
			)
			( signal "@baseboard_fab2_lib.baseboard_fab2(sch_1):sata6g_pch_pcie_up_sata_txp(3)"
				( pinPairRef "@baseboard_fab2_lib.baseboard_fab2(sch_1):\PP5745\" )
				( objectStatus "SATA6G_PCH_PCIE_UP_SATA_TXP<3>" )
			)
			( signal "@baseboard_fab2_lib.baseboard_fab2(sch_1):sata6g_pch_pcie_up_sata_txn(4)"
				( pinPairRef "@baseboard_fab2_lib.baseboard_fab2(sch_1):\PP5746\" )
				( objectStatus "SATA6G_PCH_PCIE_UP_SATA_TXN<4>" )
			)
			( signal "@baseboard_fab2_lib.baseboard_fab2(sch_1):sata6g_p4_tx_c_dn"
				( pinPairRef "@baseboard_fab2_lib.baseboard_fab2(sch_1):\PP5747\" )
				( objectStatus "SATA6G_P4_TX_C_DN" )
			)
			( signal "@baseboard_fab2_lib.baseboard_fab2(sch_1):sata6g_p4_tx_c_dp"
				( pinPairRef "@baseboard_fab2_lib.baseboard_fab2(sch_1):\PP5748\" )
				( objectStatus "SATA6G_P4_TX_C_DP" )
			)
			( signal "@baseboard_fab2_lib.baseboard_fab2(sch_1):sata6g_pch_pcie_up_sata_txp(4)"
				( pinPairRef "@baseboard_fab2_lib.baseboard_fab2(sch_1):\PP5749\" )
				( objectStatus "SATA6G_PCH_PCIE_UP_SATA_TXP<4>" )
			)
			( signal "@baseboard_fab2_lib.baseboard_fab2(sch_1):sata6g_pch_pcie_up_sata_txn(5)"
				( pinPairRef "@baseboard_fab2_lib.baseboard_fab2(sch_1):\PP5750\" )
				( objectStatus "SATA6G_PCH_PCIE_UP_SATA_TXN<5>" )
			)
			( signal "@baseboard_fab2_lib.baseboard_fab2(sch_1):sata6g_p5_tx_c_dn"
				( pinPairRef "@baseboard_fab2_lib.baseboard_fab2(sch_1):\PP5751\" )
				( objectStatus "SATA6G_P5_TX_C_DN" )
			)
			( signal "@baseboard_fab2_lib.baseboard_fab2(sch_1):sata6g_p5_tx_c_dp"
				( pinPairRef "@baseboard_fab2_lib.baseboard_fab2(sch_1):\PP5752\" )
				( objectStatus "SATA6G_P5_TX_C_DP" )
			)
			( signal "@baseboard_fab2_lib.baseboard_fab2(sch_1):sata6g_pch_pcie_up_sata_txp(5)"
				( pinPairRef "@baseboard_fab2_lib.baseboard_fab2(sch_1):\PP5753\" )
				( objectStatus "SATA6G_PCH_PCIE_UP_SATA_TXP<5>" )
			)
			( signal "@baseboard_fab2_lib.baseboard_fab2(sch_1):sata6g_pch_pcie_up_sata_txn(6)"
				( pinPairRef "@baseboard_fab2_lib.baseboard_fab2(sch_1):\PP5754\" )
				( objectStatus "SATA6G_PCH_PCIE_UP_SATA_TXN<6>" )
			)
			( signal "@baseboard_fab2_lib.baseboard_fab2(sch_1):sata6g_p6_tx_c_dn"
				( pinPairRef "@baseboard_fab2_lib.baseboard_fab2(sch_1):\PP5755\" )
				( objectStatus "SATA6G_P6_TX_C_DN" )
			)
			( signal "@baseboard_fab2_lib.baseboard_fab2(sch_1):sata6g_p6_tx_c_dp"
				( pinPairRef "@baseboard_fab2_lib.baseboard_fab2(sch_1):\PP5756\" )
				( objectStatus "SATA6G_P6_TX_C_DP" )
			)
			( signal "@baseboard_fab2_lib.baseboard_fab2(sch_1):sata6g_pch_pcie_up_sata_txp(6)"
				( pinPairRef "@baseboard_fab2_lib.baseboard_fab2(sch_1):\PP5757\" )
				( objectStatus "SATA6G_PCH_PCIE_UP_SATA_TXP<6>" )
			)
			( signal "@baseboard_fab2_lib.baseboard_fab2(sch_1):sata6g_pch_pcie_up_sata_txn(7)"
				( pinPairRef "@baseboard_fab2_lib.baseboard_fab2(sch_1):\PP5758\" )
				( objectStatus "SATA6G_PCH_PCIE_UP_SATA_TXN<7>" )
			)
			( signal "@baseboard_fab2_lib.baseboard_fab2(sch_1):sata6g_p7_tx_c_dn"
				( pinPairRef "@baseboard_fab2_lib.baseboard_fab2(sch_1):\PP5759\" )
				( objectStatus "SATA6G_P7_TX_C_DN" )
			)
			( signal "@baseboard_fab2_lib.baseboard_fab2(sch_1):sata6g_p7_tx_c_dp"
				( pinPairRef "@baseboard_fab2_lib.baseboard_fab2(sch_1):\PP5760\" )
				( objectStatus "SATA6G_P7_TX_C_DP" )
			)
			( signal "@baseboard_fab2_lib.baseboard_fab2(sch_1):sata6g_pch_pcie_up_sata_txp(7)"
				( pinPairRef "@baseboard_fab2_lib.baseboard_fab2(sch_1):\PP5761\" )
				( objectStatus "SATA6G_PCH_PCIE_UP_SATA_TXP<7>" )
			)
			( signal "@baseboard_fab2_lib.baseboard_fab2(sch_1):sata6g_rx_dn(0)"
				( pinPairRef "@baseboard_fab2_lib.baseboard_fab2(sch_1):\PP5714\" )
				( objectStatus "SATA6G_RX_DN<0>" )
			)
			( signal "@baseboard_fab2_lib.baseboard_fab2(sch_1):sata6g_p8_rx_c_dn"
				( pinPairRef "@baseboard_fab2_lib.baseboard_fab2(sch_1):\PP5715\" )
				( objectStatus "SATA6G_P8_RX_C_DN" )
			)
			( signal "@baseboard_fab2_lib.baseboard_fab2(sch_1):sata6g_p8_rx_c_dp"
				( pinPairRef "@baseboard_fab2_lib.baseboard_fab2(sch_1):\PP5716\" )
				( objectStatus "SATA6G_P8_RX_C_DP" )
			)
			( signal "@baseboard_fab2_lib.baseboard_fab2(sch_1):sata6g_rx_dp(0)"
				( pinPairRef "@baseboard_fab2_lib.baseboard_fab2(sch_1):\PP5717\" )
				( objectStatus "SATA6G_RX_DP<0>" )
			)
			( signal "@baseboard_fab2_lib.baseboard_fab2(sch_1):sata6g_rx_dn(1)"
				( pinPairRef "@baseboard_fab2_lib.baseboard_fab2(sch_1):\PP5722\" )
				( objectStatus "SATA6G_RX_DN<1>" )
			)
			( signal "@baseboard_fab2_lib.baseboard_fab2(sch_1):sata6g_p9_rx_c_dn"
				( pinPairRef "@baseboard_fab2_lib.baseboard_fab2(sch_1):\PP5723\" )
				( objectStatus "SATA6G_P9_RX_C_DN" )
			)
			( signal "@baseboard_fab2_lib.baseboard_fab2(sch_1):sata6g_p9_rx_c_dp"
				( pinPairRef "@baseboard_fab2_lib.baseboard_fab2(sch_1):\PP5724\" )
				( objectStatus "SATA6G_P9_RX_C_DP" )
			)
			( signal "@baseboard_fab2_lib.baseboard_fab2(sch_1):sata6g_rx_dp(1)"
				( pinPairRef "@baseboard_fab2_lib.baseboard_fab2(sch_1):\PP5725\" )
				( objectStatus "SATA6G_RX_DP<1>" )
			)
			( signal "@baseboard_fab2_lib.baseboard_fab2(sch_1):sata6g_rx_dn(2)"
				( pinPairRef "@baseboard_fab2_lib.baseboard_fab2(sch_1):\PP5698\" )
				( objectStatus "SATA6G_RX_DN<2>" )
			)
			( signal "@baseboard_fab2_lib.baseboard_fab2(sch_1):sata6g_p10_rx_c_dn"
				( pinPairRef "@baseboard_fab2_lib.baseboard_fab2(sch_1):\PP5699\" )
				( objectStatus "SATA6G_P10_RX_C_DN" )
			)
			( signal "@baseboard_fab2_lib.baseboard_fab2(sch_1):sata6g_p10_rx_c_dp"
				( pinPairRef "@baseboard_fab2_lib.baseboard_fab2(sch_1):\PP5700\" )
				( objectStatus "SATA6G_P10_RX_C_DP" )
			)
			( signal "@baseboard_fab2_lib.baseboard_fab2(sch_1):sata6g_rx_dp(2)"
				( pinPairRef "@baseboard_fab2_lib.baseboard_fab2(sch_1):\PP5701\" )
				( objectStatus "SATA6G_RX_DP<2>" )
			)
			( signal "@baseboard_fab2_lib.baseboard_fab2(sch_1):sata6g_rx_dn(3)"
				( pinPairRef "@baseboard_fab2_lib.baseboard_fab2(sch_1):\PP5706\" )
				( objectStatus "SATA6G_RX_DN<3>" )
			)
			( signal "@baseboard_fab2_lib.baseboard_fab2(sch_1):sata6g_p11_rx_c_dn"
				( pinPairRef "@baseboard_fab2_lib.baseboard_fab2(sch_1):\PP5707\" )
				( objectStatus "SATA6G_P11_RX_C_DN" )
			)
			( signal "@baseboard_fab2_lib.baseboard_fab2(sch_1):sata6g_p11_rx_c_dp"
				( pinPairRef "@baseboard_fab2_lib.baseboard_fab2(sch_1):\PP5708\" )
				( objectStatus "SATA6G_P11_RX_C_DP" )
			)
			( signal "@baseboard_fab2_lib.baseboard_fab2(sch_1):sata6g_rx_dp(3)"
				( pinPairRef "@baseboard_fab2_lib.baseboard_fab2(sch_1):\PP5709\" )
				( objectStatus "SATA6G_RX_DP<3>" )
			)
			( signal "@baseboard_fab2_lib.baseboard_fab2(sch_1):sata6g_s1_rx_c_dn"
				( objectStatus "SATA6G_S1_RX_C_DN" )
			)
			( signal "@baseboard_fab2_lib.baseboard_fab2(sch_1):sata6g_s1_rx_dn"
				( objectStatus "SATA6G_S1_RX_DN" )
			)
			( signal "@baseboard_fab2_lib.baseboard_fab2(sch_1):sata6g_s1_rx_dp"
				( objectStatus "SATA6G_S1_RX_DP" )
			)
			( signal "@baseboard_fab2_lib.baseboard_fab2(sch_1):sata6g_s1_rx_c_dp"
				( objectStatus "SATA6G_S1_RX_C_DP" )
			)
			( signal "@baseboard_fab2_lib.baseboard_fab2(sch_1):sata6g_s1_tx_c_dn"
				( pinPairRef "@baseboard_fab2_lib.baseboard_fab2(sch_1):\PP5668\" )
				( objectStatus "SATA6G_S1_TX_C_DN" )
			)
			( signal "@baseboard_fab2_lib.baseboard_fab2(sch_1):sata6g_s1_tx_dn"
				( pinPairRef "@baseboard_fab2_lib.baseboard_fab2(sch_1):\PP5669\" )
				( objectStatus "SATA6G_S1_TX_DN" )
			)
			( signal "@baseboard_fab2_lib.baseboard_fab2(sch_1):sata6g_s1_tx_dp"
				( pinPairRef "@baseboard_fab2_lib.baseboard_fab2(sch_1):\PP5670\" )
				( objectStatus "SATA6G_S1_TX_DP" )
			)
			( signal "@baseboard_fab2_lib.baseboard_fab2(sch_1):sata6g_s1_tx_c_dp"
				( pinPairRef "@baseboard_fab2_lib.baseboard_fab2(sch_1):\PP5671\" )
				( objectStatus "SATA6G_S1_TX_C_DP" )
			)
			( signal "@baseboard_fab2_lib.baseboard_fab2(sch_1):sata6g_tx_dn(0)"
				( pinPairRef "@baseboard_fab2_lib.baseboard_fab2(sch_1):\PP5718\" )
				( objectStatus "SATA6G_TX_DN<0>" )
			)
			( signal "@baseboard_fab2_lib.baseboard_fab2(sch_1):sata6g_p8_tx_c_dn"
				( pinPairRef "@baseboard_fab2_lib.baseboard_fab2(sch_1):\PP5719\" )
				( objectStatus "SATA6G_P8_TX_C_DN" )
			)
			( signal "@baseboard_fab2_lib.baseboard_fab2(sch_1):sata6g_p8_tx_c_dp"
				( pinPairRef "@baseboard_fab2_lib.baseboard_fab2(sch_1):\PP5720\" )
				( objectStatus "SATA6G_P8_TX_C_DP" )
			)
			( signal "@baseboard_fab2_lib.baseboard_fab2(sch_1):sata6g_tx_dp(0)"
				( pinPairRef "@baseboard_fab2_lib.baseboard_fab2(sch_1):\PP5721\" )
				( objectStatus "SATA6G_TX_DP<0>" )
			)
			( signal "@baseboard_fab2_lib.baseboard_fab2(sch_1):sata6g_tx_dn(1)"
				( pinPairRef "@baseboard_fab2_lib.baseboard_fab2(sch_1):\PP5726\" )
				( objectStatus "SATA6G_TX_DN<1>" )
			)
			( signal "@baseboard_fab2_lib.baseboard_fab2(sch_1):sata6g_p9_tx_c_dn"
				( pinPairRef "@baseboard_fab2_lib.baseboard_fab2(sch_1):\PP5727\" )
				( objectStatus "SATA6G_P9_TX_C_DN" )
			)
			( signal "@baseboard_fab2_lib.baseboard_fab2(sch_1):sata6g_p9_tx_c_dp"
				( pinPairRef "@baseboard_fab2_lib.baseboard_fab2(sch_1):\PP5728\" )
				( objectStatus "SATA6G_P9_TX_C_DP" )
			)
			( signal "@baseboard_fab2_lib.baseboard_fab2(sch_1):sata6g_tx_dp(1)"
				( pinPairRef "@baseboard_fab2_lib.baseboard_fab2(sch_1):\PP5729\" )
				( objectStatus "SATA6G_TX_DP<1>" )
			)
			( signal "@baseboard_fab2_lib.baseboard_fab2(sch_1):sata6g_tx_dn(2)"
				( pinPairRef "@baseboard_fab2_lib.baseboard_fab2(sch_1):\PP5702\" )
				( objectStatus "SATA6G_TX_DN<2>" )
			)
			( signal "@baseboard_fab2_lib.baseboard_fab2(sch_1):sata6g_p10_tx_c_dn"
				( pinPairRef "@baseboard_fab2_lib.baseboard_fab2(sch_1):\PP5703\" )
				( objectStatus "SATA6G_P10_TX_C_DN" )
			)
			( signal "@baseboard_fab2_lib.baseboard_fab2(sch_1):sata6g_p10_tx_c_dp"
				( pinPairRef "@baseboard_fab2_lib.baseboard_fab2(sch_1):\PP5704\" )
				( objectStatus "SATA6G_P10_TX_C_DP" )
			)
			( signal "@baseboard_fab2_lib.baseboard_fab2(sch_1):sata6g_tx_dp(2)"
				( pinPairRef "@baseboard_fab2_lib.baseboard_fab2(sch_1):\PP5705\" )
				( objectStatus "SATA6G_TX_DP<2>" )
			)
			( signal "@baseboard_fab2_lib.baseboard_fab2(sch_1):sata6g_tx_dn(3)"
				( pinPairRef "@baseboard_fab2_lib.baseboard_fab2(sch_1):\PP5710\" )
				( objectStatus "SATA6G_TX_DN<3>" )
			)
			( signal "@baseboard_fab2_lib.baseboard_fab2(sch_1):sata6g_p11_tx_c_dn"
				( pinPairRef "@baseboard_fab2_lib.baseboard_fab2(sch_1):\PP5711\" )
				( objectStatus "SATA6G_P11_TX_C_DN" )
			)
			( signal "@baseboard_fab2_lib.baseboard_fab2(sch_1):sata6g_p11_tx_c_dp"
				( pinPairRef "@baseboard_fab2_lib.baseboard_fab2(sch_1):\PP5712\" )
				( objectStatus "SATA6G_P11_TX_C_DP" )
			)
			( signal "@baseboard_fab2_lib.baseboard_fab2(sch_1):sata6g_tx_dp(3)"
				( pinPairRef "@baseboard_fab2_lib.baseboard_fab2(sch_1):\PP5713\" )
				( objectStatus "SATA6G_TX_DP<3>" )
			)
			( signal "@baseboard_fab2_lib.baseboard_fab2(sch_1):sata6g_s0_rx_dn"
				( pinPairRef "@baseboard_fab2_lib.baseboard_fab2(sch_1):\PP6143\" )
				( objectStatus "SATA6G_S0_RX_DN" )
			)
			( signal "@baseboard_fab2_lib.baseboard_fab2(sch_1):sata6g_s0_rx_dp"
				( pinPairRef "@baseboard_fab2_lib.baseboard_fab2(sch_1):\PP6142\" )
				( objectStatus "SATA6G_S0_RX_DP" )
			)
			( signal "@baseboard_fab2_lib.baseboard_fab2(sch_1):sata6g_s0_tx_dn"
				( pinPairRef "@baseboard_fab2_lib.baseboard_fab2(sch_1):\PP6141\" )
				( objectStatus "SATA6G_S0_TX_DN" )
			)
			( signal "@baseboard_fab2_lib.baseboard_fab2(sch_1):sata6g_s0_tx_dp"
				( pinPairRef "@baseboard_fab2_lib.baseboard_fab2(sch_1):\PP6140\" )
				( objectStatus "SATA6G_S0_TX_DP" )
			)
			( signal "@baseboard_fab2_lib.baseboard_fab2(sch_1):rmii_bmc_ocp_crsdv"
				( objectStatus "RMII_BMC_OCP_CRSDV" )
			)
			( signal "@baseboard_fab2_lib.baseboard_fab2(sch_1):rmii_bmc_pch_sprngvlle_crsdv_r1"
				( objectStatus "RMII_BMC_PCH_SPRNGVLLE_CRSDV_R1" )
			)
			( signal "@baseboard_fab2_lib.baseboard_fab2(sch_1):rmii_bmc_pch_sprngvlle_crsdv"
				( objectStatus "RMII_BMC_PCH_SPRNGVLLE_CRSDV" )
			)
			( signal "@baseboard_fab2_lib.baseboard_fab2(sch_1):rmii_bmc_pch_sprngvlle_crsdv_r"
				( objectStatus "RMII_BMC_PCH_SPRNGVLLE_CRSDV_R" )
			)
			( signal "@baseboard_fab2_lib.baseboard_fab2(sch_1):clk_50m_ckmng_ocp_r"
				( objectStatus "CLK_50M_CKMNG_OCP_R" )
			)
			( signal "@baseboard_fab2_lib.baseboard_fab2(sch_1):clk_50m_ckmng_ocp"
				( objectStatus "CLK_50M_CKMNG_OCP" )
			)
			( signal "@baseboard_fab2_lib.baseboard_fab2(sch_1):clk_50m_ckmng_bmc_1_r"
				( objectStatus "CLK_50M_CKMNG_BMC_1_R" )
			)
			( signal "@baseboard_fab2_lib.baseboard_fab2(sch_1):clk_50m_ckmng_bmc_1"
				( objectStatus "CLK_50M_CKMNG_BMC_1" )
			)
			( signal "@baseboard_fab2_lib.baseboard_fab2(sch_1):clk_50m_ckmng_pch_10gbe_r"
				( objectStatus "CLK_50M_CKMNG_PCH_10GBE_R" )
			)
			( signal "@baseboard_fab2_lib.baseboard_fab2(sch_1):clk_50m_ckmng_pch_10gbe"
				( objectStatus "CLK_50M_CKMNG_PCH_10GBE" )
			)
			( signal "@baseboard_fab2_lib.baseboard_fab2(sch_1):clk_50m_ckmng_bmc_2"
				( objectStatus "CLK_50M_CKMNG_BMC_2" )
			)
			( signal "@baseboard_fab2_lib.baseboard_fab2(sch_1):clk_50m_ckmng_bmc_2_r"
				( objectStatus "CLK_50M_CKMNG_BMC_2_R" )
			)
			( signal "@baseboard_fab2_lib.baseboard_fab2(sch_1):clk_50m_ckmng_sprvlle"
				( objectStatus "CLK_50M_CKMNG_SPRVLLE" )
			)
			( signal "@baseboard_fab2_lib.baseboard_fab2(sch_1):clk_50m_ckmng_sprvlle_r"
				( objectStatus "CLK_50M_CKMNG_SPRVLLE_R" )
			)
			( signal "@baseboard_fab2_lib.baseboard_fab2(sch_1):rmii_pch_sprngvlle_arb_out_r"
				( objectStatus "RMII_PCH_SPRNGVLLE_ARB_OUT_R" )
			)
			( signal "@baseboard_fab2_lib.baseboard_fab2(sch_1):rmii_pch_sprngvlle_arb_out"
				( objectStatus "RMII_PCH_SPRNGVLLE_ARB_OUT" )
			)
			( signal "@baseboard_fab2_lib.baseboard_fab2(sch_1):rmii_pch_sprngvlle_arb_in_r"
				( objectStatus "RMII_PCH_SPRNGVLLE_ARB_IN_R" )
			)
			( signal "@baseboard_fab2_lib.baseboard_fab2(sch_1):rmii_pch_sprngvlle_arb_in"
				( objectStatus "RMII_PCH_SPRNGVLLE_ARB_IN" )
			)
			( signal "@baseboard_fab2_lib.baseboard_fab2(sch_1):usb_pch_bmc_p4_dp"
				( pinPairRef "@baseboard_fab2_lib.baseboard_fab2(sch_1):\PP6123\" )
				( objectStatus "USB_PCH_BMC_P4_DP" )
			)
			( signal "@baseboard_fab2_lib.baseboard_fab2(sch_1):usb_pch_bmc_p4_dn"
				( pinPairRef "@baseboard_fab2_lib.baseboard_fab2(sch_1):\PP6124\" )
				( objectStatus "USB_PCH_BMC_P4_DN" )
			)
			( signal "@baseboard_fab2_lib.baseboard_fab2(sch_1):usb2_pch_bmc_p5_dp"
				( pinPairRef "@baseboard_fab2_lib.baseboard_fab2(sch_1):\PP6121\" )
				( objectStatus "USB2_PCH_BMC_P5_DP" )
			)
			( signal "@baseboard_fab2_lib.baseboard_fab2(sch_1):usb2_pch_bmc_p5_dn"
				( pinPairRef "@baseboard_fab2_lib.baseboard_fab2(sch_1):\PP6122\" )
				( objectStatus "USB2_PCH_BMC_P5_DN" )
			)
			( signal "@baseboard_fab2_lib.baseboard_fab2(sch_1):usb2_p01_esd_dn"
				( pinPairRef "@baseboard_fab2_lib.baseboard_fab2(sch_1):\PP5794\" )
				( objectStatus "USB2_P01_ESD_DN" )
			)
			( signal "@baseboard_fab2_lib.baseboard_fab2(sch_1):usb2_p01_dn"
				( objectStatus "USB2_P01_DN" )
			)
			( signal "@baseboard_fab2_lib.baseboard_fab2(sch_1):usb2_p01_esd_dp"
				( pinPairRef "@baseboard_fab2_lib.baseboard_fab2(sch_1):\PP5795\" )
				( objectStatus "USB2_P01_ESD_DP" )
			)
			( signal "@baseboard_fab2_lib.baseboard_fab2(sch_1):usb2_p01_dp"
				( objectStatus "USB2_P01_DP" )
			)
			( signal "@baseboard_fab2_lib.baseboard_fab2(sch_1):clk_48m_usb_bmc"
				( objectStatus "CLK_48M_USB_BMC" )
			)
			( signal "@baseboard_fab2_lib.baseboard_fab2(sch_1):clk_24m_bmc_lpc_r"
				( objectStatus "CLK_24M_BMC_LPC_R" )
			)
			( signal "@baseboard_fab2_lib.baseboard_fab2(sch_1):clk_24m_bmc_lpc"
				( objectStatus "CLK_24M_BMC_LPC" )
			)
			( signal "@baseboard_fab2_lib.baseboard_fab2(sch_1):h_pmsync_clk_24m"
				( objectStatus "H_PMSYNC_CLK_24M" )
			)
			( signal "@baseboard_fab2_lib.baseboard_fab2(sch_1):h_pmsync_clk_24m_cpu0"
				( objectStatus "H_PMSYNC_CLK_24M_CPU0" )
			)
			( signal "@baseboard_fab2_lib.baseboard_fab2(sch_1):h_pmsync_clk_24m_cpu1"
				( objectStatus "H_PMSYNC_CLK_24M_CPU1" )
			)
			( signal "@baseboard_fab2_lib.baseboard_fab2(sch_1):h_pmsync_clk_24m_r"
				( objectStatus "H_PMSYNC_CLK_24M_R" )
			)
			( signal "@baseboard_fab2_lib.baseboard_fab2(sch_1):clk_32k_susclk_pld"
				( objectStatus "CLK_32K_SUSCLK_PLD" )
			)
			( signal "@baseboard_fab2_lib.baseboard_fab2(sch_1):clk_32k_susclk_pld_r"
				( objectStatus "CLK_32K_SUSCLK_PLD_R" )
			)
			( signal "@baseboard_fab2_lib.baseboard_fab2(sch_1):clk_25m_bmc"
				( objectStatus "CLK_25M_BMC" )
			)
			( signal "@baseboard_fab2_lib.baseboard_fab2(sch_1):clk_25m_bmc_r"
				( objectStatus "CLK_25M_BMC_R" )
			)
			( signal "@baseboard_fab2_lib.baseboard_fab2(sch_1):clk_25m_cpld_r"
				( objectStatus "CLK_25M_CPLD_R" )
			)
			( signal "@baseboard_fab2_lib.baseboard_fab2(sch_1):clk_25m_cpld"
				( objectStatus "CLK_25M_CPLD" )
			)
			( signal "@baseboard_fab2_lib.baseboard_fab2(sch_1):m_bmc_ddr3_dq(0)"
				( objectStatus "M_BMC_DDR3_DQ<0>" )
			)
			( signal "@baseboard_fab2_lib.baseboard_fab2(sch_1):m_bmc_ddr3_dq(1)"
				( objectStatus "M_BMC_DDR3_DQ<1>" )
			)
			( signal "@baseboard_fab2_lib.baseboard_fab2(sch_1):m_bmc_ddr3_dq(2)"
				( objectStatus "M_BMC_DDR3_DQ<2>" )
			)
			( signal "@baseboard_fab2_lib.baseboard_fab2(sch_1):m_bmc_ddr3_dq(3)"
				( objectStatus "M_BMC_DDR3_DQ<3>" )
			)
			( signal "@baseboard_fab2_lib.baseboard_fab2(sch_1):m_bmc_ddr3_dq(4)"
				( objectStatus "M_BMC_DDR3_DQ<4>" )
			)
			( signal "@baseboard_fab2_lib.baseboard_fab2(sch_1):m_bmc_ddr3_dq(5)"
				( objectStatus "M_BMC_DDR3_DQ<5>" )
			)
			( signal "@baseboard_fab2_lib.baseboard_fab2(sch_1):m_bmc_ddr3_dq(6)"
				( objectStatus "M_BMC_DDR3_DQ<6>" )
			)
			( signal "@baseboard_fab2_lib.baseboard_fab2(sch_1):m_bmc_ddr3_dq(7)"
				( objectStatus "M_BMC_DDR3_DQ<7>" )
			)
			( signal "@baseboard_fab2_lib.baseboard_fab2(sch_1):m_bmc_ddr3_dq(8)"
				( objectStatus "M_BMC_DDR3_DQ<8>" )
			)
			( signal "@baseboard_fab2_lib.baseboard_fab2(sch_1):m_bmc_ddr3_dq(9)"
				( objectStatus "M_BMC_DDR3_DQ<9>" )
			)
			( signal "@baseboard_fab2_lib.baseboard_fab2(sch_1):m_bmc_ddr3_dq(10)"
				( objectStatus "M_BMC_DDR3_DQ<10>" )
			)
			( signal "@baseboard_fab2_lib.baseboard_fab2(sch_1):m_bmc_ddr3_dq(11)"
				( objectStatus "M_BMC_DDR3_DQ<11>" )
			)
			( signal "@baseboard_fab2_lib.baseboard_fab2(sch_1):m_bmc_ddr3_dq(12)"
				( objectStatus "M_BMC_DDR3_DQ<12>" )
			)
			( signal "@baseboard_fab2_lib.baseboard_fab2(sch_1):m_bmc_ddr3_dq(13)"
				( objectStatus "M_BMC_DDR3_DQ<13>" )
			)
			( signal "@baseboard_fab2_lib.baseboard_fab2(sch_1):m_bmc_ddr3_dq(14)"
				( objectStatus "M_BMC_DDR3_DQ<14>" )
			)
			( signal "@baseboard_fab2_lib.baseboard_fab2(sch_1):m_bmc_ddr3_dq(15)"
				( objectStatus "M_BMC_DDR3_DQ<15>" )
			)
			( signal "@baseboard_fab2_lib.baseboard_fab2(sch_1):m_bmc_ddr3_ma(0)"
				( objectStatus "M_BMC_DDR3_MA<0>" )
			)
			( signal "@baseboard_fab2_lib.baseboard_fab2(sch_1):m_bmc_ddr3_ma(1)"
				( objectStatus "M_BMC_DDR3_MA<1>" )
			)
			( signal "@baseboard_fab2_lib.baseboard_fab2(sch_1):m_bmc_ddr3_ma(2)"
				( objectStatus "M_BMC_DDR3_MA<2>" )
			)
			( signal "@baseboard_fab2_lib.baseboard_fab2(sch_1):m_bmc_ddr3_ma(3)"
				( objectStatus "M_BMC_DDR3_MA<3>" )
			)
			( signal "@baseboard_fab2_lib.baseboard_fab2(sch_1):m_bmc_ddr3_ma(4)"
				( objectStatus "M_BMC_DDR3_MA<4>" )
			)
			( signal "@baseboard_fab2_lib.baseboard_fab2(sch_1):m_bmc_ddr3_ma(5)"
				( objectStatus "M_BMC_DDR3_MA<5>" )
			)
			( signal "@baseboard_fab2_lib.baseboard_fab2(sch_1):m_bmc_ddr3_ma(6)"
				( objectStatus "M_BMC_DDR3_MA<6>" )
			)
			( signal "@baseboard_fab2_lib.baseboard_fab2(sch_1):m_bmc_ddr3_ma(7)"
				( objectStatus "M_BMC_DDR3_MA<7>" )
			)
			( signal "@baseboard_fab2_lib.baseboard_fab2(sch_1):m_bmc_ddr3_ma(8)"
				( objectStatus "M_BMC_DDR3_MA<8>" )
			)
			( signal "@baseboard_fab2_lib.baseboard_fab2(sch_1):m_bmc_ddr3_ma(9)"
				( objectStatus "M_BMC_DDR3_MA<9>" )
			)
			( signal "@baseboard_fab2_lib.baseboard_fab2(sch_1):m_bmc_ddr3_ma(10)"
				( objectStatus "M_BMC_DDR3_MA<10>" )
			)
			( signal "@baseboard_fab2_lib.baseboard_fab2(sch_1):m_bmc_ddr3_ma(11)"
				( objectStatus "M_BMC_DDR3_MA<11>" )
			)
			( signal "@baseboard_fab2_lib.baseboard_fab2(sch_1):m_bmc_ddr3_ma(12)"
				( objectStatus "M_BMC_DDR3_MA<12>" )
			)
			( signal "@baseboard_fab2_lib.baseboard_fab2(sch_1):m_bmc_ddr3_ma(13)"
				( objectStatus "M_BMC_DDR3_MA<13>" )
			)
			( signal "@baseboard_fab2_lib.baseboard_fab2(sch_1):m_bmc_ddr3_ma(14)"
				( objectStatus "M_BMC_DDR3_MA<14>" )
			)
			( signal "@baseboard_fab2_lib.baseboard_fab2(sch_1):m_bmc_ddr3_mck_n"
				( objectStatus "M_BMC_DDR3_MCK_N" )
			)
			( signal "@baseboard_fab2_lib.baseboard_fab2(sch_1):m_bmc_ddr3_mck_p"
				( objectStatus "M_BMC_DDR3_MCK_P" )
			)
			( signal "@baseboard_fab2_lib.baseboard_fab2(sch_1):m_bmc_ddr3_mdm_0"
				( objectStatus "M_BMC_DDR3_MDM_0" )
			)
			( signal "@baseboard_fab2_lib.baseboard_fab2(sch_1):m_bmc_ddr3_mdm_1"
				( objectStatus "M_BMC_DDR3_MDM_1" )
			)
			( signal "@baseboard_fab2_lib.baseboard_fab2(sch_1):m_bmc_ddr3_mba_0"
				( objectStatus "M_BMC_DDR3_MBA_0" )
			)
			( signal "@baseboard_fab2_lib.baseboard_fab2(sch_1):m_bmc_ddr3_mba_1"
				( objectStatus "M_BMC_DDR3_MBA_1" )
			)
			( signal "@baseboard_fab2_lib.baseboard_fab2(sch_1):m_bmc_ddr3_mba_2"
				( objectStatus "M_BMC_DDR3_MBA_2" )
			)
			( signal "@baseboard_fab2_lib.baseboard_fab2(sch_1):m_bmc_ddr3_mcas_n"
				( objectStatus "M_BMC_DDR3_MCAS_N" )
			)
			( signal "@baseboard_fab2_lib.baseboard_fab2(sch_1):m_bmc_ddr3_mcke"
				( objectStatus "M_BMC_DDR3_MCKE" )
			)
			( signal "@baseboard_fab2_lib.baseboard_fab2(sch_1):m_bmc_ddr3_mcs_n"
				( objectStatus "M_BMC_DDR3_MCS_N" )
			)
			( signal "@baseboard_fab2_lib.baseboard_fab2(sch_1):m_bmc_ddr3_modt"
				( objectStatus "M_BMC_DDR3_MODT" )
			)
			( signal "@baseboard_fab2_lib.baseboard_fab2(sch_1):m_bmc_ddr3_mras_n"
				( objectStatus "M_BMC_DDR3_MRAS_N" )
			)
			( signal "@baseboard_fab2_lib.baseboard_fab2(sch_1):m_bmc_ddr3_mwe_n"
				( objectStatus "M_BMC_DDR3_MWE_N" )
			)
			( signal "@baseboard_fab2_lib.baseboard_fab2(sch_1):m_bmc_ddr3_mdqs_0_dn"
				( objectStatus "M_BMC_DDR3_MDQS_0_DN" )
			)
			( signal "@baseboard_fab2_lib.baseboard_fab2(sch_1):m_bmc_ddr3_mdqs_0_dp"
				( objectStatus "M_BMC_DDR3_MDQS_0_DP" )
			)
			( signal "@baseboard_fab2_lib.baseboard_fab2(sch_1):m_bmc_ddr3_mdqs_1_dn"
				( objectStatus "M_BMC_DDR3_MDQS_1_DN" )
			)
			( signal "@baseboard_fab2_lib.baseboard_fab2(sch_1):m_bmc_ddr3_mdqs_1_dp"
				( objectStatus "M_BMC_DDR3_MDQS_1_DP" )
			)
			( signal "@baseboard_fab2_lib.baseboard_fab2(sch_1):h_cpu0_fast_wake_lvt3_n"
				( objectStatus "H_CPU0_FAST_WAKE_LVT3_N" )
			)
			( signal "@baseboard_fab2_lib.baseboard_fab2(sch_1):h_cpu0_fivr_fault_g"
				( electricalCSetRef "@crescent_city_bb_fab1_lib.crescent_city_bb_fab1(sch_1):\FIVR\" )
				( pinPairRef "@baseboard_fab2_lib.baseboard_fab2(sch_1):\PP5403\" )
				( objectStatus "H_CPU0_FIVR_FAULT_G" )
			)
			( signal "@baseboard_fab2_lib.baseboard_fab2(sch_1):h_cpu0_memabc_memhot"
				( objectStatus "H_CPU0_MEMABC_MEMHOT" )
			)
			( signal "@baseboard_fab2_lib.baseboard_fab2(sch_1):h_cpu0_memdef_memhot"
				( objectStatus "H_CPU0_MEMDEF_MEMHOT" )
			)
			( signal "@baseboard_fab2_lib.baseboard_fab2(sch_1):h_cpu0_thermtrip_g_n"
				( objectStatus "H_CPU0_THERMTRIP_G_N" )
			)
			( signal "@baseboard_fab2_lib.baseboard_fab2(sch_1):h_cpu1_fivr_fault_g"
				( objectStatus "H_CPU1_FIVR_FAULT_G" )
			)
			( signal "@baseboard_fab2_lib.baseboard_fab2(sch_1):h_cpu1_memghj_memhot"
				( objectStatus "H_CPU1_MEMGHJ_MEMHOT" )
			)
			( signal "@baseboard_fab2_lib.baseboard_fab2(sch_1):h_cpu1_memklm_memhot"
				( objectStatus "H_CPU1_MEMKLM_MEMHOT" )
			)
			( signal "@baseboard_fab2_lib.baseboard_fab2(sch_1):h_cpu1_thermtrip_g_n"
				( objectStatus "H_CPU1_THERMTRIP_G_N" )
			)
			( signal "@baseboard_fab2_lib.baseboard_fab2(sch_1):h_cpu0_fast_wake"
				( objectStatus "H_CPU0_FAST_WAKE" )
			)
			( signal "@baseboard_fab2_lib.baseboard_fab2(sch_1):fm_cpu0_thermtrip_latch_lvt3_n"
				( objectStatus "FM_CPU0_THERMTRIP_LATCH_LVT3_N" )
			)
			( signal "@baseboard_fab2_lib.baseboard_fab2(sch_1):fm_cpu1_thermtrip_latch_lvt3_n"
				( objectStatus "FM_CPU1_THERMTRIP_LATCH_LVT3_N" )
			)
			( signal "@baseboard_fab2_lib.baseboard_fab2(sch_1):h_cpu_err2_gtl_n"
				( objectStatus "H_CPU_ERR2_GTL_N" )
			)
			( signal "@baseboard_fab2_lib.baseboard_fab2(sch_1):h_cpu_err2_g_r_n"
				( objectStatus "H_CPU_ERR2_G_R_N" )
			)
			( signal "@baseboard_fab2_lib.baseboard_fab2(sch_1):h_cpu1_err2_g_n"
				( objectStatus "H_CPU1_ERR2_G_N" )
			)
			( signal "@baseboard_fab2_lib.baseboard_fab2(sch_1):h_cpu0_err2_g_n"
				( objectStatus "H_CPU0_ERR2_G_N" )
			)
			( signal "@baseboard_fab2_lib.baseboard_fab2(sch_1):h_cpu0_fast_wake_b_n"
				( objectStatus "H_CPU0_FAST_WAKE_B_N" )
			)
			( signal "@baseboard_fab2_lib.baseboard_fab2(sch_1):h_cpu0_fast_wake_n"
				( pinPairRef "@baseboard_fab2_lib.baseboard_fab2(sch_1):\PP5652\" )
				( objectStatus "H_CPU0_FAST_WAKE_N" )
			)
			( signal "@baseboard_fab2_lib.baseboard_fab2(sch_1):h_cpu1_fast_wake_n"
				( pinPairRef "@baseboard_fab2_lib.baseboard_fab2(sch_1):\PP5653\" )
				( objectStatus "H_CPU1_FAST_WAKE_N" )
			)
			( signal "@baseboard_fab2_lib.baseboard_fab2(sch_1):h_pm_sync_gtl"
				( objectStatus "H_PM_SYNC_GTL" )
			)
			( signal "@baseboard_fab2_lib.baseboard_fab2(sch_1):h_pm_sync1_gtl_r"
				( pinPairRef "@baseboard_fab2_lib.baseboard_fab2(sch_1):\PP40\" )
				( objectStatus "H_PM_SYNC1_GTL_R" )
			)
			( signal "@baseboard_fab2_lib.baseboard_fab2(sch_1):h_pm_sync_gtl_r1"
				( pinPairRef "@baseboard_fab2_lib.baseboard_fab2(sch_1):\PP41\" )
				( objectStatus "H_PM_SYNC_GTL_R1" )
			)
			( signal "@baseboard_fab2_lib.baseboard_fab2(sch_1):h_pm_sync_gtl_r2"
				( pinPairRef "@baseboard_fab2_lib.baseboard_fab2(sch_1):\PP42\" )
				( objectStatus "H_PM_SYNC_GTL_R2" )
			)
			( signal "@baseboard_fab2_lib.baseboard_fab2(sch_1):h_cpu_msmi_g_n"
				( pinPairRef "@baseboard_fab2_lib.baseboard_fab2(sch_1):\PP16\" )
				( objectStatus "H_CPU_MSMI_G_N" )
			)
			( signal "@baseboard_fab2_lib.baseboard_fab2(sch_1):h_cpu1_msmi_g_n"
				( pinPairRef "@baseboard_fab2_lib.baseboard_fab2(sch_1):\PP17\" )
				( objectStatus "H_CPU1_MSMI_G_N" )
			)
			( signal "@baseboard_fab2_lib.baseboard_fab2(sch_1):h_cpu0_msmi_g_n"
				( pinPairRef "@baseboard_fab2_lib.baseboard_fab2(sch_1):\PP18\" )
				( objectStatus "H_CPU0_MSMI_G_N" )
			)
			( signal "@baseboard_fab2_lib.baseboard_fab2(sch_1):h_cpu_caterr_g_n"
				( pinPairRef "@baseboard_fab2_lib.baseboard_fab2(sch_1):\PP13\" )
				( objectStatus "H_CPU_CATERR_G_N" )
			)
			( signal "@baseboard_fab2_lib.baseboard_fab2(sch_1):h_cpu0_caterr_g_n"
				( pinPairRef "@baseboard_fab2_lib.baseboard_fab2(sch_1):\PP14\" )
				( objectStatus "H_CPU0_CATERR_G_N" )
			)
			( signal "@baseboard_fab2_lib.baseboard_fab2(sch_1):h_cpu1_caterr_g_n"
				( pinPairRef "@baseboard_fab2_lib.baseboard_fab2(sch_1):\PP15\" )
				( objectStatus "H_CPU1_CATERR_G_N" )
			)
			( signal "@baseboard_fab2_lib.baseboard_fab2(sch_1):h_cpu1_prochot_g_pch_n"
				( objectStatus "H_CPU1_PROCHOT_G_PCH_N" )
			)
			( signal "@baseboard_fab2_lib.baseboard_fab2(sch_1):h_cpu1_prochot_g_n"
				( objectStatus "H_CPU1_PROCHOT_G_N" )
			)
			( signal "@baseboard_fab2_lib.baseboard_fab2(sch_1):fm_cpu1_prochot_lvt3_n"
				( objectStatus "FM_CPU1_PROCHOT_LVT3_N" )
			)
			( signal "@baseboard_fab2_lib.baseboard_fab2(sch_1):fm_cpu1_prochot_lvt3_k_n"
				( objectStatus "FM_CPU1_PROCHOT_LVT3_K_N" )
			)
			( signal "@baseboard_fab2_lib.baseboard_fab2(sch_1):h_cpu1_memklm_memhot_g_pch_n"
				( objectStatus "H_CPU1_MEMKLM_MEMHOT_G_PCH_N" )
			)
			( signal "@baseboard_fab2_lib.baseboard_fab2(sch_1):h_cpu1_memklm_memhot_g_n"
				( attribute "RATSNEST_SCHEDULE" "User Defined"
					( Origin gBackEnd )
				)
				( objectStatus "H_CPU1_MEMKLM_MEMHOT_G_N" )
			)
			( signal "@baseboard_fab2_lib.baseboard_fab2(sch_1):h_cpu1_memklm_memhot_lvt3_n"
				( objectStatus "H_CPU1_MEMKLM_MEMHOT_LVT3_N" )
			)
			( signal "@baseboard_fab2_lib.baseboard_fab2(sch_1):h_cpu1_memklm_memhot_lvt3_k_n"
				( objectStatus "H_CPU1_MEMKLM_MEMHOT_LVT3_K_N" )
			)
			( signal "@baseboard_fab2_lib.baseboard_fab2(sch_1):h_cpu1_memghj_memhot_g_pch_n"
				( objectStatus "H_CPU1_MEMGHJ_MEMHOT_G_PCH_N" )
			)
			( signal "@baseboard_fab2_lib.baseboard_fab2(sch_1):h_cpu1_memghj_memhot_g_n"
				( attribute "RATSNEST_SCHEDULE" "User Defined"
					( Origin gBackEnd )
				)
				( objectStatus "H_CPU1_MEMGHJ_MEMHOT_G_N" )
			)
			( signal "@baseboard_fab2_lib.baseboard_fab2(sch_1):h_cpu1_memghj_memhot_lvt3_n"
				( objectStatus "H_CPU1_MEMGHJ_MEMHOT_LVT3_N" )
			)
			( signal "@baseboard_fab2_lib.baseboard_fab2(sch_1):h_cpu1_memghj_memhot_lvt3_k_n"
				( objectStatus "H_CPU1_MEMGHJ_MEMHOT_LVT3_K_N" )
			)
			( signal "@baseboard_fab2_lib.baseboard_fab2(sch_1):h_cpu0_prochot_g_pch_n"
				( objectStatus "H_CPU0_PROCHOT_G_PCH_N" )
			)
			( signal "@baseboard_fab2_lib.baseboard_fab2(sch_1):h_cpu0_prochot_g_n"
				( attribute "RATSNEST_SCHEDULE" "User Defined"
					( Origin gBackEnd )
				)
				( objectStatus "H_CPU0_PROCHOT_G_N" )
			)
			( signal "@baseboard_fab2_lib.baseboard_fab2(sch_1):fm_cpu0_prochot_lvt3_n"
				( objectStatus "FM_CPU0_PROCHOT_LVT3_N" )
			)
			( signal "@baseboard_fab2_lib.baseboard_fab2(sch_1):fm_cpu0_prochot_lvt3_k_n"
				( objectStatus "FM_CPU0_PROCHOT_LVT3_K_N" )
			)
			( signal "@baseboard_fab2_lib.baseboard_fab2(sch_1):h_cpu0_memdef_memhot_g_pch_n"
				( objectStatus "H_CPU0_MEMDEF_MEMHOT_G_PCH_N" )
			)
			( signal "@baseboard_fab2_lib.baseboard_fab2(sch_1):h_cpu0_memdef_memhot_lvt3_n"
				( objectStatus "H_CPU0_MEMDEF_MEMHOT_LVT3_N" )
			)
			( signal "@baseboard_fab2_lib.baseboard_fab2(sch_1):h_cpu0_memdef_memhot_g_n"
				( attribute "RATSNEST_SCHEDULE" "User Defined"
					( Origin gBackEnd )
				)
				( objectStatus "H_CPU0_MEMDEF_MEMHOT_G_N" )
			)
			( signal "@baseboard_fab2_lib.baseboard_fab2(sch_1):h_cpu0_memdef_memhot_lvt3_k_n"
				( objectStatus "H_CPU0_MEMDEF_MEMHOT_LVT3_K_N" )
			)
			( signal "@baseboard_fab2_lib.baseboard_fab2(sch_1):h_cpu0_memabc_memhot_g_pch_n"
				( objectStatus "H_CPU0_MEMABC_MEMHOT_G_PCH_N" )
			)
			( signal "@baseboard_fab2_lib.baseboard_fab2(sch_1):h_cpu0_memabc_memhot_g_n"
				( attribute "RATSNEST_SCHEDULE" "User Defined"
					( Origin gBackEnd )
				)
				( objectStatus "H_CPU0_MEMABC_MEMHOT_G_N" )
			)
			( signal "@baseboard_fab2_lib.baseboard_fab2(sch_1):h_cpu0_memabc_memhot_lvt3_n"
				( objectStatus "H_CPU0_MEMABC_MEMHOT_LVT3_N" )
			)
			( signal "@baseboard_fab2_lib.baseboard_fab2(sch_1):h_cpu0_memabc_memhot_lvt3_k_n"
				( objectStatus "H_CPU0_MEMABC_MEMHOT_LVT3_K_N" )
			)
			( signal "@baseboard_fab2_lib.baseboard_fab2(sch_1):fm_cpu_err0_lvt3_k_n"
				( objectStatus "FM_CPU_ERR0_LVT3_K_N" )
			)
			( signal "@baseboard_fab2_lib.baseboard_fab2(sch_1):fm_cpu_err1_lvt3_n"
				( objectStatus "FM_CPU_ERR1_LVT3_N" )
			)
			( signal "@baseboard_fab2_lib.baseboard_fab2(sch_1):fm_cpu_err0_lvt3_n"
				( objectStatus "FM_CPU_ERR0_LVT3_N" )
			)
			( signal "@baseboard_fab2_lib.baseboard_fab2(sch_1):h_cpu_err1_pch_n"
				( objectStatus "H_CPU_ERR1_PCH_N" )
			)
			( signal "@baseboard_fab2_lib.baseboard_fab2(sch_1):h_cpu_err1_gtl_r_n"
				( objectStatus "H_CPU_ERR1_GTL_R_N" )
			)
			( signal "@baseboard_fab2_lib.baseboard_fab2(sch_1):h_cpu_err1_gtl_n"
				( objectStatus "H_CPU_ERR1_GTL_N" )
			)
			( signal "@baseboard_fab2_lib.baseboard_fab2(sch_1):h_cpu0_err1_g_n"
				( objectStatus "H_CPU0_ERR1_G_N" )
			)
			( signal "@baseboard_fab2_lib.baseboard_fab2(sch_1):h_cpu1_err1_g_n"
				( objectStatus "H_CPU1_ERR1_G_N" )
			)
			( signal "@baseboard_fab2_lib.baseboard_fab2(sch_1):h_cpu_err0_pch_n"
				( objectStatus "H_CPU_ERR0_PCH_N" )
			)
			( signal "@baseboard_fab2_lib.baseboard_fab2(sch_1):h_cpu_err0_gtl_r_n"
				( objectStatus "H_CPU_ERR0_GTL_R_N" )
			)
			( signal "@baseboard_fab2_lib.baseboard_fab2(sch_1):h_cpu_err0_gtl_n"
				( objectStatus "H_CPU_ERR0_GTL_N" )
			)
			( signal "@baseboard_fab2_lib.baseboard_fab2(sch_1):h_cpu0_err0_g_n"
				( objectStatus "H_CPU0_ERR0_G_N" )
			)
			( signal "@baseboard_fab2_lib.baseboard_fab2(sch_1):h_cpu1_err0_g_n"
				( objectStatus "H_CPU1_ERR0_G_N" )
			)
			( signal "@baseboard_fab2_lib.baseboard_fab2(sch_1):dmi_cpu0_pch_tx_c_dn(0)"
				( pinPairRef "@baseboard_fab2_lib.baseboard_fab2(sch_1):\PP68\" )
				( objectStatus "DMI_CPU0_PCH_TX_C_DN<0>" )
			)
			( signal "@baseboard_fab2_lib.baseboard_fab2(sch_1):dmi_cpu0_pch_tx_dn(0)"
				( pinPairRef "@baseboard_fab2_lib.baseboard_fab2(sch_1):\PP69\" )
				( objectStatus "DMI_CPU0_PCH_TX_DN<0>" )
			)
			( signal "@baseboard_fab2_lib.baseboard_fab2(sch_1):dmi_cpu0_pch_tx_dp(0)"
				( pinPairRef "@baseboard_fab2_lib.baseboard_fab2(sch_1):\PP70\" )
				( objectStatus "DMI_CPU0_PCH_TX_DP<0>" )
			)
			( signal "@baseboard_fab2_lib.baseboard_fab2(sch_1):dmi_cpu0_pch_tx_c_dp(0)"
				( pinPairRef "@baseboard_fab2_lib.baseboard_fab2(sch_1):\PP71\" )
				( objectStatus "DMI_CPU0_PCH_TX_C_DP<0>" )
			)
			( signal "@baseboard_fab2_lib.baseboard_fab2(sch_1):dmi_cpu0_pch_tx_c_dn(1)"
				( pinPairRef "@baseboard_fab2_lib.baseboard_fab2(sch_1):\PP72\" )
				( objectStatus "DMI_CPU0_PCH_TX_C_DN<1>" )
			)
			( signal "@baseboard_fab2_lib.baseboard_fab2(sch_1):dmi_cpu0_pch_tx_dn(1)"
				( pinPairRef "@baseboard_fab2_lib.baseboard_fab2(sch_1):\PP73\" )
				( objectStatus "DMI_CPU0_PCH_TX_DN<1>" )
			)
			( signal "@baseboard_fab2_lib.baseboard_fab2(sch_1):dmi_cpu0_pch_tx_dp(1)"
				( pinPairRef "@baseboard_fab2_lib.baseboard_fab2(sch_1):\PP74\" )
				( objectStatus "DMI_CPU0_PCH_TX_DP<1>" )
			)
			( signal "@baseboard_fab2_lib.baseboard_fab2(sch_1):dmi_cpu0_pch_tx_c_dp(1)"
				( pinPairRef "@baseboard_fab2_lib.baseboard_fab2(sch_1):\PP75\" )
				( objectStatus "DMI_CPU0_PCH_TX_C_DP<1>" )
			)
			( signal "@baseboard_fab2_lib.baseboard_fab2(sch_1):dmi_cpu0_pch_tx_c_dn(2)"
				( pinPairRef "@baseboard_fab2_lib.baseboard_fab2(sch_1):\PP76\" )
				( objectStatus "DMI_CPU0_PCH_TX_C_DN<2>" )
			)
			( signal "@baseboard_fab2_lib.baseboard_fab2(sch_1):dmi_cpu0_pch_tx_dn(2)"
				( pinPairRef "@baseboard_fab2_lib.baseboard_fab2(sch_1):\PP77\" )
				( objectStatus "DMI_CPU0_PCH_TX_DN<2>" )
			)
			( signal "@baseboard_fab2_lib.baseboard_fab2(sch_1):dmi_cpu0_pch_tx_dp(2)"
				( pinPairRef "@baseboard_fab2_lib.baseboard_fab2(sch_1):\PP78\" )
				( objectStatus "DMI_CPU0_PCH_TX_DP<2>" )
			)
			( signal "@baseboard_fab2_lib.baseboard_fab2(sch_1):dmi_cpu0_pch_tx_c_dp(2)"
				( pinPairRef "@baseboard_fab2_lib.baseboard_fab2(sch_1):\PP79\" )
				( objectStatus "DMI_CPU0_PCH_TX_C_DP<2>" )
			)
			( signal "@baseboard_fab2_lib.baseboard_fab2(sch_1):dmi_cpu0_pch_tx_c_dn(3)"
				( pinPairRef "@baseboard_fab2_lib.baseboard_fab2(sch_1):\PP80\" )
				( objectStatus "DMI_CPU0_PCH_TX_C_DN<3>" )
			)
			( signal "@baseboard_fab2_lib.baseboard_fab2(sch_1):dmi_cpu0_pch_tx_dn(3)"
				( pinPairRef "@baseboard_fab2_lib.baseboard_fab2(sch_1):\PP81\" )
				( objectStatus "DMI_CPU0_PCH_TX_DN<3>" )
			)
			( signal "@baseboard_fab2_lib.baseboard_fab2(sch_1):dmi_cpu0_pch_tx_dp(3)"
				( pinPairRef "@baseboard_fab2_lib.baseboard_fab2(sch_1):\PP82\" )
				( objectStatus "DMI_CPU0_PCH_TX_DP<3>" )
			)
			( signal "@baseboard_fab2_lib.baseboard_fab2(sch_1):dmi_cpu0_pch_tx_c_dp(3)"
				( pinPairRef "@baseboard_fab2_lib.baseboard_fab2(sch_1):\PP83\" )
				( objectStatus "DMI_CPU0_PCH_TX_C_DP<3>" )
			)
			( signal "@baseboard_fab2_lib.baseboard_fab2(sch_1):nic_mdi_sprv_rj45_0_r_dn"
				( attribute "NO_TEST" "1"
					( Origin gBackEnd )
				)
				( objectStatus "NIC_MDI_SPRV_RJ45_0_R_DN" )
			)
			( signal "@baseboard_fab2_lib.baseboard_fab2(sch_1):nic_mdi_sprv_rj45_0_dn"
				( attribute "NO_TEST" "1"
					( Origin gBackEnd )
				)
				( objectStatus "NIC_MDI_SPRV_RJ45_0_DN" )
			)
			( signal "@baseboard_fab2_lib.baseboard_fab2(sch_1):nic_mdi_sprv_rj45_0_r_dp"
				( attribute "NO_TEST" "1"
					( Origin gBackEnd )
				)
				( objectStatus "NIC_MDI_SPRV_RJ45_0_R_DP" )
			)
			( signal "@baseboard_fab2_lib.baseboard_fab2(sch_1):nic_mdi_sprv_rj45_0_dp"
				( attribute "NO_TEST" "1"
					( Origin gBackEnd )
				)
				( objectStatus "NIC_MDI_SPRV_RJ45_0_DP" )
			)
			( signal "@baseboard_fab2_lib.baseboard_fab2(sch_1):nic_mdi_sprv_rj45_1_r_dn"
				( attribute "NO_TEST" "1"
					( Origin gBackEnd )
				)
				( objectStatus "NIC_MDI_SPRV_RJ45_1_R_DN" )
			)
			( signal "@baseboard_fab2_lib.baseboard_fab2(sch_1):nic_mdi_sprv_rj45_1_dn"
				( attribute "NO_TEST" "1"
					( Origin gBackEnd )
				)
				( objectStatus "NIC_MDI_SPRV_RJ45_1_DN" )
			)
			( signal "@baseboard_fab2_lib.baseboard_fab2(sch_1):nic_mdi_sprv_rj45_1_r_dp"
				( attribute "NO_TEST" "1"
					( Origin gBackEnd )
				)
				( objectStatus "NIC_MDI_SPRV_RJ45_1_R_DP" )
			)
			( signal "@baseboard_fab2_lib.baseboard_fab2(sch_1):nic_mdi_sprv_rj45_1_dp"
				( attribute "NO_TEST" "1"
					( Origin gBackEnd )
				)
				( objectStatus "NIC_MDI_SPRV_RJ45_1_DP" )
			)
			( signal "@baseboard_fab2_lib.baseboard_fab2(sch_1):nic_mdi_mng_rx_dp"
				( electricalCSetRef "@crescent_city_bb_fab1_lib.crescent_city_bb_fab1(sch_1):\NIC_MDI_MNG\" )
				( attribute "NO_TEST" "1"
					( Origin gBackEnd )
				)
				( objectStatus "NIC_MDI_MNG_RX_DP" )
			)
			( signal "@baseboard_fab2_lib.baseboard_fab2(sch_1):nic_mdi_mng_rx_dn"
				( electricalCSetRef "@crescent_city_bb_fab1_lib.crescent_city_bb_fab1(sch_1):\NIC_MDI_MNG\" )
				( attribute "NO_TEST" "1"
					( Origin gBackEnd )
				)
				( objectStatus "NIC_MDI_MNG_RX_DN" )
			)
			( signal "@baseboard_fab2_lib.baseboard_fab2(sch_1):nic_mdi_mng_tx_dp"
				( electricalCSetRef "@crescent_city_bb_fab1_lib.crescent_city_bb_fab1(sch_1):\NIC_MDI_MNG\" )
				( attribute "NO_TEST" "1"
					( Origin gBackEnd )
				)
				( objectStatus "NIC_MDI_MNG_TX_DP" )
			)
			( signal "@baseboard_fab2_lib.baseboard_fab2(sch_1):nic_mdi_mng_tx_dn"
				( electricalCSetRef "@crescent_city_bb_fab1_lib.crescent_city_bb_fab1(sch_1):\NIC_MDI_MNG\" )
				( attribute "NO_TEST" "1"
					( Origin gBackEnd )
				)
				( objectStatus "NIC_MDI_MNG_TX_DN" )
			)
			( signal "@baseboard_fab2_lib.baseboard_fab2(sch_1):a_extclkn"
				( objectStatus "A_EXTCLKN" )
			)
			( signal "@baseboard_fab2_lib.baseboard_fab2(sch_1):a_extclkp"
				( objectStatus "A_EXTCLKP" )
			)
			( signal "@baseboard_fab2_lib.baseboard_fab2(sch_1):a_usb2_vbus"
				( objectStatus "A_USB2_VBUS" )
			)
			( signal "@baseboard_fab2_lib.baseboard_fab2(sch_1):p3e_pch_m2_tx_dn(1)"
				( pinPairRef "@baseboard_fab2_lib.baseboard_fab2(sch_1):\PP84\" )
				( objectStatus "P3E_PCH_M2_TX_DN<1>" )
			)
			( signal "@baseboard_fab2_lib.baseboard_fab2(sch_1):p3e_pch_m2_tx_c_dn(1)"
				( pinPairRef "@baseboard_fab2_lib.baseboard_fab2(sch_1):\PP85\" )
				( objectStatus "P3E_PCH_M2_TX_C_DN<1>" )
			)
			( signal "@baseboard_fab2_lib.baseboard_fab2(sch_1):p3e_pch_m2_tx_dp(1)"
				( pinPairRef "@baseboard_fab2_lib.baseboard_fab2(sch_1):\PP86\" )
				( objectStatus "P3E_PCH_M2_TX_DP<1>" )
			)
			( signal "@baseboard_fab2_lib.baseboard_fab2(sch_1):p3e_pch_m2_tx_c_dp(1)"
				( pinPairRef "@baseboard_fab2_lib.baseboard_fab2(sch_1):\PP87\" )
				( objectStatus "P3E_PCH_M2_TX_C_DP<1>" )
			)
			( signal "@baseboard_fab2_lib.baseboard_fab2(sch_1):p3e_pch_m2_tx_dn(2)"
				( pinPairRef "@baseboard_fab2_lib.baseboard_fab2(sch_1):\PP88\" )
				( objectStatus "P3E_PCH_M2_TX_DN<2>" )
			)
			( signal "@baseboard_fab2_lib.baseboard_fab2(sch_1):p3e_pch_m2_tx_c_dn(2)"
				( pinPairRef "@baseboard_fab2_lib.baseboard_fab2(sch_1):\PP89\" )
				( objectStatus "P3E_PCH_M2_TX_C_DN<2>" )
			)
			( signal "@baseboard_fab2_lib.baseboard_fab2(sch_1):p3e_pch_m2_tx_dp(2)"
				( pinPairRef "@baseboard_fab2_lib.baseboard_fab2(sch_1):\PP90\" )
				( objectStatus "P3E_PCH_M2_TX_DP<2>" )
			)
			( signal "@baseboard_fab2_lib.baseboard_fab2(sch_1):p3e_pch_m2_tx_c_dp(2)"
				( pinPairRef "@baseboard_fab2_lib.baseboard_fab2(sch_1):\PP91\" )
				( objectStatus "P3E_PCH_M2_TX_C_DP<2>" )
			)
			( signal "@baseboard_fab2_lib.baseboard_fab2(sch_1):p3e_pch_m2_tx_dn(3)"
				( pinPairRef "@baseboard_fab2_lib.baseboard_fab2(sch_1):\PP92\" )
				( objectStatus "P3E_PCH_M2_TX_DN<3>" )
			)
			( signal "@baseboard_fab2_lib.baseboard_fab2(sch_1):p3e_pch_m2_tx_c_dn(3)"
				( pinPairRef "@baseboard_fab2_lib.baseboard_fab2(sch_1):\PP93\" )
				( objectStatus "P3E_PCH_M2_TX_C_DN<3>" )
			)
			( signal "@baseboard_fab2_lib.baseboard_fab2(sch_1):p3e_pch_m2_tx_dp(3)"
				( pinPairRef "@baseboard_fab2_lib.baseboard_fab2(sch_1):\PP94\" )
				( objectStatus "P3E_PCH_M2_TX_DP<3>" )
			)
			( signal "@baseboard_fab2_lib.baseboard_fab2(sch_1):p3e_pch_m2_tx_c_dp(3)"
				( pinPairRef "@baseboard_fab2_lib.baseboard_fab2(sch_1):\PP95\" )
				( objectStatus "P3E_PCH_M2_TX_C_DP<3>" )
			)
			( signal "@baseboard_fab2_lib.baseboard_fab2(sch_1):p3e_pch_tx_0_dn"
				( pinPairRef "@baseboard_fab2_lib.baseboard_fab2(sch_1):\PP5686\" )
				( objectStatus "P3E_PCH_TX_0_DN" )
			)
			( signal "@baseboard_fab2_lib.baseboard_fab2(sch_1):p3e_pch_m2_sata6g_tx_r_dn"
				( pinPairRef "@baseboard_fab2_lib.baseboard_fab2(sch_1):\PP5687\" )
				( pinPairRef "@baseboard_fab2_lib.baseboard_fab2(sch_1):\PP5688\" )
				( objectStatus "P3E_PCH_M2_SATA6G_TX_R_DN" )
			)
			( signal "@baseboard_fab2_lib.baseboard_fab2(sch_1):p3e_pch_tx_0_dp"
				( pinPairRef "@baseboard_fab2_lib.baseboard_fab2(sch_1):\PP5689\" )
				( objectStatus "P3E_PCH_TX_0_DP" )
			)
			( signal "@baseboard_fab2_lib.baseboard_fab2(sch_1):p3e_pch_m2_sata6g_tx_r_dp"
				( pinPairRef "@baseboard_fab2_lib.baseboard_fab2(sch_1):\PP5690\" )
				( pinPairRef "@baseboard_fab2_lib.baseboard_fab2(sch_1):\PP5691\" )
				( objectStatus "P3E_PCH_M2_SATA6G_TX_R_DP" )
			)
			( signal "@baseboard_fab2_lib.baseboard_fab2(sch_1):p3e_pch_m2_rx_dp(1)"
				( electricalCSetRef "@crescent_city_bb_fab1_lib.crescent_city_bb_fab1(sch_1):\PCIE_SLOT_A\" )
				( pinPairRef "@baseboard_fab2_lib.baseboard_fab2(sch_1):\PP5367\" )
				( objectStatus "P3E_PCH_M2_RX_DP<1>" )
			)
			( signal "@baseboard_fab2_lib.baseboard_fab2(sch_1):p3e_pch_m2_rx_dn(1)"
				( electricalCSetRef "@crescent_city_bb_fab1_lib.crescent_city_bb_fab1(sch_1):\PCIE_SLOT_A\" )
				( pinPairRef "@baseboard_fab2_lib.baseboard_fab2(sch_1):\PP5370\" )
				( objectStatus "P3E_PCH_M2_RX_DN<1>" )
			)
			( signal "@baseboard_fab2_lib.baseboard_fab2(sch_1):p3e_pch_m2_rx_dp(2)"
				( electricalCSetRef "@crescent_city_bb_fab1_lib.crescent_city_bb_fab1(sch_1):\PCIE_SLOT_A\" )
				( pinPairRef "@baseboard_fab2_lib.baseboard_fab2(sch_1):\PP5368\" )
				( objectStatus "P3E_PCH_M2_RX_DP<2>" )
			)
			( signal "@baseboard_fab2_lib.baseboard_fab2(sch_1):p3e_pch_m2_rx_dn(2)"
				( electricalCSetRef "@crescent_city_bb_fab1_lib.crescent_city_bb_fab1(sch_1):\PCIE_SLOT_A\" )
				( pinPairRef "@baseboard_fab2_lib.baseboard_fab2(sch_1):\PP5371\" )
				( objectStatus "P3E_PCH_M2_RX_DN<2>" )
			)
			( signal "@baseboard_fab2_lib.baseboard_fab2(sch_1):p3e_pch_m2_rx_dp(3)"
				( electricalCSetRef "@crescent_city_bb_fab1_lib.crescent_city_bb_fab1(sch_1):\PCIE_SLOT_A\" )
				( pinPairRef "@baseboard_fab2_lib.baseboard_fab2(sch_1):\PP5369\" )
				( objectStatus "P3E_PCH_M2_RX_DP<3>" )
			)
			( signal "@baseboard_fab2_lib.baseboard_fab2(sch_1):p3e_pch_m2_rx_dn(3)"
				( electricalCSetRef "@crescent_city_bb_fab1_lib.crescent_city_bb_fab1(sch_1):\PCIE_SLOT_A\" )
				( pinPairRef "@baseboard_fab2_lib.baseboard_fab2(sch_1):\PP5372\" )
				( objectStatus "P3E_PCH_M2_RX_DN<3>" )
			)
			( signal "@baseboard_fab2_lib.baseboard_fab2(sch_1):p3e_pch_rx_0_dn"
				( pinPairRef "@baseboard_fab2_lib.baseboard_fab2(sch_1):\PP5684\" )
				( objectStatus "P3E_PCH_RX_0_DN" )
			)
			( signal "@baseboard_fab2_lib.baseboard_fab2(sch_1):p3e_pch_m2_sata6g_rx_r_dn"
				( objectStatus "P3E_PCH_M2_SATA6G_RX_R_DN" )
			)
			( signal "@baseboard_fab2_lib.baseboard_fab2(sch_1):p3e_pch_rx_0_dp"
				( pinPairRef "@baseboard_fab2_lib.baseboard_fab2(sch_1):\PP5685\" )
				( objectStatus "P3E_PCH_RX_0_DP" )
			)
			( signal "@baseboard_fab2_lib.baseboard_fab2(sch_1):p3e_pch_m2_sata6g_rx_r_dp"
				( objectStatus "P3E_PCH_M2_SATA6G_RX_R_DP" )
			)
			( signal "@baseboard_fab2_lib.baseboard_fab2(sch_1):a_hsc_inap"
				( objectStatus "A_HSC_INAP" )
			)
			( signal "@baseboard_fab2_lib.baseboard_fab2(sch_1):a_pg_p5v"
				( objectStatus "A_PG_P5V" )
			)
			( signal "@baseboard_fab2_lib.baseboard_fab2(sch_1):a_pg_p12v_main"
				( objectStatus "A_PG_P12V_MAIN" )
			)
			( signal "@baseboard_fab2_lib.baseboard_fab2(sch_1):vr_pvccin_cpu1_vd12"
				( objectStatus "VR_PVCCIN_CPU1_VD12" )
			)
			( signal "@baseboard_fab2_lib.baseboard_fab2(sch_1):a_p12v_stby_fph_gate"
				( objectStatus "A_P12V_STBY_FPH_GATE" )
			)
			( signal "@baseboard_fab2_lib.baseboard_fab2(sch_1):vr_pvccin_cpu0_pwm1"
				( attribute "RATSNEST_SCHEDULE" "MIN_DAISY_CHAIN"
					( Origin gBackEnd )
				)
				( attribute "VOLTAGE" "3.6"
					( Units "uVoltage" "V" 1.000000)
					( Origin gFrontEnd )
				)
				( objectStatus "VR_PVCCIN_CPU0_PWM1" )
			)
			( signal "@baseboard_fab2_lib.baseboard_fab2(sch_1):vr_pvccin_cpu0_pwm2"
				( attribute "RATSNEST_SCHEDULE" "MIN_DAISY_CHAIN"
					( Origin gBackEnd )
				)
				( attribute "VOLTAGE" "3.6"
					( Units "uVoltage" "V" 1.000000)
					( Origin gFrontEnd )
				)
				( objectStatus "VR_PVCCIN_CPU0_PWM2" )
			)
			( signal "@baseboard_fab2_lib.baseboard_fab2(sch_1):vr_pvccin_cpu0_pwm3"
				( attribute "RATSNEST_SCHEDULE" "MIN_DAISY_CHAIN"
					( Origin gBackEnd )
				)
				( attribute "VOLTAGE" "3.6"
					( Units "uVoltage" "V" 1.000000)
					( Origin gFrontEnd )
				)
				( objectStatus "VR_PVCCIN_CPU0_PWM3" )
			)
			( signal "@baseboard_fab2_lib.baseboard_fab2(sch_1):vr_pvccin_cpu0_pwm4"
				( attribute "RATSNEST_SCHEDULE" "MIN_DAISY_CHAIN"
					( Origin gBackEnd )
				)
				( attribute "VOLTAGE" "3.6"
					( Units "uVoltage" "V" 1.000000)
					( Origin gFrontEnd )
				)
				( objectStatus "VR_PVCCIN_CPU0_PWM4" )
			)
			( signal "@baseboard_fab2_lib.baseboard_fab2(sch_1):vr_pvccin_cpu0_pwm5"
				( attribute "RATSNEST_SCHEDULE" "MIN_DAISY_CHAIN"
					( Origin gBackEnd )
				)
				( attribute "VOLTAGE" "3.6"
					( Units "uVoltage" "V" 1.000000)
					( Origin gFrontEnd )
				)
				( objectStatus "VR_PVCCIN_CPU0_PWM5" )
			)
			( signal "@baseboard_fab2_lib.baseboard_fab2(sch_1):vr_pvccin_cpu1_pwm1"
				( attribute "RATSNEST_SCHEDULE" "MIN_DAISY_CHAIN"
					( Origin gBackEnd )
				)
				( attribute "VOLTAGE" "3.6"
					( Units "uVoltage" "V" 1.000000)
					( Origin gFrontEnd )
				)
				( objectStatus "VR_PVCCIN_CPU1_PWM1" )
			)
			( signal "@baseboard_fab2_lib.baseboard_fab2(sch_1):vr_pvccin_cpu1_pwm2"
				( attribute "RATSNEST_SCHEDULE" "MIN_DAISY_CHAIN"
					( Origin gBackEnd )
				)
				( attribute "VOLTAGE" "3.6"
					( Units "uVoltage" "V" 1.000000)
					( Origin gFrontEnd )
				)
				( objectStatus "VR_PVCCIN_CPU1_PWM2" )
			)
			( signal "@baseboard_fab2_lib.baseboard_fab2(sch_1):vr_pvccin_cpu1_pwm3"
				( attribute "RATSNEST_SCHEDULE" "MIN_DAISY_CHAIN"
					( Origin gBackEnd )
				)
				( attribute "VOLTAGE" "3.6"
					( Units "uVoltage" "V" 1.000000)
					( Origin gFrontEnd )
				)
				( objectStatus "VR_PVCCIN_CPU1_PWM3" )
			)
			( signal "@baseboard_fab2_lib.baseboard_fab2(sch_1):vr_pvccin_cpu1_pwm4"
				( attribute "RATSNEST_SCHEDULE" "MIN_DAISY_CHAIN"
					( Origin gBackEnd )
				)
				( attribute "VOLTAGE" "3.6"
					( Units "uVoltage" "V" 1.000000)
					( Origin gFrontEnd )
				)
				( objectStatus "VR_PVCCIN_CPU1_PWM4" )
			)
			( signal "@baseboard_fab2_lib.baseboard_fab2(sch_1):vr_pvccin_cpu1_pwm5"
				( attribute "RATSNEST_SCHEDULE" "MIN_DAISY_CHAIN"
					( Origin gBackEnd )
				)
				( attribute "VOLTAGE" "3.6"
					( Units "uVoltage" "V" 1.000000)
					( Origin gFrontEnd )
				)
				( objectStatus "VR_PVCCIN_CPU1_PWM5" )
			)
			( signal "@baseboard_fab2_lib.baseboard_fab2(sch_1):vr_pvccio_cpu0_pwm1"
				( attribute "RATSNEST_SCHEDULE" "MIN_DAISY_CHAIN"
					( Origin gBackEnd )
				)
				( attribute "VOLTAGE" "3.3"
					( Units "uVoltage" "V" 1.000000)
					( Origin gFrontEnd )
				)
				( objectStatus "VR_PVCCIO_CPU0_PWM1" )
			)
			( signal "@baseboard_fab2_lib.baseboard_fab2(sch_1):vr_pvccio_cpu1_pwm1"
				( attribute "RATSNEST_SCHEDULE" "MIN_DAISY_CHAIN"
					( Origin gBackEnd )
				)
				( attribute "VOLTAGE" "3.6"
					( Units "uVoltage" "V" 1.000000)
					( Origin gFrontEnd )
				)
				( objectStatus "VR_PVCCIO_CPU1_PWM1" )
			)
			( signal "@baseboard_fab2_lib.baseboard_fab2(sch_1):vr_pvddq_abc_pwm1"
				( attribute "RATSNEST_SCHEDULE" "MIN_DAISY_CHAIN"
					( Origin gBackEnd )
				)
				( objectStatus "VR_PVDDQ_ABC_PWM1" )
			)
			( signal "@baseboard_fab2_lib.baseboard_fab2(sch_1):vr_pvddq_abc_pwm2"
				( attribute "RATSNEST_SCHEDULE" "MIN_DAISY_CHAIN"
					( Origin gBackEnd )
				)
				( objectStatus "VR_PVDDQ_ABC_PWM2" )
			)
			( signal "@baseboard_fab2_lib.baseboard_fab2(sch_1):vr_pvddq_def_pwm1"
				( attribute "RATSNEST_SCHEDULE" "MIN_DAISY_CHAIN"
					( Origin gBackEnd )
				)
				( objectStatus "VR_PVDDQ_DEF_PWM1" )
			)
			( signal "@baseboard_fab2_lib.baseboard_fab2(sch_1):vr_pvddq_def_pwm2"
				( attribute "RATSNEST_SCHEDULE" "MIN_DAISY_CHAIN"
					( Origin gBackEnd )
				)
				( objectStatus "VR_PVDDQ_DEF_PWM2" )
			)
			( signal "@baseboard_fab2_lib.baseboard_fab2(sch_1):vr_pvddq_ghj_pwm1"
				( attribute "RATSNEST_SCHEDULE" "MIN_DAISY_CHAIN"
					( Origin gBackEnd )
				)
				( objectStatus "VR_PVDDQ_GHJ_PWM1" )
			)
			( signal "@baseboard_fab2_lib.baseboard_fab2(sch_1):vr_pvddq_ghj_pwm2"
				( attribute "RATSNEST_SCHEDULE" "MIN_DAISY_CHAIN"
					( Origin gBackEnd )
				)
				( objectStatus "VR_PVDDQ_GHJ_PWM2" )
			)
			( signal "@baseboard_fab2_lib.baseboard_fab2(sch_1):vr_pvddq_klm_pwm1"
				( attribute "RATSNEST_SCHEDULE" "MIN_DAISY_CHAIN"
					( Origin gBackEnd )
				)
				( objectStatus "VR_PVDDQ_KLM_PWM1" )
			)
			( signal "@baseboard_fab2_lib.baseboard_fab2(sch_1):vr_pvddq_klm_pwm2"
				( attribute "RATSNEST_SCHEDULE" "MIN_DAISY_CHAIN"
					( Origin gBackEnd )
				)
				( objectStatus "VR_PVDDQ_KLM_PWM2" )
			)
			( signal "@baseboard_fab2_lib.baseboard_fab2(sch_1):vr_pvnn_pch_pwm1"
				( attribute "RATSNEST_SCHEDULE" "MIN_DAISY_CHAIN"
					( Origin gBackEnd )
				)
				( objectStatus "VR_PVNN_PCH_PWM1" )
			)
			( signal "@baseboard_fab2_lib.baseboard_fab2(sch_1):vr_pvsa_cpu0_pwm"
				( attribute "RATSNEST_SCHEDULE" "MIN_DAISY_CHAIN"
					( Origin gBackEnd )
				)
				( objectStatus "VR_PVSA_CPU0_PWM" )
			)
			( signal "@baseboard_fab2_lib.baseboard_fab2(sch_1):vr_pvsa_cpu1_pwm"
				( attribute "RATSNEST_SCHEDULE" "MIN_DAISY_CHAIN"
					( Origin gBackEnd )
				)
				( attribute "VOLTAGE" "3.6"
					( Units "uVoltage" "V" 1.000000)
					( Origin gFrontEnd )
				)
				( objectStatus "VR_PVSA_CPU1_PWM" )
			)
			( signal "@baseboard_fab2_lib.baseboard_fab2(sch_1):vr_p1v05_pch_stby_pwm1"
				( attribute "RATSNEST_SCHEDULE" "MIN_DAISY_CHAIN"
					( Origin gBackEnd )
				)
				( objectStatus "VR_P1V05_PCH_STBY_PWM1" )
			)
			( signal "@baseboard_fab2_lib.baseboard_fab2(sch_1):a_p3v_bat_r"
				( attribute "VOLTAGE" "+3 V"
					( Units "uVoltage" "V" 1.000000)
					( Origin gFrontEnd )
				)
				( objectStatus "A_P3V_BAT_R" )
			)
			( signal "@baseboard_fab2_lib.baseboard_fab2(sch_1):a_p3v_bat_scaled"
				( attribute "VOLTAGE" "+1V"
					( Units "uVoltage" "V" 1.000000)
					( Origin gFrontEnd )
				)
				( objectStatus "A_P3V_BAT_SCALED" )
			)
			( signal "@baseboard_fab2_lib.baseboard_fab2(sch_1):a_hsc_uv"
				( objectStatus "A_HSC_UV" )
			)
			( signal "@baseboard_fab2_lib.baseboard_fab2(sch_1):a_hsc_ov"
				( objectStatus "A_HSC_OV" )
			)
			( signal "@baseboard_fab2_lib.baseboard_fab2(sch_1):a_adm1085_cext"
				( objectStatus "A_ADM1085_CEXT" )
			)
			( signal "@baseboard_fab2_lib.baseboard_fab2(sch_1):a_cbot"
				( objectStatus "A_CBOT" )
			)
			( signal "@baseboard_fab2_lib.baseboard_fab2(sch_1):a_ctop"
				( objectStatus "A_CTOP" )
			)
			( signal "@baseboard_fab2_lib.baseboard_fab2(sch_1):a_cpu0_upi2_rbias"
				( objectStatus "A_CPU0_UPI2_RBIAS" )
			)
			( signal "@baseboard_fab2_lib.baseboard_fab2(sch_1):a_cpu0_upi01_rbias"
				( objectStatus "A_CPU0_UPI01_RBIAS" )
			)
			( signal "@baseboard_fab2_lib.baseboard_fab2(sch_1):a_cpu0_mcp01_rbias"
				( objectStatus "A_CPU0_MCP01_RBIAS" )
			)
			( signal "@baseboard_fab2_lib.baseboard_fab2(sch_1):a_cpu0_pe3_rbias"
				( objectStatus "A_CPU0_PE3_RBIAS" )
			)
			( signal "@baseboard_fab2_lib.baseboard_fab2(sch_1):a_cpu0_pe012_rbias"
				( objectStatus "A_CPU0_PE012_RBIAS" )
			)
			( signal "@baseboard_fab2_lib.baseboard_fab2(sch_1):a_cpu1_upi2_rbias"
				( objectStatus "A_CPU1_UPI2_RBIAS" )
			)
			( signal "@baseboard_fab2_lib.baseboard_fab2(sch_1):a_cpu1_upi01_rbias"
				( objectStatus "A_CPU1_UPI01_RBIAS" )
			)
			( signal "@baseboard_fab2_lib.baseboard_fab2(sch_1):a_cpu1_mcp01_rbias"
				( objectStatus "A_CPU1_MCP01_RBIAS" )
			)
			( signal "@baseboard_fab2_lib.baseboard_fab2(sch_1):a_cpu1_pe3_rbias"
				( objectStatus "A_CPU1_PE3_RBIAS" )
			)
			( signal "@baseboard_fab2_lib.baseboard_fab2(sch_1):a_cpu1_pe012_rbias"
				( objectStatus "A_CPU1_PE012_RBIAS" )
			)
			( signal "@baseboard_fab2_lib.baseboard_fab2(sch_1):a_dacrset"
				( objectStatus "A_DACRSET" )
			)
			( signal "@baseboard_fab2_lib.baseboard_fab2(sch_1):a_1p8_3p3_rcomp"
				( objectStatus "A_1P8_3P3_RCOMP" )
			)
			( signal "@baseboard_fab2_lib.baseboard_fab2(sch_1):a_rcomp_3p3"
				( objectStatus "A_RCOMP_3P3" )
			)
			( signal "@baseboard_fab2_lib.baseboard_fab2(sch_1):a_hsc_iset"
				( objectStatus "A_HSC_ISET" )
			)
			( signal "@baseboard_fab2_lib.baseboard_fab2(sch_1):a_hsc_iset_s"
				( objectStatus "A_HSC_ISET_S" )
			)
			( signal "@baseboard_fab2_lib.baseboard_fab2(sch_1):a_hsc_iset_s2"
				( objectStatus "A_HSC_ISET_S2" )
			)
			( signal "@baseboard_fab2_lib.baseboard_fab2(sch_1):a_hsc_istart"
				( objectStatus "A_HSC_ISTART" )
			)
			( signal "@baseboard_fab2_lib.baseboard_fab2(sch_1):a_hsc_pset"
				( objectStatus "A_HSC_PSET" )
			)
			( signal "@baseboard_fab2_lib.baseboard_fab2(sch_1):a_kr0_rbias"
				( objectStatus "A_KR0_RBIAS" )
			)
			( signal "@baseboard_fab2_lib.baseboard_fab2(sch_1):a_kr1_rbias"
				( objectStatus "A_KR1_RBIAS" )
			)
			( signal "@baseboard_fab2_lib.baseboard_fab2(sch_1):a_pch_xclk_biasref"
				( objectStatus "A_PCH_XCLK_BIASREF" )
			)
			( signal "@baseboard_fab2_lib.baseboard_fab2(sch_1):a_pcieup_rcomp_n"
				( objectStatus "A_PCIEUP_RCOMP_N" )
			)
			( signal "@baseboard_fab2_lib.baseboard_fab2(sch_1):a_pcieup_rcomp_p"
				( objectStatus "A_PCIEUP_RCOMP_P" )
			)
			( signal "@baseboard_fab2_lib.baseboard_fab2(sch_1):a_pcie_rcomp_n"
				( objectStatus "A_PCIE_RCOMP_N" )
			)
			( signal "@baseboard_fab2_lib.baseboard_fab2(sch_1):a_pcie_rcomp_p"
				( objectStatus "A_PCIE_RCOMP_P" )
			)
			( signal "@baseboard_fab2_lib.baseboard_fab2(sch_1):a_pvccrtc_ext_cap"
				( attribute "VOLTAGE" "2.5 V"
					( Units "uVoltage" "V" 1.000000)
					( Origin gBackEnd )
				)
				( objectStatus "A_PVCCRTC_EXT_CAP" )
			)
			( signal "@baseboard_fab2_lib.baseboard_fab2(sch_1):a_usb2vres"
				( objectStatus "A_USB2VRES" )
			)
			( signal "@baseboard_fab2_lib.baseboard_fab2(sch_1):a_usb2_comp"
				( objectStatus "A_USB2_COMP" )
			)
			( signal "@baseboard_fab2_lib.baseboard_fab2(sch_1):a_hsc_vcap"
				( objectStatus "A_HSC_VCAP" )
			)
			( signal "@baseboard_fab2_lib.baseboard_fab2(sch_1):a_cpu0_abc_rcomp0"
				( objectStatus "A_CPU0_ABC_RCOMP0" )
			)
			( signal "@baseboard_fab2_lib.baseboard_fab2(sch_1):a_cpu0_abc_rcomp1"
				( objectStatus "A_CPU0_ABC_RCOMP1" )
			)
			( signal "@baseboard_fab2_lib.baseboard_fab2(sch_1):a_cpu0_abc_rcomp2"
				( objectStatus "A_CPU0_ABC_RCOMP2" )
			)
			( signal "@baseboard_fab2_lib.baseboard_fab2(sch_1):a_cpu0_def_rcomp0"
				( objectStatus "A_CPU0_DEF_RCOMP0" )
			)
			( signal "@baseboard_fab2_lib.baseboard_fab2(sch_1):a_cpu0_def_rcomp1"
				( objectStatus "A_CPU0_DEF_RCOMP1" )
			)
			( signal "@baseboard_fab2_lib.baseboard_fab2(sch_1):a_cpu0_def_rcomp2"
				( objectStatus "A_CPU0_DEF_RCOMP2" )
			)
			( signal "@baseboard_fab2_lib.baseboard_fab2(sch_1):a_cpu1_ghj_rcomp0"
				( objectStatus "A_CPU1_GHJ_RCOMP0" )
			)
			( signal "@baseboard_fab2_lib.baseboard_fab2(sch_1):a_cpu1_ghj_rcomp1"
				( objectStatus "A_CPU1_GHJ_RCOMP1" )
			)
			( signal "@baseboard_fab2_lib.baseboard_fab2(sch_1):a_cpu1_ghj_rcomp2"
				( objectStatus "A_CPU1_GHJ_RCOMP2" )
			)
			( signal "@baseboard_fab2_lib.baseboard_fab2(sch_1):a_cpu1_klm_rcomp0"
				( objectStatus "A_CPU1_KLM_RCOMP0" )
			)
			( signal "@baseboard_fab2_lib.baseboard_fab2(sch_1):a_cpu1_klm_rcomp1"
				( objectStatus "A_CPU1_KLM_RCOMP1" )
			)
			( signal "@baseboard_fab2_lib.baseboard_fab2(sch_1):a_cpu1_klm_rcomp2"
				( objectStatus "A_CPU1_KLM_RCOMP2" )
			)
			( signal "@baseboard_fab2_lib.baseboard_fab2(sch_1):a_hsc_c"
				( objectStatus "A_HSC_C" )
			)
			( signal "@baseboard_fab2_lib.baseboard_fab2(sch_1):a_hsc_csout"
				( objectStatus "A_HSC_CSOUT" )
			)
			( signal "@baseboard_fab2_lib.baseboard_fab2(sch_1):a_hsc_high"
				( objectStatus "A_HSC_HIGH" )
			)
			( signal "@baseboard_fab2_lib.baseboard_fab2(sch_1):a_hsc_high_en"
				( objectStatus "A_HSC_HIGH_EN" )
			)
			( signal "@baseboard_fab2_lib.baseboard_fab2(sch_1):a_hsc_low"
				( objectStatus "A_HSC_LOW" )
			)
			( signal "@baseboard_fab2_lib.baseboard_fab2(sch_1):a_hsc_low_gate"
				( objectStatus "A_HSC_LOW_GATE" )
			)
			( signal "@baseboard_fab2_lib.baseboard_fab2(sch_1):a_hsc_ocp_sel"
				( objectStatus "A_HSC_OCP_SEL" )
			)
			( signal "@baseboard_fab2_lib.baseboard_fab2(sch_1):a_hsc_pwgin"
				( objectStatus "A_HSC_PWGIN" )
			)
			( signal "@baseboard_fab2_lib.baseboard_fab2(sch_1):a_hsc_gate1_r"
				( objectStatus "A_HSC_GATE1_R" )
			)
			( signal "@baseboard_fab2_lib.baseboard_fab2(sch_1):a_hsc_gate2_r"
				( objectStatus "A_HSC_GATE2_R" )
			)
			( signal "@baseboard_fab2_lib.baseboard_fab2(sch_1):a_hsc_gate3_r"
				( objectStatus "A_HSC_GATE3_R" )
			)
			( signal "@baseboard_fab2_lib.baseboard_fab2(sch_1):a_hsc_low_en"
				( objectStatus "A_HSC_LOW_EN" )
			)
			( signal "@baseboard_fab2_lib.baseboard_fab2(sch_1):a_hsc_timer"
				( objectStatus "A_HSC_TIMER" )
			)
			( signal "@baseboard_fab2_lib.baseboard_fab2(sch_1):a_hsc_timer_r"
				( objectStatus "A_HSC_TIMER_R" )
			)
			( signal "@baseboard_fab2_lib.baseboard_fab2(sch_1):a_p12v_stby_adr_trigger"
				( objectStatus "A_P12V_STBY_ADR_TRIGGER" )
			)
			( signal "@baseboard_fab2_lib.baseboard_fab2(sch_1):a_p12v_stby_fp_trigger"
				( objectStatus "A_P12V_STBY_FP_TRIGGER" )
			)
			( signal "@baseboard_fab2_lib.baseboard_fab2(sch_1):a_comp_ckmng"
				( objectStatus "A_COMP_CKMNG" )
			)
			( signal "@baseboard_fab2_lib.baseboard_fab2(sch_1):a_pvnn_stby_pch_sensor"
				( attribute "VOLTAGE" "+1.2V"
					( Units "uVoltage" "V" 1.000000)
					( Origin gFrontEnd )
				)
				( objectStatus "A_PVNN_STBY_PCH_SENSOR" )
			)
			( signal "@baseboard_fab2_lib.baseboard_fab2(sch_1):a_p1v05_stby_pch_sensor"
				( attribute "VOLTAGE" "+1.2V"
					( Units "uVoltage" "V" 1.000000)
					( Origin gFrontEnd )
				)
				( objectStatus "A_P1V05_STBY_PCH_SENSOR" )
			)
			( signal "@baseboard_fab2_lib.baseboard_fab2(sch_1):a_p3v3_scaled"
				( attribute "VOLTAGE" "+2V"
					( Units "uVoltage" "V" 1.000000)
					( Origin gFrontEnd )
				)
				( objectStatus "A_P3V3_SCALED" )
			)
			( signal "@baseboard_fab2_lib.baseboard_fab2(sch_1):a_p3v3_stby_scaled"
				( attribute "VOLTAGE" "+1.8V"
					( Units "uVoltage" "V" 1.000000)
					( Origin gFrontEnd )
				)
				( objectStatus "A_P3V3_STBY_SCALED" )
			)
			( signal "@baseboard_fab2_lib.baseboard_fab2(sch_1):a_p5v_scaled"
				( attribute "VOLTAGE" "+2V"
					( Units "uVoltage" "V" 1.000000)
					( Origin gFrontEnd )
				)
				( objectStatus "A_P5V_SCALED" )
			)
			( signal "@baseboard_fab2_lib.baseboard_fab2(sch_1):a_p5v_stby_scaled"
				( attribute "VOLTAGE" "+2V"
					( Units "uVoltage" "V" 1.000000)
					( Origin gFrontEnd )
				)
				( objectStatus "A_P5V_STBY_SCALED" )
			)
			( signal "@baseboard_fab2_lib.baseboard_fab2(sch_1):a_p12v_stby_scaled"
				( attribute "VOLTAGE" "+2V"
					( Units "uVoltage" "V" 1.000000)
					( Origin gFrontEnd )
				)
				( objectStatus "A_P12V_STBY_SCALED" )
			)
			( signal "@baseboard_fab2_lib.baseboard_fab2(sch_1):a_hsc_vout"
				( objectStatus "A_HSC_VOUT" )
			)
			( signal "@baseboard_fab2_lib.baseboard_fab2(sch_1):p3v3_stby_bmc_adcvrefp"
				( attribute "VOLTAGE" "+3.3V"
					( Units "uVoltage" "V" 1.000000)
					( Origin gFrontEnd )
				)
				( objectStatus "P3V3_STBY_BMC_ADCVREFP" )
			)
			( signal "@baseboard_fab2_lib.baseboard_fab2(sch_1):p3v3_stby_bmc_adcvrefn"
				( attribute "VOLTAGE" "+3.3V"
					( Units "uVoltage" "V" 1.000000)
					( Origin gFrontEnd )
				)
				( objectStatus "P3V3_STBY_BMC_ADCVREFN" )
			)
			( signal "@baseboard_fab2_lib.baseboard_fab2(sch_1):p0v7_gtl2104_5_vref"
				( attribute "VOLTAGE" "0.734"
					( Units "uVoltage" "V" 1.000000)
					( Origin gFrontEnd )
				)
				( objectStatus "P0V7_GTL2104_5_VREF" )
			)
			( signal "@baseboard_fab2_lib.baseboard_fab2(sch_1):a_hsc_hsn"
				( objectStatus "A_HSC_HSN" )
			)
			( signal "@baseboard_fab2_lib.baseboard_fab2(sch_1):a_hsc_hsp"
				( objectStatus "A_HSC_HSP" )
			)
			( signal "@baseboard_fab2_lib.baseboard_fab2(sch_1):a_hsc_mon"
				( objectStatus "A_HSC_MON" )
			)
			( signal "@baseboard_fab2_lib.baseboard_fab2(sch_1):a_hsc_mop"
				( objectStatus "A_HSC_MOP" )
			)
			( signal "@baseboard_fab2_lib.baseboard_fab2(sch_1):vr_pvccin_cpu0_avinsen"
				( attribute "VOLTAGE" "0.8"
					( Units "uVoltage" "V" 1.000000)
					( Origin gFrontEnd )
				)
				( objectStatus "VR_PVCCIN_CPU0_AVINSEN" )
			)
			( signal "@baseboard_fab2_lib.baseboard_fab2(sch_1):vr_pvccin_cpu0_vdd"
				( attribute "VOLTAGE" "3.3"
					( Units "uVoltage" "V" 1.000000)
					( Origin gFrontEnd )
				)
				( objectStatus "VR_PVCCIN_CPU0_VDD" )
			)
			( signal "@baseboard_fab2_lib.baseboard_fab2(sch_1):vr_pvccin_cpu1_avinsen"
				( attribute "VOLTAGE" "0.8"
					( Units "uVoltage" "V" 1.000000)
					( Origin gFrontEnd )
				)
				( objectStatus "VR_PVCCIN_CPU1_AVINSEN" )
			)
			( signal "@baseboard_fab2_lib.baseboard_fab2(sch_1):pu_vr_pvccin_cpu1_imon"
				( objectStatus "PU_VR_PVCCIN_CPU1_IMON" )
			)
			( signal "@baseboard_fab2_lib.baseboard_fab2(sch_1):vr_pvccin_cpu0_vd12"
				( objectStatus "VR_PVCCIN_CPU0_VD12" )
			)
			( signal "@baseboard_fab2_lib.baseboard_fab2(sch_1):p0v7_gtl2104_vref_1"
				( attribute "RATSNEST_SCHEDULE" "MIN_TREE"
					( Origin gBackEnd )
				)
				( attribute "VOLTAGE" "+0.7 V"
					( Units "uVoltage" "V" 1.000000)
					( Origin gFrontEnd )
				)
				( objectStatus "P0V7_GTL2104_VREF_1" )
			)
			( signal "@baseboard_fab2_lib.baseboard_fab2(sch_1):p0v7_gtl2104_vref_0"
				( attribute "RATSNEST_SCHEDULE" "MIN_TREE"
					( Origin gBackEnd )
				)
				( attribute "VOLTAGE" "+0.7 V"
					( Units "uVoltage" "V" 1.000000)
					( Origin gFrontEnd )
				)
				( objectStatus "P0V7_GTL2104_VREF_0" )
			)
			( signal "@baseboard_fab2_lib.baseboard_fab2(sch_1):vr_pvccio_cpu0_avsp"
				( attribute "VOLTAGE" "2"
					( Units "uVoltage" "V" 1.000000)
					( Origin gFrontEnd )
				)
				( objectStatus "VR_PVCCIO_CPU0_AVSP" )
			)
			( signal "@baseboard_fab2_lib.baseboard_fab2(sch_1):a_hsc_gate"
				( objectStatus "A_HSC_GATE" )
			)
			( signal "@baseboard_fab2_lib.baseboard_fab2(sch_1):a_hsc_temp"
				( objectStatus "A_HSC_TEMP" )
			)
			( signal "@baseboard_fab2_lib.baseboard_fab2(sch_1):peci_pch"
				( pinPairRef "@baseboard_fab2_lib.baseboard_fab2(sch_1):\PP5499\" )
				( objectStatus "PECI_PCH" )
			)
			( signal "@baseboard_fab2_lib.baseboard_fab2(sch_1):peci_bmc"
				( objectStatus "PECI_BMC" )
			)
			( signal "@baseboard_fab2_lib.baseboard_fab2(sch_1):peci_bmc_r"
				( objectStatus "PECI_BMC_R" )
			)
			( signal "@baseboard_fab2_lib.baseboard_fab2(sch_1):peci_cpu_g"
				( objectStatus "PECI_CPU_G" )
			)
			( signal "@baseboard_fab2_lib.baseboard_fab2(sch_1):h_cpu0_abc_memhot_lvt3_r_n"
				( objectStatus "H_CPU0_ABC_MEMHOT_LVT3_R_N" )
			)
			( signal "@baseboard_fab2_lib.baseboard_fab2(sch_1):h_cpu0_def_memhot_lvt3_r_n"
				( objectStatus "H_CPU0_DEF_MEMHOT_LVT3_R_N" )
			)
			( signal "@baseboard_fab2_lib.baseboard_fab2(sch_1):h_cpu1_ghj_memhot_lvt3_r_n"
				( objectStatus "H_CPU1_GHJ_MEMHOT_LVT3_R_N" )
			)
			( signal "@baseboard_fab2_lib.baseboard_fab2(sch_1):h_cpu1_klm_memhot_lvt3_r_n"
				( objectStatus "H_CPU1_KLM_MEMHOT_LVT3_R_N" )
			)
			( signal "@baseboard_fab2_lib.baseboard_fab2(sch_1):h_cpu0_memabc_memhot_g_r_n"
				( objectStatus "H_CPU0_MEMABC_MEMHOT_G_R_N" )
			)
			( signal "@baseboard_fab2_lib.baseboard_fab2(sch_1):h_cpu0_memabc_memhot_lvt3_bmc_n"
				( objectStatus "H_CPU0_MEMABC_MEMHOT_LVT3_BMC_N" )
			)
			( signal "@baseboard_fab2_lib.baseboard_fab2(sch_1):h_cpu0_memdef_memhot_g_r_n"
				( objectStatus "H_CPU0_MEMDEF_MEMHOT_G_R_N" )
			)
			( signal "@baseboard_fab2_lib.baseboard_fab2(sch_1):h_cpu0_memdef_memhot_lvt3_bmc_n"
				( objectStatus "H_CPU0_MEMDEF_MEMHOT_LVT3_BMC_N" )
			)
			( signal "@baseboard_fab2_lib.baseboard_fab2(sch_1):h_cpu0_prochot_g_r_n"
				( objectStatus "H_CPU0_PROCHOT_G_R_N" )
			)
			( signal "@baseboard_fab2_lib.baseboard_fab2(sch_1):h_cpu1_memghj_memhot_g_r_n"
				( objectStatus "H_CPU1_MEMGHJ_MEMHOT_G_R_N" )
			)
			( signal "@baseboard_fab2_lib.baseboard_fab2(sch_1):h_cpu1_memghj_memhot_lvt3_bmc_n"
				( objectStatus "H_CPU1_MEMGHJ_MEMHOT_LVT3_BMC_N" )
			)
			( signal "@baseboard_fab2_lib.baseboard_fab2(sch_1):h_cpu1_memklm_memhot_g_r_n"
				( objectStatus "H_CPU1_MEMKLM_MEMHOT_G_R_N" )
			)
			( signal "@baseboard_fab2_lib.baseboard_fab2(sch_1):h_cpu1_memklm_memhot_lvt3_bmc_n"
				( objectStatus "H_CPU1_MEMKLM_MEMHOT_LVT3_BMC_N" )
			)
			( signal "@baseboard_fab2_lib.baseboard_fab2(sch_1):h_cpu1_prochot_g_r_n"
				( objectStatus "H_CPU1_PROCHOT_G_R_N" )
			)
			( signal "@baseboard_fab2_lib.baseboard_fab2(sch_1):h_cpu_bmcinit_r"
				( objectStatus "H_CPU_BMCINIT_R" )
			)
			( signal "@baseboard_fab2_lib.baseboard_fab2(sch_1):h_cpu0_memabc_memhot_pch_n"
				( objectStatus "H_CPU0_MEMABC_MEMHOT_PCH_N" )
			)
			( signal "@baseboard_fab2_lib.baseboard_fab2(sch_1):h_cpu0_memdef_memhot_pch_n"
				( objectStatus "H_CPU0_MEMDEF_MEMHOT_PCH_N" )
			)
			( signal "@baseboard_fab2_lib.baseboard_fab2(sch_1):h_cpu1_memghj_memhot_pch_n"
				( objectStatus "H_CPU1_MEMGHJ_MEMHOT_PCH_N" )
			)
			( signal "@baseboard_fab2_lib.baseboard_fab2(sch_1):h_cpu1_memklm_memhot_pch_n"
				( objectStatus "H_CPU1_MEMKLM_MEMHOT_PCH_N" )
			)
			( signal "@baseboard_fab2_lib.baseboard_fab2(sch_1):usb3_p01_fb_txn"
				( pinPairRef "@baseboard_fab2_lib.baseboard_fab2(sch_1):\PP5696\" )
				( objectStatus "USB3_P01_FB_TXN" )
			)
			( signal "@baseboard_fab2_lib.baseboard_fab2(sch_1):usb3_p01_c_txn"
				( objectStatus "USB3_P01_C_TXN" )
			)
			( signal "@baseboard_fab2_lib.baseboard_fab2(sch_1):usb3_p01_txn"
				( objectStatus "USB3_P01_TXN" )
			)
			( signal "@baseboard_fab2_lib.baseboard_fab2(sch_1):usb3_p01_txp"
				( objectStatus "USB3_P01_TXP" )
			)
			( signal "@baseboard_fab2_lib.baseboard_fab2(sch_1):usb3_p01_c_txp"
				( objectStatus "USB3_P01_C_TXP" )
			)
			( signal "@baseboard_fab2_lib.baseboard_fab2(sch_1):usb3_p01_fb_txp"
				( pinPairRef "@baseboard_fab2_lib.baseboard_fab2(sch_1):\PP5697\" )
				( objectStatus "USB3_P01_FB_TXP" )
			)
			( signal "@baseboard_fab2_lib.baseboard_fab2(sch_1):vr_pvpp_abc_snub"
				( objectStatus "VR_PVPP_ABC_SNUB" )
			)
			( signal "@baseboard_fab2_lib.baseboard_fab2(sch_1):vr_pvpp_def_snub"
				( objectStatus "VR_PVPP_DEF_SNUB" )
			)
			( signal "@baseboard_fab2_lib.baseboard_fab2(sch_1):vr_pvpp_ghj_snub"
				( objectStatus "VR_PVPP_GHJ_SNUB" )
			)
			( signal "@baseboard_fab2_lib.baseboard_fab2(sch_1):vr_pvpp_klm_snub"
				( objectStatus "VR_PVPP_KLM_SNUB" )
			)
			( signal "@baseboard_fab2_lib.baseboard_fab2(sch_1):vr_p3v3_stby_snub"
				( objectStatus "VR_P3V3_STBY_SNUB" )
			)
			( signal "@baseboard_fab2_lib.baseboard_fab2(sch_1):l1_z100_ms"
				( objectStatus "L1_Z100_MS" )
			)
			( signal "@baseboard_fab2_lib.baseboard_fab2(sch_1):l14_z100_ms"
				( objectStatus "L14_Z100_MS" )
			)
			( signal "@baseboard_fab2_lib.baseboard_fab2(sch_1):vr_p5v_stby_comp"
				( objectStatus "VR_P5V_STBY_COMP" )
			)
			( signal "@baseboard_fab2_lib.baseboard_fab2(sch_1):vr_p5v_stby_rc_comp"
				( objectStatus "VR_P5V_STBY_RC_COMP" )
			)
			( signal "@baseboard_fab2_lib.baseboard_fab2(sch_1):vr_p3v3_stby_lgate"
				( objectStatus "VR_P3V3_STBY_LGATE" )
			)
			( signal "@baseboard_fab2_lib.baseboard_fab2(sch_1):upi_cpu1_cpu0_p1p1_dp(0)"
				( pinPairRef "@baseboard_fab2_lib.baseboard_fab2(sch_1):\PP3143\" )
				( objectStatus "UPI_CPU1_CPU0_P1P1_DP<0>" )
			)
			( signal "@baseboard_fab2_lib.baseboard_fab2(sch_1):upi_cpu1_cpu0_p1p1_dn(0)"
				( pinPairRef "@baseboard_fab2_lib.baseboard_fab2(sch_1):\PP3144\" )
				( objectStatus "UPI_CPU1_CPU0_P1P1_DN<0>" )
			)
			( signal "@baseboard_fab2_lib.baseboard_fab2(sch_1):upi_cpu1_cpu0_p1p1_dp(1)"
				( pinPairRef "@baseboard_fab2_lib.baseboard_fab2(sch_1):\PP3145\" )
				( objectStatus "UPI_CPU1_CPU0_P1P1_DP<1>" )
			)
			( signal "@baseboard_fab2_lib.baseboard_fab2(sch_1):upi_cpu1_cpu0_p1p1_dn(1)"
				( pinPairRef "@baseboard_fab2_lib.baseboard_fab2(sch_1):\PP3146\" )
				( objectStatus "UPI_CPU1_CPU0_P1P1_DN<1>" )
			)
			( signal "@baseboard_fab2_lib.baseboard_fab2(sch_1):upi_cpu1_cpu0_p1p1_dp(2)"
				( pinPairRef "@baseboard_fab2_lib.baseboard_fab2(sch_1):\PP3139\" )
				( objectStatus "UPI_CPU1_CPU0_P1P1_DP<2>" )
			)
			( signal "@baseboard_fab2_lib.baseboard_fab2(sch_1):upi_cpu1_cpu0_p1p1_dn(2)"
				( pinPairRef "@baseboard_fab2_lib.baseboard_fab2(sch_1):\PP3140\" )
				( objectStatus "UPI_CPU1_CPU0_P1P1_DN<2>" )
			)
			( signal "@baseboard_fab2_lib.baseboard_fab2(sch_1):upi_cpu1_cpu0_p1p1_dp(3)"
				( pinPairRef "@baseboard_fab2_lib.baseboard_fab2(sch_1):\PP3141\" )
				( objectStatus "UPI_CPU1_CPU0_P1P1_DP<3>" )
			)
			( signal "@baseboard_fab2_lib.baseboard_fab2(sch_1):upi_cpu1_cpu0_p1p1_dn(3)"
				( pinPairRef "@baseboard_fab2_lib.baseboard_fab2(sch_1):\PP3142\" )
				( objectStatus "UPI_CPU1_CPU0_P1P1_DN<3>" )
			)
			( signal "@baseboard_fab2_lib.baseboard_fab2(sch_1):upi_cpu1_cpu0_p1p1_dp(4)"
				( pinPairRef "@baseboard_fab2_lib.baseboard_fab2(sch_1):\PP3135\" )
				( objectStatus "UPI_CPU1_CPU0_P1P1_DP<4>" )
			)
			( signal "@baseboard_fab2_lib.baseboard_fab2(sch_1):upi_cpu1_cpu0_p1p1_dn(4)"
				( pinPairRef "@baseboard_fab2_lib.baseboard_fab2(sch_1):\PP3136\" )
				( objectStatus "UPI_CPU1_CPU0_P1P1_DN<4>" )
			)
			( signal "@baseboard_fab2_lib.baseboard_fab2(sch_1):upi_cpu1_cpu0_p1p1_dp(5)"
				( pinPairRef "@baseboard_fab2_lib.baseboard_fab2(sch_1):\PP3137\" )
				( objectStatus "UPI_CPU1_CPU0_P1P1_DP<5>" )
			)
			( signal "@baseboard_fab2_lib.baseboard_fab2(sch_1):upi_cpu1_cpu0_p1p1_dn(5)"
				( pinPairRef "@baseboard_fab2_lib.baseboard_fab2(sch_1):\PP3138\" )
				( objectStatus "UPI_CPU1_CPU0_P1P1_DN<5>" )
			)
			( signal "@baseboard_fab2_lib.baseboard_fab2(sch_1):upi_cpu1_cpu0_p1p1_dp(6)"
				( pinPairRef "@baseboard_fab2_lib.baseboard_fab2(sch_1):\PP3131\" )
				( objectStatus "UPI_CPU1_CPU0_P1P1_DP<6>" )
			)
			( signal "@baseboard_fab2_lib.baseboard_fab2(sch_1):upi_cpu1_cpu0_p1p1_dn(6)"
				( pinPairRef "@baseboard_fab2_lib.baseboard_fab2(sch_1):\PP3132\" )
				( objectStatus "UPI_CPU1_CPU0_P1P1_DN<6>" )
			)
			( signal "@baseboard_fab2_lib.baseboard_fab2(sch_1):upi_cpu1_cpu0_p1p1_dp(7)"
				( pinPairRef "@baseboard_fab2_lib.baseboard_fab2(sch_1):\PP3133\" )
				( objectStatus "UPI_CPU1_CPU0_P1P1_DP<7>" )
			)
			( signal "@baseboard_fab2_lib.baseboard_fab2(sch_1):upi_cpu1_cpu0_p1p1_dn(7)"
				( pinPairRef "@baseboard_fab2_lib.baseboard_fab2(sch_1):\PP3134\" )
				( objectStatus "UPI_CPU1_CPU0_P1P1_DN<7>" )
			)
			( signal "@baseboard_fab2_lib.baseboard_fab2(sch_1):upi_cpu1_cpu0_p1p1_dp(8)"
				( pinPairRef "@baseboard_fab2_lib.baseboard_fab2(sch_1):\PP3127\" )
				( objectStatus "UPI_CPU1_CPU0_P1P1_DP<8>" )
			)
			( signal "@baseboard_fab2_lib.baseboard_fab2(sch_1):upi_cpu1_cpu0_p1p1_dn(8)"
				( pinPairRef "@baseboard_fab2_lib.baseboard_fab2(sch_1):\PP3128\" )
				( objectStatus "UPI_CPU1_CPU0_P1P1_DN<8>" )
			)
			( signal "@baseboard_fab2_lib.baseboard_fab2(sch_1):upi_cpu1_cpu0_p1p1_dp(9)"
				( pinPairRef "@baseboard_fab2_lib.baseboard_fab2(sch_1):\PP3129\" )
				( objectStatus "UPI_CPU1_CPU0_P1P1_DP<9>" )
			)
			( signal "@baseboard_fab2_lib.baseboard_fab2(sch_1):upi_cpu1_cpu0_p1p1_dn(9)"
				( pinPairRef "@baseboard_fab2_lib.baseboard_fab2(sch_1):\PP3130\" )
				( objectStatus "UPI_CPU1_CPU0_P1P1_DN<9>" )
			)
			( signal "@baseboard_fab2_lib.baseboard_fab2(sch_1):upi_cpu1_cpu0_p1p1_dp(10)"
				( pinPairRef "@baseboard_fab2_lib.baseboard_fab2(sch_1):\PP3123\" )
				( objectStatus "UPI_CPU1_CPU0_P1P1_DP<10>" )
			)
			( signal "@baseboard_fab2_lib.baseboard_fab2(sch_1):upi_cpu1_cpu0_p1p1_dn(10)"
				( pinPairRef "@baseboard_fab2_lib.baseboard_fab2(sch_1):\PP3124\" )
				( objectStatus "UPI_CPU1_CPU0_P1P1_DN<10>" )
			)
			( signal "@baseboard_fab2_lib.baseboard_fab2(sch_1):upi_cpu1_cpu0_p1p1_dp(11)"
				( pinPairRef "@baseboard_fab2_lib.baseboard_fab2(sch_1):\PP3125\" )
				( objectStatus "UPI_CPU1_CPU0_P1P1_DP<11>" )
			)
			( signal "@baseboard_fab2_lib.baseboard_fab2(sch_1):upi_cpu1_cpu0_p1p1_dn(11)"
				( pinPairRef "@baseboard_fab2_lib.baseboard_fab2(sch_1):\PP3126\" )
				( objectStatus "UPI_CPU1_CPU0_P1P1_DN<11>" )
			)
			( signal "@baseboard_fab2_lib.baseboard_fab2(sch_1):upi_cpu1_cpu0_p1p1_dp(12)"
				( pinPairRef "@baseboard_fab2_lib.baseboard_fab2(sch_1):\PP3119\" )
				( objectStatus "UPI_CPU1_CPU0_P1P1_DP<12>" )
			)
			( signal "@baseboard_fab2_lib.baseboard_fab2(sch_1):upi_cpu1_cpu0_p1p1_dn(12)"
				( pinPairRef "@baseboard_fab2_lib.baseboard_fab2(sch_1):\PP3120\" )
				( objectStatus "UPI_CPU1_CPU0_P1P1_DN<12>" )
			)
			( signal "@baseboard_fab2_lib.baseboard_fab2(sch_1):upi_cpu1_cpu0_p1p1_dp(13)"
				( pinPairRef "@baseboard_fab2_lib.baseboard_fab2(sch_1):\PP3121\" )
				( objectStatus "UPI_CPU1_CPU0_P1P1_DP<13>" )
			)
			( signal "@baseboard_fab2_lib.baseboard_fab2(sch_1):upi_cpu1_cpu0_p1p1_dn(13)"
				( pinPairRef "@baseboard_fab2_lib.baseboard_fab2(sch_1):\PP3122\" )
				( objectStatus "UPI_CPU1_CPU0_P1P1_DN<13>" )
			)
			( signal "@baseboard_fab2_lib.baseboard_fab2(sch_1):upi_cpu1_cpu0_p1p1_dp(14)"
				( pinPairRef "@baseboard_fab2_lib.baseboard_fab2(sch_1):\PP3115\" )
				( objectStatus "UPI_CPU1_CPU0_P1P1_DP<14>" )
			)
			( signal "@baseboard_fab2_lib.baseboard_fab2(sch_1):upi_cpu1_cpu0_p1p1_dn(14)"
				( pinPairRef "@baseboard_fab2_lib.baseboard_fab2(sch_1):\PP3116\" )
				( objectStatus "UPI_CPU1_CPU0_P1P1_DN<14>" )
			)
			( signal "@baseboard_fab2_lib.baseboard_fab2(sch_1):upi_cpu1_cpu0_p1p1_dp(15)"
				( pinPairRef "@baseboard_fab2_lib.baseboard_fab2(sch_1):\PP3117\" )
				( objectStatus "UPI_CPU1_CPU0_P1P1_DP<15>" )
			)
			( signal "@baseboard_fab2_lib.baseboard_fab2(sch_1):upi_cpu1_cpu0_p1p1_dn(15)"
				( pinPairRef "@baseboard_fab2_lib.baseboard_fab2(sch_1):\PP3118\" )
				( objectStatus "UPI_CPU1_CPU0_P1P1_DN<15>" )
			)
			( signal "@baseboard_fab2_lib.baseboard_fab2(sch_1):upi_cpu1_cpu0_p1p1_dp(16)"
				( pinPairRef "@baseboard_fab2_lib.baseboard_fab2(sch_1):\PP3111\" )
				( objectStatus "UPI_CPU1_CPU0_P1P1_DP<16>" )
			)
			( signal "@baseboard_fab2_lib.baseboard_fab2(sch_1):upi_cpu1_cpu0_p1p1_dn(16)"
				( pinPairRef "@baseboard_fab2_lib.baseboard_fab2(sch_1):\PP3112\" )
				( objectStatus "UPI_CPU1_CPU0_P1P1_DN<16>" )
			)
			( signal "@baseboard_fab2_lib.baseboard_fab2(sch_1):upi_cpu1_cpu0_p1p1_dp(17)"
				( pinPairRef "@baseboard_fab2_lib.baseboard_fab2(sch_1):\PP3113\" )
				( objectStatus "UPI_CPU1_CPU0_P1P1_DP<17>" )
			)
			( signal "@baseboard_fab2_lib.baseboard_fab2(sch_1):upi_cpu1_cpu0_p1p1_dn(17)"
				( pinPairRef "@baseboard_fab2_lib.baseboard_fab2(sch_1):\PP3114\" )
				( objectStatus "UPI_CPU1_CPU0_P1P1_DN<17>" )
			)
			( signal "@baseboard_fab2_lib.baseboard_fab2(sch_1):upi_cpu1_cpu0_p1p1_dp(18)"
				( pinPairRef "@baseboard_fab2_lib.baseboard_fab2(sch_1):\PP3107\" )
				( objectStatus "UPI_CPU1_CPU0_P1P1_DP<18>" )
			)
			( signal "@baseboard_fab2_lib.baseboard_fab2(sch_1):upi_cpu1_cpu0_p1p1_dn(18)"
				( pinPairRef "@baseboard_fab2_lib.baseboard_fab2(sch_1):\PP3108\" )
				( objectStatus "UPI_CPU1_CPU0_P1P1_DN<18>" )
			)
			( signal "@baseboard_fab2_lib.baseboard_fab2(sch_1):upi_cpu1_cpu0_p1p1_dp(19)"
				( pinPairRef "@baseboard_fab2_lib.baseboard_fab2(sch_1):\PP3109\" )
				( objectStatus "UPI_CPU1_CPU0_P1P1_DP<19>" )
			)
			( signal "@baseboard_fab2_lib.baseboard_fab2(sch_1):upi_cpu1_cpu0_p1p1_dn(19)"
				( pinPairRef "@baseboard_fab2_lib.baseboard_fab2(sch_1):\PP3110\" )
				( objectStatus "UPI_CPU1_CPU0_P1P1_DN<19>" )
			)
			( signal "@baseboard_fab2_lib.baseboard_fab2(sch_1):upi_cpu1_cpu0_p0p0_dp(0)"
				( pinPairRef "@baseboard_fab2_lib.baseboard_fab2(sch_1):\PP3183\" )
				( objectStatus "UPI_CPU1_CPU0_P0P0_DP<0>" )
			)
			( signal "@baseboard_fab2_lib.baseboard_fab2(sch_1):upi_cpu1_cpu0_p0p0_dn(0)"
				( pinPairRef "@baseboard_fab2_lib.baseboard_fab2(sch_1):\PP3184\" )
				( objectStatus "UPI_CPU1_CPU0_P0P0_DN<0>" )
			)
			( signal "@baseboard_fab2_lib.baseboard_fab2(sch_1):upi_cpu1_cpu0_p0p0_dp(1)"
				( pinPairRef "@baseboard_fab2_lib.baseboard_fab2(sch_1):\PP3185\" )
				( objectStatus "UPI_CPU1_CPU0_P0P0_DP<1>" )
			)
			( signal "@baseboard_fab2_lib.baseboard_fab2(sch_1):upi_cpu1_cpu0_p0p0_dn(1)"
				( pinPairRef "@baseboard_fab2_lib.baseboard_fab2(sch_1):\PP3186\" )
				( objectStatus "UPI_CPU1_CPU0_P0P0_DN<1>" )
			)
			( signal "@baseboard_fab2_lib.baseboard_fab2(sch_1):upi_cpu1_cpu0_p0p0_dp(2)"
				( pinPairRef "@baseboard_fab2_lib.baseboard_fab2(sch_1):\PP3179\" )
				( objectStatus "UPI_CPU1_CPU0_P0P0_DP<2>" )
			)
			( signal "@baseboard_fab2_lib.baseboard_fab2(sch_1):upi_cpu1_cpu0_p0p0_dn(2)"
				( pinPairRef "@baseboard_fab2_lib.baseboard_fab2(sch_1):\PP3180\" )
				( objectStatus "UPI_CPU1_CPU0_P0P0_DN<2>" )
			)
			( signal "@baseboard_fab2_lib.baseboard_fab2(sch_1):upi_cpu1_cpu0_p0p0_dp(3)"
				( pinPairRef "@baseboard_fab2_lib.baseboard_fab2(sch_1):\PP3181\" )
				( objectStatus "UPI_CPU1_CPU0_P0P0_DP<3>" )
			)
			( signal "@baseboard_fab2_lib.baseboard_fab2(sch_1):upi_cpu1_cpu0_p0p0_dn(3)"
				( pinPairRef "@baseboard_fab2_lib.baseboard_fab2(sch_1):\PP3182\" )
				( objectStatus "UPI_CPU1_CPU0_P0P0_DN<3>" )
			)
			( signal "@baseboard_fab2_lib.baseboard_fab2(sch_1):upi_cpu1_cpu0_p0p0_dp(4)"
				( pinPairRef "@baseboard_fab2_lib.baseboard_fab2(sch_1):\PP3175\" )
				( objectStatus "UPI_CPU1_CPU0_P0P0_DP<4>" )
			)
			( signal "@baseboard_fab2_lib.baseboard_fab2(sch_1):upi_cpu1_cpu0_p0p0_dn(4)"
				( pinPairRef "@baseboard_fab2_lib.baseboard_fab2(sch_1):\PP3176\" )
				( objectStatus "UPI_CPU1_CPU0_P0P0_DN<4>" )
			)
			( signal "@baseboard_fab2_lib.baseboard_fab2(sch_1):upi_cpu1_cpu0_p0p0_dp(5)"
				( pinPairRef "@baseboard_fab2_lib.baseboard_fab2(sch_1):\PP3177\" )
				( objectStatus "UPI_CPU1_CPU0_P0P0_DP<5>" )
			)
			( signal "@baseboard_fab2_lib.baseboard_fab2(sch_1):upi_cpu1_cpu0_p0p0_dn(5)"
				( pinPairRef "@baseboard_fab2_lib.baseboard_fab2(sch_1):\PP3178\" )
				( objectStatus "UPI_CPU1_CPU0_P0P0_DN<5>" )
			)
			( signal "@baseboard_fab2_lib.baseboard_fab2(sch_1):upi_cpu1_cpu0_p0p0_dp(6)"
				( pinPairRef "@baseboard_fab2_lib.baseboard_fab2(sch_1):\PP3171\" )
				( objectStatus "UPI_CPU1_CPU0_P0P0_DP<6>" )
			)
			( signal "@baseboard_fab2_lib.baseboard_fab2(sch_1):upi_cpu1_cpu0_p0p0_dn(6)"
				( pinPairRef "@baseboard_fab2_lib.baseboard_fab2(sch_1):\PP3172\" )
				( objectStatus "UPI_CPU1_CPU0_P0P0_DN<6>" )
			)
			( signal "@baseboard_fab2_lib.baseboard_fab2(sch_1):upi_cpu1_cpu0_p0p0_dp(7)"
				( pinPairRef "@baseboard_fab2_lib.baseboard_fab2(sch_1):\PP3173\" )
				( objectStatus "UPI_CPU1_CPU0_P0P0_DP<7>" )
			)
			( signal "@baseboard_fab2_lib.baseboard_fab2(sch_1):upi_cpu1_cpu0_p0p0_dn(7)"
				( pinPairRef "@baseboard_fab2_lib.baseboard_fab2(sch_1):\PP3174\" )
				( objectStatus "UPI_CPU1_CPU0_P0P0_DN<7>" )
			)
			( signal "@baseboard_fab2_lib.baseboard_fab2(sch_1):upi_cpu1_cpu0_p0p0_dp(8)"
				( pinPairRef "@baseboard_fab2_lib.baseboard_fab2(sch_1):\PP3167\" )
				( objectStatus "UPI_CPU1_CPU0_P0P0_DP<8>" )
			)
			( signal "@baseboard_fab2_lib.baseboard_fab2(sch_1):upi_cpu1_cpu0_p0p0_dn(8)"
				( pinPairRef "@baseboard_fab2_lib.baseboard_fab2(sch_1):\PP3168\" )
				( objectStatus "UPI_CPU1_CPU0_P0P0_DN<8>" )
			)
			( signal "@baseboard_fab2_lib.baseboard_fab2(sch_1):upi_cpu1_cpu0_p0p0_dp(9)"
				( pinPairRef "@baseboard_fab2_lib.baseboard_fab2(sch_1):\PP3169\" )
				( objectStatus "UPI_CPU1_CPU0_P0P0_DP<9>" )
			)
			( signal "@baseboard_fab2_lib.baseboard_fab2(sch_1):upi_cpu1_cpu0_p0p0_dn(9)"
				( pinPairRef "@baseboard_fab2_lib.baseboard_fab2(sch_1):\PP3170\" )
				( objectStatus "UPI_CPU1_CPU0_P0P0_DN<9>" )
			)
			( signal "@baseboard_fab2_lib.baseboard_fab2(sch_1):upi_cpu1_cpu0_p0p0_dp(10)"
				( pinPairRef "@baseboard_fab2_lib.baseboard_fab2(sch_1):\PP3163\" )
				( objectStatus "UPI_CPU1_CPU0_P0P0_DP<10>" )
			)
			( signal "@baseboard_fab2_lib.baseboard_fab2(sch_1):upi_cpu1_cpu0_p0p0_dn(10)"
				( pinPairRef "@baseboard_fab2_lib.baseboard_fab2(sch_1):\PP3164\" )
				( objectStatus "UPI_CPU1_CPU0_P0P0_DN<10>" )
			)
			( signal "@baseboard_fab2_lib.baseboard_fab2(sch_1):upi_cpu1_cpu0_p0p0_dp(11)"
				( pinPairRef "@baseboard_fab2_lib.baseboard_fab2(sch_1):\PP3165\" )
				( objectStatus "UPI_CPU1_CPU0_P0P0_DP<11>" )
			)
			( signal "@baseboard_fab2_lib.baseboard_fab2(sch_1):upi_cpu1_cpu0_p0p0_dn(11)"
				( pinPairRef "@baseboard_fab2_lib.baseboard_fab2(sch_1):\PP3166\" )
				( objectStatus "UPI_CPU1_CPU0_P0P0_DN<11>" )
			)
			( signal "@baseboard_fab2_lib.baseboard_fab2(sch_1):upi_cpu1_cpu0_p0p0_dp(12)"
				( pinPairRef "@baseboard_fab2_lib.baseboard_fab2(sch_1):\PP3159\" )
				( objectStatus "UPI_CPU1_CPU0_P0P0_DP<12>" )
			)
			( signal "@baseboard_fab2_lib.baseboard_fab2(sch_1):upi_cpu1_cpu0_p0p0_dn(12)"
				( pinPairRef "@baseboard_fab2_lib.baseboard_fab2(sch_1):\PP3160\" )
				( objectStatus "UPI_CPU1_CPU0_P0P0_DN<12>" )
			)
			( signal "@baseboard_fab2_lib.baseboard_fab2(sch_1):upi_cpu1_cpu0_p0p0_dp(13)"
				( pinPairRef "@baseboard_fab2_lib.baseboard_fab2(sch_1):\PP3161\" )
				( objectStatus "UPI_CPU1_CPU0_P0P0_DP<13>" )
			)
			( signal "@baseboard_fab2_lib.baseboard_fab2(sch_1):upi_cpu1_cpu0_p0p0_dn(13)"
				( pinPairRef "@baseboard_fab2_lib.baseboard_fab2(sch_1):\PP3162\" )
				( objectStatus "UPI_CPU1_CPU0_P0P0_DN<13>" )
			)
			( signal "@baseboard_fab2_lib.baseboard_fab2(sch_1):upi_cpu1_cpu0_p0p0_dp(14)"
				( pinPairRef "@baseboard_fab2_lib.baseboard_fab2(sch_1):\PP3155\" )
				( objectStatus "UPI_CPU1_CPU0_P0P0_DP<14>" )
			)
			( signal "@baseboard_fab2_lib.baseboard_fab2(sch_1):upi_cpu1_cpu0_p0p0_dn(14)"
				( pinPairRef "@baseboard_fab2_lib.baseboard_fab2(sch_1):\PP3156\" )
				( objectStatus "UPI_CPU1_CPU0_P0P0_DN<14>" )
			)
			( signal "@baseboard_fab2_lib.baseboard_fab2(sch_1):upi_cpu1_cpu0_p0p0_dp(15)"
				( pinPairRef "@baseboard_fab2_lib.baseboard_fab2(sch_1):\PP3157\" )
				( objectStatus "UPI_CPU1_CPU0_P0P0_DP<15>" )
			)
			( signal "@baseboard_fab2_lib.baseboard_fab2(sch_1):upi_cpu1_cpu0_p0p0_dn(15)"
				( pinPairRef "@baseboard_fab2_lib.baseboard_fab2(sch_1):\PP3158\" )
				( objectStatus "UPI_CPU1_CPU0_P0P0_DN<15>" )
			)
			( signal "@baseboard_fab2_lib.baseboard_fab2(sch_1):upi_cpu1_cpu0_p0p0_dp(16)"
				( pinPairRef "@baseboard_fab2_lib.baseboard_fab2(sch_1):\PP3151\" )
				( objectStatus "UPI_CPU1_CPU0_P0P0_DP<16>" )
			)
			( signal "@baseboard_fab2_lib.baseboard_fab2(sch_1):upi_cpu1_cpu0_p0p0_dn(16)"
				( pinPairRef "@baseboard_fab2_lib.baseboard_fab2(sch_1):\PP3152\" )
				( objectStatus "UPI_CPU1_CPU0_P0P0_DN<16>" )
			)
			( signal "@baseboard_fab2_lib.baseboard_fab2(sch_1):upi_cpu1_cpu0_p0p0_dp(17)"
				( pinPairRef "@baseboard_fab2_lib.baseboard_fab2(sch_1):\PP3153\" )
				( objectStatus "UPI_CPU1_CPU0_P0P0_DP<17>" )
			)
			( signal "@baseboard_fab2_lib.baseboard_fab2(sch_1):upi_cpu1_cpu0_p0p0_dn(17)"
				( pinPairRef "@baseboard_fab2_lib.baseboard_fab2(sch_1):\PP3154\" )
				( objectStatus "UPI_CPU1_CPU0_P0P0_DN<17>" )
			)
			( signal "@baseboard_fab2_lib.baseboard_fab2(sch_1):upi_cpu1_cpu0_p0p0_dp(18)"
				( pinPairRef "@baseboard_fab2_lib.baseboard_fab2(sch_1):\PP3147\" )
				( objectStatus "UPI_CPU1_CPU0_P0P0_DP<18>" )
			)
			( signal "@baseboard_fab2_lib.baseboard_fab2(sch_1):upi_cpu1_cpu0_p0p0_dn(18)"
				( pinPairRef "@baseboard_fab2_lib.baseboard_fab2(sch_1):\PP3148\" )
				( objectStatus "UPI_CPU1_CPU0_P0P0_DN<18>" )
			)
			( signal "@baseboard_fab2_lib.baseboard_fab2(sch_1):upi_cpu1_cpu0_p0p0_dp(19)"
				( pinPairRef "@baseboard_fab2_lib.baseboard_fab2(sch_1):\PP3149\" )
				( objectStatus "UPI_CPU1_CPU0_P0P0_DP<19>" )
			)
			( signal "@baseboard_fab2_lib.baseboard_fab2(sch_1):upi_cpu1_cpu0_p0p0_dn(19)"
				( pinPairRef "@baseboard_fab2_lib.baseboard_fab2(sch_1):\PP3150\" )
				( objectStatus "UPI_CPU1_CPU0_P0P0_DN<19>" )
			)
			( signal "@baseboard_fab2_lib.baseboard_fab2(sch_1):upi_cpu0_cpu1_p1p1_dp(0)"
				( pinPairRef "@baseboard_fab2_lib.baseboard_fab2(sch_1):\PP3223\" )
				( objectStatus "UPI_CPU0_CPU1_P1P1_DP<0>" )
			)
			( signal "@baseboard_fab2_lib.baseboard_fab2(sch_1):upi_cpu0_cpu1_p1p1_dn(0)"
				( pinPairRef "@baseboard_fab2_lib.baseboard_fab2(sch_1):\PP3224\" )
				( objectStatus "UPI_CPU0_CPU1_P1P1_DN<0>" )
			)
			( signal "@baseboard_fab2_lib.baseboard_fab2(sch_1):upi_cpu0_cpu1_p1p1_dp(1)"
				( pinPairRef "@baseboard_fab2_lib.baseboard_fab2(sch_1):\PP3225\" )
				( objectStatus "UPI_CPU0_CPU1_P1P1_DP<1>" )
			)
			( signal "@baseboard_fab2_lib.baseboard_fab2(sch_1):upi_cpu0_cpu1_p1p1_dn(1)"
				( pinPairRef "@baseboard_fab2_lib.baseboard_fab2(sch_1):\PP3226\" )
				( objectStatus "UPI_CPU0_CPU1_P1P1_DN<1>" )
			)
			( signal "@baseboard_fab2_lib.baseboard_fab2(sch_1):upi_cpu0_cpu1_p1p1_dp(2)"
				( pinPairRef "@baseboard_fab2_lib.baseboard_fab2(sch_1):\PP3219\" )
				( objectStatus "UPI_CPU0_CPU1_P1P1_DP<2>" )
			)
			( signal "@baseboard_fab2_lib.baseboard_fab2(sch_1):upi_cpu0_cpu1_p1p1_dn(2)"
				( pinPairRef "@baseboard_fab2_lib.baseboard_fab2(sch_1):\PP3220\" )
				( objectStatus "UPI_CPU0_CPU1_P1P1_DN<2>" )
			)
			( signal "@baseboard_fab2_lib.baseboard_fab2(sch_1):upi_cpu0_cpu1_p1p1_dp(3)"
				( pinPairRef "@baseboard_fab2_lib.baseboard_fab2(sch_1):\PP3221\" )
				( objectStatus "UPI_CPU0_CPU1_P1P1_DP<3>" )
			)
			( signal "@baseboard_fab2_lib.baseboard_fab2(sch_1):upi_cpu0_cpu1_p1p1_dn(3)"
				( pinPairRef "@baseboard_fab2_lib.baseboard_fab2(sch_1):\PP3222\" )
				( objectStatus "UPI_CPU0_CPU1_P1P1_DN<3>" )
			)
			( signal "@baseboard_fab2_lib.baseboard_fab2(sch_1):upi_cpu0_cpu1_p1p1_dp(4)"
				( pinPairRef "@baseboard_fab2_lib.baseboard_fab2(sch_1):\PP3215\" )
				( objectStatus "UPI_CPU0_CPU1_P1P1_DP<4>" )
			)
			( signal "@baseboard_fab2_lib.baseboard_fab2(sch_1):upi_cpu0_cpu1_p1p1_dn(4)"
				( pinPairRef "@baseboard_fab2_lib.baseboard_fab2(sch_1):\PP3216\" )
				( objectStatus "UPI_CPU0_CPU1_P1P1_DN<4>" )
			)
			( signal "@baseboard_fab2_lib.baseboard_fab2(sch_1):upi_cpu0_cpu1_p1p1_dp(5)"
				( pinPairRef "@baseboard_fab2_lib.baseboard_fab2(sch_1):\PP3217\" )
				( objectStatus "UPI_CPU0_CPU1_P1P1_DP<5>" )
			)
			( signal "@baseboard_fab2_lib.baseboard_fab2(sch_1):upi_cpu0_cpu1_p1p1_dn(5)"
				( pinPairRef "@baseboard_fab2_lib.baseboard_fab2(sch_1):\PP3218\" )
				( objectStatus "UPI_CPU0_CPU1_P1P1_DN<5>" )
			)
			( signal "@baseboard_fab2_lib.baseboard_fab2(sch_1):upi_cpu0_cpu1_p1p1_dp(6)"
				( pinPairRef "@baseboard_fab2_lib.baseboard_fab2(sch_1):\PP3211\" )
				( objectStatus "UPI_CPU0_CPU1_P1P1_DP<6>" )
			)
			( signal "@baseboard_fab2_lib.baseboard_fab2(sch_1):upi_cpu0_cpu1_p1p1_dn(6)"
				( pinPairRef "@baseboard_fab2_lib.baseboard_fab2(sch_1):\PP3212\" )
				( objectStatus "UPI_CPU0_CPU1_P1P1_DN<6>" )
			)
			( signal "@baseboard_fab2_lib.baseboard_fab2(sch_1):upi_cpu0_cpu1_p1p1_dp(7)"
				( pinPairRef "@baseboard_fab2_lib.baseboard_fab2(sch_1):\PP3213\" )
				( objectStatus "UPI_CPU0_CPU1_P1P1_DP<7>" )
			)
			( signal "@baseboard_fab2_lib.baseboard_fab2(sch_1):upi_cpu0_cpu1_p1p1_dn(7)"
				( pinPairRef "@baseboard_fab2_lib.baseboard_fab2(sch_1):\PP3214\" )
				( objectStatus "UPI_CPU0_CPU1_P1P1_DN<7>" )
			)
			( signal "@baseboard_fab2_lib.baseboard_fab2(sch_1):upi_cpu0_cpu1_p1p1_dp(8)"
				( pinPairRef "@baseboard_fab2_lib.baseboard_fab2(sch_1):\PP3207\" )
				( objectStatus "UPI_CPU0_CPU1_P1P1_DP<8>" )
			)
			( signal "@baseboard_fab2_lib.baseboard_fab2(sch_1):upi_cpu0_cpu1_p1p1_dn(8)"
				( pinPairRef "@baseboard_fab2_lib.baseboard_fab2(sch_1):\PP3208\" )
				( objectStatus "UPI_CPU0_CPU1_P1P1_DN<8>" )
			)
			( signal "@baseboard_fab2_lib.baseboard_fab2(sch_1):upi_cpu0_cpu1_p1p1_dp(9)"
				( pinPairRef "@baseboard_fab2_lib.baseboard_fab2(sch_1):\PP3209\" )
				( objectStatus "UPI_CPU0_CPU1_P1P1_DP<9>" )
			)
			( signal "@baseboard_fab2_lib.baseboard_fab2(sch_1):upi_cpu0_cpu1_p1p1_dn(9)"
				( pinPairRef "@baseboard_fab2_lib.baseboard_fab2(sch_1):\PP3210\" )
				( objectStatus "UPI_CPU0_CPU1_P1P1_DN<9>" )
			)
			( signal "@baseboard_fab2_lib.baseboard_fab2(sch_1):upi_cpu0_cpu1_p1p1_dp(10)"
				( pinPairRef "@baseboard_fab2_lib.baseboard_fab2(sch_1):\PP3203\" )
				( objectStatus "UPI_CPU0_CPU1_P1P1_DP<10>" )
			)
			( signal "@baseboard_fab2_lib.baseboard_fab2(sch_1):upi_cpu0_cpu1_p1p1_dn(10)"
				( pinPairRef "@baseboard_fab2_lib.baseboard_fab2(sch_1):\PP3204\" )
				( objectStatus "UPI_CPU0_CPU1_P1P1_DN<10>" )
			)
			( signal "@baseboard_fab2_lib.baseboard_fab2(sch_1):upi_cpu0_cpu1_p1p1_dp(11)"
				( pinPairRef "@baseboard_fab2_lib.baseboard_fab2(sch_1):\PP3205\" )
				( objectStatus "UPI_CPU0_CPU1_P1P1_DP<11>" )
			)
			( signal "@baseboard_fab2_lib.baseboard_fab2(sch_1):upi_cpu0_cpu1_p1p1_dn(11)"
				( pinPairRef "@baseboard_fab2_lib.baseboard_fab2(sch_1):\PP3206\" )
				( objectStatus "UPI_CPU0_CPU1_P1P1_DN<11>" )
			)
			( signal "@baseboard_fab2_lib.baseboard_fab2(sch_1):upi_cpu0_cpu1_p1p1_dp(12)"
				( pinPairRef "@baseboard_fab2_lib.baseboard_fab2(sch_1):\PP3199\" )
				( objectStatus "UPI_CPU0_CPU1_P1P1_DP<12>" )
			)
			( signal "@baseboard_fab2_lib.baseboard_fab2(sch_1):upi_cpu0_cpu1_p1p1_dn(12)"
				( pinPairRef "@baseboard_fab2_lib.baseboard_fab2(sch_1):\PP3200\" )
				( objectStatus "UPI_CPU0_CPU1_P1P1_DN<12>" )
			)
			( signal "@baseboard_fab2_lib.baseboard_fab2(sch_1):upi_cpu0_cpu1_p1p1_dp(13)"
				( pinPairRef "@baseboard_fab2_lib.baseboard_fab2(sch_1):\PP3201\" )
				( objectStatus "UPI_CPU0_CPU1_P1P1_DP<13>" )
			)
			( signal "@baseboard_fab2_lib.baseboard_fab2(sch_1):upi_cpu0_cpu1_p1p1_dn(13)"
				( pinPairRef "@baseboard_fab2_lib.baseboard_fab2(sch_1):\PP3202\" )
				( objectStatus "UPI_CPU0_CPU1_P1P1_DN<13>" )
			)
			( signal "@baseboard_fab2_lib.baseboard_fab2(sch_1):upi_cpu0_cpu1_p1p1_dp(14)"
				( pinPairRef "@baseboard_fab2_lib.baseboard_fab2(sch_1):\PP3195\" )
				( objectStatus "UPI_CPU0_CPU1_P1P1_DP<14>" )
			)
			( signal "@baseboard_fab2_lib.baseboard_fab2(sch_1):upi_cpu0_cpu1_p1p1_dn(14)"
				( pinPairRef "@baseboard_fab2_lib.baseboard_fab2(sch_1):\PP3196\" )
				( objectStatus "UPI_CPU0_CPU1_P1P1_DN<14>" )
			)
			( signal "@baseboard_fab2_lib.baseboard_fab2(sch_1):upi_cpu0_cpu1_p1p1_dp(15)"
				( pinPairRef "@baseboard_fab2_lib.baseboard_fab2(sch_1):\PP3197\" )
				( objectStatus "UPI_CPU0_CPU1_P1P1_DP<15>" )
			)
			( signal "@baseboard_fab2_lib.baseboard_fab2(sch_1):upi_cpu0_cpu1_p1p1_dn(15)"
				( pinPairRef "@baseboard_fab2_lib.baseboard_fab2(sch_1):\PP3198\" )
				( objectStatus "UPI_CPU0_CPU1_P1P1_DN<15>" )
			)
			( signal "@baseboard_fab2_lib.baseboard_fab2(sch_1):upi_cpu0_cpu1_p1p1_dp(16)"
				( pinPairRef "@baseboard_fab2_lib.baseboard_fab2(sch_1):\PP3191\" )
				( objectStatus "UPI_CPU0_CPU1_P1P1_DP<16>" )
			)
			( signal "@baseboard_fab2_lib.baseboard_fab2(sch_1):upi_cpu0_cpu1_p1p1_dn(16)"
				( pinPairRef "@baseboard_fab2_lib.baseboard_fab2(sch_1):\PP3192\" )
				( objectStatus "UPI_CPU0_CPU1_P1P1_DN<16>" )
			)
			( signal "@baseboard_fab2_lib.baseboard_fab2(sch_1):upi_cpu0_cpu1_p1p1_dp(17)"
				( pinPairRef "@baseboard_fab2_lib.baseboard_fab2(sch_1):\PP3193\" )
				( objectStatus "UPI_CPU0_CPU1_P1P1_DP<17>" )
			)
			( signal "@baseboard_fab2_lib.baseboard_fab2(sch_1):upi_cpu0_cpu1_p1p1_dn(17)"
				( pinPairRef "@baseboard_fab2_lib.baseboard_fab2(sch_1):\PP3194\" )
				( objectStatus "UPI_CPU0_CPU1_P1P1_DN<17>" )
			)
			( signal "@baseboard_fab2_lib.baseboard_fab2(sch_1):upi_cpu0_cpu1_p1p1_dp(18)"
				( pinPairRef "@baseboard_fab2_lib.baseboard_fab2(sch_1):\PP3187\" )
				( objectStatus "UPI_CPU0_CPU1_P1P1_DP<18>" )
			)
			( signal "@baseboard_fab2_lib.baseboard_fab2(sch_1):upi_cpu0_cpu1_p1p1_dn(18)"
				( pinPairRef "@baseboard_fab2_lib.baseboard_fab2(sch_1):\PP3188\" )
				( objectStatus "UPI_CPU0_CPU1_P1P1_DN<18>" )
			)
			( signal "@baseboard_fab2_lib.baseboard_fab2(sch_1):upi_cpu0_cpu1_p1p1_dp(19)"
				( pinPairRef "@baseboard_fab2_lib.baseboard_fab2(sch_1):\PP3189\" )
				( objectStatus "UPI_CPU0_CPU1_P1P1_DP<19>" )
			)
			( signal "@baseboard_fab2_lib.baseboard_fab2(sch_1):upi_cpu0_cpu1_p1p1_dn(19)"
				( pinPairRef "@baseboard_fab2_lib.baseboard_fab2(sch_1):\PP3190\" )
				( objectStatus "UPI_CPU0_CPU1_P1P1_DN<19>" )
			)
			( signal "@baseboard_fab2_lib.baseboard_fab2(sch_1):upi_cpu0_cpu1_p0p0_dp(0)"
				( pinPairRef "@baseboard_fab2_lib.baseboard_fab2(sch_1):\PP3263\" )
				( objectStatus "UPI_CPU0_CPU1_P0P0_DP<0>" )
			)
			( signal "@baseboard_fab2_lib.baseboard_fab2(sch_1):upi_cpu0_cpu1_p0p0_dn(0)"
				( pinPairRef "@baseboard_fab2_lib.baseboard_fab2(sch_1):\PP3264\" )
				( objectStatus "UPI_CPU0_CPU1_P0P0_DN<0>" )
			)
			( signal "@baseboard_fab2_lib.baseboard_fab2(sch_1):upi_cpu0_cpu1_p0p0_dp(1)"
				( pinPairRef "@baseboard_fab2_lib.baseboard_fab2(sch_1):\PP3265\" )
				( objectStatus "UPI_CPU0_CPU1_P0P0_DP<1>" )
			)
			( signal "@baseboard_fab2_lib.baseboard_fab2(sch_1):upi_cpu0_cpu1_p0p0_dn(1)"
				( pinPairRef "@baseboard_fab2_lib.baseboard_fab2(sch_1):\PP3266\" )
				( objectStatus "UPI_CPU0_CPU1_P0P0_DN<1>" )
			)
			( signal "@baseboard_fab2_lib.baseboard_fab2(sch_1):upi_cpu0_cpu1_p0p0_dp(2)"
				( pinPairRef "@baseboard_fab2_lib.baseboard_fab2(sch_1):\PP3259\" )
				( objectStatus "UPI_CPU0_CPU1_P0P0_DP<2>" )
			)
			( signal "@baseboard_fab2_lib.baseboard_fab2(sch_1):upi_cpu0_cpu1_p0p0_dn(2)"
				( pinPairRef "@baseboard_fab2_lib.baseboard_fab2(sch_1):\PP3260\" )
				( objectStatus "UPI_CPU0_CPU1_P0P0_DN<2>" )
			)
			( signal "@baseboard_fab2_lib.baseboard_fab2(sch_1):upi_cpu0_cpu1_p0p0_dp(3)"
				( pinPairRef "@baseboard_fab2_lib.baseboard_fab2(sch_1):\PP3261\" )
				( objectStatus "UPI_CPU0_CPU1_P0P0_DP<3>" )
			)
			( signal "@baseboard_fab2_lib.baseboard_fab2(sch_1):upi_cpu0_cpu1_p0p0_dn(3)"
				( pinPairRef "@baseboard_fab2_lib.baseboard_fab2(sch_1):\PP3262\" )
				( objectStatus "UPI_CPU0_CPU1_P0P0_DN<3>" )
			)
			( signal "@baseboard_fab2_lib.baseboard_fab2(sch_1):upi_cpu0_cpu1_p0p0_dp(4)"
				( pinPairRef "@baseboard_fab2_lib.baseboard_fab2(sch_1):\PP3255\" )
				( objectStatus "UPI_CPU0_CPU1_P0P0_DP<4>" )
			)
			( signal "@baseboard_fab2_lib.baseboard_fab2(sch_1):upi_cpu0_cpu1_p0p0_dn(4)"
				( pinPairRef "@baseboard_fab2_lib.baseboard_fab2(sch_1):\PP3256\" )
				( objectStatus "UPI_CPU0_CPU1_P0P0_DN<4>" )
			)
			( signal "@baseboard_fab2_lib.baseboard_fab2(sch_1):upi_cpu0_cpu1_p0p0_dp(5)"
				( pinPairRef "@baseboard_fab2_lib.baseboard_fab2(sch_1):\PP3257\" )
				( objectStatus "UPI_CPU0_CPU1_P0P0_DP<5>" )
			)
			( signal "@baseboard_fab2_lib.baseboard_fab2(sch_1):upi_cpu0_cpu1_p0p0_dn(5)"
				( pinPairRef "@baseboard_fab2_lib.baseboard_fab2(sch_1):\PP3258\" )
				( objectStatus "UPI_CPU0_CPU1_P0P0_DN<5>" )
			)
			( signal "@baseboard_fab2_lib.baseboard_fab2(sch_1):upi_cpu0_cpu1_p0p0_dp(6)"
				( pinPairRef "@baseboard_fab2_lib.baseboard_fab2(sch_1):\PP3251\" )
				( objectStatus "UPI_CPU0_CPU1_P0P0_DP<6>" )
			)
			( signal "@baseboard_fab2_lib.baseboard_fab2(sch_1):upi_cpu0_cpu1_p0p0_dn(6)"
				( pinPairRef "@baseboard_fab2_lib.baseboard_fab2(sch_1):\PP3252\" )
				( objectStatus "UPI_CPU0_CPU1_P0P0_DN<6>" )
			)
			( signal "@baseboard_fab2_lib.baseboard_fab2(sch_1):upi_cpu0_cpu1_p0p0_dp(7)"
				( pinPairRef "@baseboard_fab2_lib.baseboard_fab2(sch_1):\PP3253\" )
				( objectStatus "UPI_CPU0_CPU1_P0P0_DP<7>" )
			)
			( signal "@baseboard_fab2_lib.baseboard_fab2(sch_1):upi_cpu0_cpu1_p0p0_dn(7)"
				( pinPairRef "@baseboard_fab2_lib.baseboard_fab2(sch_1):\PP3254\" )
				( objectStatus "UPI_CPU0_CPU1_P0P0_DN<7>" )
			)
			( signal "@baseboard_fab2_lib.baseboard_fab2(sch_1):upi_cpu0_cpu1_p0p0_dp(8)"
				( pinPairRef "@baseboard_fab2_lib.baseboard_fab2(sch_1):\PP3247\" )
				( objectStatus "UPI_CPU0_CPU1_P0P0_DP<8>" )
			)
			( signal "@baseboard_fab2_lib.baseboard_fab2(sch_1):upi_cpu0_cpu1_p0p0_dn(8)"
				( pinPairRef "@baseboard_fab2_lib.baseboard_fab2(sch_1):\PP3248\" )
				( objectStatus "UPI_CPU0_CPU1_P0P0_DN<8>" )
			)
			( signal "@baseboard_fab2_lib.baseboard_fab2(sch_1):upi_cpu0_cpu1_p0p0_dp(9)"
				( pinPairRef "@baseboard_fab2_lib.baseboard_fab2(sch_1):\PP3249\" )
				( objectStatus "UPI_CPU0_CPU1_P0P0_DP<9>" )
			)
			( signal "@baseboard_fab2_lib.baseboard_fab2(sch_1):upi_cpu0_cpu1_p0p0_dn(9)"
				( pinPairRef "@baseboard_fab2_lib.baseboard_fab2(sch_1):\PP3250\" )
				( objectStatus "UPI_CPU0_CPU1_P0P0_DN<9>" )
			)
			( signal "@baseboard_fab2_lib.baseboard_fab2(sch_1):upi_cpu0_cpu1_p0p0_dp(10)"
				( pinPairRef "@baseboard_fab2_lib.baseboard_fab2(sch_1):\PP3243\" )
				( objectStatus "UPI_CPU0_CPU1_P0P0_DP<10>" )
			)
			( signal "@baseboard_fab2_lib.baseboard_fab2(sch_1):upi_cpu0_cpu1_p0p0_dn(10)"
				( pinPairRef "@baseboard_fab2_lib.baseboard_fab2(sch_1):\PP3244\" )
				( objectStatus "UPI_CPU0_CPU1_P0P0_DN<10>" )
			)
			( signal "@baseboard_fab2_lib.baseboard_fab2(sch_1):upi_cpu0_cpu1_p0p0_dp(11)"
				( pinPairRef "@baseboard_fab2_lib.baseboard_fab2(sch_1):\PP3245\" )
				( objectStatus "UPI_CPU0_CPU1_P0P0_DP<11>" )
			)
			( signal "@baseboard_fab2_lib.baseboard_fab2(sch_1):upi_cpu0_cpu1_p0p0_dn(11)"
				( pinPairRef "@baseboard_fab2_lib.baseboard_fab2(sch_1):\PP3246\" )
				( objectStatus "UPI_CPU0_CPU1_P0P0_DN<11>" )
			)
			( signal "@baseboard_fab2_lib.baseboard_fab2(sch_1):upi_cpu0_cpu1_p0p0_dp(12)"
				( pinPairRef "@baseboard_fab2_lib.baseboard_fab2(sch_1):\PP3239\" )
				( objectStatus "UPI_CPU0_CPU1_P0P0_DP<12>" )
			)
			( signal "@baseboard_fab2_lib.baseboard_fab2(sch_1):upi_cpu0_cpu1_p0p0_dn(12)"
				( pinPairRef "@baseboard_fab2_lib.baseboard_fab2(sch_1):\PP3240\" )
				( objectStatus "UPI_CPU0_CPU1_P0P0_DN<12>" )
			)
			( signal "@baseboard_fab2_lib.baseboard_fab2(sch_1):upi_cpu0_cpu1_p0p0_dp(13)"
				( pinPairRef "@baseboard_fab2_lib.baseboard_fab2(sch_1):\PP3241\" )
				( objectStatus "UPI_CPU0_CPU1_P0P0_DP<13>" )
			)
			( signal "@baseboard_fab2_lib.baseboard_fab2(sch_1):upi_cpu0_cpu1_p0p0_dn(13)"
				( pinPairRef "@baseboard_fab2_lib.baseboard_fab2(sch_1):\PP3242\" )
				( objectStatus "UPI_CPU0_CPU1_P0P0_DN<13>" )
			)
			( signal "@baseboard_fab2_lib.baseboard_fab2(sch_1):upi_cpu0_cpu1_p0p0_dp(14)"
				( pinPairRef "@baseboard_fab2_lib.baseboard_fab2(sch_1):\PP3235\" )
				( objectStatus "UPI_CPU0_CPU1_P0P0_DP<14>" )
			)
			( signal "@baseboard_fab2_lib.baseboard_fab2(sch_1):upi_cpu0_cpu1_p0p0_dn(14)"
				( pinPairRef "@baseboard_fab2_lib.baseboard_fab2(sch_1):\PP3236\" )
				( objectStatus "UPI_CPU0_CPU1_P0P0_DN<14>" )
			)
			( signal "@baseboard_fab2_lib.baseboard_fab2(sch_1):upi_cpu0_cpu1_p0p0_dp(15)"
				( pinPairRef "@baseboard_fab2_lib.baseboard_fab2(sch_1):\PP3237\" )
				( objectStatus "UPI_CPU0_CPU1_P0P0_DP<15>" )
			)
			( signal "@baseboard_fab2_lib.baseboard_fab2(sch_1):upi_cpu0_cpu1_p0p0_dn(15)"
				( pinPairRef "@baseboard_fab2_lib.baseboard_fab2(sch_1):\PP3238\" )
				( objectStatus "UPI_CPU0_CPU1_P0P0_DN<15>" )
			)
			( signal "@baseboard_fab2_lib.baseboard_fab2(sch_1):upi_cpu0_cpu1_p0p0_dp(16)"
				( pinPairRef "@baseboard_fab2_lib.baseboard_fab2(sch_1):\PP3231\" )
				( objectStatus "UPI_CPU0_CPU1_P0P0_DP<16>" )
			)
			( signal "@baseboard_fab2_lib.baseboard_fab2(sch_1):upi_cpu0_cpu1_p0p0_dn(16)"
				( pinPairRef "@baseboard_fab2_lib.baseboard_fab2(sch_1):\PP3232\" )
				( objectStatus "UPI_CPU0_CPU1_P0P0_DN<16>" )
			)
			( signal "@baseboard_fab2_lib.baseboard_fab2(sch_1):upi_cpu0_cpu1_p0p0_dp(17)"
				( pinPairRef "@baseboard_fab2_lib.baseboard_fab2(sch_1):\PP3233\" )
				( objectStatus "UPI_CPU0_CPU1_P0P0_DP<17>" )
			)
			( signal "@baseboard_fab2_lib.baseboard_fab2(sch_1):upi_cpu0_cpu1_p0p0_dn(17)"
				( pinPairRef "@baseboard_fab2_lib.baseboard_fab2(sch_1):\PP3234\" )
				( objectStatus "UPI_CPU0_CPU1_P0P0_DN<17>" )
			)
			( signal "@baseboard_fab2_lib.baseboard_fab2(sch_1):upi_cpu0_cpu1_p0p0_dp(18)"
				( pinPairRef "@baseboard_fab2_lib.baseboard_fab2(sch_1):\PP3227\" )
				( objectStatus "UPI_CPU0_CPU1_P0P0_DP<18>" )
			)
			( signal "@baseboard_fab2_lib.baseboard_fab2(sch_1):upi_cpu0_cpu1_p0p0_dn(18)"
				( pinPairRef "@baseboard_fab2_lib.baseboard_fab2(sch_1):\PP3228\" )
				( objectStatus "UPI_CPU0_CPU1_P0P0_DN<18>" )
			)
			( signal "@baseboard_fab2_lib.baseboard_fab2(sch_1):upi_cpu0_cpu1_p0p0_dp(19)"
				( pinPairRef "@baseboard_fab2_lib.baseboard_fab2(sch_1):\PP3229\" )
				( objectStatus "UPI_CPU0_CPU1_P0P0_DP<19>" )
			)
			( signal "@baseboard_fab2_lib.baseboard_fab2(sch_1):upi_cpu0_cpu1_p0p0_dn(19)"
				( pinPairRef "@baseboard_fab2_lib.baseboard_fab2(sch_1):\PP3230\" )
				( objectStatus "UPI_CPU0_CPU1_P0P0_DN<19>" )
			)
			( signal "@baseboard_fab2_lib.baseboard_fab2(sch_1):m_m_c(2)"
				( pinPairRef "@baseboard_fab2_lib.baseboard_fab2(sch_1):\PP3329\" )
				( pinPairRef "@baseboard_fab2_lib.baseboard_fab2(sch_1):\PP3330\" )
				( attribute "NO_TEST" "1"
					( Origin gBackEnd )
				)
				( objectStatus "M_M_C<2>" )
			)
			( signal "@baseboard_fab2_lib.baseboard_fab2(sch_1):m_m_ma(17)"
				( pinPairRef "@baseboard_fab2_lib.baseboard_fab2(sch_1):\PP3331\" )
				( pinPairRef "@baseboard_fab2_lib.baseboard_fab2(sch_1):\PP3332\" )
				( attribute "NO_TEST" "1"
					( Origin gBackEnd )
				)
				( objectStatus "M_M_MA<17>" )
			)
			( signal "@baseboard_fab2_lib.baseboard_fab2(sch_1):m_m_ma(13)"
				( pinPairRef "@baseboard_fab2_lib.baseboard_fab2(sch_1):\PP3325\" )
				( pinPairRef "@baseboard_fab2_lib.baseboard_fab2(sch_1):\PP3326\" )
				( objectStatus "M_M_MA<13>" )
			)
			( signal "@baseboard_fab2_lib.baseboard_fab2(sch_1):m_m_ma(15)"
				( pinPairRef "@baseboard_fab2_lib.baseboard_fab2(sch_1):\PP3327\" )
				( pinPairRef "@baseboard_fab2_lib.baseboard_fab2(sch_1):\PP3328\" )
				( attribute "NO_TEST" "1"
					( Origin gBackEnd )
				)
				( objectStatus "M_M_MA<15>" )
			)
			( signal "@baseboard_fab2_lib.baseboard_fab2(sch_1):m_m_ma(14)"
				( pinPairRef "@baseboard_fab2_lib.baseboard_fab2(sch_1):\PP3321\" )
				( pinPairRef "@baseboard_fab2_lib.baseboard_fab2(sch_1):\PP3322\" )
				( attribute "NO_TEST" "1"
					( Origin gBackEnd )
				)
				( objectStatus "M_M_MA<14>" )
			)
			( signal "@baseboard_fab2_lib.baseboard_fab2(sch_1):m_m_ma(16)"
				( pinPairRef "@baseboard_fab2_lib.baseboard_fab2(sch_1):\PP3323\" )
				( pinPairRef "@baseboard_fab2_lib.baseboard_fab2(sch_1):\PP3324\" )
				( objectStatus "M_M_MA<16>" )
			)
			( signal "@baseboard_fab2_lib.baseboard_fab2(sch_1):m_m_ba(1)"
				( pinPairRef "@baseboard_fab2_lib.baseboard_fab2(sch_1):\PP3317\" )
				( pinPairRef "@baseboard_fab2_lib.baseboard_fab2(sch_1):\PP3318\" )
				( attribute "NO_TEST" "1"
					( Origin gBackEnd )
				)
				( objectStatus "M_M_BA<1>" )
			)
			( signal "@baseboard_fab2_lib.baseboard_fab2(sch_1):m_m_ma(10)"
				( pinPairRef "@baseboard_fab2_lib.baseboard_fab2(sch_1):\PP3319\" )
				( pinPairRef "@baseboard_fab2_lib.baseboard_fab2(sch_1):\PP3320\" )
				( objectStatus "M_M_MA<10>" )
			)
			( signal "@baseboard_fab2_lib.baseboard_fab2(sch_1):m_m_ba(0)"
				( pinPairRef "@baseboard_fab2_lib.baseboard_fab2(sch_1):\PP3313\" )
				( pinPairRef "@baseboard_fab2_lib.baseboard_fab2(sch_1):\PP3314\" )
				( attribute "NO_TEST" "1"
					( Origin gBackEnd )
				)
				( objectStatus "M_M_BA<0>" )
			)
			( signal "@baseboard_fab2_lib.baseboard_fab2(sch_1):m_m_ma(0)"
				( pinPairRef "@baseboard_fab2_lib.baseboard_fab2(sch_1):\PP3315\" )
				( pinPairRef "@baseboard_fab2_lib.baseboard_fab2(sch_1):\PP3316\" )
				( attribute "NO_TEST" "1"
					( Origin gBackEnd )
				)
				( objectStatus "M_M_MA<0>" )
			)
			( signal "@baseboard_fab2_lib.baseboard_fab2(sch_1):m_m_par"
				( pinPairRef "@baseboard_fab2_lib.baseboard_fab2(sch_1):\PP3311\" )
				( pinPairRef "@baseboard_fab2_lib.baseboard_fab2(sch_1):\PP3312\" )
				( objectStatus "M_M_PAR" )
			)
			( signal "@baseboard_fab2_lib.baseboard_fab2(sch_1):m_m_ma(1)"
				( pinPairRef "@baseboard_fab2_lib.baseboard_fab2(sch_1):\PP3307\" )
				( pinPairRef "@baseboard_fab2_lib.baseboard_fab2(sch_1):\PP3308\" )
				( attribute "NO_TEST" "1"
					( Origin gBackEnd )
				)
				( objectStatus "M_M_MA<1>" )
			)
			( signal "@baseboard_fab2_lib.baseboard_fab2(sch_1):m_m_ma(3)"
				( pinPairRef "@baseboard_fab2_lib.baseboard_fab2(sch_1):\PP3309\" )
				( pinPairRef "@baseboard_fab2_lib.baseboard_fab2(sch_1):\PP3310\" )
				( objectStatus "M_M_MA<3>" )
			)
			( signal "@baseboard_fab2_lib.baseboard_fab2(sch_1):m_m_ma(2)"
				( pinPairRef "@baseboard_fab2_lib.baseboard_fab2(sch_1):\PP3303\" )
				( pinPairRef "@baseboard_fab2_lib.baseboard_fab2(sch_1):\PP3304\" )
				( objectStatus "M_M_MA<2>" )
			)
			( signal "@baseboard_fab2_lib.baseboard_fab2(sch_1):m_m_ma(4)"
				( pinPairRef "@baseboard_fab2_lib.baseboard_fab2(sch_1):\PP3305\" )
				( pinPairRef "@baseboard_fab2_lib.baseboard_fab2(sch_1):\PP3306\" )
				( attribute "NO_TEST" "1"
					( Origin gBackEnd )
				)
				( objectStatus "M_M_MA<4>" )
			)
			( signal "@baseboard_fab2_lib.baseboard_fab2(sch_1):m_m_ma(5)"
				( pinPairRef "@baseboard_fab2_lib.baseboard_fab2(sch_1):\PP3299\" )
				( pinPairRef "@baseboard_fab2_lib.baseboard_fab2(sch_1):\PP3300\" )
				( attribute "NO_TEST" "1"
					( Origin gBackEnd )
				)
				( objectStatus "M_M_MA<5>" )
			)
			( signal "@baseboard_fab2_lib.baseboard_fab2(sch_1):m_m_ma(6)"
				( pinPairRef "@baseboard_fab2_lib.baseboard_fab2(sch_1):\PP3301\" )
				( pinPairRef "@baseboard_fab2_lib.baseboard_fab2(sch_1):\PP3302\" )
				( objectStatus "M_M_MA<6>" )
			)
			( signal "@baseboard_fab2_lib.baseboard_fab2(sch_1):m_m_ma(7)"
				( pinPairRef "@baseboard_fab2_lib.baseboard_fab2(sch_1):\PP3295\" )
				( pinPairRef "@baseboard_fab2_lib.baseboard_fab2(sch_1):\PP3296\" )
				( attribute "NO_TEST" "1"
					( Origin gBackEnd )
				)
				( objectStatus "M_M_MA<7>" )
			)
			( signal "@baseboard_fab2_lib.baseboard_fab2(sch_1):m_m_ma(8)"
				( pinPairRef "@baseboard_fab2_lib.baseboard_fab2(sch_1):\PP3297\" )
				( pinPairRef "@baseboard_fab2_lib.baseboard_fab2(sch_1):\PP3298\" )
				( objectStatus "M_M_MA<8>" )
			)
			( signal "@baseboard_fab2_lib.baseboard_fab2(sch_1):m_m_ma(9)"
				( pinPairRef "@baseboard_fab2_lib.baseboard_fab2(sch_1):\PP3291\" )
				( pinPairRef "@baseboard_fab2_lib.baseboard_fab2(sch_1):\PP3292\" )
				( objectStatus "M_M_MA<9>" )
			)
			( signal "@baseboard_fab2_lib.baseboard_fab2(sch_1):m_m_ma(12)"
				( pinPairRef "@baseboard_fab2_lib.baseboard_fab2(sch_1):\PP3293\" )
				( pinPairRef "@baseboard_fab2_lib.baseboard_fab2(sch_1):\PP3294\" )
				( objectStatus "M_M_MA<12>" )
			)
			( signal "@baseboard_fab2_lib.baseboard_fab2(sch_1):m_m_bg(1)"
				( pinPairRef "@baseboard_fab2_lib.baseboard_fab2(sch_1):\PP3287\" )
				( pinPairRef "@baseboard_fab2_lib.baseboard_fab2(sch_1):\PP3288\" )
				( attribute "NO_TEST" "1"
					( Origin gBackEnd )
				)
				( objectStatus "M_M_BG<1>" )
			)
			( signal "@baseboard_fab2_lib.baseboard_fab2(sch_1):m_m_ma(11)"
				( pinPairRef "@baseboard_fab2_lib.baseboard_fab2(sch_1):\PP3289\" )
				( pinPairRef "@baseboard_fab2_lib.baseboard_fab2(sch_1):\PP3290\" )
				( objectStatus "M_M_MA<11>" )
			)
			( signal "@baseboard_fab2_lib.baseboard_fab2(sch_1):m_m_act_n"
				( pinPairRef "@baseboard_fab2_lib.baseboard_fab2(sch_1):\PP3283\" )
				( pinPairRef "@baseboard_fab2_lib.baseboard_fab2(sch_1):\PP3284\" )
				( attribute "NO_TEST" "1"
					( Origin gBackEnd )
				)
				( objectStatus "M_M_ACT_N" )
			)
			( signal "@baseboard_fab2_lib.baseboard_fab2(sch_1):m_m_bg(0)"
				( pinPairRef "@baseboard_fab2_lib.baseboard_fab2(sch_1):\PP3285\" )
				( pinPairRef "@baseboard_fab2_lib.baseboard_fab2(sch_1):\PP3286\" )
				( objectStatus "M_M_BG<0>" )
			)
			( signal "@baseboard_fab2_lib.baseboard_fab2(sch_1):m_m_cs_n(0)"
				( pinPairRef "@baseboard_fab2_lib.baseboard_fab2(sch_1):\PP3281\" )
				( objectStatus "M_M_CS_N<0>" )
			)
			( signal "@baseboard_fab2_lib.baseboard_fab2(sch_1):m_m_odt(0)"
				( pinPairRef "@baseboard_fab2_lib.baseboard_fab2(sch_1):\PP3282\" )
				( objectStatus "M_M_ODT<0>" )
			)
			( signal "@baseboard_fab2_lib.baseboard_fab2(sch_1):m_m_cke(0)"
				( pinPairRef "@baseboard_fab2_lib.baseboard_fab2(sch_1):\PP3280\" )
				( objectStatus "M_M_CKE<0>" )
			)
			( signal "@baseboard_fab2_lib.baseboard_fab2(sch_1):m_m_cs_n(2)"
				( pinPairRef "@baseboard_fab2_lib.baseboard_fab2(sch_1):\PP3279\" )
				( attribute "NO_TEST" "1"
					( Origin gBackEnd )
				)
				( objectStatus "M_M_CS_N<2>" )
			)
			( signal "@baseboard_fab2_lib.baseboard_fab2(sch_1):m_m_cs_n(3)"
				( pinPairRef "@baseboard_fab2_lib.baseboard_fab2(sch_1):\PP3278\" )
				( objectStatus "M_M_CS_N<3>" )
			)
			( signal "@baseboard_fab2_lib.baseboard_fab2(sch_1):m_m_cs_n(1)"
				( pinPairRef "@baseboard_fab2_lib.baseboard_fab2(sch_1):\PP3276\" )
				( attribute "NO_TEST" "1"
					( Origin gBackEnd )
				)
				( objectStatus "M_M_CS_N<1>" )
			)
			( signal "@baseboard_fab2_lib.baseboard_fab2(sch_1):m_m_odt(1)"
				( pinPairRef "@baseboard_fab2_lib.baseboard_fab2(sch_1):\PP3277\" )
				( objectStatus "M_M_ODT<1>" )
			)
			( signal "@baseboard_fab2_lib.baseboard_fab2(sch_1):m_m_cke(1)"
				( pinPairRef "@baseboard_fab2_lib.baseboard_fab2(sch_1):\PP3275\" )
				( objectStatus "M_M_CKE<1>" )
			)
			( signal "@baseboard_fab2_lib.baseboard_fab2(sch_1):m_m_cs_n(4)"
				( pinPairRef "@baseboard_fab2_lib.baseboard_fab2(sch_1):\PP3273\" )
				( attribute "NO_TEST" "1"
					( Origin gBackEnd )
				)
				( objectStatus "M_M_CS_N<4>" )
			)
			( signal "@baseboard_fab2_lib.baseboard_fab2(sch_1):m_m_odt(2)"
				( pinPairRef "@baseboard_fab2_lib.baseboard_fab2(sch_1):\PP3274\" )
				( objectStatus "M_M_ODT<2>" )
			)
			( signal "@baseboard_fab2_lib.baseboard_fab2(sch_1):m_m_cke(2)"
				( pinPairRef "@baseboard_fab2_lib.baseboard_fab2(sch_1):\PP3272\" )
				( objectStatus "M_M_CKE<2>" )
			)
			( signal "@baseboard_fab2_lib.baseboard_fab2(sch_1):m_m_cs_n(6)"
				( pinPairRef "@baseboard_fab2_lib.baseboard_fab2(sch_1):\PP3270\" )
				( attribute "NO_TEST" "1"
					( Origin gBackEnd )
				)
				( objectStatus "M_M_CS_N<6>" )
			)
			( signal "@baseboard_fab2_lib.baseboard_fab2(sch_1):m_m_cs_n(7)"
				( pinPairRef "@baseboard_fab2_lib.baseboard_fab2(sch_1):\PP3271\" )
				( objectStatus "M_M_CS_N<7>" )
			)
			( signal "@baseboard_fab2_lib.baseboard_fab2(sch_1):m_m_cs_n(5)"
				( pinPairRef "@baseboard_fab2_lib.baseboard_fab2(sch_1):\PP3268\" )
				( attribute "NO_TEST" "1"
					( Origin gBackEnd )
				)
				( objectStatus "M_M_CS_N<5>" )
			)
			( signal "@baseboard_fab2_lib.baseboard_fab2(sch_1):m_m_odt(3)"
				( pinPairRef "@baseboard_fab2_lib.baseboard_fab2(sch_1):\PP3269\" )
				( attribute "NO_TEST" "1"
					( Origin gBackEnd )
				)
				( objectStatus "M_M_ODT<3>" )
			)
			( signal "@baseboard_fab2_lib.baseboard_fab2(sch_1):m_m_cke(3)"
				( pinPairRef "@baseboard_fab2_lib.baseboard_fab2(sch_1):\PP3267\" )
				( attribute "NO_TEST" "1"
					( Origin gBackEnd )
				)
				( objectStatus "M_M_CKE<3>" )
			)
			( signal "@baseboard_fab2_lib.baseboard_fab2(sch_1):m_m_clk_dn(0)"
				( objectStatus "M_M_CLK_DN<0>" )
			)
			( signal "@baseboard_fab2_lib.baseboard_fab2(sch_1):m_m_clk_dp(0)"
				( electricalCSetRef "@crescent_city_bb_fab1_lib.crescent_city_bb_fab1(sch_1):\M_A_CLK_DP_0_\" )
				( attribute "NO_TEST" "1"
					( Origin gBackEnd )
				)
				( attribute "RELATIVE_PROPAGATION_DELAY_SCOPE" "G"
					( Parent
						( matchGroupRef "@crescent_city_bb_fab1_lib.crescent_city_bb_fab1(sch_1):\MG_DDR_FAR_DIMM-CLK0_CLS_DDR_M_CAC-CLKS\" )
					)
					( Origin gBackEnd )
				)
				( attribute "RELATIVE_PROPAGATION_DELAY_PATH_TYPE" "L:S"
					( Parent
						( matchGroupRef "@crescent_city_bb_fab1_lib.crescent_city_bb_fab1(sch_1):\MG_DDR_FAR_DIMM-CLK0_CLS_DDR_M_CAC-CLKS\" )
					)
					( Origin gBackEnd )
				)
				( attribute "RELATIVE_PROPAGATION_DELAY" "TARGET,TARGET"
					( Parent
						( matchGroupRef "@crescent_city_bb_fab1_lib.crescent_city_bb_fab1(sch_1):\MG_DDR_FAR_DIMM-CLK0_CLS_DDR_M_CAC-CLKS\" )
					)
					( Units "uMatchProp" "ns" 1.000000)
					( Origin gBackEnd )
				)
				( objectStatus "M_M_CLK_DP<0>" )
			)
			( signal "@baseboard_fab2_lib.baseboard_fab2(sch_1):m_m_clk_dn(2)"
				( objectStatus "M_M_CLK_DN<2>" )
			)
			( signal "@baseboard_fab2_lib.baseboard_fab2(sch_1):m_m_clk_dp(2)"
				( electricalCSetRef "@crescent_city_bb_fab1_lib.crescent_city_bb_fab1(sch_1):\DDR_CLK1\" )
				( attribute "NO_TEST" "1"
					( Origin gBackEnd )
				)
				( attribute "RELATIVE_PROPAGATION_DELAY_SCOPE" "G"
					( Parent
						( matchGroupRef "@crescent_city_bb_fab1_lib.crescent_city_bb_fab1(sch_1):\MG_DDR_NEAR_DIMM-CLK1_CLS_DDR_M_CAC-CLKS\" )
					)
					( Origin gBackEnd )
				)
				( attribute "RELATIVE_PROPAGATION_DELAY_PATH_TYPE" "L:S"
					( Parent
						( matchGroupRef "@crescent_city_bb_fab1_lib.crescent_city_bb_fab1(sch_1):\MG_DDR_NEAR_DIMM-CLK1_CLS_DDR_M_CAC-CLKS\" )
					)
					( Origin gBackEnd )
				)
				( attribute "RELATIVE_PROPAGATION_DELAY" "TARGET,TARGET"
					( Parent
						( matchGroupRef "@crescent_city_bb_fab1_lib.crescent_city_bb_fab1(sch_1):\MG_DDR_NEAR_DIMM-CLK1_CLS_DDR_M_CAC-CLKS\" )
					)
					( Units "uMatchProp" "ns" 1.000000)
					( Origin gBackEnd )
				)
				( objectStatus "M_M_CLK_DP<2>" )
			)
			( signal "@baseboard_fab2_lib.baseboard_fab2(sch_1):m_l_c(2)"
				( pinPairRef "@baseboard_fab2_lib.baseboard_fab2(sch_1):\PP3395\" )
				( pinPairRef "@baseboard_fab2_lib.baseboard_fab2(sch_1):\PP3396\" )
				( objectStatus "M_L_C<2>" )
			)
			( signal "@baseboard_fab2_lib.baseboard_fab2(sch_1):m_l_ma(17)"
				( pinPairRef "@baseboard_fab2_lib.baseboard_fab2(sch_1):\PP3397\" )
				( pinPairRef "@baseboard_fab2_lib.baseboard_fab2(sch_1):\PP3398\" )
				( attribute "NO_TEST" "1"
					( Origin gBackEnd )
				)
				( objectStatus "M_L_MA<17>" )
			)
			( signal "@baseboard_fab2_lib.baseboard_fab2(sch_1):m_l_ma(13)"
				( pinPairRef "@baseboard_fab2_lib.baseboard_fab2(sch_1):\PP3391\" )
				( pinPairRef "@baseboard_fab2_lib.baseboard_fab2(sch_1):\PP3392\" )
				( objectStatus "M_L_MA<13>" )
			)
			( signal "@baseboard_fab2_lib.baseboard_fab2(sch_1):m_l_ma(15)"
				( pinPairRef "@baseboard_fab2_lib.baseboard_fab2(sch_1):\PP3393\" )
				( pinPairRef "@baseboard_fab2_lib.baseboard_fab2(sch_1):\PP3394\" )
				( attribute "NO_TEST" "1"
					( Origin gBackEnd )
				)
				( objectStatus "M_L_MA<15>" )
			)
			( signal "@baseboard_fab2_lib.baseboard_fab2(sch_1):m_l_ma(14)"
				( pinPairRef "@baseboard_fab2_lib.baseboard_fab2(sch_1):\PP3387\" )
				( pinPairRef "@baseboard_fab2_lib.baseboard_fab2(sch_1):\PP3388\" )
				( attribute "NO_TEST" "1"
					( Origin gBackEnd )
				)
				( objectStatus "M_L_MA<14>" )
			)
			( signal "@baseboard_fab2_lib.baseboard_fab2(sch_1):m_l_ma(16)"
				( pinPairRef "@baseboard_fab2_lib.baseboard_fab2(sch_1):\PP3389\" )
				( pinPairRef "@baseboard_fab2_lib.baseboard_fab2(sch_1):\PP3390\" )
				( objectStatus "M_L_MA<16>" )
			)
			( signal "@baseboard_fab2_lib.baseboard_fab2(sch_1):m_l_ba(1)"
				( pinPairRef "@baseboard_fab2_lib.baseboard_fab2(sch_1):\PP3383\" )
				( pinPairRef "@baseboard_fab2_lib.baseboard_fab2(sch_1):\PP3384\" )
				( attribute "NO_TEST" "1"
					( Origin gBackEnd )
				)
				( objectStatus "M_L_BA<1>" )
			)
			( signal "@baseboard_fab2_lib.baseboard_fab2(sch_1):m_l_ma(10)"
				( pinPairRef "@baseboard_fab2_lib.baseboard_fab2(sch_1):\PP3385\" )
				( pinPairRef "@baseboard_fab2_lib.baseboard_fab2(sch_1):\PP3386\" )
				( objectStatus "M_L_MA<10>" )
			)
			( signal "@baseboard_fab2_lib.baseboard_fab2(sch_1):m_l_ba(0)"
				( pinPairRef "@baseboard_fab2_lib.baseboard_fab2(sch_1):\PP3379\" )
				( pinPairRef "@baseboard_fab2_lib.baseboard_fab2(sch_1):\PP3380\" )
				( attribute "NO_TEST" "1"
					( Origin gBackEnd )
				)
				( objectStatus "M_L_BA<0>" )
			)
			( signal "@baseboard_fab2_lib.baseboard_fab2(sch_1):m_l_ma(0)"
				( pinPairRef "@baseboard_fab2_lib.baseboard_fab2(sch_1):\PP3381\" )
				( pinPairRef "@baseboard_fab2_lib.baseboard_fab2(sch_1):\PP3382\" )
				( objectStatus "M_L_MA<0>" )
			)
			( signal "@baseboard_fab2_lib.baseboard_fab2(sch_1):m_l_par"
				( pinPairRef "@baseboard_fab2_lib.baseboard_fab2(sch_1):\PP3377\" )
				( pinPairRef "@baseboard_fab2_lib.baseboard_fab2(sch_1):\PP3378\" )
				( attribute "NO_TEST" "1"
					( Origin gBackEnd )
				)
				( objectStatus "M_L_PAR" )
			)
			( signal "@baseboard_fab2_lib.baseboard_fab2(sch_1):m_l_ma(1)"
				( pinPairRef "@baseboard_fab2_lib.baseboard_fab2(sch_1):\PP3373\" )
				( pinPairRef "@baseboard_fab2_lib.baseboard_fab2(sch_1):\PP3374\" )
				( objectStatus "M_L_MA<1>" )
			)
			( signal "@baseboard_fab2_lib.baseboard_fab2(sch_1):m_l_ma(3)"
				( pinPairRef "@baseboard_fab2_lib.baseboard_fab2(sch_1):\PP3375\" )
				( pinPairRef "@baseboard_fab2_lib.baseboard_fab2(sch_1):\PP3376\" )
				( attribute "NO_TEST" "1"
					( Origin gBackEnd )
				)
				( objectStatus "M_L_MA<3>" )
			)
			( signal "@baseboard_fab2_lib.baseboard_fab2(sch_1):m_l_ma(2)"
				( pinPairRef "@baseboard_fab2_lib.baseboard_fab2(sch_1):\PP3369\" )
				( pinPairRef "@baseboard_fab2_lib.baseboard_fab2(sch_1):\PP3370\" )
				( attribute "NO_TEST" "1"
					( Origin gBackEnd )
				)
				( objectStatus "M_L_MA<2>" )
			)
			( signal "@baseboard_fab2_lib.baseboard_fab2(sch_1):m_l_ma(4)"
				( pinPairRef "@baseboard_fab2_lib.baseboard_fab2(sch_1):\PP3371\" )
				( pinPairRef "@baseboard_fab2_lib.baseboard_fab2(sch_1):\PP3372\" )
				( objectStatus "M_L_MA<4>" )
			)
			( signal "@baseboard_fab2_lib.baseboard_fab2(sch_1):m_l_ma(5)"
				( pinPairRef "@baseboard_fab2_lib.baseboard_fab2(sch_1):\PP3365\" )
				( pinPairRef "@baseboard_fab2_lib.baseboard_fab2(sch_1):\PP3366\" )
				( objectStatus "M_L_MA<5>" )
			)
			( signal "@baseboard_fab2_lib.baseboard_fab2(sch_1):m_l_ma(6)"
				( pinPairRef "@baseboard_fab2_lib.baseboard_fab2(sch_1):\PP3367\" )
				( pinPairRef "@baseboard_fab2_lib.baseboard_fab2(sch_1):\PP3368\" )
				( attribute "NO_TEST" "1"
					( Origin gBackEnd )
				)
				( objectStatus "M_L_MA<6>" )
			)
			( signal "@baseboard_fab2_lib.baseboard_fab2(sch_1):m_l_ma(7)"
				( pinPairRef "@baseboard_fab2_lib.baseboard_fab2(sch_1):\PP3361\" )
				( pinPairRef "@baseboard_fab2_lib.baseboard_fab2(sch_1):\PP3362\" )
				( objectStatus "M_L_MA<7>" )
			)
			( signal "@baseboard_fab2_lib.baseboard_fab2(sch_1):m_l_ma(8)"
				( pinPairRef "@baseboard_fab2_lib.baseboard_fab2(sch_1):\PP3363\" )
				( pinPairRef "@baseboard_fab2_lib.baseboard_fab2(sch_1):\PP3364\" )
				( attribute "NO_TEST" "1"
					( Origin gBackEnd )
				)
				( objectStatus "M_L_MA<8>" )
			)
			( signal "@baseboard_fab2_lib.baseboard_fab2(sch_1):m_l_ma(9)"
				( pinPairRef "@baseboard_fab2_lib.baseboard_fab2(sch_1):\PP3357\" )
				( pinPairRef "@baseboard_fab2_lib.baseboard_fab2(sch_1):\PP3358\" )
				( attribute "NO_TEST" "1"
					( Origin gBackEnd )
				)
				( objectStatus "M_L_MA<9>" )
			)
			( signal "@baseboard_fab2_lib.baseboard_fab2(sch_1):m_l_ma(12)"
				( pinPairRef "@baseboard_fab2_lib.baseboard_fab2(sch_1):\PP3359\" )
				( pinPairRef "@baseboard_fab2_lib.baseboard_fab2(sch_1):\PP3360\" )
				( objectStatus "M_L_MA<12>" )
			)
			( signal "@baseboard_fab2_lib.baseboard_fab2(sch_1):m_l_bg(1)"
				( pinPairRef "@baseboard_fab2_lib.baseboard_fab2(sch_1):\PP3353\" )
				( pinPairRef "@baseboard_fab2_lib.baseboard_fab2(sch_1):\PP3354\" )
				( attribute "NO_TEST" "1"
					( Origin gBackEnd )
				)
				( objectStatus "M_L_BG<1>" )
			)
			( signal "@baseboard_fab2_lib.baseboard_fab2(sch_1):m_l_ma(11)"
				( pinPairRef "@baseboard_fab2_lib.baseboard_fab2(sch_1):\PP3355\" )
				( pinPairRef "@baseboard_fab2_lib.baseboard_fab2(sch_1):\PP3356\" )
				( attribute "NO_TEST" "1"
					( Origin gBackEnd )
				)
				( objectStatus "M_L_MA<11>" )
			)
			( signal "@baseboard_fab2_lib.baseboard_fab2(sch_1):m_l_act_n"
				( pinPairRef "@baseboard_fab2_lib.baseboard_fab2(sch_1):\PP3349\" )
				( pinPairRef "@baseboard_fab2_lib.baseboard_fab2(sch_1):\PP3350\" )
				( attribute "NO_TEST" "1"
					( Origin gBackEnd )
				)
				( objectStatus "M_L_ACT_N" )
			)
			( signal "@baseboard_fab2_lib.baseboard_fab2(sch_1):m_l_bg(0)"
				( pinPairRef "@baseboard_fab2_lib.baseboard_fab2(sch_1):\PP3351\" )
				( pinPairRef "@baseboard_fab2_lib.baseboard_fab2(sch_1):\PP3352\" )
				( attribute "NO_TEST" "1"
					( Origin gBackEnd )
				)
				( objectStatus "M_L_BG<0>" )
			)
			( signal "@baseboard_fab2_lib.baseboard_fab2(sch_1):m_l_cs_n(0)"
				( pinPairRef "@baseboard_fab2_lib.baseboard_fab2(sch_1):\PP3347\" )
				( attribute "NO_TEST" "1"
					( Origin gBackEnd )
				)
				( objectStatus "M_L_CS_N<0>" )
			)
			( signal "@baseboard_fab2_lib.baseboard_fab2(sch_1):m_l_odt(0)"
				( pinPairRef "@baseboard_fab2_lib.baseboard_fab2(sch_1):\PP3348\" )
				( attribute "NO_TEST" "1"
					( Origin gBackEnd )
				)
				( objectStatus "M_L_ODT<0>" )
			)
			( signal "@baseboard_fab2_lib.baseboard_fab2(sch_1):m_l_cke(0)"
				( pinPairRef "@baseboard_fab2_lib.baseboard_fab2(sch_1):\PP3346\" )
				( attribute "NO_TEST" "1"
					( Origin gBackEnd )
				)
				( objectStatus "M_L_CKE<0>" )
			)
			( signal "@baseboard_fab2_lib.baseboard_fab2(sch_1):m_l_cs_n(2)"
				( pinPairRef "@baseboard_fab2_lib.baseboard_fab2(sch_1):\PP3345\" )
				( attribute "NO_TEST" "1"
					( Origin gBackEnd )
				)
				( objectStatus "M_L_CS_N<2>" )
			)
			( signal "@baseboard_fab2_lib.baseboard_fab2(sch_1):m_l_cs_n(3)"
				( pinPairRef "@baseboard_fab2_lib.baseboard_fab2(sch_1):\PP3344\" )
				( objectStatus "M_L_CS_N<3>" )
			)
			( signal "@baseboard_fab2_lib.baseboard_fab2(sch_1):m_l_cs_n(1)"
				( pinPairRef "@baseboard_fab2_lib.baseboard_fab2(sch_1):\PP3342\" )
				( objectStatus "M_L_CS_N<1>" )
			)
			( signal "@baseboard_fab2_lib.baseboard_fab2(sch_1):m_l_odt(1)"
				( pinPairRef "@baseboard_fab2_lib.baseboard_fab2(sch_1):\PP3343\" )
				( objectStatus "M_L_ODT<1>" )
			)
			( signal "@baseboard_fab2_lib.baseboard_fab2(sch_1):m_l_cke(1)"
				( pinPairRef "@baseboard_fab2_lib.baseboard_fab2(sch_1):\PP3341\" )
				( objectStatus "M_L_CKE<1>" )
			)
			( signal "@baseboard_fab2_lib.baseboard_fab2(sch_1):m_l_cs_n(4)"
				( pinPairRef "@baseboard_fab2_lib.baseboard_fab2(sch_1):\PP3339\" )
				( objectStatus "M_L_CS_N<4>" )
			)
			( signal "@baseboard_fab2_lib.baseboard_fab2(sch_1):m_l_odt(2)"
				( pinPairRef "@baseboard_fab2_lib.baseboard_fab2(sch_1):\PP3340\" )
				( objectStatus "M_L_ODT<2>" )
			)
			( signal "@baseboard_fab2_lib.baseboard_fab2(sch_1):m_l_cke(2)"
				( pinPairRef "@baseboard_fab2_lib.baseboard_fab2(sch_1):\PP3338\" )
				( attribute "NO_TEST" "1"
					( Origin gBackEnd )
				)
				( objectStatus "M_L_CKE<2>" )
			)
			( signal "@baseboard_fab2_lib.baseboard_fab2(sch_1):m_l_cs_n(6)"
				( pinPairRef "@baseboard_fab2_lib.baseboard_fab2(sch_1):\PP3336\" )
				( objectStatus "M_L_CS_N<6>" )
			)
			( signal "@baseboard_fab2_lib.baseboard_fab2(sch_1):m_l_cs_n(7)"
				( pinPairRef "@baseboard_fab2_lib.baseboard_fab2(sch_1):\PP3337\" )
				( objectStatus "M_L_CS_N<7>" )
			)
			( signal "@baseboard_fab2_lib.baseboard_fab2(sch_1):m_l_cs_n(5)"
				( pinPairRef "@baseboard_fab2_lib.baseboard_fab2(sch_1):\PP3334\" )
				( attribute "NO_TEST" "1"
					( Origin gBackEnd )
				)
				( objectStatus "M_L_CS_N<5>" )
			)
			( signal "@baseboard_fab2_lib.baseboard_fab2(sch_1):m_l_odt(3)"
				( pinPairRef "@baseboard_fab2_lib.baseboard_fab2(sch_1):\PP3335\" )
				( attribute "NO_TEST" "1"
					( Origin gBackEnd )
				)
				( objectStatus "M_L_ODT<3>" )
			)
			( signal "@baseboard_fab2_lib.baseboard_fab2(sch_1):m_l_cke(3)"
				( pinPairRef "@baseboard_fab2_lib.baseboard_fab2(sch_1):\PP3333\" )
				( attribute "NO_TEST" "1"
					( Origin gBackEnd )
				)
				( objectStatus "M_L_CKE<3>" )
			)
			( signal "@baseboard_fab2_lib.baseboard_fab2(sch_1):m_l_clk_dn(0)"
				( attribute "NO_TEST" "1"
					( Origin gBackEnd )
				)
				( objectStatus "M_L_CLK_DN<0>" )
			)
			( signal "@baseboard_fab2_lib.baseboard_fab2(sch_1):m_l_clk_dp(0)"
				( electricalCSetRef "@crescent_city_bb_fab1_lib.crescent_city_bb_fab1(sch_1):\M_A_CLK_DP_0_\" )
				( attribute "RELATIVE_PROPAGATION_DELAY_SCOPE" "G"
					( Parent
						( matchGroupRef "@crescent_city_bb_fab1_lib.crescent_city_bb_fab1(sch_1):\MG_DDR_FAR_DIMM-CLK0_CLS_DDR_L_CAC-CLKS\" )
					)
					( Origin gBackEnd )
				)
				( attribute "RELATIVE_PROPAGATION_DELAY_PATH_TYPE" "L:S"
					( Parent
						( matchGroupRef "@crescent_city_bb_fab1_lib.crescent_city_bb_fab1(sch_1):\MG_DDR_FAR_DIMM-CLK0_CLS_DDR_L_CAC-CLKS\" )
					)
					( Origin gBackEnd )
				)
				( attribute "RELATIVE_PROPAGATION_DELAY" "TARGET,TARGET"
					( Parent
						( matchGroupRef "@crescent_city_bb_fab1_lib.crescent_city_bb_fab1(sch_1):\MG_DDR_FAR_DIMM-CLK0_CLS_DDR_L_CAC-CLKS\" )
					)
					( Units "uMatchProp" "ns" 1.000000)
					( Origin gBackEnd )
				)
				( objectStatus "M_L_CLK_DP<0>" )
			)
			( signal "@baseboard_fab2_lib.baseboard_fab2(sch_1):m_l_clk_dn(2)"
				( attribute "NO_TEST" "1"
					( Origin gBackEnd )
				)
				( objectStatus "M_L_CLK_DN<2>" )
			)
			( signal "@baseboard_fab2_lib.baseboard_fab2(sch_1):m_l_clk_dp(2)"
				( electricalCSetRef "@crescent_city_bb_fab1_lib.crescent_city_bb_fab1(sch_1):\DDR_CLK1\" )
				( attribute "RELATIVE_PROPAGATION_DELAY_SCOPE" "G"
					( Parent
						( matchGroupRef "@crescent_city_bb_fab1_lib.crescent_city_bb_fab1(sch_1):\MG_DDR_NEAR_DIMM-CLK1_CLS_DDR_L_CAC-CLKS\" )
					)
					( Origin gBackEnd )
				)
				( attribute "RELATIVE_PROPAGATION_DELAY_PATH_TYPE" "L:S"
					( Parent
						( matchGroupRef "@crescent_city_bb_fab1_lib.crescent_city_bb_fab1(sch_1):\MG_DDR_NEAR_DIMM-CLK1_CLS_DDR_L_CAC-CLKS\" )
					)
					( Origin gBackEnd )
				)
				( attribute "RELATIVE_PROPAGATION_DELAY" "TARGET,TARGET"
					( Parent
						( matchGroupRef "@crescent_city_bb_fab1_lib.crescent_city_bb_fab1(sch_1):\MG_DDR_NEAR_DIMM-CLK1_CLS_DDR_L_CAC-CLKS\" )
					)
					( Units "uMatchProp" "ns" 1.000000)
					( Origin gBackEnd )
				)
				( objectStatus "M_L_CLK_DP<2>" )
			)
			( signal "@baseboard_fab2_lib.baseboard_fab2(sch_1):m_k_c(2)"
				( pinPairRef "@baseboard_fab2_lib.baseboard_fab2(sch_1):\PP3461\" )
				( pinPairRef "@baseboard_fab2_lib.baseboard_fab2(sch_1):\PP3462\" )
				( attribute "NO_TEST" "1"
					( Origin gBackEnd )
				)
				( objectStatus "M_K_C<2>" )
			)
			( signal "@baseboard_fab2_lib.baseboard_fab2(sch_1):m_k_ma(17)"
				( pinPairRef "@baseboard_fab2_lib.baseboard_fab2(sch_1):\PP3463\" )
				( pinPairRef "@baseboard_fab2_lib.baseboard_fab2(sch_1):\PP3464\" )
				( attribute "NO_TEST" "1"
					( Origin gBackEnd )
				)
				( objectStatus "M_K_MA<17>" )
			)
			( signal "@baseboard_fab2_lib.baseboard_fab2(sch_1):m_k_ma(13)"
				( pinPairRef "@baseboard_fab2_lib.baseboard_fab2(sch_1):\PP3457\" )
				( pinPairRef "@baseboard_fab2_lib.baseboard_fab2(sch_1):\PP3458\" )
				( objectStatus "M_K_MA<13>" )
			)
			( signal "@baseboard_fab2_lib.baseboard_fab2(sch_1):m_k_ma(15)"
				( pinPairRef "@baseboard_fab2_lib.baseboard_fab2(sch_1):\PP3459\" )
				( pinPairRef "@baseboard_fab2_lib.baseboard_fab2(sch_1):\PP3460\" )
				( attribute "NO_TEST" "1"
					( Origin gBackEnd )
				)
				( objectStatus "M_K_MA<15>" )
			)
			( signal "@baseboard_fab2_lib.baseboard_fab2(sch_1):m_k_ma(14)"
				( pinPairRef "@baseboard_fab2_lib.baseboard_fab2(sch_1):\PP3453\" )
				( pinPairRef "@baseboard_fab2_lib.baseboard_fab2(sch_1):\PP3454\" )
				( attribute "NO_TEST" "1"
					( Origin gBackEnd )
				)
				( objectStatus "M_K_MA<14>" )
			)
			( signal "@baseboard_fab2_lib.baseboard_fab2(sch_1):m_k_ma(16)"
				( pinPairRef "@baseboard_fab2_lib.baseboard_fab2(sch_1):\PP3455\" )
				( pinPairRef "@baseboard_fab2_lib.baseboard_fab2(sch_1):\PP3456\" )
				( attribute "NO_TEST" "1"
					( Origin gBackEnd )
				)
				( objectStatus "M_K_MA<16>" )
			)
			( signal "@baseboard_fab2_lib.baseboard_fab2(sch_1):m_k_ba(1)"
				( pinPairRef "@baseboard_fab2_lib.baseboard_fab2(sch_1):\PP3449\" )
				( pinPairRef "@baseboard_fab2_lib.baseboard_fab2(sch_1):\PP3450\" )
				( attribute "NO_TEST" "1"
					( Origin gBackEnd )
				)
				( objectStatus "M_K_BA<1>" )
			)
			( signal "@baseboard_fab2_lib.baseboard_fab2(sch_1):m_k_ma(10)"
				( pinPairRef "@baseboard_fab2_lib.baseboard_fab2(sch_1):\PP3451\" )
				( pinPairRef "@baseboard_fab2_lib.baseboard_fab2(sch_1):\PP3452\" )
				( objectStatus "M_K_MA<10>" )
			)
			( signal "@baseboard_fab2_lib.baseboard_fab2(sch_1):m_k_ba(0)"
				( pinPairRef "@baseboard_fab2_lib.baseboard_fab2(sch_1):\PP3445\" )
				( pinPairRef "@baseboard_fab2_lib.baseboard_fab2(sch_1):\PP3446\" )
				( attribute "NO_TEST" "1"
					( Origin gBackEnd )
				)
				( objectStatus "M_K_BA<0>" )
			)
			( signal "@baseboard_fab2_lib.baseboard_fab2(sch_1):m_k_ma(0)"
				( pinPairRef "@baseboard_fab2_lib.baseboard_fab2(sch_1):\PP3447\" )
				( pinPairRef "@baseboard_fab2_lib.baseboard_fab2(sch_1):\PP3448\" )
				( attribute "NO_TEST" "1"
					( Origin gBackEnd )
				)
				( objectStatus "M_K_MA<0>" )
			)
			( signal "@baseboard_fab2_lib.baseboard_fab2(sch_1):m_k_par"
				( pinPairRef "@baseboard_fab2_lib.baseboard_fab2(sch_1):\PP3443\" )
				( pinPairRef "@baseboard_fab2_lib.baseboard_fab2(sch_1):\PP3444\" )
				( attribute "NO_TEST" "1"
					( Origin gBackEnd )
				)
				( objectStatus "M_K_PAR" )
			)
			( signal "@baseboard_fab2_lib.baseboard_fab2(sch_1):m_k_ma(1)"
				( pinPairRef "@baseboard_fab2_lib.baseboard_fab2(sch_1):\PP3439\" )
				( pinPairRef "@baseboard_fab2_lib.baseboard_fab2(sch_1):\PP3440\" )
				( attribute "NO_TEST" "1"
					( Origin gBackEnd )
				)
				( objectStatus "M_K_MA<1>" )
			)
			( signal "@baseboard_fab2_lib.baseboard_fab2(sch_1):m_k_ma(3)"
				( pinPairRef "@baseboard_fab2_lib.baseboard_fab2(sch_1):\PP3441\" )
				( pinPairRef "@baseboard_fab2_lib.baseboard_fab2(sch_1):\PP3442\" )
				( attribute "NO_TEST" "1"
					( Origin gBackEnd )
				)
				( objectStatus "M_K_MA<3>" )
			)
			( signal "@baseboard_fab2_lib.baseboard_fab2(sch_1):m_k_ma(2)"
				( pinPairRef "@baseboard_fab2_lib.baseboard_fab2(sch_1):\PP3435\" )
				( pinPairRef "@baseboard_fab2_lib.baseboard_fab2(sch_1):\PP3436\" )
				( attribute "NO_TEST" "1"
					( Origin gBackEnd )
				)
				( objectStatus "M_K_MA<2>" )
			)
			( signal "@baseboard_fab2_lib.baseboard_fab2(sch_1):m_k_ma(4)"
				( pinPairRef "@baseboard_fab2_lib.baseboard_fab2(sch_1):\PP3437\" )
				( pinPairRef "@baseboard_fab2_lib.baseboard_fab2(sch_1):\PP3438\" )
				( attribute "NO_TEST" "1"
					( Origin gBackEnd )
				)
				( objectStatus "M_K_MA<4>" )
			)
			( signal "@baseboard_fab2_lib.baseboard_fab2(sch_1):m_k_ma(5)"
				( pinPairRef "@baseboard_fab2_lib.baseboard_fab2(sch_1):\PP3431\" )
				( pinPairRef "@baseboard_fab2_lib.baseboard_fab2(sch_1):\PP3432\" )
				( attribute "NO_TEST" "1"
					( Origin gBackEnd )
				)
				( objectStatus "M_K_MA<5>" )
			)
			( signal "@baseboard_fab2_lib.baseboard_fab2(sch_1):m_k_ma(6)"
				( pinPairRef "@baseboard_fab2_lib.baseboard_fab2(sch_1):\PP3433\" )
				( pinPairRef "@baseboard_fab2_lib.baseboard_fab2(sch_1):\PP3434\" )
				( attribute "NO_TEST" "1"
					( Origin gBackEnd )
				)
				( objectStatus "M_K_MA<6>" )
			)
			( signal "@baseboard_fab2_lib.baseboard_fab2(sch_1):m_k_ma(7)"
				( pinPairRef "@baseboard_fab2_lib.baseboard_fab2(sch_1):\PP3427\" )
				( pinPairRef "@baseboard_fab2_lib.baseboard_fab2(sch_1):\PP3428\" )
				( attribute "NO_TEST" "1"
					( Origin gBackEnd )
				)
				( objectStatus "M_K_MA<7>" )
			)
			( signal "@baseboard_fab2_lib.baseboard_fab2(sch_1):m_k_ma(8)"
				( pinPairRef "@baseboard_fab2_lib.baseboard_fab2(sch_1):\PP3429\" )
				( pinPairRef "@baseboard_fab2_lib.baseboard_fab2(sch_1):\PP3430\" )
				( attribute "NO_TEST" "1"
					( Origin gBackEnd )
				)
				( objectStatus "M_K_MA<8>" )
			)
			( signal "@baseboard_fab2_lib.baseboard_fab2(sch_1):m_k_ma(9)"
				( pinPairRef "@baseboard_fab2_lib.baseboard_fab2(sch_1):\PP3423\" )
				( pinPairRef "@baseboard_fab2_lib.baseboard_fab2(sch_1):\PP3424\" )
				( objectStatus "M_K_MA<9>" )
			)
			( signal "@baseboard_fab2_lib.baseboard_fab2(sch_1):m_k_ma(12)"
				( pinPairRef "@baseboard_fab2_lib.baseboard_fab2(sch_1):\PP3425\" )
				( pinPairRef "@baseboard_fab2_lib.baseboard_fab2(sch_1):\PP3426\" )
				( objectStatus "M_K_MA<12>" )
			)
			( signal "@baseboard_fab2_lib.baseboard_fab2(sch_1):m_k_bg(1)"
				( pinPairRef "@baseboard_fab2_lib.baseboard_fab2(sch_1):\PP3419\" )
				( pinPairRef "@baseboard_fab2_lib.baseboard_fab2(sch_1):\PP3420\" )
				( objectStatus "M_K_BG<1>" )
			)
			( signal "@baseboard_fab2_lib.baseboard_fab2(sch_1):m_k_ma(11)"
				( pinPairRef "@baseboard_fab2_lib.baseboard_fab2(sch_1):\PP3421\" )
				( pinPairRef "@baseboard_fab2_lib.baseboard_fab2(sch_1):\PP3422\" )
				( attribute "NO_TEST" "1"
					( Origin gBackEnd )
				)
				( objectStatus "M_K_MA<11>" )
			)
			( signal "@baseboard_fab2_lib.baseboard_fab2(sch_1):m_k_act_n"
				( pinPairRef "@baseboard_fab2_lib.baseboard_fab2(sch_1):\PP3415\" )
				( pinPairRef "@baseboard_fab2_lib.baseboard_fab2(sch_1):\PP3416\" )
				( attribute "NO_TEST" "1"
					( Origin gBackEnd )
				)
				( objectStatus "M_K_ACT_N" )
			)
			( signal "@baseboard_fab2_lib.baseboard_fab2(sch_1):m_k_bg(0)"
				( pinPairRef "@baseboard_fab2_lib.baseboard_fab2(sch_1):\PP3417\" )
				( pinPairRef "@baseboard_fab2_lib.baseboard_fab2(sch_1):\PP3418\" )
				( attribute "NO_TEST" "1"
					( Origin gBackEnd )
				)
				( objectStatus "M_K_BG<0>" )
			)
			( signal "@baseboard_fab2_lib.baseboard_fab2(sch_1):m_k_cs_n(0)"
				( pinPairRef "@baseboard_fab2_lib.baseboard_fab2(sch_1):\PP3413\" )
				( attribute "NO_TEST" "1"
					( Origin gBackEnd )
				)
				( objectStatus "M_K_CS_N<0>" )
			)
			( signal "@baseboard_fab2_lib.baseboard_fab2(sch_1):m_k_odt(0)"
				( pinPairRef "@baseboard_fab2_lib.baseboard_fab2(sch_1):\PP3414\" )
				( attribute "NO_TEST" "1"
					( Origin gBackEnd )
				)
				( objectStatus "M_K_ODT<0>" )
			)
			( signal "@baseboard_fab2_lib.baseboard_fab2(sch_1):m_k_cke(0)"
				( pinPairRef "@baseboard_fab2_lib.baseboard_fab2(sch_1):\PP3412\" )
				( attribute "NO_TEST" "1"
					( Origin gBackEnd )
				)
				( objectStatus "M_K_CKE<0>" )
			)
			( signal "@baseboard_fab2_lib.baseboard_fab2(sch_1):m_k_cs_n(2)"
				( pinPairRef "@baseboard_fab2_lib.baseboard_fab2(sch_1):\PP3411\" )
				( attribute "NO_TEST" "1"
					( Origin gBackEnd )
				)
				( objectStatus "M_K_CS_N<2>" )
			)
			( signal "@baseboard_fab2_lib.baseboard_fab2(sch_1):m_k_cs_n(3)"
				( pinPairRef "@baseboard_fab2_lib.baseboard_fab2(sch_1):\PP3410\" )
				( attribute "NO_TEST" "1"
					( Origin gBackEnd )
				)
				( objectStatus "M_K_CS_N<3>" )
			)
			( signal "@baseboard_fab2_lib.baseboard_fab2(sch_1):m_k_cs_n(1)"
				( pinPairRef "@baseboard_fab2_lib.baseboard_fab2(sch_1):\PP3408\" )
				( attribute "NO_TEST" "1"
					( Origin gBackEnd )
				)
				( objectStatus "M_K_CS_N<1>" )
			)
			( signal "@baseboard_fab2_lib.baseboard_fab2(sch_1):m_k_odt(1)"
				( pinPairRef "@baseboard_fab2_lib.baseboard_fab2(sch_1):\PP3409\" )
				( attribute "NO_TEST" "1"
					( Origin gBackEnd )
				)
				( objectStatus "M_K_ODT<1>" )
			)
			( signal "@baseboard_fab2_lib.baseboard_fab2(sch_1):m_k_cke(1)"
				( pinPairRef "@baseboard_fab2_lib.baseboard_fab2(sch_1):\PP3407\" )
				( attribute "NO_TEST" "1"
					( Origin gBackEnd )
				)
				( objectStatus "M_K_CKE<1>" )
			)
			( signal "@baseboard_fab2_lib.baseboard_fab2(sch_1):m_k_cs_n(4)"
				( pinPairRef "@baseboard_fab2_lib.baseboard_fab2(sch_1):\PP3405\" )
				( attribute "NO_TEST" "1"
					( Origin gBackEnd )
				)
				( objectStatus "M_K_CS_N<4>" )
			)
			( signal "@baseboard_fab2_lib.baseboard_fab2(sch_1):m_k_odt(2)"
				( pinPairRef "@baseboard_fab2_lib.baseboard_fab2(sch_1):\PP3406\" )
				( attribute "NO_TEST" "1"
					( Origin gBackEnd )
				)
				( objectStatus "M_K_ODT<2>" )
			)
			( signal "@baseboard_fab2_lib.baseboard_fab2(sch_1):m_k_cke(2)"
				( pinPairRef "@baseboard_fab2_lib.baseboard_fab2(sch_1):\PP3404\" )
				( attribute "NO_TEST" "1"
					( Origin gBackEnd )
				)
				( objectStatus "M_K_CKE<2>" )
			)
			( signal "@baseboard_fab2_lib.baseboard_fab2(sch_1):m_k_cs_n(6)"
				( pinPairRef "@baseboard_fab2_lib.baseboard_fab2(sch_1):\PP3402\" )
				( attribute "NO_TEST" "1"
					( Origin gBackEnd )
				)
				( objectStatus "M_K_CS_N<6>" )
			)
			( signal "@baseboard_fab2_lib.baseboard_fab2(sch_1):m_k_cs_n(7)"
				( pinPairRef "@baseboard_fab2_lib.baseboard_fab2(sch_1):\PP3403\" )
				( attribute "NO_TEST" "1"
					( Origin gBackEnd )
				)
				( objectStatus "M_K_CS_N<7>" )
			)
			( signal "@baseboard_fab2_lib.baseboard_fab2(sch_1):m_k_cs_n(5)"
				( pinPairRef "@baseboard_fab2_lib.baseboard_fab2(sch_1):\PP3400\" )
				( attribute "NO_TEST" "1"
					( Origin gBackEnd )
				)
				( objectStatus "M_K_CS_N<5>" )
			)
			( signal "@baseboard_fab2_lib.baseboard_fab2(sch_1):m_k_odt(3)"
				( pinPairRef "@baseboard_fab2_lib.baseboard_fab2(sch_1):\PP3401\" )
				( attribute "NO_TEST" "1"
					( Origin gBackEnd )
				)
				( objectStatus "M_K_ODT<3>" )
			)
			( signal "@baseboard_fab2_lib.baseboard_fab2(sch_1):m_k_cke(3)"
				( pinPairRef "@baseboard_fab2_lib.baseboard_fab2(sch_1):\PP3399\" )
				( attribute "NO_TEST" "1"
					( Origin gBackEnd )
				)
				( objectStatus "M_K_CKE<3>" )
			)
			( signal "@baseboard_fab2_lib.baseboard_fab2(sch_1):m_k_clk_dn(0)"
				( attribute "NO_TEST" "1"
					( Origin gBackEnd )
				)
				( objectStatus "M_K_CLK_DN<0>" )
			)
			( signal "@baseboard_fab2_lib.baseboard_fab2(sch_1):m_k_clk_dp(0)"
				( electricalCSetRef "@crescent_city_bb_fab1_lib.crescent_city_bb_fab1(sch_1):\M_A_CLK_DP_0_\" )
				( attribute "NO_TEST" "1"
					( Origin gBackEnd )
				)
				( attribute "RELATIVE_PROPAGATION_DELAY_SCOPE" "G"
					( Parent
						( matchGroupRef "@crescent_city_bb_fab1_lib.crescent_city_bb_fab1(sch_1):\MG_DDR_FAR_DIMM-CLK0_CLS_DDR_K_CAC-CLKS\" )
					)
					( Origin gBackEnd )
				)
				( attribute "RELATIVE_PROPAGATION_DELAY_PATH_TYPE" "L:S"
					( Parent
						( matchGroupRef "@crescent_city_bb_fab1_lib.crescent_city_bb_fab1(sch_1):\MG_DDR_FAR_DIMM-CLK0_CLS_DDR_K_CAC-CLKS\" )
					)
					( Origin gBackEnd )
				)
				( attribute "RELATIVE_PROPAGATION_DELAY" "TARGET,TARGET"
					( Parent
						( matchGroupRef "@crescent_city_bb_fab1_lib.crescent_city_bb_fab1(sch_1):\MG_DDR_FAR_DIMM-CLK0_CLS_DDR_K_CAC-CLKS\" )
					)
					( Units "uMatchProp" "ns" 1.000000)
					( Origin gBackEnd )
				)
				( objectStatus "M_K_CLK_DP<0>" )
			)
			( signal "@baseboard_fab2_lib.baseboard_fab2(sch_1):m_k_clk_dp(2)"
				( electricalCSetRef "@crescent_city_bb_fab1_lib.crescent_city_bb_fab1(sch_1):\DDR_CLK1\" )
				( attribute "NO_TEST" "1"
					( Origin gBackEnd )
				)
				( attribute "RELATIVE_PROPAGATION_DELAY_SCOPE" "G"
					( Parent
						( matchGroupRef "@crescent_city_bb_fab1_lib.crescent_city_bb_fab1(sch_1):\MG_DDR_NEAR_DIMM-CLK1_CLS_DDR_K_CAC-CLKS\" )
					)
					( Origin gBackEnd )
				)
				( attribute "RELATIVE_PROPAGATION_DELAY_PATH_TYPE" "L:S"
					( Parent
						( matchGroupRef "@crescent_city_bb_fab1_lib.crescent_city_bb_fab1(sch_1):\MG_DDR_NEAR_DIMM-CLK1_CLS_DDR_K_CAC-CLKS\" )
					)
					( Origin gBackEnd )
				)
				( attribute "RELATIVE_PROPAGATION_DELAY" "TARGET,TARGET"
					( Parent
						( matchGroupRef "@crescent_city_bb_fab1_lib.crescent_city_bb_fab1(sch_1):\MG_DDR_NEAR_DIMM-CLK1_CLS_DDR_K_CAC-CLKS\" )
					)
					( Units "uMatchProp" "ns" 1.000000)
					( Origin gBackEnd )
				)
				( objectStatus "M_K_CLK_DP<2>" )
			)
			( signal "@baseboard_fab2_lib.baseboard_fab2(sch_1):m_k_clk_dn(2)"
				( attribute "NO_TEST" "1"
					( Origin gBackEnd )
				)
				( objectStatus "M_K_CLK_DN<2>" )
			)
			( signal "@baseboard_fab2_lib.baseboard_fab2(sch_1):m_j_c(2)"
				( pinPairRef "@baseboard_fab2_lib.baseboard_fab2(sch_1):\PP3527\" )
				( pinPairRef "@baseboard_fab2_lib.baseboard_fab2(sch_1):\PP3528\" )
				( objectStatus "M_J_C<2>" )
			)
			( signal "@baseboard_fab2_lib.baseboard_fab2(sch_1):m_j_ma(17)"
				( pinPairRef "@baseboard_fab2_lib.baseboard_fab2(sch_1):\PP3529\" )
				( pinPairRef "@baseboard_fab2_lib.baseboard_fab2(sch_1):\PP3530\" )
				( attribute "NO_TEST" "1"
					( Origin gBackEnd )
				)
				( objectStatus "M_J_MA<17>" )
			)
			( signal "@baseboard_fab2_lib.baseboard_fab2(sch_1):m_j_ma(13)"
				( pinPairRef "@baseboard_fab2_lib.baseboard_fab2(sch_1):\PP3523\" )
				( pinPairRef "@baseboard_fab2_lib.baseboard_fab2(sch_1):\PP3524\" )
				( attribute "NO_TEST" "1"
					( Origin gBackEnd )
				)
				( objectStatus "M_J_MA<13>" )
			)
			( signal "@baseboard_fab2_lib.baseboard_fab2(sch_1):m_j_ma(15)"
				( pinPairRef "@baseboard_fab2_lib.baseboard_fab2(sch_1):\PP3525\" )
				( pinPairRef "@baseboard_fab2_lib.baseboard_fab2(sch_1):\PP3526\" )
				( objectStatus "M_J_MA<15>" )
			)
			( signal "@baseboard_fab2_lib.baseboard_fab2(sch_1):m_j_ma(14)"
				( pinPairRef "@baseboard_fab2_lib.baseboard_fab2(sch_1):\PP3519\" )
				( pinPairRef "@baseboard_fab2_lib.baseboard_fab2(sch_1):\PP3520\" )
				( objectStatus "M_J_MA<14>" )
			)
			( signal "@baseboard_fab2_lib.baseboard_fab2(sch_1):m_j_ma(16)"
				( pinPairRef "@baseboard_fab2_lib.baseboard_fab2(sch_1):\PP3521\" )
				( pinPairRef "@baseboard_fab2_lib.baseboard_fab2(sch_1):\PP3522\" )
				( objectStatus "M_J_MA<16>" )
			)
			( signal "@baseboard_fab2_lib.baseboard_fab2(sch_1):m_j_ba(1)"
				( pinPairRef "@baseboard_fab2_lib.baseboard_fab2(sch_1):\PP3515\" )
				( pinPairRef "@baseboard_fab2_lib.baseboard_fab2(sch_1):\PP3516\" )
				( objectStatus "M_J_BA<1>" )
			)
			( signal "@baseboard_fab2_lib.baseboard_fab2(sch_1):m_j_ma(10)"
				( pinPairRef "@baseboard_fab2_lib.baseboard_fab2(sch_1):\PP3517\" )
				( pinPairRef "@baseboard_fab2_lib.baseboard_fab2(sch_1):\PP3518\" )
				( attribute "NO_TEST" "1"
					( Origin gBackEnd )
				)
				( objectStatus "M_J_MA<10>" )
			)
			( signal "@baseboard_fab2_lib.baseboard_fab2(sch_1):m_j_ba(0)"
				( pinPairRef "@baseboard_fab2_lib.baseboard_fab2(sch_1):\PP3511\" )
				( pinPairRef "@baseboard_fab2_lib.baseboard_fab2(sch_1):\PP3512\" )
				( attribute "NO_TEST" "1"
					( Origin gBackEnd )
				)
				( objectStatus "M_J_BA<0>" )
			)
			( signal "@baseboard_fab2_lib.baseboard_fab2(sch_1):m_j_ma(0)"
				( pinPairRef "@baseboard_fab2_lib.baseboard_fab2(sch_1):\PP3513\" )
				( pinPairRef "@baseboard_fab2_lib.baseboard_fab2(sch_1):\PP3514\" )
				( attribute "NO_TEST" "1"
					( Origin gBackEnd )
				)
				( objectStatus "M_J_MA<0>" )
			)
			( signal "@baseboard_fab2_lib.baseboard_fab2(sch_1):m_j_par"
				( pinPairRef "@baseboard_fab2_lib.baseboard_fab2(sch_1):\PP3509\" )
				( pinPairRef "@baseboard_fab2_lib.baseboard_fab2(sch_1):\PP3510\" )
				( attribute "NO_TEST" "1"
					( Origin gBackEnd )
				)
				( objectStatus "M_J_PAR" )
			)
			( signal "@baseboard_fab2_lib.baseboard_fab2(sch_1):m_j_ma(1)"
				( pinPairRef "@baseboard_fab2_lib.baseboard_fab2(sch_1):\PP3505\" )
				( pinPairRef "@baseboard_fab2_lib.baseboard_fab2(sch_1):\PP3506\" )
				( objectStatus "M_J_MA<1>" )
			)
			( signal "@baseboard_fab2_lib.baseboard_fab2(sch_1):m_j_ma(3)"
				( pinPairRef "@baseboard_fab2_lib.baseboard_fab2(sch_1):\PP3507\" )
				( pinPairRef "@baseboard_fab2_lib.baseboard_fab2(sch_1):\PP3508\" )
				( objectStatus "M_J_MA<3>" )
			)
			( signal "@baseboard_fab2_lib.baseboard_fab2(sch_1):m_j_ma(2)"
				( pinPairRef "@baseboard_fab2_lib.baseboard_fab2(sch_1):\PP3501\" )
				( pinPairRef "@baseboard_fab2_lib.baseboard_fab2(sch_1):\PP3502\" )
				( attribute "NO_TEST" "1"
					( Origin gBackEnd )
				)
				( objectStatus "M_J_MA<2>" )
			)
			( signal "@baseboard_fab2_lib.baseboard_fab2(sch_1):m_j_ma(4)"
				( pinPairRef "@baseboard_fab2_lib.baseboard_fab2(sch_1):\PP3503\" )
				( pinPairRef "@baseboard_fab2_lib.baseboard_fab2(sch_1):\PP3504\" )
				( attribute "NO_TEST" "1"
					( Origin gBackEnd )
				)
				( objectStatus "M_J_MA<4>" )
			)
			( signal "@baseboard_fab2_lib.baseboard_fab2(sch_1):m_j_ma(5)"
				( pinPairRef "@baseboard_fab2_lib.baseboard_fab2(sch_1):\PP3497\" )
				( pinPairRef "@baseboard_fab2_lib.baseboard_fab2(sch_1):\PP3498\" )
				( attribute "NO_TEST" "1"
					( Origin gBackEnd )
				)
				( objectStatus "M_J_MA<5>" )
			)
			( signal "@baseboard_fab2_lib.baseboard_fab2(sch_1):m_j_ma(6)"
				( pinPairRef "@baseboard_fab2_lib.baseboard_fab2(sch_1):\PP3499\" )
				( pinPairRef "@baseboard_fab2_lib.baseboard_fab2(sch_1):\PP3500\" )
				( objectStatus "M_J_MA<6>" )
			)
			( signal "@baseboard_fab2_lib.baseboard_fab2(sch_1):m_j_ma(7)"
				( pinPairRef "@baseboard_fab2_lib.baseboard_fab2(sch_1):\PP3493\" )
				( pinPairRef "@baseboard_fab2_lib.baseboard_fab2(sch_1):\PP3494\" )
				( objectStatus "M_J_MA<7>" )
			)
			( signal "@baseboard_fab2_lib.baseboard_fab2(sch_1):m_j_ma(8)"
				( pinPairRef "@baseboard_fab2_lib.baseboard_fab2(sch_1):\PP3495\" )
				( pinPairRef "@baseboard_fab2_lib.baseboard_fab2(sch_1):\PP3496\" )
				( attribute "NO_TEST" "1"
					( Origin gBackEnd )
				)
				( objectStatus "M_J_MA<8>" )
			)
			( signal "@baseboard_fab2_lib.baseboard_fab2(sch_1):m_j_ma(9)"
				( pinPairRef "@baseboard_fab2_lib.baseboard_fab2(sch_1):\PP3489\" )
				( pinPairRef "@baseboard_fab2_lib.baseboard_fab2(sch_1):\PP3490\" )
				( attribute "NO_TEST" "1"
					( Origin gBackEnd )
				)
				( objectStatus "M_J_MA<9>" )
			)
			( signal "@baseboard_fab2_lib.baseboard_fab2(sch_1):m_j_ma(12)"
				( pinPairRef "@baseboard_fab2_lib.baseboard_fab2(sch_1):\PP3491\" )
				( pinPairRef "@baseboard_fab2_lib.baseboard_fab2(sch_1):\PP3492\" )
				( attribute "NO_TEST" "1"
					( Origin gBackEnd )
				)
				( objectStatus "M_J_MA<12>" )
			)
			( signal "@baseboard_fab2_lib.baseboard_fab2(sch_1):m_j_bg(1)"
				( pinPairRef "@baseboard_fab2_lib.baseboard_fab2(sch_1):\PP3485\" )
				( pinPairRef "@baseboard_fab2_lib.baseboard_fab2(sch_1):\PP3486\" )
				( objectStatus "M_J_BG<1>" )
			)
			( signal "@baseboard_fab2_lib.baseboard_fab2(sch_1):m_j_ma(11)"
				( pinPairRef "@baseboard_fab2_lib.baseboard_fab2(sch_1):\PP3487\" )
				( pinPairRef "@baseboard_fab2_lib.baseboard_fab2(sch_1):\PP3488\" )
				( attribute "NO_TEST" "1"
					( Origin gBackEnd )
				)
				( objectStatus "M_J_MA<11>" )
			)
			( signal "@baseboard_fab2_lib.baseboard_fab2(sch_1):m_j_act_n"
				( pinPairRef "@baseboard_fab2_lib.baseboard_fab2(sch_1):\PP3481\" )
				( pinPairRef "@baseboard_fab2_lib.baseboard_fab2(sch_1):\PP3482\" )
				( objectStatus "M_J_ACT_N" )
			)
			( signal "@baseboard_fab2_lib.baseboard_fab2(sch_1):m_j_bg(0)"
				( pinPairRef "@baseboard_fab2_lib.baseboard_fab2(sch_1):\PP3483\" )
				( pinPairRef "@baseboard_fab2_lib.baseboard_fab2(sch_1):\PP3484\" )
				( attribute "NO_TEST" "1"
					( Origin gBackEnd )
				)
				( objectStatus "M_J_BG<0>" )
			)
			( signal "@baseboard_fab2_lib.baseboard_fab2(sch_1):m_j_cs_n(0)"
				( pinPairRef "@baseboard_fab2_lib.baseboard_fab2(sch_1):\PP3479\" )
				( attribute "NO_TEST" "1"
					( Origin gBackEnd )
				)
				( objectStatus "M_J_CS_N<0>" )
			)
			( signal "@baseboard_fab2_lib.baseboard_fab2(sch_1):m_j_odt(0)"
				( pinPairRef "@baseboard_fab2_lib.baseboard_fab2(sch_1):\PP3480\" )
				( attribute "NO_TEST" "1"
					( Origin gBackEnd )
				)
				( objectStatus "M_J_ODT<0>" )
			)
			( signal "@baseboard_fab2_lib.baseboard_fab2(sch_1):m_j_cke(0)"
				( pinPairRef "@baseboard_fab2_lib.baseboard_fab2(sch_1):\PP3478\" )
				( attribute "NO_TEST" "1"
					( Origin gBackEnd )
				)
				( objectStatus "M_J_CKE<0>" )
			)
			( signal "@baseboard_fab2_lib.baseboard_fab2(sch_1):m_j_cs_n(2)"
				( pinPairRef "@baseboard_fab2_lib.baseboard_fab2(sch_1):\PP3477\" )
				( objectStatus "M_J_CS_N<2>" )
			)
			( signal "@baseboard_fab2_lib.baseboard_fab2(sch_1):m_j_cs_n(3)"
				( pinPairRef "@baseboard_fab2_lib.baseboard_fab2(sch_1):\PP3476\" )
				( attribute "NO_TEST" "1"
					( Origin gBackEnd )
				)
				( objectStatus "M_J_CS_N<3>" )
			)
			( signal "@baseboard_fab2_lib.baseboard_fab2(sch_1):m_j_cs_n(1)"
				( pinPairRef "@baseboard_fab2_lib.baseboard_fab2(sch_1):\PP3474\" )
				( objectStatus "M_J_CS_N<1>" )
			)
			( signal "@baseboard_fab2_lib.baseboard_fab2(sch_1):m_j_odt(1)"
				( pinPairRef "@baseboard_fab2_lib.baseboard_fab2(sch_1):\PP3475\" )
				( attribute "NO_TEST" "1"
					( Origin gBackEnd )
				)
				( objectStatus "M_J_ODT<1>" )
			)
			( signal "@baseboard_fab2_lib.baseboard_fab2(sch_1):m_j_cke(1)"
				( pinPairRef "@baseboard_fab2_lib.baseboard_fab2(sch_1):\PP3473\" )
				( attribute "NO_TEST" "1"
					( Origin gBackEnd )
				)
				( objectStatus "M_J_CKE<1>" )
			)
			( signal "@baseboard_fab2_lib.baseboard_fab2(sch_1):m_j_cs_n(4)"
				( pinPairRef "@baseboard_fab2_lib.baseboard_fab2(sch_1):\PP3471\" )
				( attribute "NO_TEST" "1"
					( Origin gBackEnd )
				)
				( objectStatus "M_J_CS_N<4>" )
			)
			( signal "@baseboard_fab2_lib.baseboard_fab2(sch_1):m_j_odt(2)"
				( pinPairRef "@baseboard_fab2_lib.baseboard_fab2(sch_1):\PP3472\" )
				( attribute "NO_TEST" "1"
					( Origin gBackEnd )
				)
				( objectStatus "M_J_ODT<2>" )
			)
			( signal "@baseboard_fab2_lib.baseboard_fab2(sch_1):m_j_cke(2)"
				( pinPairRef "@baseboard_fab2_lib.baseboard_fab2(sch_1):\PP3470\" )
				( attribute "NO_TEST" "1"
					( Origin gBackEnd )
				)
				( objectStatus "M_J_CKE<2>" )
			)
			( signal "@baseboard_fab2_lib.baseboard_fab2(sch_1):m_j_cs_n(6)"
				( pinPairRef "@baseboard_fab2_lib.baseboard_fab2(sch_1):\PP3468\" )
				( objectStatus "M_J_CS_N<6>" )
			)
			( signal "@baseboard_fab2_lib.baseboard_fab2(sch_1):m_j_cs_n(7)"
				( pinPairRef "@baseboard_fab2_lib.baseboard_fab2(sch_1):\PP3469\" )
				( attribute "NO_TEST" "1"
					( Origin gBackEnd )
				)
				( objectStatus "M_J_CS_N<7>" )
			)
			( signal "@baseboard_fab2_lib.baseboard_fab2(sch_1):m_j_cs_n(5)"
				( pinPairRef "@baseboard_fab2_lib.baseboard_fab2(sch_1):\PP3466\" )
				( objectStatus "M_J_CS_N<5>" )
			)
			( signal "@baseboard_fab2_lib.baseboard_fab2(sch_1):m_j_odt(3)"
				( pinPairRef "@baseboard_fab2_lib.baseboard_fab2(sch_1):\PP3467\" )
				( objectStatus "M_J_ODT<3>" )
			)
			( signal "@baseboard_fab2_lib.baseboard_fab2(sch_1):m_j_cke(3)"
				( pinPairRef "@baseboard_fab2_lib.baseboard_fab2(sch_1):\PP3465\" )
				( objectStatus "M_J_CKE<3>" )
			)
			( signal "@baseboard_fab2_lib.baseboard_fab2(sch_1):m_j_clk_dn(0)"
				( attribute "NO_TEST" "1"
					( Origin gBackEnd )
				)
				( objectStatus "M_J_CLK_DN<0>" )
			)
			( signal "@baseboard_fab2_lib.baseboard_fab2(sch_1):m_j_clk_dp(0)"
				( electricalCSetRef "@crescent_city_bb_fab1_lib.crescent_city_bb_fab1(sch_1):\M_A_CLK_DP_0_\" )
				( attribute "RELATIVE_PROPAGATION_DELAY_SCOPE" "G"
					( Parent
						( matchGroupRef "@crescent_city_bb_fab1_lib.crescent_city_bb_fab1(sch_1):\MG_DDR_FAR_DIMM-CLK0_CLS_DDR_J_CAC-CLKS\" )
					)
					( Origin gBackEnd )
				)
				( attribute "RELATIVE_PROPAGATION_DELAY_PATH_TYPE" "L:S"
					( Parent
						( matchGroupRef "@crescent_city_bb_fab1_lib.crescent_city_bb_fab1(sch_1):\MG_DDR_FAR_DIMM-CLK0_CLS_DDR_J_CAC-CLKS\" )
					)
					( Origin gBackEnd )
				)
				( attribute "RELATIVE_PROPAGATION_DELAY" "TARGET,TARGET"
					( Parent
						( matchGroupRef "@crescent_city_bb_fab1_lib.crescent_city_bb_fab1(sch_1):\MG_DDR_FAR_DIMM-CLK0_CLS_DDR_J_CAC-CLKS\" )
					)
					( Units "uMatchProp" "ns" 1.000000)
					( Origin gBackEnd )
				)
				( objectStatus "M_J_CLK_DP<0>" )
			)
			( signal "@baseboard_fab2_lib.baseboard_fab2(sch_1):m_j_clk_dp(2)"
				( electricalCSetRef "@crescent_city_bb_fab1_lib.crescent_city_bb_fab1(sch_1):\DDR_CLK1\" )
				( attribute "RELATIVE_PROPAGATION_DELAY_SCOPE" "G"
					( Parent
						( matchGroupRef "@crescent_city_bb_fab1_lib.crescent_city_bb_fab1(sch_1):\MG_DDR_NEAR_DIMM-CLK1_CLS_DDR_J_CAC-CLKS\" )
					)
					( Origin gBackEnd )
				)
				( attribute "RELATIVE_PROPAGATION_DELAY_PATH_TYPE" "L:S"
					( Parent
						( matchGroupRef "@crescent_city_bb_fab1_lib.crescent_city_bb_fab1(sch_1):\MG_DDR_NEAR_DIMM-CLK1_CLS_DDR_J_CAC-CLKS\" )
					)
					( Origin gBackEnd )
				)
				( attribute "RELATIVE_PROPAGATION_DELAY" "TARGET,TARGET"
					( Parent
						( matchGroupRef "@crescent_city_bb_fab1_lib.crescent_city_bb_fab1(sch_1):\MG_DDR_NEAR_DIMM-CLK1_CLS_DDR_J_CAC-CLKS\" )
					)
					( Units "uMatchProp" "ns" 1.000000)
					( Origin gBackEnd )
				)
				( objectStatus "M_J_CLK_DP<2>" )
			)
			( signal "@baseboard_fab2_lib.baseboard_fab2(sch_1):m_j_clk_dn(2)"
				( attribute "NO_TEST" "1"
					( Origin gBackEnd )
				)
				( objectStatus "M_J_CLK_DN<2>" )
			)
			( signal "@baseboard_fab2_lib.baseboard_fab2(sch_1):m_h_c(2)"
				( pinPairRef "@baseboard_fab2_lib.baseboard_fab2(sch_1):\PP3593\" )
				( pinPairRef "@baseboard_fab2_lib.baseboard_fab2(sch_1):\PP3594\" )
				( attribute "NO_TEST" "1"
					( Origin gBackEnd )
				)
				( objectStatus "M_H_C<2>" )
			)
			( signal "@baseboard_fab2_lib.baseboard_fab2(sch_1):m_h_ma(17)"
				( pinPairRef "@baseboard_fab2_lib.baseboard_fab2(sch_1):\PP3595\" )
				( pinPairRef "@baseboard_fab2_lib.baseboard_fab2(sch_1):\PP3596\" )
				( objectStatus "M_H_MA<17>" )
			)
			( signal "@baseboard_fab2_lib.baseboard_fab2(sch_1):m_h_ma(13)"
				( pinPairRef "@baseboard_fab2_lib.baseboard_fab2(sch_1):\PP3589\" )
				( pinPairRef "@baseboard_fab2_lib.baseboard_fab2(sch_1):\PP3590\" )
				( attribute "NO_TEST" "1"
					( Origin gBackEnd )
				)
				( objectStatus "M_H_MA<13>" )
			)
			( signal "@baseboard_fab2_lib.baseboard_fab2(sch_1):m_h_ma(14)"
				( pinPairRef "@baseboard_fab2_lib.baseboard_fab2(sch_1):\PP3591\" )
				( pinPairRef "@baseboard_fab2_lib.baseboard_fab2(sch_1):\PP3592\" )
				( objectStatus "M_H_MA<14>" )
			)
			( signal "@baseboard_fab2_lib.baseboard_fab2(sch_1):m_h_ma(15)"
				( pinPairRef "@baseboard_fab2_lib.baseboard_fab2(sch_1):\PP3585\" )
				( pinPairRef "@baseboard_fab2_lib.baseboard_fab2(sch_1):\PP3586\" )
				( objectStatus "M_H_MA<15>" )
			)
			( signal "@baseboard_fab2_lib.baseboard_fab2(sch_1):m_h_ma(16)"
				( pinPairRef "@baseboard_fab2_lib.baseboard_fab2(sch_1):\PP3587\" )
				( pinPairRef "@baseboard_fab2_lib.baseboard_fab2(sch_1):\PP3588\" )
				( attribute "NO_TEST" "1"
					( Origin gBackEnd )
				)
				( objectStatus "M_H_MA<16>" )
			)
			( signal "@baseboard_fab2_lib.baseboard_fab2(sch_1):m_h_ba(1)"
				( pinPairRef "@baseboard_fab2_lib.baseboard_fab2(sch_1):\PP3581\" )
				( pinPairRef "@baseboard_fab2_lib.baseboard_fab2(sch_1):\PP3582\" )
				( attribute "NO_TEST" "1"
					( Origin gBackEnd )
				)
				( objectStatus "M_H_BA<1>" )
			)
			( signal "@baseboard_fab2_lib.baseboard_fab2(sch_1):m_h_ma(10)"
				( pinPairRef "@baseboard_fab2_lib.baseboard_fab2(sch_1):\PP3583\" )
				( pinPairRef "@baseboard_fab2_lib.baseboard_fab2(sch_1):\PP3584\" )
				( attribute "NO_TEST" "1"
					( Origin gBackEnd )
				)
				( objectStatus "M_H_MA<10>" )
			)
			( signal "@baseboard_fab2_lib.baseboard_fab2(sch_1):m_h_ba(0)"
				( pinPairRef "@baseboard_fab2_lib.baseboard_fab2(sch_1):\PP3577\" )
				( pinPairRef "@baseboard_fab2_lib.baseboard_fab2(sch_1):\PP3578\" )
				( objectStatus "M_H_BA<0>" )
			)
			( signal "@baseboard_fab2_lib.baseboard_fab2(sch_1):m_h_ma(0)"
				( pinPairRef "@baseboard_fab2_lib.baseboard_fab2(sch_1):\PP3579\" )
				( pinPairRef "@baseboard_fab2_lib.baseboard_fab2(sch_1):\PP3580\" )
				( objectStatus "M_H_MA<0>" )
			)
			( signal "@baseboard_fab2_lib.baseboard_fab2(sch_1):m_h_par"
				( pinPairRef "@baseboard_fab2_lib.baseboard_fab2(sch_1):\PP3575\" )
				( pinPairRef "@baseboard_fab2_lib.baseboard_fab2(sch_1):\PP3576\" )
				( attribute "NO_TEST" "1"
					( Origin gBackEnd )
				)
				( objectStatus "M_H_PAR" )
			)
			( signal "@baseboard_fab2_lib.baseboard_fab2(sch_1):m_h_ma(1)"
				( pinPairRef "@baseboard_fab2_lib.baseboard_fab2(sch_1):\PP3571\" )
				( pinPairRef "@baseboard_fab2_lib.baseboard_fab2(sch_1):\PP3572\" )
				( objectStatus "M_H_MA<1>" )
			)
			( signal "@baseboard_fab2_lib.baseboard_fab2(sch_1):m_h_ma(3)"
				( pinPairRef "@baseboard_fab2_lib.baseboard_fab2(sch_1):\PP3573\" )
				( pinPairRef "@baseboard_fab2_lib.baseboard_fab2(sch_1):\PP3574\" )
				( objectStatus "M_H_MA<3>" )
			)
			( signal "@baseboard_fab2_lib.baseboard_fab2(sch_1):m_h_ma(2)"
				( pinPairRef "@baseboard_fab2_lib.baseboard_fab2(sch_1):\PP3567\" )
				( pinPairRef "@baseboard_fab2_lib.baseboard_fab2(sch_1):\PP3568\" )
				( attribute "NO_TEST" "1"
					( Origin gBackEnd )
				)
				( objectStatus "M_H_MA<2>" )
			)
			( signal "@baseboard_fab2_lib.baseboard_fab2(sch_1):m_h_ma(4)"
				( pinPairRef "@baseboard_fab2_lib.baseboard_fab2(sch_1):\PP3569\" )
				( pinPairRef "@baseboard_fab2_lib.baseboard_fab2(sch_1):\PP3570\" )
				( attribute "NO_TEST" "1"
					( Origin gBackEnd )
				)
				( objectStatus "M_H_MA<4>" )
			)
			( signal "@baseboard_fab2_lib.baseboard_fab2(sch_1):m_h_ma(5)"
				( pinPairRef "@baseboard_fab2_lib.baseboard_fab2(sch_1):\PP3563\" )
				( pinPairRef "@baseboard_fab2_lib.baseboard_fab2(sch_1):\PP3564\" )
				( attribute "NO_TEST" "1"
					( Origin gBackEnd )
				)
				( objectStatus "M_H_MA<5>" )
			)
			( signal "@baseboard_fab2_lib.baseboard_fab2(sch_1):m_h_ma(6)"
				( pinPairRef "@baseboard_fab2_lib.baseboard_fab2(sch_1):\PP3565\" )
				( pinPairRef "@baseboard_fab2_lib.baseboard_fab2(sch_1):\PP3566\" )
				( objectStatus "M_H_MA<6>" )
			)
			( signal "@baseboard_fab2_lib.baseboard_fab2(sch_1):m_h_ma(7)"
				( pinPairRef "@baseboard_fab2_lib.baseboard_fab2(sch_1):\PP3559\" )
				( pinPairRef "@baseboard_fab2_lib.baseboard_fab2(sch_1):\PP3560\" )
				( attribute "NO_TEST" "1"
					( Origin gBackEnd )
				)
				( objectStatus "M_H_MA<7>" )
			)
			( signal "@baseboard_fab2_lib.baseboard_fab2(sch_1):m_h_ma(8)"
				( pinPairRef "@baseboard_fab2_lib.baseboard_fab2(sch_1):\PP3561\" )
				( pinPairRef "@baseboard_fab2_lib.baseboard_fab2(sch_1):\PP3562\" )
				( objectStatus "M_H_MA<8>" )
			)
			( signal "@baseboard_fab2_lib.baseboard_fab2(sch_1):m_h_ma(9)"
				( pinPairRef "@baseboard_fab2_lib.baseboard_fab2(sch_1):\PP3555\" )
				( pinPairRef "@baseboard_fab2_lib.baseboard_fab2(sch_1):\PP3556\" )
				( attribute "NO_TEST" "1"
					( Origin gBackEnd )
				)
				( objectStatus "M_H_MA<9>" )
			)
			( signal "@baseboard_fab2_lib.baseboard_fab2(sch_1):m_h_ma(12)"
				( pinPairRef "@baseboard_fab2_lib.baseboard_fab2(sch_1):\PP3557\" )
				( pinPairRef "@baseboard_fab2_lib.baseboard_fab2(sch_1):\PP3558\" )
				( objectStatus "M_H_MA<12>" )
			)
			( signal "@baseboard_fab2_lib.baseboard_fab2(sch_1):m_h_bg(1)"
				( pinPairRef "@baseboard_fab2_lib.baseboard_fab2(sch_1):\PP3551\" )
				( pinPairRef "@baseboard_fab2_lib.baseboard_fab2(sch_1):\PP3552\" )
				( objectStatus "M_H_BG<1>" )
			)
			( signal "@baseboard_fab2_lib.baseboard_fab2(sch_1):m_h_ma(11)"
				( pinPairRef "@baseboard_fab2_lib.baseboard_fab2(sch_1):\PP3553\" )
				( pinPairRef "@baseboard_fab2_lib.baseboard_fab2(sch_1):\PP3554\" )
				( attribute "NO_TEST" "1"
					( Origin gBackEnd )
				)
				( objectStatus "M_H_MA<11>" )
			)
			( signal "@baseboard_fab2_lib.baseboard_fab2(sch_1):m_h_act_n"
				( pinPairRef "@baseboard_fab2_lib.baseboard_fab2(sch_1):\PP3547\" )
				( pinPairRef "@baseboard_fab2_lib.baseboard_fab2(sch_1):\PP3548\" )
				( objectStatus "M_H_ACT_N" )
			)
			( signal "@baseboard_fab2_lib.baseboard_fab2(sch_1):m_h_bg(0)"
				( pinPairRef "@baseboard_fab2_lib.baseboard_fab2(sch_1):\PP3549\" )
				( pinPairRef "@baseboard_fab2_lib.baseboard_fab2(sch_1):\PP3550\" )
				( attribute "NO_TEST" "1"
					( Origin gBackEnd )
				)
				( objectStatus "M_H_BG<0>" )
			)
			( signal "@baseboard_fab2_lib.baseboard_fab2(sch_1):m_h_cs_n(0)"
				( pinPairRef "@baseboard_fab2_lib.baseboard_fab2(sch_1):\PP3545\" )
				( attribute "NO_TEST" "1"
					( Origin gBackEnd )
				)
				( objectStatus "M_H_CS_N<0>" )
			)
			( signal "@baseboard_fab2_lib.baseboard_fab2(sch_1):m_h_odt(0)"
				( pinPairRef "@baseboard_fab2_lib.baseboard_fab2(sch_1):\PP3546\" )
				( objectStatus "M_H_ODT<0>" )
			)
			( signal "@baseboard_fab2_lib.baseboard_fab2(sch_1):m_h_cke(0)"
				( pinPairRef "@baseboard_fab2_lib.baseboard_fab2(sch_1):\PP3544\" )
				( objectStatus "M_H_CKE<0>" )
			)
			( signal "@baseboard_fab2_lib.baseboard_fab2(sch_1):m_h_cs_n(2)"
				( pinPairRef "@baseboard_fab2_lib.baseboard_fab2(sch_1):\PP3543\" )
				( objectStatus "M_H_CS_N<2>" )
			)
			( signal "@baseboard_fab2_lib.baseboard_fab2(sch_1):m_h_cs_n(3)"
				( pinPairRef "@baseboard_fab2_lib.baseboard_fab2(sch_1):\PP3542\" )
				( attribute "NO_TEST" "1"
					( Origin gBackEnd )
				)
				( objectStatus "M_H_CS_N<3>" )
			)
			( signal "@baseboard_fab2_lib.baseboard_fab2(sch_1):m_h_cs_n(1)"
				( pinPairRef "@baseboard_fab2_lib.baseboard_fab2(sch_1):\PP3540\" )
				( attribute "NO_TEST" "1"
					( Origin gBackEnd )
				)
				( objectStatus "M_H_CS_N<1>" )
			)
			( signal "@baseboard_fab2_lib.baseboard_fab2(sch_1):m_h_odt(1)"
				( pinPairRef "@baseboard_fab2_lib.baseboard_fab2(sch_1):\PP3541\" )
				( attribute "NO_TEST" "1"
					( Origin gBackEnd )
				)
				( objectStatus "M_H_ODT<1>" )
			)
			( signal "@baseboard_fab2_lib.baseboard_fab2(sch_1):m_h_cke(1)"
				( pinPairRef "@baseboard_fab2_lib.baseboard_fab2(sch_1):\PP3539\" )
				( attribute "NO_TEST" "1"
					( Origin gBackEnd )
				)
				( objectStatus "M_H_CKE<1>" )
			)
			( signal "@baseboard_fab2_lib.baseboard_fab2(sch_1):m_h_cs_n(4)"
				( pinPairRef "@baseboard_fab2_lib.baseboard_fab2(sch_1):\PP3537\" )
				( objectStatus "M_H_CS_N<4>" )
			)
			( signal "@baseboard_fab2_lib.baseboard_fab2(sch_1):m_h_odt(2)"
				( pinPairRef "@baseboard_fab2_lib.baseboard_fab2(sch_1):\PP3538\" )
				( attribute "NO_TEST" "1"
					( Origin gBackEnd )
				)
				( objectStatus "M_H_ODT<2>" )
			)
			( signal "@baseboard_fab2_lib.baseboard_fab2(sch_1):m_h_cke(2)"
				( pinPairRef "@baseboard_fab2_lib.baseboard_fab2(sch_1):\PP3536\" )
				( attribute "NO_TEST" "1"
					( Origin gBackEnd )
				)
				( objectStatus "M_H_CKE<2>" )
			)
			( signal "@baseboard_fab2_lib.baseboard_fab2(sch_1):m_h_cs_n(6)"
				( pinPairRef "@baseboard_fab2_lib.baseboard_fab2(sch_1):\PP3534\" )
				( objectStatus "M_H_CS_N<6>" )
			)
			( signal "@baseboard_fab2_lib.baseboard_fab2(sch_1):m_h_cs_n(7)"
				( pinPairRef "@baseboard_fab2_lib.baseboard_fab2(sch_1):\PP3535\" )
				( attribute "NO_TEST" "1"
					( Origin gBackEnd )
				)
				( objectStatus "M_H_CS_N<7>" )
			)
			( signal "@baseboard_fab2_lib.baseboard_fab2(sch_1):m_h_cs_n(5)"
				( pinPairRef "@baseboard_fab2_lib.baseboard_fab2(sch_1):\PP3532\" )
				( objectStatus "M_H_CS_N<5>" )
			)
			( signal "@baseboard_fab2_lib.baseboard_fab2(sch_1):m_h_odt(3)"
				( pinPairRef "@baseboard_fab2_lib.baseboard_fab2(sch_1):\PP3533\" )
				( objectStatus "M_H_ODT<3>" )
			)
			( signal "@baseboard_fab2_lib.baseboard_fab2(sch_1):m_h_cke(3)"
				( pinPairRef "@baseboard_fab2_lib.baseboard_fab2(sch_1):\PP3531\" )
				( objectStatus "M_H_CKE<3>" )
			)
			( signal "@baseboard_fab2_lib.baseboard_fab2(sch_1):m_h_clk_dn(0)"
				( attribute "NO_TEST" "1"
					( Origin gBackEnd )
				)
				( objectStatus "M_H_CLK_DN<0>" )
			)
			( signal "@baseboard_fab2_lib.baseboard_fab2(sch_1):m_h_clk_dp(0)"
				( electricalCSetRef "@crescent_city_bb_fab1_lib.crescent_city_bb_fab1(sch_1):\M_A_CLK_DP_0_\" )
				( attribute "RELATIVE_PROPAGATION_DELAY_SCOPE" "G"
					( Parent
						( matchGroupRef "@crescent_city_bb_fab1_lib.crescent_city_bb_fab1(sch_1):\MG_DDR_FAR_DIMM-CLK0_CLS_DDR_H_CAC-CLKS\" )
					)
					( Origin gBackEnd )
				)
				( attribute "RELATIVE_PROPAGATION_DELAY_PATH_TYPE" "L:S"
					( Parent
						( matchGroupRef "@crescent_city_bb_fab1_lib.crescent_city_bb_fab1(sch_1):\MG_DDR_FAR_DIMM-CLK0_CLS_DDR_H_CAC-CLKS\" )
					)
					( Origin gBackEnd )
				)
				( attribute "RELATIVE_PROPAGATION_DELAY" "TARGET,TARGET"
					( Parent
						( matchGroupRef "@crescent_city_bb_fab1_lib.crescent_city_bb_fab1(sch_1):\MG_DDR_FAR_DIMM-CLK0_CLS_DDR_H_CAC-CLKS\" )
					)
					( Units "uMatchProp" "ns" 1.000000)
					( Origin gBackEnd )
				)
				( objectStatus "M_H_CLK_DP<0>" )
			)
			( signal "@baseboard_fab2_lib.baseboard_fab2(sch_1):m_h_clk_dn(2)"
				( objectStatus "M_H_CLK_DN<2>" )
			)
			( signal "@baseboard_fab2_lib.baseboard_fab2(sch_1):m_h_clk_dp(2)"
				( electricalCSetRef "@crescent_city_bb_fab1_lib.crescent_city_bb_fab1(sch_1):\DDR_CLK1\" )
				( attribute "NO_TEST" "1"
					( Origin gBackEnd )
				)
				( attribute "RELATIVE_PROPAGATION_DELAY_SCOPE" "G"
					( Parent
						( matchGroupRef "@crescent_city_bb_fab1_lib.crescent_city_bb_fab1(sch_1):\MG_DDR_NEAR_DIMM-CLK1_CLS_DDR_H_CAC-CLKS\" )
					)
					( Origin gBackEnd )
				)
				( attribute "RELATIVE_PROPAGATION_DELAY_PATH_TYPE" "L:S"
					( Parent
						( matchGroupRef "@crescent_city_bb_fab1_lib.crescent_city_bb_fab1(sch_1):\MG_DDR_NEAR_DIMM-CLK1_CLS_DDR_H_CAC-CLKS\" )
					)
					( Origin gBackEnd )
				)
				( attribute "RELATIVE_PROPAGATION_DELAY" "TARGET,TARGET"
					( Parent
						( matchGroupRef "@crescent_city_bb_fab1_lib.crescent_city_bb_fab1(sch_1):\MG_DDR_NEAR_DIMM-CLK1_CLS_DDR_H_CAC-CLKS\" )
					)
					( Units "uMatchProp" "ns" 1.000000)
					( Origin gBackEnd )
				)
				( objectStatus "M_H_CLK_DP<2>" )
			)
			( signal "@baseboard_fab2_lib.baseboard_fab2(sch_1):m_g_c(2)"
				( pinPairRef "@baseboard_fab2_lib.baseboard_fab2(sch_1):\PP3659\" )
				( pinPairRef "@baseboard_fab2_lib.baseboard_fab2(sch_1):\PP3660\" )
				( attribute "NO_TEST" "1"
					( Origin gBackEnd )
				)
				( objectStatus "M_G_C<2>" )
			)
			( signal "@baseboard_fab2_lib.baseboard_fab2(sch_1):m_g_ma(17)"
				( pinPairRef "@baseboard_fab2_lib.baseboard_fab2(sch_1):\PP3661\" )
				( pinPairRef "@baseboard_fab2_lib.baseboard_fab2(sch_1):\PP3662\" )
				( attribute "NO_TEST" "1"
					( Origin gBackEnd )
				)
				( objectStatus "M_G_MA<17>" )
			)
			( signal "@baseboard_fab2_lib.baseboard_fab2(sch_1):m_g_ma(13)"
				( pinPairRef "@baseboard_fab2_lib.baseboard_fab2(sch_1):\PP3655\" )
				( pinPairRef "@baseboard_fab2_lib.baseboard_fab2(sch_1):\PP3656\" )
				( objectStatus "M_G_MA<13>" )
			)
			( signal "@baseboard_fab2_lib.baseboard_fab2(sch_1):m_g_ma(15)"
				( pinPairRef "@baseboard_fab2_lib.baseboard_fab2(sch_1):\PP3657\" )
				( pinPairRef "@baseboard_fab2_lib.baseboard_fab2(sch_1):\PP3658\" )
				( attribute "NO_TEST" "1"
					( Origin gBackEnd )
				)
				( objectStatus "M_G_MA<15>" )
			)
			( signal "@baseboard_fab2_lib.baseboard_fab2(sch_1):m_g_ma(14)"
				( pinPairRef "@baseboard_fab2_lib.baseboard_fab2(sch_1):\PP3651\" )
				( pinPairRef "@baseboard_fab2_lib.baseboard_fab2(sch_1):\PP3652\" )
				( objectStatus "M_G_MA<14>" )
			)
			( signal "@baseboard_fab2_lib.baseboard_fab2(sch_1):m_g_ma(16)"
				( pinPairRef "@baseboard_fab2_lib.baseboard_fab2(sch_1):\PP3653\" )
				( pinPairRef "@baseboard_fab2_lib.baseboard_fab2(sch_1):\PP3654\" )
				( objectStatus "M_G_MA<16>" )
			)
			( signal "@baseboard_fab2_lib.baseboard_fab2(sch_1):m_g_ba(1)"
				( pinPairRef "@baseboard_fab2_lib.baseboard_fab2(sch_1):\PP3647\" )
				( pinPairRef "@baseboard_fab2_lib.baseboard_fab2(sch_1):\PP3648\" )
				( attribute "NO_TEST" "1"
					( Origin gBackEnd )
				)
				( objectStatus "M_G_BA<1>" )
			)
			( signal "@baseboard_fab2_lib.baseboard_fab2(sch_1):m_g_ma(10)"
				( pinPairRef "@baseboard_fab2_lib.baseboard_fab2(sch_1):\PP3649\" )
				( pinPairRef "@baseboard_fab2_lib.baseboard_fab2(sch_1):\PP3650\" )
				( objectStatus "M_G_MA<10>" )
			)
			( signal "@baseboard_fab2_lib.baseboard_fab2(sch_1):m_g_ba(0)"
				( pinPairRef "@baseboard_fab2_lib.baseboard_fab2(sch_1):\PP3643\" )
				( pinPairRef "@baseboard_fab2_lib.baseboard_fab2(sch_1):\PP3644\" )
				( objectStatus "M_G_BA<0>" )
			)
			( signal "@baseboard_fab2_lib.baseboard_fab2(sch_1):m_g_ma(0)"
				( pinPairRef "@baseboard_fab2_lib.baseboard_fab2(sch_1):\PP3645\" )
				( pinPairRef "@baseboard_fab2_lib.baseboard_fab2(sch_1):\PP3646\" )
				( objectStatus "M_G_MA<0>" )
			)
			( signal "@baseboard_fab2_lib.baseboard_fab2(sch_1):m_g_par"
				( pinPairRef "@baseboard_fab2_lib.baseboard_fab2(sch_1):\PP3641\" )
				( pinPairRef "@baseboard_fab2_lib.baseboard_fab2(sch_1):\PP3642\" )
				( objectStatus "M_G_PAR" )
			)
			( signal "@baseboard_fab2_lib.baseboard_fab2(sch_1):m_g_ma(1)"
				( pinPairRef "@baseboard_fab2_lib.baseboard_fab2(sch_1):\PP3637\" )
				( pinPairRef "@baseboard_fab2_lib.baseboard_fab2(sch_1):\PP3638\" )
				( objectStatus "M_G_MA<1>" )
			)
			( signal "@baseboard_fab2_lib.baseboard_fab2(sch_1):m_g_ma(3)"
				( pinPairRef "@baseboard_fab2_lib.baseboard_fab2(sch_1):\PP3639\" )
				( pinPairRef "@baseboard_fab2_lib.baseboard_fab2(sch_1):\PP3640\" )
				( objectStatus "M_G_MA<3>" )
			)
			( signal "@baseboard_fab2_lib.baseboard_fab2(sch_1):m_g_ma(2)"
				( pinPairRef "@baseboard_fab2_lib.baseboard_fab2(sch_1):\PP3633\" )
				( pinPairRef "@baseboard_fab2_lib.baseboard_fab2(sch_1):\PP3634\" )
				( attribute "NO_TEST" "1"
					( Origin gBackEnd )
				)
				( objectStatus "M_G_MA<2>" )
			)
			( signal "@baseboard_fab2_lib.baseboard_fab2(sch_1):m_g_ma(4)"
				( pinPairRef "@baseboard_fab2_lib.baseboard_fab2(sch_1):\PP3635\" )
				( pinPairRef "@baseboard_fab2_lib.baseboard_fab2(sch_1):\PP3636\" )
				( objectStatus "M_G_MA<4>" )
			)
			( signal "@baseboard_fab2_lib.baseboard_fab2(sch_1):m_g_ma(5)"
				( pinPairRef "@baseboard_fab2_lib.baseboard_fab2(sch_1):\PP3629\" )
				( pinPairRef "@baseboard_fab2_lib.baseboard_fab2(sch_1):\PP3630\" )
				( objectStatus "M_G_MA<5>" )
			)
			( signal "@baseboard_fab2_lib.baseboard_fab2(sch_1):m_g_ma(6)"
				( pinPairRef "@baseboard_fab2_lib.baseboard_fab2(sch_1):\PP3631\" )
				( pinPairRef "@baseboard_fab2_lib.baseboard_fab2(sch_1):\PP3632\" )
				( objectStatus "M_G_MA<6>" )
			)
			( signal "@baseboard_fab2_lib.baseboard_fab2(sch_1):m_g_ma(7)"
				( pinPairRef "@baseboard_fab2_lib.baseboard_fab2(sch_1):\PP3625\" )
				( pinPairRef "@baseboard_fab2_lib.baseboard_fab2(sch_1):\PP3626\" )
				( objectStatus "M_G_MA<7>" )
			)
			( signal "@baseboard_fab2_lib.baseboard_fab2(sch_1):m_g_ma(8)"
				( pinPairRef "@baseboard_fab2_lib.baseboard_fab2(sch_1):\PP3627\" )
				( pinPairRef "@baseboard_fab2_lib.baseboard_fab2(sch_1):\PP3628\" )
				( objectStatus "M_G_MA<8>" )
			)
			( signal "@baseboard_fab2_lib.baseboard_fab2(sch_1):m_g_ma(9)"
				( pinPairRef "@baseboard_fab2_lib.baseboard_fab2(sch_1):\PP3621\" )
				( pinPairRef "@baseboard_fab2_lib.baseboard_fab2(sch_1):\PP3622\" )
				( attribute "NO_TEST" "1"
					( Origin gBackEnd )
				)
				( objectStatus "M_G_MA<9>" )
			)
			( signal "@baseboard_fab2_lib.baseboard_fab2(sch_1):m_g_ma(12)"
				( pinPairRef "@baseboard_fab2_lib.baseboard_fab2(sch_1):\PP3623\" )
				( pinPairRef "@baseboard_fab2_lib.baseboard_fab2(sch_1):\PP3624\" )
				( attribute "NO_TEST" "1"
					( Origin gBackEnd )
				)
				( objectStatus "M_G_MA<12>" )
			)
			( signal "@baseboard_fab2_lib.baseboard_fab2(sch_1):m_g_bg(1)"
				( pinPairRef "@baseboard_fab2_lib.baseboard_fab2(sch_1):\PP3617\" )
				( pinPairRef "@baseboard_fab2_lib.baseboard_fab2(sch_1):\PP3618\" )
				( objectStatus "M_G_BG<1>" )
			)
			( signal "@baseboard_fab2_lib.baseboard_fab2(sch_1):m_g_ma(11)"
				( pinPairRef "@baseboard_fab2_lib.baseboard_fab2(sch_1):\PP3619\" )
				( pinPairRef "@baseboard_fab2_lib.baseboard_fab2(sch_1):\PP3620\" )
				( attribute "NO_TEST" "1"
					( Origin gBackEnd )
				)
				( objectStatus "M_G_MA<11>" )
			)
			( signal "@baseboard_fab2_lib.baseboard_fab2(sch_1):m_g_act_n"
				( pinPairRef "@baseboard_fab2_lib.baseboard_fab2(sch_1):\PP3613\" )
				( pinPairRef "@baseboard_fab2_lib.baseboard_fab2(sch_1):\PP3614\" )
				( objectStatus "M_G_ACT_N" )
			)
			( signal "@baseboard_fab2_lib.baseboard_fab2(sch_1):m_g_bg(0)"
				( pinPairRef "@baseboard_fab2_lib.baseboard_fab2(sch_1):\PP3615\" )
				( pinPairRef "@baseboard_fab2_lib.baseboard_fab2(sch_1):\PP3616\" )
				( objectStatus "M_G_BG<0>" )
			)
			( signal "@baseboard_fab2_lib.baseboard_fab2(sch_1):m_g_cs_n(0)"
				( pinPairRef "@baseboard_fab2_lib.baseboard_fab2(sch_1):\PP3611\" )
				( objectStatus "M_G_CS_N<0>" )
			)
			( signal "@baseboard_fab2_lib.baseboard_fab2(sch_1):m_g_odt(0)"
				( pinPairRef "@baseboard_fab2_lib.baseboard_fab2(sch_1):\PP3612\" )
				( objectStatus "M_G_ODT<0>" )
			)
			( signal "@baseboard_fab2_lib.baseboard_fab2(sch_1):m_g_cke(0)"
				( pinPairRef "@baseboard_fab2_lib.baseboard_fab2(sch_1):\PP3610\" )
				( objectStatus "M_G_CKE<0>" )
			)
			( signal "@baseboard_fab2_lib.baseboard_fab2(sch_1):m_g_cs_n(2)"
				( pinPairRef "@baseboard_fab2_lib.baseboard_fab2(sch_1):\PP3609\" )
				( objectStatus "M_G_CS_N<2>" )
			)
			( signal "@baseboard_fab2_lib.baseboard_fab2(sch_1):m_g_cs_n(3)"
				( pinPairRef "@baseboard_fab2_lib.baseboard_fab2(sch_1):\PP3608\" )
				( attribute "NO_TEST" "1"
					( Origin gBackEnd )
				)
				( objectStatus "M_G_CS_N<3>" )
			)
			( signal "@baseboard_fab2_lib.baseboard_fab2(sch_1):m_g_cs_n(1)"
				( pinPairRef "@baseboard_fab2_lib.baseboard_fab2(sch_1):\PP3606\" )
				( objectStatus "M_G_CS_N<1>" )
			)
			( signal "@baseboard_fab2_lib.baseboard_fab2(sch_1):m_g_odt(1)"
				( pinPairRef "@baseboard_fab2_lib.baseboard_fab2(sch_1):\PP3607\" )
				( objectStatus "M_G_ODT<1>" )
			)
			( signal "@baseboard_fab2_lib.baseboard_fab2(sch_1):m_g_cke(1)"
				( pinPairRef "@baseboard_fab2_lib.baseboard_fab2(sch_1):\PP3605\" )
				( attribute "NO_TEST" "1"
					( Origin gBackEnd )
				)
				( objectStatus "M_G_CKE<1>" )
			)
			( signal "@baseboard_fab2_lib.baseboard_fab2(sch_1):m_g_cs_n(4)"
				( pinPairRef "@baseboard_fab2_lib.baseboard_fab2(sch_1):\PP3603\" )
				( objectStatus "M_G_CS_N<4>" )
			)
			( signal "@baseboard_fab2_lib.baseboard_fab2(sch_1):m_g_odt(2)"
				( pinPairRef "@baseboard_fab2_lib.baseboard_fab2(sch_1):\PP3604\" )
				( objectStatus "M_G_ODT<2>" )
			)
			( signal "@baseboard_fab2_lib.baseboard_fab2(sch_1):m_g_cke(2)"
				( pinPairRef "@baseboard_fab2_lib.baseboard_fab2(sch_1):\PP3602\" )
				( objectStatus "M_G_CKE<2>" )
			)
			( signal "@baseboard_fab2_lib.baseboard_fab2(sch_1):m_g_cs_n(6)"
				( pinPairRef "@baseboard_fab2_lib.baseboard_fab2(sch_1):\PP3600\" )
				( objectStatus "M_G_CS_N<6>" )
			)
			( signal "@baseboard_fab2_lib.baseboard_fab2(sch_1):m_g_cs_n(7)"
				( pinPairRef "@baseboard_fab2_lib.baseboard_fab2(sch_1):\PP3601\" )
				( objectStatus "M_G_CS_N<7>" )
			)
			( signal "@baseboard_fab2_lib.baseboard_fab2(sch_1):m_g_cs_n(5)"
				( pinPairRef "@baseboard_fab2_lib.baseboard_fab2(sch_1):\PP3598\" )
				( objectStatus "M_G_CS_N<5>" )
			)
			( signal "@baseboard_fab2_lib.baseboard_fab2(sch_1):m_g_odt(3)"
				( pinPairRef "@baseboard_fab2_lib.baseboard_fab2(sch_1):\PP3599\" )
				( objectStatus "M_G_ODT<3>" )
			)
			( signal "@baseboard_fab2_lib.baseboard_fab2(sch_1):m_g_cke(3)"
				( pinPairRef "@baseboard_fab2_lib.baseboard_fab2(sch_1):\PP3597\" )
				( objectStatus "M_G_CKE<3>" )
			)
			( signal "@baseboard_fab2_lib.baseboard_fab2(sch_1):m_g_clk_dn(0)"
				( attribute "NO_TEST" "1"
					( Origin gBackEnd )
				)
				( objectStatus "M_G_CLK_DN<0>" )
			)
			( signal "@baseboard_fab2_lib.baseboard_fab2(sch_1):m_g_clk_dp(0)"
				( electricalCSetRef "@crescent_city_bb_fab1_lib.crescent_city_bb_fab1(sch_1):\M_A_CLK_DP_0_\" )
				( attribute "NO_TEST" "1"
					( Origin gBackEnd )
				)
				( attribute "RELATIVE_PROPAGATION_DELAY_SCOPE" "G"
					( Parent
						( matchGroupRef "@crescent_city_bb_fab1_lib.crescent_city_bb_fab1(sch_1):\MG_DDR_FAR_DIMM-CLK0_CLS_DDR_G_CAC-CLKS\" )
					)
					( Origin gBackEnd )
				)
				( attribute "RELATIVE_PROPAGATION_DELAY_PATH_TYPE" "L:S"
					( Parent
						( matchGroupRef "@crescent_city_bb_fab1_lib.crescent_city_bb_fab1(sch_1):\MG_DDR_FAR_DIMM-CLK0_CLS_DDR_G_CAC-CLKS\" )
					)
					( Origin gBackEnd )
				)
				( attribute "RELATIVE_PROPAGATION_DELAY" "TARGET,TARGET"
					( Parent
						( matchGroupRef "@crescent_city_bb_fab1_lib.crescent_city_bb_fab1(sch_1):\MG_DDR_FAR_DIMM-CLK0_CLS_DDR_G_CAC-CLKS\" )
					)
					( Units "uMatchProp" "ns" 1.000000)
					( Origin gBackEnd )
				)
				( objectStatus "M_G_CLK_DP<0>" )
			)
			( signal "@baseboard_fab2_lib.baseboard_fab2(sch_1):m_g_clk_dp(2)"
				( objectStatus "M_G_CLK_DP<2>" )
			)
			( signal "@baseboard_fab2_lib.baseboard_fab2(sch_1):m_g_clk_dn(2)"
				( electricalCSetRef "@crescent_city_bb_fab1_lib.crescent_city_bb_fab1(sch_1):\DDR_CLK1\" )
				( attribute "RELATIVE_PROPAGATION_DELAY_SCOPE" "G"
					( Parent
						( matchGroupRef "@crescent_city_bb_fab1_lib.crescent_city_bb_fab1(sch_1):\MG_DDR_NEAR_DIMM-CLK1_CLS_DDR_G_CAC-CLKS\" )
					)
					( Origin gBackEnd )
				)
				( attribute "RELATIVE_PROPAGATION_DELAY_PATH_TYPE" "L:S"
					( Parent
						( matchGroupRef "@crescent_city_bb_fab1_lib.crescent_city_bb_fab1(sch_1):\MG_DDR_NEAR_DIMM-CLK1_CLS_DDR_G_CAC-CLKS\" )
					)
					( Origin gBackEnd )
				)
				( attribute "RELATIVE_PROPAGATION_DELAY" "TARGET,TARGET"
					( Parent
						( matchGroupRef "@crescent_city_bb_fab1_lib.crescent_city_bb_fab1(sch_1):\MG_DDR_NEAR_DIMM-CLK1_CLS_DDR_G_CAC-CLKS\" )
					)
					( Units "uMatchProp" "ns" 1.000000)
					( Origin gBackEnd )
				)
				( objectStatus "M_G_CLK_DN<2>" )
			)
			( signal "@baseboard_fab2_lib.baseboard_fab2(sch_1):m_f_c(2)"
				( pinPairRef "@baseboard_fab2_lib.baseboard_fab2(sch_1):\PP3725\" )
				( pinPairRef "@baseboard_fab2_lib.baseboard_fab2(sch_1):\PP3726\" )
				( objectStatus "M_F_C<2>" )
			)
			( signal "@baseboard_fab2_lib.baseboard_fab2(sch_1):m_f_ma(17)"
				( pinPairRef "@baseboard_fab2_lib.baseboard_fab2(sch_1):\PP3727\" )
				( pinPairRef "@baseboard_fab2_lib.baseboard_fab2(sch_1):\PP3728\" )
				( attribute "NO_TEST" "1"
					( Origin gBackEnd )
				)
				( objectStatus "M_F_MA<17>" )
			)
			( signal "@baseboard_fab2_lib.baseboard_fab2(sch_1):m_f_ma(13)"
				( pinPairRef "@baseboard_fab2_lib.baseboard_fab2(sch_1):\PP3721\" )
				( pinPairRef "@baseboard_fab2_lib.baseboard_fab2(sch_1):\PP3722\" )
				( attribute "NO_TEST" "1"
					( Origin gBackEnd )
				)
				( objectStatus "M_F_MA<13>" )
			)
			( signal "@baseboard_fab2_lib.baseboard_fab2(sch_1):m_f_ma(15)"
				( pinPairRef "@baseboard_fab2_lib.baseboard_fab2(sch_1):\PP3723\" )
				( pinPairRef "@baseboard_fab2_lib.baseboard_fab2(sch_1):\PP3724\" )
				( attribute "NO_TEST" "1"
					( Origin gBackEnd )
				)
				( objectStatus "M_F_MA<15>" )
			)
			( signal "@baseboard_fab2_lib.baseboard_fab2(sch_1):m_f_ma(14)"
				( pinPairRef "@baseboard_fab2_lib.baseboard_fab2(sch_1):\PP3717\" )
				( pinPairRef "@baseboard_fab2_lib.baseboard_fab2(sch_1):\PP3718\" )
				( objectStatus "M_F_MA<14>" )
			)
			( signal "@baseboard_fab2_lib.baseboard_fab2(sch_1):m_f_ma(16)"
				( pinPairRef "@baseboard_fab2_lib.baseboard_fab2(sch_1):\PP3719\" )
				( pinPairRef "@baseboard_fab2_lib.baseboard_fab2(sch_1):\PP3720\" )
				( attribute "NO_TEST" "1"
					( Origin gBackEnd )
				)
				( objectStatus "M_F_MA<16>" )
			)
			( signal "@baseboard_fab2_lib.baseboard_fab2(sch_1):m_f_ba(1)"
				( pinPairRef "@baseboard_fab2_lib.baseboard_fab2(sch_1):\PP3713\" )
				( pinPairRef "@baseboard_fab2_lib.baseboard_fab2(sch_1):\PP3714\" )
				( objectStatus "M_F_BA<1>" )
			)
			( signal "@baseboard_fab2_lib.baseboard_fab2(sch_1):m_f_ma(10)"
				( pinPairRef "@baseboard_fab2_lib.baseboard_fab2(sch_1):\PP3715\" )
				( pinPairRef "@baseboard_fab2_lib.baseboard_fab2(sch_1):\PP3716\" )
				( attribute "NO_TEST" "1"
					( Origin gBackEnd )
				)
				( objectStatus "M_F_MA<10>" )
			)
			( signal "@baseboard_fab2_lib.baseboard_fab2(sch_1):m_f_ba(0)"
				( pinPairRef "@baseboard_fab2_lib.baseboard_fab2(sch_1):\PP3709\" )
				( pinPairRef "@baseboard_fab2_lib.baseboard_fab2(sch_1):\PP3710\" )
				( objectStatus "M_F_BA<0>" )
			)
			( signal "@baseboard_fab2_lib.baseboard_fab2(sch_1):m_f_ma(0)"
				( pinPairRef "@baseboard_fab2_lib.baseboard_fab2(sch_1):\PP3711\" )
				( pinPairRef "@baseboard_fab2_lib.baseboard_fab2(sch_1):\PP3712\" )
				( objectStatus "M_F_MA<0>" )
			)
			( signal "@baseboard_fab2_lib.baseboard_fab2(sch_1):m_f_par"
				( pinPairRef "@baseboard_fab2_lib.baseboard_fab2(sch_1):\PP3707\" )
				( pinPairRef "@baseboard_fab2_lib.baseboard_fab2(sch_1):\PP3708\" )
				( attribute "NO_TEST" "1"
					( Origin gBackEnd )
				)
				( objectStatus "M_F_PAR" )
			)
			( signal "@baseboard_fab2_lib.baseboard_fab2(sch_1):m_f_ma(1)"
				( pinPairRef "@baseboard_fab2_lib.baseboard_fab2(sch_1):\PP3703\" )
				( pinPairRef "@baseboard_fab2_lib.baseboard_fab2(sch_1):\PP3704\" )
				( objectStatus "M_F_MA<1>" )
			)
			( signal "@baseboard_fab2_lib.baseboard_fab2(sch_1):m_f_ma(3)"
				( pinPairRef "@baseboard_fab2_lib.baseboard_fab2(sch_1):\PP3705\" )
				( pinPairRef "@baseboard_fab2_lib.baseboard_fab2(sch_1):\PP3706\" )
				( attribute "NO_TEST" "1"
					( Origin gBackEnd )
				)
				( objectStatus "M_F_MA<3>" )
			)
			( signal "@baseboard_fab2_lib.baseboard_fab2(sch_1):m_f_ma(2)"
				( pinPairRef "@baseboard_fab2_lib.baseboard_fab2(sch_1):\PP3699\" )
				( pinPairRef "@baseboard_fab2_lib.baseboard_fab2(sch_1):\PP3700\" )
				( attribute "NO_TEST" "1"
					( Origin gBackEnd )
				)
				( objectStatus "M_F_MA<2>" )
			)
			( signal "@baseboard_fab2_lib.baseboard_fab2(sch_1):m_f_ma(4)"
				( pinPairRef "@baseboard_fab2_lib.baseboard_fab2(sch_1):\PP3701\" )
				( pinPairRef "@baseboard_fab2_lib.baseboard_fab2(sch_1):\PP3702\" )
				( objectStatus "M_F_MA<4>" )
			)
			( signal "@baseboard_fab2_lib.baseboard_fab2(sch_1):m_f_ma(5)"
				( pinPairRef "@baseboard_fab2_lib.baseboard_fab2(sch_1):\PP3695\" )
				( pinPairRef "@baseboard_fab2_lib.baseboard_fab2(sch_1):\PP3696\" )
				( objectStatus "M_F_MA<5>" )
			)
			( signal "@baseboard_fab2_lib.baseboard_fab2(sch_1):m_f_ma(6)"
				( pinPairRef "@baseboard_fab2_lib.baseboard_fab2(sch_1):\PP3697\" )
				( pinPairRef "@baseboard_fab2_lib.baseboard_fab2(sch_1):\PP3698\" )
				( attribute "NO_TEST" "1"
					( Origin gBackEnd )
				)
				( objectStatus "M_F_MA<6>" )
			)
			( signal "@baseboard_fab2_lib.baseboard_fab2(sch_1):m_f_ma(7)"
				( pinPairRef "@baseboard_fab2_lib.baseboard_fab2(sch_1):\PP3691\" )
				( pinPairRef "@baseboard_fab2_lib.baseboard_fab2(sch_1):\PP3692\" )
				( objectStatus "M_F_MA<7>" )
			)
			( signal "@baseboard_fab2_lib.baseboard_fab2(sch_1):m_f_ma(8)"
				( pinPairRef "@baseboard_fab2_lib.baseboard_fab2(sch_1):\PP3693\" )
				( pinPairRef "@baseboard_fab2_lib.baseboard_fab2(sch_1):\PP3694\" )
				( attribute "NO_TEST" "1"
					( Origin gBackEnd )
				)
				( objectStatus "M_F_MA<8>" )
			)
			( signal "@baseboard_fab2_lib.baseboard_fab2(sch_1):m_f_ma(9)"
				( pinPairRef "@baseboard_fab2_lib.baseboard_fab2(sch_1):\PP3687\" )
				( pinPairRef "@baseboard_fab2_lib.baseboard_fab2(sch_1):\PP3688\" )
				( attribute "NO_TEST" "1"
					( Origin gBackEnd )
				)
				( objectStatus "M_F_MA<9>" )
			)
			( signal "@baseboard_fab2_lib.baseboard_fab2(sch_1):m_f_ma(12)"
				( pinPairRef "@baseboard_fab2_lib.baseboard_fab2(sch_1):\PP3689\" )
				( pinPairRef "@baseboard_fab2_lib.baseboard_fab2(sch_1):\PP3690\" )
				( attribute "NO_TEST" "1"
					( Origin gBackEnd )
				)
				( objectStatus "M_F_MA<12>" )
			)
			( signal "@baseboard_fab2_lib.baseboard_fab2(sch_1):m_f_bg(1)"
				( pinPairRef "@baseboard_fab2_lib.baseboard_fab2(sch_1):\PP3683\" )
				( pinPairRef "@baseboard_fab2_lib.baseboard_fab2(sch_1):\PP3684\" )
				( objectStatus "M_F_BG<1>" )
			)
			( signal "@baseboard_fab2_lib.baseboard_fab2(sch_1):m_f_ma(11)"
				( pinPairRef "@baseboard_fab2_lib.baseboard_fab2(sch_1):\PP3685\" )
				( pinPairRef "@baseboard_fab2_lib.baseboard_fab2(sch_1):\PP3686\" )
				( attribute "NO_TEST" "1"
					( Origin gBackEnd )
				)
				( objectStatus "M_F_MA<11>" )
			)
			( signal "@baseboard_fab2_lib.baseboard_fab2(sch_1):m_f_act_n"
				( pinPairRef "@baseboard_fab2_lib.baseboard_fab2(sch_1):\PP3679\" )
				( pinPairRef "@baseboard_fab2_lib.baseboard_fab2(sch_1):\PP3680\" )
				( objectStatus "M_F_ACT_N" )
			)
			( signal "@baseboard_fab2_lib.baseboard_fab2(sch_1):m_f_bg(0)"
				( pinPairRef "@baseboard_fab2_lib.baseboard_fab2(sch_1):\PP3681\" )
				( pinPairRef "@baseboard_fab2_lib.baseboard_fab2(sch_1):\PP3682\" )
				( attribute "NO_TEST" "1"
					( Origin gBackEnd )
				)
				( objectStatus "M_F_BG<0>" )
			)
			( signal "@baseboard_fab2_lib.baseboard_fab2(sch_1):m_f_cs_n(0)"
				( pinPairRef "@baseboard_fab2_lib.baseboard_fab2(sch_1):\PP3677\" )
				( attribute "NO_TEST" "1"
					( Origin gBackEnd )
				)
				( objectStatus "M_F_CS_N<0>" )
			)
			( signal "@baseboard_fab2_lib.baseboard_fab2(sch_1):m_f_odt(0)"
				( pinPairRef "@baseboard_fab2_lib.baseboard_fab2(sch_1):\PP3678\" )
				( attribute "NO_TEST" "1"
					( Origin gBackEnd )
				)
				( objectStatus "M_F_ODT<0>" )
			)
			( signal "@baseboard_fab2_lib.baseboard_fab2(sch_1):m_f_cke(0)"
				( pinPairRef "@baseboard_fab2_lib.baseboard_fab2(sch_1):\PP3676\" )
				( attribute "NO_TEST" "1"
					( Origin gBackEnd )
				)
				( objectStatus "M_F_CKE<0>" )
			)
			( signal "@baseboard_fab2_lib.baseboard_fab2(sch_1):m_f_cs_n(2)"
				( pinPairRef "@baseboard_fab2_lib.baseboard_fab2(sch_1):\PP3675\" )
				( objectStatus "M_F_CS_N<2>" )
			)
			( signal "@baseboard_fab2_lib.baseboard_fab2(sch_1):m_f_cs_n(3)"
				( pinPairRef "@baseboard_fab2_lib.baseboard_fab2(sch_1):\PP3674\" )
				( attribute "NO_TEST" "1"
					( Origin gBackEnd )
				)
				( objectStatus "M_F_CS_N<3>" )
			)
			( signal "@baseboard_fab2_lib.baseboard_fab2(sch_1):m_f_cs_n(1)"
				( pinPairRef "@baseboard_fab2_lib.baseboard_fab2(sch_1):\PP3672\" )
				( objectStatus "M_F_CS_N<1>" )
			)
			( signal "@baseboard_fab2_lib.baseboard_fab2(sch_1):m_f_odt(1)"
				( pinPairRef "@baseboard_fab2_lib.baseboard_fab2(sch_1):\PP3673\" )
				( attribute "NO_TEST" "1"
					( Origin gBackEnd )
				)
				( objectStatus "M_F_ODT<1>" )
			)
			( signal "@baseboard_fab2_lib.baseboard_fab2(sch_1):m_f_cke(1)"
				( pinPairRef "@baseboard_fab2_lib.baseboard_fab2(sch_1):\PP3671\" )
				( attribute "NO_TEST" "1"
					( Origin gBackEnd )
				)
				( objectStatus "M_F_CKE<1>" )
			)
			( signal "@baseboard_fab2_lib.baseboard_fab2(sch_1):m_f_cs_n(4)"
				( pinPairRef "@baseboard_fab2_lib.baseboard_fab2(sch_1):\PP3669\" )
				( objectStatus "M_F_CS_N<4>" )
			)
			( signal "@baseboard_fab2_lib.baseboard_fab2(sch_1):m_f_odt(2)"
				( pinPairRef "@baseboard_fab2_lib.baseboard_fab2(sch_1):\PP3670\" )
				( attribute "NO_TEST" "1"
					( Origin gBackEnd )
				)
				( objectStatus "M_F_ODT<2>" )
			)
			( signal "@baseboard_fab2_lib.baseboard_fab2(sch_1):m_f_cke(2)"
				( pinPairRef "@baseboard_fab2_lib.baseboard_fab2(sch_1):\PP3668\" )
				( attribute "NO_TEST" "1"
					( Origin gBackEnd )
				)
				( objectStatus "M_F_CKE<2>" )
			)
			( signal "@baseboard_fab2_lib.baseboard_fab2(sch_1):m_f_cs_n(6)"
				( pinPairRef "@baseboard_fab2_lib.baseboard_fab2(sch_1):\PP3666\" )
				( objectStatus "M_F_CS_N<6>" )
			)
			( signal "@baseboard_fab2_lib.baseboard_fab2(sch_1):m_f_cs_n(7)"
				( pinPairRef "@baseboard_fab2_lib.baseboard_fab2(sch_1):\PP3667\" )
				( attribute "NO_TEST" "1"
					( Origin gBackEnd )
				)
				( objectStatus "M_F_CS_N<7>" )
			)
			( signal "@baseboard_fab2_lib.baseboard_fab2(sch_1):m_f_cs_n(5)"
				( pinPairRef "@baseboard_fab2_lib.baseboard_fab2(sch_1):\PP3664\" )
				( objectStatus "M_F_CS_N<5>" )
			)
			( signal "@baseboard_fab2_lib.baseboard_fab2(sch_1):m_f_odt(3)"
				( pinPairRef "@baseboard_fab2_lib.baseboard_fab2(sch_1):\PP3665\" )
				( objectStatus "M_F_ODT<3>" )
			)
			( signal "@baseboard_fab2_lib.baseboard_fab2(sch_1):m_f_cke(3)"
				( pinPairRef "@baseboard_fab2_lib.baseboard_fab2(sch_1):\PP3663\" )
				( objectStatus "M_F_CKE<3>" )
			)
			( signal "@baseboard_fab2_lib.baseboard_fab2(sch_1):m_f_clk_dn(0)"
				( attribute "NO_TEST" "1"
					( Origin gBackEnd )
				)
				( objectStatus "M_F_CLK_DN<0>" )
			)
			( signal "@baseboard_fab2_lib.baseboard_fab2(sch_1):m_f_clk_dp(0)"
				( electricalCSetRef "@crescent_city_bb_fab1_lib.crescent_city_bb_fab1(sch_1):\M_A_CLK_DP_0_\" )
				( attribute "RELATIVE_PROPAGATION_DELAY_SCOPE" "G"
					( Parent
						( matchGroupRef "@crescent_city_bb_fab1_lib.crescent_city_bb_fab1(sch_1):\MG_DDR_FAR_DIMM-CLK0_CLS_DDR_F_CAC-CLKS\" )
					)
					( Origin gBackEnd )
				)
				( attribute "RELATIVE_PROPAGATION_DELAY_PATH_TYPE" "L:S"
					( Parent
						( matchGroupRef "@crescent_city_bb_fab1_lib.crescent_city_bb_fab1(sch_1):\MG_DDR_FAR_DIMM-CLK0_CLS_DDR_F_CAC-CLKS\" )
					)
					( Origin gBackEnd )
				)
				( attribute "RELATIVE_PROPAGATION_DELAY" "TARGET,TARGET"
					( Parent
						( matchGroupRef "@crescent_city_bb_fab1_lib.crescent_city_bb_fab1(sch_1):\MG_DDR_FAR_DIMM-CLK0_CLS_DDR_F_CAC-CLKS\" )
					)
					( Units "uMatchProp" "ns" 1.000000)
					( Origin gBackEnd )
				)
				( objectStatus "M_F_CLK_DP<0>" )
			)
			( signal "@baseboard_fab2_lib.baseboard_fab2(sch_1):m_f_clk_dn(2)"
				( attribute "NO_TEST" "1"
					( Origin gBackEnd )
				)
				( objectStatus "M_F_CLK_DN<2>" )
			)
			( signal "@baseboard_fab2_lib.baseboard_fab2(sch_1):m_f_clk_dp(2)"
				( electricalCSetRef "@crescent_city_bb_fab1_lib.crescent_city_bb_fab1(sch_1):\DDR_CLK1\" )
				( attribute "RELATIVE_PROPAGATION_DELAY_SCOPE" "G"
					( Parent
						( matchGroupRef "@crescent_city_bb_fab1_lib.crescent_city_bb_fab1(sch_1):\MG_DDR_NEAR_DIMM-CLK1_CLS_DDR_F_CAC-CLKS\" )
					)
					( Origin gBackEnd )
				)
				( attribute "RELATIVE_PROPAGATION_DELAY_PATH_TYPE" "L:S"
					( Parent
						( matchGroupRef "@crescent_city_bb_fab1_lib.crescent_city_bb_fab1(sch_1):\MG_DDR_NEAR_DIMM-CLK1_CLS_DDR_F_CAC-CLKS\" )
					)
					( Origin gBackEnd )
				)
				( attribute "RELATIVE_PROPAGATION_DELAY" "TARGET,TARGET"
					( Parent
						( matchGroupRef "@crescent_city_bb_fab1_lib.crescent_city_bb_fab1(sch_1):\MG_DDR_NEAR_DIMM-CLK1_CLS_DDR_F_CAC-CLKS\" )
					)
					( Units "uMatchProp" "ns" 1.000000)
					( Origin gBackEnd )
				)
				( objectStatus "M_F_CLK_DP<2>" )
			)
			( signal "@baseboard_fab2_lib.baseboard_fab2(sch_1):m_e_c(2)"
				( pinPairRef "@baseboard_fab2_lib.baseboard_fab2(sch_1):\PP3791\" )
				( pinPairRef "@baseboard_fab2_lib.baseboard_fab2(sch_1):\PP3792\" )
				( attribute "NO_TEST" "1"
					( Origin gBackEnd )
				)
				( objectStatus "M_E_C<2>" )
			)
			( signal "@baseboard_fab2_lib.baseboard_fab2(sch_1):m_e_ma(17)"
				( pinPairRef "@baseboard_fab2_lib.baseboard_fab2(sch_1):\PP3793\" )
				( pinPairRef "@baseboard_fab2_lib.baseboard_fab2(sch_1):\PP3794\" )
				( objectStatus "M_E_MA<17>" )
			)
			( signal "@baseboard_fab2_lib.baseboard_fab2(sch_1):m_e_ma(13)"
				( pinPairRef "@baseboard_fab2_lib.baseboard_fab2(sch_1):\PP3787\" )
				( pinPairRef "@baseboard_fab2_lib.baseboard_fab2(sch_1):\PP3788\" )
				( attribute "NO_TEST" "1"
					( Origin gBackEnd )
				)
				( objectStatus "M_E_MA<13>" )
			)
			( signal "@baseboard_fab2_lib.baseboard_fab2(sch_1):m_e_ma(15)"
				( pinPairRef "@baseboard_fab2_lib.baseboard_fab2(sch_1):\PP3789\" )
				( pinPairRef "@baseboard_fab2_lib.baseboard_fab2(sch_1):\PP3790\" )
				( objectStatus "M_E_MA<15>" )
			)
			( signal "@baseboard_fab2_lib.baseboard_fab2(sch_1):m_e_ma(14)"
				( pinPairRef "@baseboard_fab2_lib.baseboard_fab2(sch_1):\PP3783\" )
				( pinPairRef "@baseboard_fab2_lib.baseboard_fab2(sch_1):\PP3784\" )
				( objectStatus "M_E_MA<14>" )
			)
			( signal "@baseboard_fab2_lib.baseboard_fab2(sch_1):m_e_ma(16)"
				( pinPairRef "@baseboard_fab2_lib.baseboard_fab2(sch_1):\PP3785\" )
				( pinPairRef "@baseboard_fab2_lib.baseboard_fab2(sch_1):\PP3786\" )
				( attribute "NO_TEST" "1"
					( Origin gBackEnd )
				)
				( objectStatus "M_E_MA<16>" )
			)
			( signal "@baseboard_fab2_lib.baseboard_fab2(sch_1):m_e_ba(1)"
				( pinPairRef "@baseboard_fab2_lib.baseboard_fab2(sch_1):\PP3779\" )
				( pinPairRef "@baseboard_fab2_lib.baseboard_fab2(sch_1):\PP3780\" )
				( objectStatus "M_E_BA<1>" )
			)
			( signal "@baseboard_fab2_lib.baseboard_fab2(sch_1):m_e_ma(10)"
				( pinPairRef "@baseboard_fab2_lib.baseboard_fab2(sch_1):\PP3781\" )
				( pinPairRef "@baseboard_fab2_lib.baseboard_fab2(sch_1):\PP3782\" )
				( attribute "NO_TEST" "1"
					( Origin gBackEnd )
				)
				( objectStatus "M_E_MA<10>" )
			)
			( signal "@baseboard_fab2_lib.baseboard_fab2(sch_1):m_e_ba(0)"
				( pinPairRef "@baseboard_fab2_lib.baseboard_fab2(sch_1):\PP3775\" )
				( pinPairRef "@baseboard_fab2_lib.baseboard_fab2(sch_1):\PP3776\" )
				( objectStatus "M_E_BA<0>" )
			)
			( signal "@baseboard_fab2_lib.baseboard_fab2(sch_1):m_e_ma(0)"
				( pinPairRef "@baseboard_fab2_lib.baseboard_fab2(sch_1):\PP3777\" )
				( pinPairRef "@baseboard_fab2_lib.baseboard_fab2(sch_1):\PP3778\" )
				( attribute "NO_TEST" "1"
					( Origin gBackEnd )
				)
				( objectStatus "M_E_MA<0>" )
			)
			( signal "@baseboard_fab2_lib.baseboard_fab2(sch_1):m_e_par"
				( pinPairRef "@baseboard_fab2_lib.baseboard_fab2(sch_1):\PP3773\" )
				( pinPairRef "@baseboard_fab2_lib.baseboard_fab2(sch_1):\PP3774\" )
				( objectStatus "M_E_PAR" )
			)
			( signal "@baseboard_fab2_lib.baseboard_fab2(sch_1):m_e_ma(1)"
				( pinPairRef "@baseboard_fab2_lib.baseboard_fab2(sch_1):\PP3769\" )
				( pinPairRef "@baseboard_fab2_lib.baseboard_fab2(sch_1):\PP3770\" )
				( attribute "NO_TEST" "1"
					( Origin gBackEnd )
				)
				( objectStatus "M_E_MA<1>" )
			)
			( signal "@baseboard_fab2_lib.baseboard_fab2(sch_1):m_e_ma(3)"
				( pinPairRef "@baseboard_fab2_lib.baseboard_fab2(sch_1):\PP3771\" )
				( pinPairRef "@baseboard_fab2_lib.baseboard_fab2(sch_1):\PP3772\" )
				( objectStatus "M_E_MA<3>" )
			)
			( signal "@baseboard_fab2_lib.baseboard_fab2(sch_1):m_e_ma(2)"
				( pinPairRef "@baseboard_fab2_lib.baseboard_fab2(sch_1):\PP3765\" )
				( pinPairRef "@baseboard_fab2_lib.baseboard_fab2(sch_1):\PP3766\" )
				( objectStatus "M_E_MA<2>" )
			)
			( signal "@baseboard_fab2_lib.baseboard_fab2(sch_1):m_e_ma(4)"
				( pinPairRef "@baseboard_fab2_lib.baseboard_fab2(sch_1):\PP3767\" )
				( pinPairRef "@baseboard_fab2_lib.baseboard_fab2(sch_1):\PP3768\" )
				( attribute "NO_TEST" "1"
					( Origin gBackEnd )
				)
				( objectStatus "M_E_MA<4>" )
			)
			( signal "@baseboard_fab2_lib.baseboard_fab2(sch_1):m_e_ma(5)"
				( pinPairRef "@baseboard_fab2_lib.baseboard_fab2(sch_1):\PP3761\" )
				( pinPairRef "@baseboard_fab2_lib.baseboard_fab2(sch_1):\PP3762\" )
				( attribute "NO_TEST" "1"
					( Origin gBackEnd )
				)
				( objectStatus "M_E_MA<5>" )
			)
			( signal "@baseboard_fab2_lib.baseboard_fab2(sch_1):m_e_ma(6)"
				( pinPairRef "@baseboard_fab2_lib.baseboard_fab2(sch_1):\PP3763\" )
				( pinPairRef "@baseboard_fab2_lib.baseboard_fab2(sch_1):\PP3764\" )
				( objectStatus "M_E_MA<6>" )
			)
			( signal "@baseboard_fab2_lib.baseboard_fab2(sch_1):m_e_ma(7)"
				( pinPairRef "@baseboard_fab2_lib.baseboard_fab2(sch_1):\PP3757\" )
				( pinPairRef "@baseboard_fab2_lib.baseboard_fab2(sch_1):\PP3758\" )
				( attribute "NO_TEST" "1"
					( Origin gBackEnd )
				)
				( objectStatus "M_E_MA<7>" )
			)
			( signal "@baseboard_fab2_lib.baseboard_fab2(sch_1):m_e_ma(8)"
				( pinPairRef "@baseboard_fab2_lib.baseboard_fab2(sch_1):\PP3759\" )
				( pinPairRef "@baseboard_fab2_lib.baseboard_fab2(sch_1):\PP3760\" )
				( objectStatus "M_E_MA<8>" )
			)
			( signal "@baseboard_fab2_lib.baseboard_fab2(sch_1):m_e_ma(9)"
				( pinPairRef "@baseboard_fab2_lib.baseboard_fab2(sch_1):\PP3753\" )
				( pinPairRef "@baseboard_fab2_lib.baseboard_fab2(sch_1):\PP3754\" )
				( objectStatus "M_E_MA<9>" )
			)
			( signal "@baseboard_fab2_lib.baseboard_fab2(sch_1):m_e_ma(12)"
				( pinPairRef "@baseboard_fab2_lib.baseboard_fab2(sch_1):\PP3755\" )
				( pinPairRef "@baseboard_fab2_lib.baseboard_fab2(sch_1):\PP3756\" )
				( attribute "NO_TEST" "1"
					( Origin gBackEnd )
				)
				( objectStatus "M_E_MA<12>" )
			)
			( signal "@baseboard_fab2_lib.baseboard_fab2(sch_1):m_e_bg(1)"
				( pinPairRef "@baseboard_fab2_lib.baseboard_fab2(sch_1):\PP3749\" )
				( pinPairRef "@baseboard_fab2_lib.baseboard_fab2(sch_1):\PP3750\" )
				( objectStatus "M_E_BG<1>" )
			)
			( signal "@baseboard_fab2_lib.baseboard_fab2(sch_1):m_e_ma(11)"
				( pinPairRef "@baseboard_fab2_lib.baseboard_fab2(sch_1):\PP3751\" )
				( pinPairRef "@baseboard_fab2_lib.baseboard_fab2(sch_1):\PP3752\" )
				( objectStatus "M_E_MA<11>" )
			)
			( signal "@baseboard_fab2_lib.baseboard_fab2(sch_1):m_e_act_n"
				( pinPairRef "@baseboard_fab2_lib.baseboard_fab2(sch_1):\PP3745\" )
				( pinPairRef "@baseboard_fab2_lib.baseboard_fab2(sch_1):\PP3746\" )
				( objectStatus "M_E_ACT_N" )
			)
			( signal "@baseboard_fab2_lib.baseboard_fab2(sch_1):m_e_bg(0)"
				( pinPairRef "@baseboard_fab2_lib.baseboard_fab2(sch_1):\PP3747\" )
				( pinPairRef "@baseboard_fab2_lib.baseboard_fab2(sch_1):\PP3748\" )
				( objectStatus "M_E_BG<0>" )
			)
			( signal "@baseboard_fab2_lib.baseboard_fab2(sch_1):m_e_cs_n(0)"
				( pinPairRef "@baseboard_fab2_lib.baseboard_fab2(sch_1):\PP3743\" )
				( objectStatus "M_E_CS_N<0>" )
			)
			( signal "@baseboard_fab2_lib.baseboard_fab2(sch_1):m_e_odt(0)"
				( pinPairRef "@baseboard_fab2_lib.baseboard_fab2(sch_1):\PP3744\" )
				( objectStatus "M_E_ODT<0>" )
			)
			( signal "@baseboard_fab2_lib.baseboard_fab2(sch_1):m_e_cke(0)"
				( pinPairRef "@baseboard_fab2_lib.baseboard_fab2(sch_1):\PP3742\" )
				( attribute "NO_TEST" "1"
					( Origin gBackEnd )
				)
				( objectStatus "M_E_CKE<0>" )
			)
			( signal "@baseboard_fab2_lib.baseboard_fab2(sch_1):m_e_cs_n(2)"
				( pinPairRef "@baseboard_fab2_lib.baseboard_fab2(sch_1):\PP3741\" )
				( objectStatus "M_E_CS_N<2>" )
			)
			( signal "@baseboard_fab2_lib.baseboard_fab2(sch_1):m_e_cs_n(3)"
				( pinPairRef "@baseboard_fab2_lib.baseboard_fab2(sch_1):\PP3740\" )
				( attribute "NO_TEST" "1"
					( Origin gBackEnd )
				)
				( objectStatus "M_E_CS_N<3>" )
			)
			( signal "@baseboard_fab2_lib.baseboard_fab2(sch_1):m_e_cs_n(1)"
				( pinPairRef "@baseboard_fab2_lib.baseboard_fab2(sch_1):\PP3738\" )
				( attribute "NO_TEST" "1"
					( Origin gBackEnd )
				)
				( objectStatus "M_E_CS_N<1>" )
			)
			( signal "@baseboard_fab2_lib.baseboard_fab2(sch_1):m_e_odt(1)"
				( pinPairRef "@baseboard_fab2_lib.baseboard_fab2(sch_1):\PP3739\" )
				( attribute "NO_TEST" "1"
					( Origin gBackEnd )
				)
				( objectStatus "M_E_ODT<1>" )
			)
			( signal "@baseboard_fab2_lib.baseboard_fab2(sch_1):m_e_cke(1)"
				( pinPairRef "@baseboard_fab2_lib.baseboard_fab2(sch_1):\PP3737\" )
				( attribute "NO_TEST" "1"
					( Origin gBackEnd )
				)
				( objectStatus "M_E_CKE<1>" )
			)
			( signal "@baseboard_fab2_lib.baseboard_fab2(sch_1):m_e_cs_n(4)"
				( pinPairRef "@baseboard_fab2_lib.baseboard_fab2(sch_1):\PP3735\" )
				( attribute "NO_TEST" "1"
					( Origin gBackEnd )
				)
				( objectStatus "M_E_CS_N<4>" )
			)
			( signal "@baseboard_fab2_lib.baseboard_fab2(sch_1):m_e_odt(2)"
				( pinPairRef "@baseboard_fab2_lib.baseboard_fab2(sch_1):\PP3736\" )
				( attribute "NO_TEST" "1"
					( Origin gBackEnd )
				)
				( objectStatus "M_E_ODT<2>" )
			)
			( signal "@baseboard_fab2_lib.baseboard_fab2(sch_1):m_e_cke(2)"
				( pinPairRef "@baseboard_fab2_lib.baseboard_fab2(sch_1):\PP3734\" )
				( objectStatus "M_E_CKE<2>" )
			)
			( signal "@baseboard_fab2_lib.baseboard_fab2(sch_1):m_e_cs_n(6)"
				( pinPairRef "@baseboard_fab2_lib.baseboard_fab2(sch_1):\PP3732\" )
				( attribute "NO_TEST" "1"
					( Origin gBackEnd )
				)
				( objectStatus "M_E_CS_N<6>" )
			)
			( signal "@baseboard_fab2_lib.baseboard_fab2(sch_1):m_e_cs_n(7)"
				( pinPairRef "@baseboard_fab2_lib.baseboard_fab2(sch_1):\PP3733\" )
				( attribute "NO_TEST" "1"
					( Origin gBackEnd )
				)
				( objectStatus "M_E_CS_N<7>" )
			)
			( signal "@baseboard_fab2_lib.baseboard_fab2(sch_1):m_e_cs_n(5)"
				( pinPairRef "@baseboard_fab2_lib.baseboard_fab2(sch_1):\PP3730\" )
				( objectStatus "M_E_CS_N<5>" )
			)
			( signal "@baseboard_fab2_lib.baseboard_fab2(sch_1):m_e_odt(3)"
				( pinPairRef "@baseboard_fab2_lib.baseboard_fab2(sch_1):\PP3731\" )
				( objectStatus "M_E_ODT<3>" )
			)
			( signal "@baseboard_fab2_lib.baseboard_fab2(sch_1):m_e_cke(3)"
				( pinPairRef "@baseboard_fab2_lib.baseboard_fab2(sch_1):\PP3729\" )
				( objectStatus "M_E_CKE<3>" )
			)
			( signal "@baseboard_fab2_lib.baseboard_fab2(sch_1):m_e_clk_dn(0)"
				( objectStatus "M_E_CLK_DN<0>" )
			)
			( signal "@baseboard_fab2_lib.baseboard_fab2(sch_1):m_e_clk_dp(0)"
				( electricalCSetRef "@crescent_city_bb_fab1_lib.crescent_city_bb_fab1(sch_1):\M_A_CLK_DP_0_\" )
				( attribute "NO_TEST" "1"
					( Origin gBackEnd )
				)
				( attribute "RELATIVE_PROPAGATION_DELAY_SCOPE" "G"
					( Parent
						( matchGroupRef "@crescent_city_bb_fab1_lib.crescent_city_bb_fab1(sch_1):\MG_DDR_FAR_DIMM-CLK0_CLS_DDR_E_CAC-CLKS\" )
					)
					( Origin gBackEnd )
				)
				( attribute "RELATIVE_PROPAGATION_DELAY_PATH_TYPE" "L:S"
					( Parent
						( matchGroupRef "@crescent_city_bb_fab1_lib.crescent_city_bb_fab1(sch_1):\MG_DDR_FAR_DIMM-CLK0_CLS_DDR_E_CAC-CLKS\" )
					)
					( Origin gBackEnd )
				)
				( attribute "RELATIVE_PROPAGATION_DELAY" "TARGET,TARGET"
					( Parent
						( matchGroupRef "@crescent_city_bb_fab1_lib.crescent_city_bb_fab1(sch_1):\MG_DDR_FAR_DIMM-CLK0_CLS_DDR_E_CAC-CLKS\" )
					)
					( Units "uMatchProp" "ns" 1.000000)
					( Origin gBackEnd )
				)
				( objectStatus "M_E_CLK_DP<0>" )
			)
			( signal "@baseboard_fab2_lib.baseboard_fab2(sch_1):m_e_clk_dn(2)"
				( objectStatus "M_E_CLK_DN<2>" )
			)
			( signal "@baseboard_fab2_lib.baseboard_fab2(sch_1):m_e_clk_dp(2)"
				( electricalCSetRef "@crescent_city_bb_fab1_lib.crescent_city_bb_fab1(sch_1):\DDR_CLK1\" )
				( attribute "NO_TEST" "1"
					( Origin gBackEnd )
				)
				( attribute "RELATIVE_PROPAGATION_DELAY_SCOPE" "G"
					( Parent
						( matchGroupRef "@crescent_city_bb_fab1_lib.crescent_city_bb_fab1(sch_1):\MG_DDR_NEAR_DIMM-CLK1_CLS_DDR_E_CAC-CLKS\" )
					)
					( Origin gBackEnd )
				)
				( attribute "RELATIVE_PROPAGATION_DELAY_PATH_TYPE" "L:S"
					( Parent
						( matchGroupRef "@crescent_city_bb_fab1_lib.crescent_city_bb_fab1(sch_1):\MG_DDR_NEAR_DIMM-CLK1_CLS_DDR_E_CAC-CLKS\" )
					)
					( Origin gBackEnd )
				)
				( attribute "RELATIVE_PROPAGATION_DELAY" "TARGET,TARGET"
					( Parent
						( matchGroupRef "@crescent_city_bb_fab1_lib.crescent_city_bb_fab1(sch_1):\MG_DDR_NEAR_DIMM-CLK1_CLS_DDR_E_CAC-CLKS\" )
					)
					( Units "uMatchProp" "ns" 1.000000)
					( Origin gBackEnd )
				)
				( objectStatus "M_E_CLK_DP<2>" )
			)
			( signal "@baseboard_fab2_lib.baseboard_fab2(sch_1):m_d_ma(17)"
				( pinPairRef "@baseboard_fab2_lib.baseboard_fab2(sch_1):\PP3857\" )
				( pinPairRef "@baseboard_fab2_lib.baseboard_fab2(sch_1):\PP3858\" )
				( objectStatus "M_D_MA<17>" )
			)
			( signal "@baseboard_fab2_lib.baseboard_fab2(sch_1):m_d_c(2)"
				( pinPairRef "@baseboard_fab2_lib.baseboard_fab2(sch_1):\PP3859\" )
				( pinPairRef "@baseboard_fab2_lib.baseboard_fab2(sch_1):\PP3860\" )
				( objectStatus "M_D_C<2>" )
			)
			( signal "@baseboard_fab2_lib.baseboard_fab2(sch_1):m_d_ma(13)"
				( pinPairRef "@baseboard_fab2_lib.baseboard_fab2(sch_1):\PP3853\" )
				( pinPairRef "@baseboard_fab2_lib.baseboard_fab2(sch_1):\PP3854\" )
				( attribute "NO_TEST" "1"
					( Origin gBackEnd )
				)
				( objectStatus "M_D_MA<13>" )
			)
			( signal "@baseboard_fab2_lib.baseboard_fab2(sch_1):m_d_ma(15)"
				( pinPairRef "@baseboard_fab2_lib.baseboard_fab2(sch_1):\PP3855\" )
				( pinPairRef "@baseboard_fab2_lib.baseboard_fab2(sch_1):\PP3856\" )
				( objectStatus "M_D_MA<15>" )
			)
			( signal "@baseboard_fab2_lib.baseboard_fab2(sch_1):m_d_ma(14)"
				( pinPairRef "@baseboard_fab2_lib.baseboard_fab2(sch_1):\PP3849\" )
				( pinPairRef "@baseboard_fab2_lib.baseboard_fab2(sch_1):\PP3850\" )
				( attribute "NO_TEST" "1"
					( Origin gBackEnd )
				)
				( objectStatus "M_D_MA<14>" )
			)
			( signal "@baseboard_fab2_lib.baseboard_fab2(sch_1):m_d_ma(16)"
				( pinPairRef "@baseboard_fab2_lib.baseboard_fab2(sch_1):\PP3851\" )
				( pinPairRef "@baseboard_fab2_lib.baseboard_fab2(sch_1):\PP3852\" )
				( attribute "NO_TEST" "1"
					( Origin gBackEnd )
				)
				( objectStatus "M_D_MA<16>" )
			)
			( signal "@baseboard_fab2_lib.baseboard_fab2(sch_1):m_d_ba(1)"
				( pinPairRef "@baseboard_fab2_lib.baseboard_fab2(sch_1):\PP3845\" )
				( pinPairRef "@baseboard_fab2_lib.baseboard_fab2(sch_1):\PP3846\" )
				( objectStatus "M_D_BA<1>" )
			)
			( signal "@baseboard_fab2_lib.baseboard_fab2(sch_1):m_d_ma(10)"
				( pinPairRef "@baseboard_fab2_lib.baseboard_fab2(sch_1):\PP3847\" )
				( pinPairRef "@baseboard_fab2_lib.baseboard_fab2(sch_1):\PP3848\" )
				( attribute "NO_TEST" "1"
					( Origin gBackEnd )
				)
				( objectStatus "M_D_MA<10>" )
			)
			( signal "@baseboard_fab2_lib.baseboard_fab2(sch_1):m_d_ba(0)"
				( pinPairRef "@baseboard_fab2_lib.baseboard_fab2(sch_1):\PP3841\" )
				( pinPairRef "@baseboard_fab2_lib.baseboard_fab2(sch_1):\PP3842\" )
				( attribute "NO_TEST" "1"
					( Origin gBackEnd )
				)
				( objectStatus "M_D_BA<0>" )
			)
			( signal "@baseboard_fab2_lib.baseboard_fab2(sch_1):m_d_ma(0)"
				( pinPairRef "@baseboard_fab2_lib.baseboard_fab2(sch_1):\PP3843\" )
				( pinPairRef "@baseboard_fab2_lib.baseboard_fab2(sch_1):\PP3844\" )
				( attribute "NO_TEST" "1"
					( Origin gBackEnd )
				)
				( objectStatus "M_D_MA<0>" )
			)
			( signal "@baseboard_fab2_lib.baseboard_fab2(sch_1):m_d_par"
				( pinPairRef "@baseboard_fab2_lib.baseboard_fab2(sch_1):\PP3839\" )
				( pinPairRef "@baseboard_fab2_lib.baseboard_fab2(sch_1):\PP3840\" )
				( attribute "NO_TEST" "1"
					( Origin gBackEnd )
				)
				( objectStatus "M_D_PAR" )
			)
			( signal "@baseboard_fab2_lib.baseboard_fab2(sch_1):m_d_ma(1)"
				( pinPairRef "@baseboard_fab2_lib.baseboard_fab2(sch_1):\PP3835\" )
				( pinPairRef "@baseboard_fab2_lib.baseboard_fab2(sch_1):\PP3836\" )
				( attribute "NO_TEST" "1"
					( Origin gBackEnd )
				)
				( objectStatus "M_D_MA<1>" )
			)
			( signal "@baseboard_fab2_lib.baseboard_fab2(sch_1):m_d_ma(3)"
				( pinPairRef "@baseboard_fab2_lib.baseboard_fab2(sch_1):\PP3837\" )
				( pinPairRef "@baseboard_fab2_lib.baseboard_fab2(sch_1):\PP3838\" )
				( attribute "NO_TEST" "1"
					( Origin gBackEnd )
				)
				( objectStatus "M_D_MA<3>" )
			)
			( signal "@baseboard_fab2_lib.baseboard_fab2(sch_1):m_d_ma(2)"
				( pinPairRef "@baseboard_fab2_lib.baseboard_fab2(sch_1):\PP3831\" )
				( pinPairRef "@baseboard_fab2_lib.baseboard_fab2(sch_1):\PP3832\" )
				( attribute "NO_TEST" "1"
					( Origin gBackEnd )
				)
				( objectStatus "M_D_MA<2>" )
			)
			( signal "@baseboard_fab2_lib.baseboard_fab2(sch_1):m_d_ma(4)"
				( pinPairRef "@baseboard_fab2_lib.baseboard_fab2(sch_1):\PP3833\" )
				( pinPairRef "@baseboard_fab2_lib.baseboard_fab2(sch_1):\PP3834\" )
				( attribute "NO_TEST" "1"
					( Origin gBackEnd )
				)
				( objectStatus "M_D_MA<4>" )
			)
			( signal "@baseboard_fab2_lib.baseboard_fab2(sch_1):m_d_ma(5)"
				( pinPairRef "@baseboard_fab2_lib.baseboard_fab2(sch_1):\PP3827\" )
				( pinPairRef "@baseboard_fab2_lib.baseboard_fab2(sch_1):\PP3828\" )
				( attribute "NO_TEST" "1"
					( Origin gBackEnd )
				)
				( objectStatus "M_D_MA<5>" )
			)
			( signal "@baseboard_fab2_lib.baseboard_fab2(sch_1):m_d_ma(6)"
				( pinPairRef "@baseboard_fab2_lib.baseboard_fab2(sch_1):\PP3829\" )
				( pinPairRef "@baseboard_fab2_lib.baseboard_fab2(sch_1):\PP3830\" )
				( attribute "NO_TEST" "1"
					( Origin gBackEnd )
				)
				( objectStatus "M_D_MA<6>" )
			)
			( signal "@baseboard_fab2_lib.baseboard_fab2(sch_1):m_d_ma(7)"
				( pinPairRef "@baseboard_fab2_lib.baseboard_fab2(sch_1):\PP3823\" )
				( pinPairRef "@baseboard_fab2_lib.baseboard_fab2(sch_1):\PP3824\" )
				( attribute "NO_TEST" "1"
					( Origin gBackEnd )
				)
				( objectStatus "M_D_MA<7>" )
			)
			( signal "@baseboard_fab2_lib.baseboard_fab2(sch_1):m_d_ma(8)"
				( pinPairRef "@baseboard_fab2_lib.baseboard_fab2(sch_1):\PP3825\" )
				( pinPairRef "@baseboard_fab2_lib.baseboard_fab2(sch_1):\PP3826\" )
				( attribute "NO_TEST" "1"
					( Origin gBackEnd )
				)
				( objectStatus "M_D_MA<8>" )
			)
			( signal "@baseboard_fab2_lib.baseboard_fab2(sch_1):m_d_ma(9)"
				( pinPairRef "@baseboard_fab2_lib.baseboard_fab2(sch_1):\PP3819\" )
				( pinPairRef "@baseboard_fab2_lib.baseboard_fab2(sch_1):\PP3820\" )
				( objectStatus "M_D_MA<9>" )
			)
			( signal "@baseboard_fab2_lib.baseboard_fab2(sch_1):m_d_ma(12)"
				( pinPairRef "@baseboard_fab2_lib.baseboard_fab2(sch_1):\PP3821\" )
				( pinPairRef "@baseboard_fab2_lib.baseboard_fab2(sch_1):\PP3822\" )
				( attribute "NO_TEST" "1"
					( Origin gBackEnd )
				)
				( objectStatus "M_D_MA<12>" )
			)
			( signal "@baseboard_fab2_lib.baseboard_fab2(sch_1):m_d_bg(1)"
				( pinPairRef "@baseboard_fab2_lib.baseboard_fab2(sch_1):\PP3815\" )
				( pinPairRef "@baseboard_fab2_lib.baseboard_fab2(sch_1):\PP3816\" )
				( attribute "NO_TEST" "1"
					( Origin gBackEnd )
				)
				( objectStatus "M_D_BG<1>" )
			)
			( signal "@baseboard_fab2_lib.baseboard_fab2(sch_1):m_d_ma(11)"
				( pinPairRef "@baseboard_fab2_lib.baseboard_fab2(sch_1):\PP3817\" )
				( pinPairRef "@baseboard_fab2_lib.baseboard_fab2(sch_1):\PP3818\" )
				( attribute "NO_TEST" "1"
					( Origin gBackEnd )
				)
				( objectStatus "M_D_MA<11>" )
			)
			( signal "@baseboard_fab2_lib.baseboard_fab2(sch_1):m_d_act_n"
				( pinPairRef "@baseboard_fab2_lib.baseboard_fab2(sch_1):\PP3811\" )
				( pinPairRef "@baseboard_fab2_lib.baseboard_fab2(sch_1):\PP3812\" )
				( attribute "NO_TEST" "1"
					( Origin gBackEnd )
				)
				( objectStatus "M_D_ACT_N" )
			)
			( signal "@baseboard_fab2_lib.baseboard_fab2(sch_1):m_d_bg(0)"
				( pinPairRef "@baseboard_fab2_lib.baseboard_fab2(sch_1):\PP3813\" )
				( pinPairRef "@baseboard_fab2_lib.baseboard_fab2(sch_1):\PP3814\" )
				( attribute "NO_TEST" "1"
					( Origin gBackEnd )
				)
				( objectStatus "M_D_BG<0>" )
			)
			( signal "@baseboard_fab2_lib.baseboard_fab2(sch_1):m_d_cs_n(0)"
				( pinPairRef "@baseboard_fab2_lib.baseboard_fab2(sch_1):\PP3809\" )
				( attribute "NO_TEST" "1"
					( Origin gBackEnd )
				)
				( objectStatus "M_D_CS_N<0>" )
			)
			( signal "@baseboard_fab2_lib.baseboard_fab2(sch_1):m_d_odt(0)"
				( pinPairRef "@baseboard_fab2_lib.baseboard_fab2(sch_1):\PP3810\" )
				( attribute "NO_TEST" "1"
					( Origin gBackEnd )
				)
				( objectStatus "M_D_ODT<0>" )
			)
			( signal "@baseboard_fab2_lib.baseboard_fab2(sch_1):m_d_cke(0)"
				( pinPairRef "@baseboard_fab2_lib.baseboard_fab2(sch_1):\PP3808\" )
				( attribute "NO_TEST" "1"
					( Origin gBackEnd )
				)
				( objectStatus "M_D_CKE<0>" )
			)
			( signal "@baseboard_fab2_lib.baseboard_fab2(sch_1):m_d_cs_n(2)"
				( pinPairRef "@baseboard_fab2_lib.baseboard_fab2(sch_1):\PP3807\" )
				( attribute "NO_TEST" "1"
					( Origin gBackEnd )
				)
				( objectStatus "M_D_CS_N<2>" )
			)
			( signal "@baseboard_fab2_lib.baseboard_fab2(sch_1):m_d_cs_n(3)"
				( pinPairRef "@baseboard_fab2_lib.baseboard_fab2(sch_1):\PP3806\" )
				( attribute "NO_TEST" "1"
					( Origin gBackEnd )
				)
				( objectStatus "M_D_CS_N<3>" )
			)
			( signal "@baseboard_fab2_lib.baseboard_fab2(sch_1):m_d_cs_n(1)"
				( pinPairRef "@baseboard_fab2_lib.baseboard_fab2(sch_1):\PP3804\" )
				( attribute "NO_TEST" "1"
					( Origin gBackEnd )
				)
				( objectStatus "M_D_CS_N<1>" )
			)
			( signal "@baseboard_fab2_lib.baseboard_fab2(sch_1):m_d_odt(1)"
				( pinPairRef "@baseboard_fab2_lib.baseboard_fab2(sch_1):\PP3805\" )
				( attribute "NO_TEST" "1"
					( Origin gBackEnd )
				)
				( objectStatus "M_D_ODT<1>" )
			)
			( signal "@baseboard_fab2_lib.baseboard_fab2(sch_1):m_d_cke(1)"
				( pinPairRef "@baseboard_fab2_lib.baseboard_fab2(sch_1):\PP3803\" )
				( attribute "NO_TEST" "1"
					( Origin gBackEnd )
				)
				( objectStatus "M_D_CKE<1>" )
			)
			( signal "@baseboard_fab2_lib.baseboard_fab2(sch_1):m_d_cs_n(4)"
				( pinPairRef "@baseboard_fab2_lib.baseboard_fab2(sch_1):\PP3801\" )
				( attribute "NO_TEST" "1"
					( Origin gBackEnd )
				)
				( objectStatus "M_D_CS_N<4>" )
			)
			( signal "@baseboard_fab2_lib.baseboard_fab2(sch_1):m_d_odt(2)"
				( pinPairRef "@baseboard_fab2_lib.baseboard_fab2(sch_1):\PP3802\" )
				( attribute "NO_TEST" "1"
					( Origin gBackEnd )
				)
				( objectStatus "M_D_ODT<2>" )
			)
			( signal "@baseboard_fab2_lib.baseboard_fab2(sch_1):m_d_cke(2)"
				( pinPairRef "@baseboard_fab2_lib.baseboard_fab2(sch_1):\PP3800\" )
				( attribute "NO_TEST" "1"
					( Origin gBackEnd )
				)
				( objectStatus "M_D_CKE<2>" )
			)
			( signal "@baseboard_fab2_lib.baseboard_fab2(sch_1):m_d_cs_n(6)"
				( pinPairRef "@baseboard_fab2_lib.baseboard_fab2(sch_1):\PP3798\" )
				( attribute "NO_TEST" "1"
					( Origin gBackEnd )
				)
				( objectStatus "M_D_CS_N<6>" )
			)
			( signal "@baseboard_fab2_lib.baseboard_fab2(sch_1):m_d_cs_n(7)"
				( pinPairRef "@baseboard_fab2_lib.baseboard_fab2(sch_1):\PP3799\" )
				( attribute "NO_TEST" "1"
					( Origin gBackEnd )
				)
				( objectStatus "M_D_CS_N<7>" )
			)
			( signal "@baseboard_fab2_lib.baseboard_fab2(sch_1):m_d_cs_n(5)"
				( pinPairRef "@baseboard_fab2_lib.baseboard_fab2(sch_1):\PP3796\" )
				( attribute "NO_TEST" "1"
					( Origin gBackEnd )
				)
				( objectStatus "M_D_CS_N<5>" )
			)
			( signal "@baseboard_fab2_lib.baseboard_fab2(sch_1):m_d_odt(3)"
				( pinPairRef "@baseboard_fab2_lib.baseboard_fab2(sch_1):\PP3797\" )
				( attribute "NO_TEST" "1"
					( Origin gBackEnd )
				)
				( objectStatus "M_D_ODT<3>" )
			)
			( signal "@baseboard_fab2_lib.baseboard_fab2(sch_1):m_d_cke(3)"
				( pinPairRef "@baseboard_fab2_lib.baseboard_fab2(sch_1):\PP3795\" )
				( attribute "NO_TEST" "1"
					( Origin gBackEnd )
				)
				( objectStatus "M_D_CKE<3>" )
			)
			( signal "@baseboard_fab2_lib.baseboard_fab2(sch_1):m_d_clk_dn(0)"
				( attribute "NO_TEST" "1"
					( Origin gBackEnd )
				)
				( objectStatus "M_D_CLK_DN<0>" )
			)
			( signal "@baseboard_fab2_lib.baseboard_fab2(sch_1):m_d_clk_dp(0)"
				( electricalCSetRef "@crescent_city_bb_fab1_lib.crescent_city_bb_fab1(sch_1):\M_A_CLK_DP_0_\" )
				( attribute "NO_TEST" "1"
					( Origin gBackEnd )
				)
				( attribute "RELATIVE_PROPAGATION_DELAY_SCOPE" "G"
					( Parent
						( matchGroupRef "@crescent_city_bb_fab1_lib.crescent_city_bb_fab1(sch_1):\MG_DDR_FAR_DIMM-CLK0_CLS_DDR_D_CAC-CLKS\" )
					)
					( Origin gBackEnd )
				)
				( attribute "RELATIVE_PROPAGATION_DELAY_PATH_TYPE" "L:S"
					( Parent
						( matchGroupRef "@crescent_city_bb_fab1_lib.crescent_city_bb_fab1(sch_1):\MG_DDR_FAR_DIMM-CLK0_CLS_DDR_D_CAC-CLKS\" )
					)
					( Origin gBackEnd )
				)
				( attribute "RELATIVE_PROPAGATION_DELAY" "TARGET,TARGET"
					( Parent
						( matchGroupRef "@crescent_city_bb_fab1_lib.crescent_city_bb_fab1(sch_1):\MG_DDR_FAR_DIMM-CLK0_CLS_DDR_D_CAC-CLKS\" )
					)
					( Units "uMatchProp" "ns" 1.000000)
					( Origin gBackEnd )
				)
				( objectStatus "M_D_CLK_DP<0>" )
			)
			( signal "@baseboard_fab2_lib.baseboard_fab2(sch_1):m_d_clk_dn(2)"
				( attribute "NO_TEST" "1"
					( Origin gBackEnd )
				)
				( objectStatus "M_D_CLK_DN<2>" )
			)
			( signal "@baseboard_fab2_lib.baseboard_fab2(sch_1):m_d_clk_dp(2)"
				( electricalCSetRef "@crescent_city_bb_fab1_lib.crescent_city_bb_fab1(sch_1):\DDR_CLK1\" )
				( attribute "NO_TEST" "1"
					( Origin gBackEnd )
				)
				( attribute "RELATIVE_PROPAGATION_DELAY_SCOPE" "G"
					( Parent
						( matchGroupRef "@crescent_city_bb_fab1_lib.crescent_city_bb_fab1(sch_1):\MG_DDR_NEAR_DIMM-CLK1_CLS_DDR_D_CAC-CLKS\" )
					)
					( Origin gBackEnd )
				)
				( attribute "RELATIVE_PROPAGATION_DELAY_PATH_TYPE" "L:S"
					( Parent
						( matchGroupRef "@crescent_city_bb_fab1_lib.crescent_city_bb_fab1(sch_1):\MG_DDR_NEAR_DIMM-CLK1_CLS_DDR_D_CAC-CLKS\" )
					)
					( Origin gBackEnd )
				)
				( attribute "RELATIVE_PROPAGATION_DELAY" "TARGET,TARGET"
					( Parent
						( matchGroupRef "@crescent_city_bb_fab1_lib.crescent_city_bb_fab1(sch_1):\MG_DDR_NEAR_DIMM-CLK1_CLS_DDR_D_CAC-CLKS\" )
					)
					( Units "uMatchProp" "ns" 1.000000)
					( Origin gBackEnd )
				)
				( objectStatus "M_D_CLK_DP<2>" )
			)
			( signal "@baseboard_fab2_lib.baseboard_fab2(sch_1):m_c_c(2)"
				( pinPairRef "@baseboard_fab2_lib.baseboard_fab2(sch_1):\PP3923\" )
				( pinPairRef "@baseboard_fab2_lib.baseboard_fab2(sch_1):\PP3924\" )
				( objectStatus "M_C_C<2>" )
			)
			( signal "@baseboard_fab2_lib.baseboard_fab2(sch_1):m_c_ma(17)"
				( pinPairRef "@baseboard_fab2_lib.baseboard_fab2(sch_1):\PP3925\" )
				( pinPairRef "@baseboard_fab2_lib.baseboard_fab2(sch_1):\PP3926\" )
				( attribute "NO_TEST" "1"
					( Origin gBackEnd )
				)
				( objectStatus "M_C_MA<17>" )
			)
			( signal "@baseboard_fab2_lib.baseboard_fab2(sch_1):m_c_ma(13)"
				( pinPairRef "@baseboard_fab2_lib.baseboard_fab2(sch_1):\PP3919\" )
				( pinPairRef "@baseboard_fab2_lib.baseboard_fab2(sch_1):\PP3920\" )
				( attribute "NO_TEST" "1"
					( Origin gBackEnd )
				)
				( objectStatus "M_C_MA<13>" )
			)
			( signal "@baseboard_fab2_lib.baseboard_fab2(sch_1):m_c_ma(15)"
				( pinPairRef "@baseboard_fab2_lib.baseboard_fab2(sch_1):\PP3921\" )
				( pinPairRef "@baseboard_fab2_lib.baseboard_fab2(sch_1):\PP3922\" )
				( objectStatus "M_C_MA<15>" )
			)
			( signal "@baseboard_fab2_lib.baseboard_fab2(sch_1):m_c_ma(14)"
				( pinPairRef "@baseboard_fab2_lib.baseboard_fab2(sch_1):\PP3915\" )
				( pinPairRef "@baseboard_fab2_lib.baseboard_fab2(sch_1):\PP3916\" )
				( objectStatus "M_C_MA<14>" )
			)
			( signal "@baseboard_fab2_lib.baseboard_fab2(sch_1):m_c_ma(16)"
				( pinPairRef "@baseboard_fab2_lib.baseboard_fab2(sch_1):\PP3917\" )
				( pinPairRef "@baseboard_fab2_lib.baseboard_fab2(sch_1):\PP3918\" )
				( attribute "NO_TEST" "1"
					( Origin gBackEnd )
				)
				( objectStatus "M_C_MA<16>" )
			)
			( signal "@baseboard_fab2_lib.baseboard_fab2(sch_1):m_c_ba(1)"
				( pinPairRef "@baseboard_fab2_lib.baseboard_fab2(sch_1):\PP3911\" )
				( pinPairRef "@baseboard_fab2_lib.baseboard_fab2(sch_1):\PP3912\" )
				( objectStatus "M_C_BA<1>" )
			)
			( signal "@baseboard_fab2_lib.baseboard_fab2(sch_1):m_c_ma(10)"
				( pinPairRef "@baseboard_fab2_lib.baseboard_fab2(sch_1):\PP3913\" )
				( pinPairRef "@baseboard_fab2_lib.baseboard_fab2(sch_1):\PP3914\" )
				( attribute "NO_TEST" "1"
					( Origin gBackEnd )
				)
				( objectStatus "M_C_MA<10>" )
			)
			( signal "@baseboard_fab2_lib.baseboard_fab2(sch_1):m_c_ba(0)"
				( pinPairRef "@baseboard_fab2_lib.baseboard_fab2(sch_1):\PP3907\" )
				( pinPairRef "@baseboard_fab2_lib.baseboard_fab2(sch_1):\PP3908\" )
				( objectStatus "M_C_BA<0>" )
			)
			( signal "@baseboard_fab2_lib.baseboard_fab2(sch_1):m_c_ma(0)"
				( pinPairRef "@baseboard_fab2_lib.baseboard_fab2(sch_1):\PP3909\" )
				( pinPairRef "@baseboard_fab2_lib.baseboard_fab2(sch_1):\PP3910\" )
				( objectStatus "M_C_MA<0>" )
			)
			( signal "@baseboard_fab2_lib.baseboard_fab2(sch_1):m_c_par"
				( pinPairRef "@baseboard_fab2_lib.baseboard_fab2(sch_1):\PP3905\" )
				( pinPairRef "@baseboard_fab2_lib.baseboard_fab2(sch_1):\PP3906\" )
				( attribute "NO_TEST" "1"
					( Origin gBackEnd )
				)
				( objectStatus "M_C_PAR" )
			)
			( signal "@baseboard_fab2_lib.baseboard_fab2(sch_1):m_c_ma(1)"
				( pinPairRef "@baseboard_fab2_lib.baseboard_fab2(sch_1):\PP3901\" )
				( pinPairRef "@baseboard_fab2_lib.baseboard_fab2(sch_1):\PP3902\" )
				( objectStatus "M_C_MA<1>" )
			)
			( signal "@baseboard_fab2_lib.baseboard_fab2(sch_1):m_c_ma(3)"
				( pinPairRef "@baseboard_fab2_lib.baseboard_fab2(sch_1):\PP3903\" )
				( pinPairRef "@baseboard_fab2_lib.baseboard_fab2(sch_1):\PP3904\" )
				( objectStatus "M_C_MA<3>" )
			)
			( signal "@baseboard_fab2_lib.baseboard_fab2(sch_1):m_c_ma(2)"
				( pinPairRef "@baseboard_fab2_lib.baseboard_fab2(sch_1):\PP3897\" )
				( pinPairRef "@baseboard_fab2_lib.baseboard_fab2(sch_1):\PP3898\" )
				( attribute "NO_TEST" "1"
					( Origin gBackEnd )
				)
				( objectStatus "M_C_MA<2>" )
			)
			( signal "@baseboard_fab2_lib.baseboard_fab2(sch_1):m_c_ma(4)"
				( pinPairRef "@baseboard_fab2_lib.baseboard_fab2(sch_1):\PP3899\" )
				( pinPairRef "@baseboard_fab2_lib.baseboard_fab2(sch_1):\PP3900\" )
				( attribute "NO_TEST" "1"
					( Origin gBackEnd )
				)
				( objectStatus "M_C_MA<4>" )
			)
			( signal "@baseboard_fab2_lib.baseboard_fab2(sch_1):m_c_ma(5)"
				( pinPairRef "@baseboard_fab2_lib.baseboard_fab2(sch_1):\PP3893\" )
				( pinPairRef "@baseboard_fab2_lib.baseboard_fab2(sch_1):\PP3894\" )
				( attribute "NO_TEST" "1"
					( Origin gBackEnd )
				)
				( objectStatus "M_C_MA<5>" )
			)
			( signal "@baseboard_fab2_lib.baseboard_fab2(sch_1):m_c_ma(6)"
				( pinPairRef "@baseboard_fab2_lib.baseboard_fab2(sch_1):\PP3895\" )
				( pinPairRef "@baseboard_fab2_lib.baseboard_fab2(sch_1):\PP3896\" )
				( objectStatus "M_C_MA<6>" )
			)
			( signal "@baseboard_fab2_lib.baseboard_fab2(sch_1):m_c_ma(7)"
				( pinPairRef "@baseboard_fab2_lib.baseboard_fab2(sch_1):\PP3889\" )
				( pinPairRef "@baseboard_fab2_lib.baseboard_fab2(sch_1):\PP3890\" )
				( objectStatus "M_C_MA<7>" )
			)
			( signal "@baseboard_fab2_lib.baseboard_fab2(sch_1):m_c_ma(8)"
				( pinPairRef "@baseboard_fab2_lib.baseboard_fab2(sch_1):\PP3891\" )
				( pinPairRef "@baseboard_fab2_lib.baseboard_fab2(sch_1):\PP3892\" )
				( attribute "NO_TEST" "1"
					( Origin gBackEnd )
				)
				( objectStatus "M_C_MA<8>" )
			)
			( signal "@baseboard_fab2_lib.baseboard_fab2(sch_1):m_c_ma(9)"
				( pinPairRef "@baseboard_fab2_lib.baseboard_fab2(sch_1):\PP3885\" )
				( pinPairRef "@baseboard_fab2_lib.baseboard_fab2(sch_1):\PP3886\" )
				( attribute "NO_TEST" "1"
					( Origin gBackEnd )
				)
				( objectStatus "M_C_MA<9>" )
			)
			( signal "@baseboard_fab2_lib.baseboard_fab2(sch_1):m_c_ma(12)"
				( pinPairRef "@baseboard_fab2_lib.baseboard_fab2(sch_1):\PP3887\" )
				( pinPairRef "@baseboard_fab2_lib.baseboard_fab2(sch_1):\PP3888\" )
				( attribute "NO_TEST" "1"
					( Origin gBackEnd )
				)
				( objectStatus "M_C_MA<12>" )
			)
			( signal "@baseboard_fab2_lib.baseboard_fab2(sch_1):m_c_bg(1)"
				( pinPairRef "@baseboard_fab2_lib.baseboard_fab2(sch_1):\PP3881\" )
				( pinPairRef "@baseboard_fab2_lib.baseboard_fab2(sch_1):\PP3882\" )
				( objectStatus "M_C_BG<1>" )
			)
			( signal "@baseboard_fab2_lib.baseboard_fab2(sch_1):m_c_ma(11)"
				( pinPairRef "@baseboard_fab2_lib.baseboard_fab2(sch_1):\PP3883\" )
				( pinPairRef "@baseboard_fab2_lib.baseboard_fab2(sch_1):\PP3884\" )
				( attribute "NO_TEST" "1"
					( Origin gBackEnd )
				)
				( objectStatus "M_C_MA<11>" )
			)
			( signal "@baseboard_fab2_lib.baseboard_fab2(sch_1):m_c_act_n"
				( pinPairRef "@baseboard_fab2_lib.baseboard_fab2(sch_1):\PP3877\" )
				( pinPairRef "@baseboard_fab2_lib.baseboard_fab2(sch_1):\PP3878\" )
				( objectStatus "M_C_ACT_N" )
			)
			( signal "@baseboard_fab2_lib.baseboard_fab2(sch_1):m_c_bg(0)"
				( pinPairRef "@baseboard_fab2_lib.baseboard_fab2(sch_1):\PP3879\" )
				( pinPairRef "@baseboard_fab2_lib.baseboard_fab2(sch_1):\PP3880\" )
				( attribute "NO_TEST" "1"
					( Origin gBackEnd )
				)
				( objectStatus "M_C_BG<0>" )
			)
			( signal "@baseboard_fab2_lib.baseboard_fab2(sch_1):m_c_cs_n(0)"
				( pinPairRef "@baseboard_fab2_lib.baseboard_fab2(sch_1):\PP3875\" )
				( attribute "NO_TEST" "1"
					( Origin gBackEnd )
				)
				( objectStatus "M_C_CS_N<0>" )
			)
			( signal "@baseboard_fab2_lib.baseboard_fab2(sch_1):m_c_odt(0)"
				( pinPairRef "@baseboard_fab2_lib.baseboard_fab2(sch_1):\PP3876\" )
				( attribute "NO_TEST" "1"
					( Origin gBackEnd )
				)
				( objectStatus "M_C_ODT<0>" )
			)
			( signal "@baseboard_fab2_lib.baseboard_fab2(sch_1):m_c_cke(0)"
				( pinPairRef "@baseboard_fab2_lib.baseboard_fab2(sch_1):\PP3874\" )
				( attribute "NO_TEST" "1"
					( Origin gBackEnd )
				)
				( objectStatus "M_C_CKE<0>" )
			)
			( signal "@baseboard_fab2_lib.baseboard_fab2(sch_1):m_c_cs_n(2)"
				( pinPairRef "@baseboard_fab2_lib.baseboard_fab2(sch_1):\PP3873\" )
				( objectStatus "M_C_CS_N<2>" )
			)
			( signal "@baseboard_fab2_lib.baseboard_fab2(sch_1):m_c_cs_n(3)"
				( pinPairRef "@baseboard_fab2_lib.baseboard_fab2(sch_1):\PP3872\" )
				( attribute "NO_TEST" "1"
					( Origin gBackEnd )
				)
				( objectStatus "M_C_CS_N<3>" )
			)
			( signal "@baseboard_fab2_lib.baseboard_fab2(sch_1):m_c_cs_n(1)"
				( pinPairRef "@baseboard_fab2_lib.baseboard_fab2(sch_1):\PP3870\" )
				( objectStatus "M_C_CS_N<1>" )
			)
			( signal "@baseboard_fab2_lib.baseboard_fab2(sch_1):m_c_odt(1)"
				( pinPairRef "@baseboard_fab2_lib.baseboard_fab2(sch_1):\PP3871\" )
				( attribute "NO_TEST" "1"
					( Origin gBackEnd )
				)
				( objectStatus "M_C_ODT<1>" )
			)
			( signal "@baseboard_fab2_lib.baseboard_fab2(sch_1):m_c_cke(1)"
				( pinPairRef "@baseboard_fab2_lib.baseboard_fab2(sch_1):\PP3869\" )
				( attribute "NO_TEST" "1"
					( Origin gBackEnd )
				)
				( objectStatus "M_C_CKE<1>" )
			)
			( signal "@baseboard_fab2_lib.baseboard_fab2(sch_1):m_c_cs_n(4)"
				( pinPairRef "@baseboard_fab2_lib.baseboard_fab2(sch_1):\PP3867\" )
				( objectStatus "M_C_CS_N<4>" )
			)
			( signal "@baseboard_fab2_lib.baseboard_fab2(sch_1):m_c_odt(2)"
				( pinPairRef "@baseboard_fab2_lib.baseboard_fab2(sch_1):\PP3868\" )
				( attribute "NO_TEST" "1"
					( Origin gBackEnd )
				)
				( objectStatus "M_C_ODT<2>" )
			)
			( signal "@baseboard_fab2_lib.baseboard_fab2(sch_1):m_c_cke(2)"
				( pinPairRef "@baseboard_fab2_lib.baseboard_fab2(sch_1):\PP3866\" )
				( objectStatus "M_C_CKE<2>" )
			)
			( signal "@baseboard_fab2_lib.baseboard_fab2(sch_1):m_c_cs_n(6)"
				( pinPairRef "@baseboard_fab2_lib.baseboard_fab2(sch_1):\PP3864\" )
				( attribute "NO_TEST" "1"
					( Origin gBackEnd )
				)
				( objectStatus "M_C_CS_N<6>" )
			)
			( signal "@baseboard_fab2_lib.baseboard_fab2(sch_1):m_c_cs_n(7)"
				( pinPairRef "@baseboard_fab2_lib.baseboard_fab2(sch_1):\PP3865\" )
				( objectStatus "M_C_CS_N<7>" )
			)
			( signal "@baseboard_fab2_lib.baseboard_fab2(sch_1):m_c_cs_n(5)"
				( pinPairRef "@baseboard_fab2_lib.baseboard_fab2(sch_1):\PP3862\" )
				( objectStatus "M_C_CS_N<5>" )
			)
			( signal "@baseboard_fab2_lib.baseboard_fab2(sch_1):m_c_odt(3)"
				( pinPairRef "@baseboard_fab2_lib.baseboard_fab2(sch_1):\PP3863\" )
				( objectStatus "M_C_ODT<3>" )
			)
			( signal "@baseboard_fab2_lib.baseboard_fab2(sch_1):m_c_cke(3)"
				( pinPairRef "@baseboard_fab2_lib.baseboard_fab2(sch_1):\PP3861\" )
				( objectStatus "M_C_CKE<3>" )
			)
			( signal "@baseboard_fab2_lib.baseboard_fab2(sch_1):m_c_clk_dn(0)"
				( attribute "NO_TEST" "1"
					( Origin gBackEnd )
				)
				( objectStatus "M_C_CLK_DN<0>" )
			)
			( signal "@baseboard_fab2_lib.baseboard_fab2(sch_1):m_c_clk_dp(0)"
				( electricalCSetRef "@crescent_city_bb_fab1_lib.crescent_city_bb_fab1(sch_1):\M_A_CLK_DP_0_\" )
				( attribute "RELATIVE_PROPAGATION_DELAY_SCOPE" "G"
					( Parent
						( matchGroupRef "@crescent_city_bb_fab1_lib.crescent_city_bb_fab1(sch_1):\MG_DDR_FAR_DIMM-CLK0_CLS_DDR_C_CAC-CLKS\" )
					)
					( Origin gBackEnd )
				)
				( attribute "RELATIVE_PROPAGATION_DELAY_PATH_TYPE" "L:S"
					( Parent
						( matchGroupRef "@crescent_city_bb_fab1_lib.crescent_city_bb_fab1(sch_1):\MG_DDR_FAR_DIMM-CLK0_CLS_DDR_C_CAC-CLKS\" )
					)
					( Origin gBackEnd )
				)
				( attribute "RELATIVE_PROPAGATION_DELAY" "TARGET,TARGET"
					( Parent
						( matchGroupRef "@crescent_city_bb_fab1_lib.crescent_city_bb_fab1(sch_1):\MG_DDR_FAR_DIMM-CLK0_CLS_DDR_C_CAC-CLKS\" )
					)
					( Units "uMatchProp" "ns" 1.000000)
					( Origin gBackEnd )
				)
				( objectStatus "M_C_CLK_DP<0>" )
			)
			( signal "@baseboard_fab2_lib.baseboard_fab2(sch_1):m_c_clk_dn(2)"
				( attribute "NO_TEST" "1"
					( Origin gBackEnd )
				)
				( objectStatus "M_C_CLK_DN<2>" )
			)
			( signal "@baseboard_fab2_lib.baseboard_fab2(sch_1):m_c_clk_dp(2)"
				( electricalCSetRef "@crescent_city_bb_fab1_lib.crescent_city_bb_fab1(sch_1):\DDR_CLK1\" )
				( attribute "RELATIVE_PROPAGATION_DELAY_SCOPE" "G"
					( Parent
						( matchGroupRef "@crescent_city_bb_fab1_lib.crescent_city_bb_fab1(sch_1):\MG_DDR_NEAR_DIMM-CLK1_CLS_DDR_C_CAC-CLKS\" )
					)
					( Origin gBackEnd )
				)
				( attribute "RELATIVE_PROPAGATION_DELAY_PATH_TYPE" "L:S"
					( Parent
						( matchGroupRef "@crescent_city_bb_fab1_lib.crescent_city_bb_fab1(sch_1):\MG_DDR_NEAR_DIMM-CLK1_CLS_DDR_C_CAC-CLKS\" )
					)
					( Origin gBackEnd )
				)
				( attribute "RELATIVE_PROPAGATION_DELAY" "TARGET,TARGET"
					( Parent
						( matchGroupRef "@crescent_city_bb_fab1_lib.crescent_city_bb_fab1(sch_1):\MG_DDR_NEAR_DIMM-CLK1_CLS_DDR_C_CAC-CLKS\" )
					)
					( Units "uMatchProp" "ns" 1.000000)
					( Origin gBackEnd )
				)
				( objectStatus "M_C_CLK_DP<2>" )
			)
			( signal "@baseboard_fab2_lib.baseboard_fab2(sch_1):m_b_c(2)"
				( pinPairRef "@baseboard_fab2_lib.baseboard_fab2(sch_1):\PP3989\" )
				( pinPairRef "@baseboard_fab2_lib.baseboard_fab2(sch_1):\PP3990\" )
				( attribute "NO_TEST" "1"
					( Origin gBackEnd )
				)
				( objectStatus "M_B_C<2>" )
			)
			( signal "@baseboard_fab2_lib.baseboard_fab2(sch_1):m_b_ma(17)"
				( pinPairRef "@baseboard_fab2_lib.baseboard_fab2(sch_1):\PP3991\" )
				( pinPairRef "@baseboard_fab2_lib.baseboard_fab2(sch_1):\PP3992\" )
				( objectStatus "M_B_MA<17>" )
			)
			( signal "@baseboard_fab2_lib.baseboard_fab2(sch_1):m_b_ma(13)"
				( pinPairRef "@baseboard_fab2_lib.baseboard_fab2(sch_1):\PP3985\" )
				( pinPairRef "@baseboard_fab2_lib.baseboard_fab2(sch_1):\PP3986\" )
				( attribute "NO_TEST" "1"
					( Origin gBackEnd )
				)
				( objectStatus "M_B_MA<13>" )
			)
			( signal "@baseboard_fab2_lib.baseboard_fab2(sch_1):m_b_ma(15)"
				( pinPairRef "@baseboard_fab2_lib.baseboard_fab2(sch_1):\PP3987\" )
				( pinPairRef "@baseboard_fab2_lib.baseboard_fab2(sch_1):\PP3988\" )
				( objectStatus "M_B_MA<15>" )
			)
			( signal "@baseboard_fab2_lib.baseboard_fab2(sch_1):m_b_ma(14)"
				( pinPairRef "@baseboard_fab2_lib.baseboard_fab2(sch_1):\PP3981\" )
				( pinPairRef "@baseboard_fab2_lib.baseboard_fab2(sch_1):\PP3982\" )
				( objectStatus "M_B_MA<14>" )
			)
			( signal "@baseboard_fab2_lib.baseboard_fab2(sch_1):m_b_ma(16)"
				( pinPairRef "@baseboard_fab2_lib.baseboard_fab2(sch_1):\PP3983\" )
				( pinPairRef "@baseboard_fab2_lib.baseboard_fab2(sch_1):\PP3984\" )
				( attribute "NO_TEST" "1"
					( Origin gBackEnd )
				)
				( objectStatus "M_B_MA<16>" )
			)
			( signal "@baseboard_fab2_lib.baseboard_fab2(sch_1):m_b_ba(1)"
				( pinPairRef "@baseboard_fab2_lib.baseboard_fab2(sch_1):\PP3977\" )
				( pinPairRef "@baseboard_fab2_lib.baseboard_fab2(sch_1):\PP3978\" )
				( objectStatus "M_B_BA<1>" )
			)
			( signal "@baseboard_fab2_lib.baseboard_fab2(sch_1):m_b_ma(10)"
				( pinPairRef "@baseboard_fab2_lib.baseboard_fab2(sch_1):\PP3979\" )
				( pinPairRef "@baseboard_fab2_lib.baseboard_fab2(sch_1):\PP3980\" )
				( attribute "NO_TEST" "1"
					( Origin gBackEnd )
				)
				( objectStatus "M_B_MA<10>" )
			)
			( signal "@baseboard_fab2_lib.baseboard_fab2(sch_1):m_b_ba(0)"
				( pinPairRef "@baseboard_fab2_lib.baseboard_fab2(sch_1):\PP3973\" )
				( pinPairRef "@baseboard_fab2_lib.baseboard_fab2(sch_1):\PP3974\" )
				( objectStatus "M_B_BA<0>" )
			)
			( signal "@baseboard_fab2_lib.baseboard_fab2(sch_1):m_b_ma(0)"
				( pinPairRef "@baseboard_fab2_lib.baseboard_fab2(sch_1):\PP3975\" )
				( pinPairRef "@baseboard_fab2_lib.baseboard_fab2(sch_1):\PP3976\" )
				( objectStatus "M_B_MA<0>" )
			)
			( signal "@baseboard_fab2_lib.baseboard_fab2(sch_1):m_b_par"
				( pinPairRef "@baseboard_fab2_lib.baseboard_fab2(sch_1):\PP3971\" )
				( pinPairRef "@baseboard_fab2_lib.baseboard_fab2(sch_1):\PP3972\" )
				( objectStatus "M_B_PAR" )
			)
			( signal "@baseboard_fab2_lib.baseboard_fab2(sch_1):m_b_ma(1)"
				( pinPairRef "@baseboard_fab2_lib.baseboard_fab2(sch_1):\PP3967\" )
				( pinPairRef "@baseboard_fab2_lib.baseboard_fab2(sch_1):\PP3968\" )
				( attribute "NO_TEST" "1"
					( Origin gBackEnd )
				)
				( objectStatus "M_B_MA<1>" )
			)
			( signal "@baseboard_fab2_lib.baseboard_fab2(sch_1):m_b_ma(3)"
				( pinPairRef "@baseboard_fab2_lib.baseboard_fab2(sch_1):\PP3969\" )
				( pinPairRef "@baseboard_fab2_lib.baseboard_fab2(sch_1):\PP3970\" )
				( objectStatus "M_B_MA<3>" )
			)
			( signal "@baseboard_fab2_lib.baseboard_fab2(sch_1):m_b_ma(2)"
				( pinPairRef "@baseboard_fab2_lib.baseboard_fab2(sch_1):\PP3963\" )
				( pinPairRef "@baseboard_fab2_lib.baseboard_fab2(sch_1):\PP3964\" )
				( objectStatus "M_B_MA<2>" )
			)
			( signal "@baseboard_fab2_lib.baseboard_fab2(sch_1):m_b_ma(4)"
				( pinPairRef "@baseboard_fab2_lib.baseboard_fab2(sch_1):\PP3965\" )
				( pinPairRef "@baseboard_fab2_lib.baseboard_fab2(sch_1):\PP3966\" )
				( attribute "NO_TEST" "1"
					( Origin gBackEnd )
				)
				( objectStatus "M_B_MA<4>" )
			)
			( signal "@baseboard_fab2_lib.baseboard_fab2(sch_1):m_b_ma(5)"
				( pinPairRef "@baseboard_fab2_lib.baseboard_fab2(sch_1):\PP3959\" )
				( pinPairRef "@baseboard_fab2_lib.baseboard_fab2(sch_1):\PP3960\" )
				( attribute "NO_TEST" "1"
					( Origin gBackEnd )
				)
				( objectStatus "M_B_MA<5>" )
			)
			( signal "@baseboard_fab2_lib.baseboard_fab2(sch_1):m_b_ma(6)"
				( pinPairRef "@baseboard_fab2_lib.baseboard_fab2(sch_1):\PP3961\" )
				( pinPairRef "@baseboard_fab2_lib.baseboard_fab2(sch_1):\PP3962\" )
				( objectStatus "M_B_MA<6>" )
			)
			( signal "@baseboard_fab2_lib.baseboard_fab2(sch_1):m_b_ma(7)"
				( pinPairRef "@baseboard_fab2_lib.baseboard_fab2(sch_1):\PP3955\" )
				( pinPairRef "@baseboard_fab2_lib.baseboard_fab2(sch_1):\PP3956\" )
				( attribute "NO_TEST" "1"
					( Origin gBackEnd )
				)
				( objectStatus "M_B_MA<7>" )
			)
			( signal "@baseboard_fab2_lib.baseboard_fab2(sch_1):m_b_ma(8)"
				( pinPairRef "@baseboard_fab2_lib.baseboard_fab2(sch_1):\PP3957\" )
				( pinPairRef "@baseboard_fab2_lib.baseboard_fab2(sch_1):\PP3958\" )
				( objectStatus "M_B_MA<8>" )
			)
			( signal "@baseboard_fab2_lib.baseboard_fab2(sch_1):m_b_ma(9)"
				( pinPairRef "@baseboard_fab2_lib.baseboard_fab2(sch_1):\PP3951\" )
				( pinPairRef "@baseboard_fab2_lib.baseboard_fab2(sch_1):\PP3952\" )
				( objectStatus "M_B_MA<9>" )
			)
			( signal "@baseboard_fab2_lib.baseboard_fab2(sch_1):m_b_ma(12)"
				( pinPairRef "@baseboard_fab2_lib.baseboard_fab2(sch_1):\PP3953\" )
				( pinPairRef "@baseboard_fab2_lib.baseboard_fab2(sch_1):\PP3954\" )
				( objectStatus "M_B_MA<12>" )
			)
			( signal "@baseboard_fab2_lib.baseboard_fab2(sch_1):m_b_bg(1)"
				( pinPairRef "@baseboard_fab2_lib.baseboard_fab2(sch_1):\PP3947\" )
				( pinPairRef "@baseboard_fab2_lib.baseboard_fab2(sch_1):\PP3948\" )
				( objectStatus "M_B_BG<1>" )
			)
			( signal "@baseboard_fab2_lib.baseboard_fab2(sch_1):m_b_ma(11)"
				( pinPairRef "@baseboard_fab2_lib.baseboard_fab2(sch_1):\PP3949\" )
				( pinPairRef "@baseboard_fab2_lib.baseboard_fab2(sch_1):\PP3950\" )
				( attribute "NO_TEST" "1"
					( Origin gBackEnd )
				)
				( objectStatus "M_B_MA<11>" )
			)
			( signal "@baseboard_fab2_lib.baseboard_fab2(sch_1):m_b_act_n"
				( pinPairRef "@baseboard_fab2_lib.baseboard_fab2(sch_1):\PP3943\" )
				( pinPairRef "@baseboard_fab2_lib.baseboard_fab2(sch_1):\PP3944\" )
				( attribute "NO_TEST" "1"
					( Origin gBackEnd )
				)
				( objectStatus "M_B_ACT_N" )
			)
			( signal "@baseboard_fab2_lib.baseboard_fab2(sch_1):m_b_bg(0)"
				( pinPairRef "@baseboard_fab2_lib.baseboard_fab2(sch_1):\PP3945\" )
				( pinPairRef "@baseboard_fab2_lib.baseboard_fab2(sch_1):\PP3946\" )
				( attribute "NO_TEST" "1"
					( Origin gBackEnd )
				)
				( objectStatus "M_B_BG<0>" )
			)
			( signal "@baseboard_fab2_lib.baseboard_fab2(sch_1):m_b_cs_n(0)"
				( pinPairRef "@baseboard_fab2_lib.baseboard_fab2(sch_1):\PP3941\" )
				( objectStatus "M_B_CS_N<0>" )
			)
			( signal "@baseboard_fab2_lib.baseboard_fab2(sch_1):m_b_odt(0)"
				( pinPairRef "@baseboard_fab2_lib.baseboard_fab2(sch_1):\PP3942\" )
				( objectStatus "M_B_ODT<0>" )
			)
			( signal "@baseboard_fab2_lib.baseboard_fab2(sch_1):m_b_cke(0)"
				( pinPairRef "@baseboard_fab2_lib.baseboard_fab2(sch_1):\PP3940\" )
				( objectStatus "M_B_CKE<0>" )
			)
			( signal "@baseboard_fab2_lib.baseboard_fab2(sch_1):m_b_cs_n(2)"
				( pinPairRef "@baseboard_fab2_lib.baseboard_fab2(sch_1):\PP3939\" )
				( objectStatus "M_B_CS_N<2>" )
			)
			( signal "@baseboard_fab2_lib.baseboard_fab2(sch_1):m_b_cs_n(3)"
				( pinPairRef "@baseboard_fab2_lib.baseboard_fab2(sch_1):\PP3938\" )
				( attribute "NO_TEST" "1"
					( Origin gBackEnd )
				)
				( objectStatus "M_B_CS_N<3>" )
			)
			( signal "@baseboard_fab2_lib.baseboard_fab2(sch_1):m_b_odt(1)"
				( pinPairRef "@baseboard_fab2_lib.baseboard_fab2(sch_1):\PP3936\" )
				( attribute "NO_TEST" "1"
					( Origin gBackEnd )
				)
				( objectStatus "M_B_ODT<1>" )
			)
			( signal "@baseboard_fab2_lib.baseboard_fab2(sch_1):m_b_cs_n(1)"
				( pinPairRef "@baseboard_fab2_lib.baseboard_fab2(sch_1):\PP3937\" )
				( attribute "NO_TEST" "1"
					( Origin gBackEnd )
				)
				( objectStatus "M_B_CS_N<1>" )
			)
			( signal "@baseboard_fab2_lib.baseboard_fab2(sch_1):m_b_cke(1)"
				( pinPairRef "@baseboard_fab2_lib.baseboard_fab2(sch_1):\PP3935\" )
				( objectStatus "M_B_CKE<1>" )
			)
			( signal "@baseboard_fab2_lib.baseboard_fab2(sch_1):m_b_cs_n(4)"
				( pinPairRef "@baseboard_fab2_lib.baseboard_fab2(sch_1):\PP3933\" )
				( attribute "NO_TEST" "1"
					( Origin gBackEnd )
				)
				( objectStatus "M_B_CS_N<4>" )
			)
			( signal "@baseboard_fab2_lib.baseboard_fab2(sch_1):m_b_odt(2)"
				( pinPairRef "@baseboard_fab2_lib.baseboard_fab2(sch_1):\PP3934\" )
				( attribute "NO_TEST" "1"
					( Origin gBackEnd )
				)
				( objectStatus "M_B_ODT<2>" )
			)
			( signal "@baseboard_fab2_lib.baseboard_fab2(sch_1):m_b_cke(2)"
				( pinPairRef "@baseboard_fab2_lib.baseboard_fab2(sch_1):\PP3932\" )
				( objectStatus "M_B_CKE<2>" )
			)
			( signal "@baseboard_fab2_lib.baseboard_fab2(sch_1):m_b_cs_n(6)"
				( pinPairRef "@baseboard_fab2_lib.baseboard_fab2(sch_1):\PP3930\" )
				( objectStatus "M_B_CS_N<6>" )
			)
			( signal "@baseboard_fab2_lib.baseboard_fab2(sch_1):m_b_cs_n(7)"
				( pinPairRef "@baseboard_fab2_lib.baseboard_fab2(sch_1):\PP3931\" )
				( attribute "NO_TEST" "1"
					( Origin gBackEnd )
				)
				( objectStatus "M_B_CS_N<7>" )
			)
			( signal "@baseboard_fab2_lib.baseboard_fab2(sch_1):m_b_cs_n(5)"
				( pinPairRef "@baseboard_fab2_lib.baseboard_fab2(sch_1):\PP3928\" )
				( objectStatus "M_B_CS_N<5>" )
			)
			( signal "@baseboard_fab2_lib.baseboard_fab2(sch_1):m_b_odt(3)"
				( pinPairRef "@baseboard_fab2_lib.baseboard_fab2(sch_1):\PP3929\" )
				( objectStatus "M_B_ODT<3>" )
			)
			( signal "@baseboard_fab2_lib.baseboard_fab2(sch_1):m_b_cke(3)"
				( pinPairRef "@baseboard_fab2_lib.baseboard_fab2(sch_1):\PP3927\" )
				( attribute "NO_TEST" "1"
					( Origin gBackEnd )
				)
				( objectStatus "M_B_CKE<3>" )
			)
			( signal "@baseboard_fab2_lib.baseboard_fab2(sch_1):m_b_clk_dn(0)"
				( attribute "NO_TEST" "1"
					( Origin gBackEnd )
				)
				( objectStatus "M_B_CLK_DN<0>" )
			)
			( signal "@baseboard_fab2_lib.baseboard_fab2(sch_1):m_b_clk_dp(0)"
				( electricalCSetRef "@crescent_city_bb_fab1_lib.crescent_city_bb_fab1(sch_1):\M_A_CLK_DP_0_\" )
				( attribute "RELATIVE_PROPAGATION_DELAY_SCOPE" "G"
					( Parent
						( matchGroupRef "@crescent_city_bb_fab1_lib.crescent_city_bb_fab1(sch_1):\MG_DDR_FAR_DIMM-CLK0_CLS_DDR_B_CAC-CLKS\" )
					)
					( Origin gBackEnd )
				)
				( attribute "RELATIVE_PROPAGATION_DELAY_PATH_TYPE" "L:S"
					( Parent
						( matchGroupRef "@crescent_city_bb_fab1_lib.crescent_city_bb_fab1(sch_1):\MG_DDR_FAR_DIMM-CLK0_CLS_DDR_B_CAC-CLKS\" )
					)
					( Origin gBackEnd )
				)
				( attribute "RELATIVE_PROPAGATION_DELAY" "TARGET,TARGET"
					( Parent
						( matchGroupRef "@crescent_city_bb_fab1_lib.crescent_city_bb_fab1(sch_1):\MG_DDR_FAR_DIMM-CLK0_CLS_DDR_B_CAC-CLKS\" )
					)
					( Units "uMatchProp" "ns" 1.000000)
					( Origin gBackEnd )
				)
				( objectStatus "M_B_CLK_DP<0>" )
			)
			( signal "@baseboard_fab2_lib.baseboard_fab2(sch_1):m_b_clk_dn(2)"
				( objectStatus "M_B_CLK_DN<2>" )
			)
			( signal "@baseboard_fab2_lib.baseboard_fab2(sch_1):m_b_clk_dp(2)"
				( electricalCSetRef "@crescent_city_bb_fab1_lib.crescent_city_bb_fab1(sch_1):\DDR_CLK1\" )
				( attribute "NO_TEST" "1"
					( Origin gBackEnd )
				)
				( attribute "RELATIVE_PROPAGATION_DELAY_SCOPE" "G"
					( Parent
						( matchGroupRef "@crescent_city_bb_fab1_lib.crescent_city_bb_fab1(sch_1):\MG_DDR_NEAR_DIMM-CLK1_CLS_DDR_B_CAC-CLKS\" )
					)
					( Origin gBackEnd )
				)
				( attribute "RELATIVE_PROPAGATION_DELAY_PATH_TYPE" "L:S"
					( Parent
						( matchGroupRef "@crescent_city_bb_fab1_lib.crescent_city_bb_fab1(sch_1):\MG_DDR_NEAR_DIMM-CLK1_CLS_DDR_B_CAC-CLKS\" )
					)
					( Origin gBackEnd )
				)
				( attribute "RELATIVE_PROPAGATION_DELAY" "TARGET,TARGET"
					( Parent
						( matchGroupRef "@crescent_city_bb_fab1_lib.crescent_city_bb_fab1(sch_1):\MG_DDR_NEAR_DIMM-CLK1_CLS_DDR_B_CAC-CLKS\" )
					)
					( Units "uMatchProp" "ns" 1.000000)
					( Origin gBackEnd )
				)
				( objectStatus "M_B_CLK_DP<2>" )
			)
			( signal "@baseboard_fab2_lib.baseboard_fab2(sch_1):m_a_c(2)"
				( pinPairRef "@baseboard_fab2_lib.baseboard_fab2(sch_1):\PP4055\" )
				( pinPairRef "@baseboard_fab2_lib.baseboard_fab2(sch_1):\PP4056\" )
				( objectStatus "M_A_C<2>" )
			)
			( signal "@baseboard_fab2_lib.baseboard_fab2(sch_1):m_a_ma(17)"
				( pinPairRef "@baseboard_fab2_lib.baseboard_fab2(sch_1):\PP4057\" )
				( pinPairRef "@baseboard_fab2_lib.baseboard_fab2(sch_1):\PP4058\" )
				( objectStatus "M_A_MA<17>" )
			)
			( signal "@baseboard_fab2_lib.baseboard_fab2(sch_1):m_a_ma(13)"
				( pinPairRef "@baseboard_fab2_lib.baseboard_fab2(sch_1):\PP4051\" )
				( pinPairRef "@baseboard_fab2_lib.baseboard_fab2(sch_1):\PP4052\" )
				( attribute "NO_TEST" "1"
					( Origin gBackEnd )
				)
				( objectStatus "M_A_MA<13>" )
			)
			( signal "@baseboard_fab2_lib.baseboard_fab2(sch_1):m_a_ma(15)"
				( pinPairRef "@baseboard_fab2_lib.baseboard_fab2(sch_1):\PP4053\" )
				( pinPairRef "@baseboard_fab2_lib.baseboard_fab2(sch_1):\PP4054\" )
				( objectStatus "M_A_MA<15>" )
			)
			( signal "@baseboard_fab2_lib.baseboard_fab2(sch_1):m_a_ma(14)"
				( pinPairRef "@baseboard_fab2_lib.baseboard_fab2(sch_1):\PP4047\" )
				( pinPairRef "@baseboard_fab2_lib.baseboard_fab2(sch_1):\PP4048\" )
				( objectStatus "M_A_MA<14>" )
			)
			( signal "@baseboard_fab2_lib.baseboard_fab2(sch_1):m_a_ma(16)"
				( pinPairRef "@baseboard_fab2_lib.baseboard_fab2(sch_1):\PP4049\" )
				( pinPairRef "@baseboard_fab2_lib.baseboard_fab2(sch_1):\PP4050\" )
				( objectStatus "M_A_MA<16>" )
			)
			( signal "@baseboard_fab2_lib.baseboard_fab2(sch_1):m_a_ma(10)"
				( pinPairRef "@baseboard_fab2_lib.baseboard_fab2(sch_1):\PP4043\" )
				( pinPairRef "@baseboard_fab2_lib.baseboard_fab2(sch_1):\PP4044\" )
				( attribute "NO_TEST" "1"
					( Origin gBackEnd )
				)
				( objectStatus "M_A_MA<10>" )
			)
			( signal "@baseboard_fab2_lib.baseboard_fab2(sch_1):m_a_ba(1)"
				( pinPairRef "@baseboard_fab2_lib.baseboard_fab2(sch_1):\PP4045\" )
				( pinPairRef "@baseboard_fab2_lib.baseboard_fab2(sch_1):\PP4046\" )
				( objectStatus "M_A_BA<1>" )
			)
			( signal "@baseboard_fab2_lib.baseboard_fab2(sch_1):m_a_ba(0)"
				( pinPairRef "@baseboard_fab2_lib.baseboard_fab2(sch_1):\PP4039\" )
				( pinPairRef "@baseboard_fab2_lib.baseboard_fab2(sch_1):\PP4040\" )
				( objectStatus "M_A_BA<0>" )
			)
			( signal "@baseboard_fab2_lib.baseboard_fab2(sch_1):m_a_ma(0)"
				( pinPairRef "@baseboard_fab2_lib.baseboard_fab2(sch_1):\PP4041\" )
				( pinPairRef "@baseboard_fab2_lib.baseboard_fab2(sch_1):\PP4042\" )
				( objectStatus "M_A_MA<0>" )
			)
			( signal "@baseboard_fab2_lib.baseboard_fab2(sch_1):m_a_par"
				( pinPairRef "@baseboard_fab2_lib.baseboard_fab2(sch_1):\PP4037\" )
				( pinPairRef "@baseboard_fab2_lib.baseboard_fab2(sch_1):\PP4038\" )
				( objectStatus "M_A_PAR" )
			)
			( signal "@baseboard_fab2_lib.baseboard_fab2(sch_1):m_a_ma(1)"
				( pinPairRef "@baseboard_fab2_lib.baseboard_fab2(sch_1):\PP4033\" )
				( pinPairRef "@baseboard_fab2_lib.baseboard_fab2(sch_1):\PP4034\" )
				( objectStatus "M_A_MA<1>" )
			)
			( signal "@baseboard_fab2_lib.baseboard_fab2(sch_1):m_a_ma(3)"
				( pinPairRef "@baseboard_fab2_lib.baseboard_fab2(sch_1):\PP4035\" )
				( pinPairRef "@baseboard_fab2_lib.baseboard_fab2(sch_1):\PP4036\" )
				( objectStatus "M_A_MA<3>" )
			)
			( signal "@baseboard_fab2_lib.baseboard_fab2(sch_1):m_a_ma(2)"
				( pinPairRef "@baseboard_fab2_lib.baseboard_fab2(sch_1):\PP4029\" )
				( pinPairRef "@baseboard_fab2_lib.baseboard_fab2(sch_1):\PP4030\" )
				( attribute "NO_TEST" "1"
					( Origin gBackEnd )
				)
				( objectStatus "M_A_MA<2>" )
			)
			( signal "@baseboard_fab2_lib.baseboard_fab2(sch_1):m_a_ma(4)"
				( pinPairRef "@baseboard_fab2_lib.baseboard_fab2(sch_1):\PP4031\" )
				( pinPairRef "@baseboard_fab2_lib.baseboard_fab2(sch_1):\PP4032\" )
				( objectStatus "M_A_MA<4>" )
			)
			( signal "@baseboard_fab2_lib.baseboard_fab2(sch_1):m_a_ma(5)"
				( pinPairRef "@baseboard_fab2_lib.baseboard_fab2(sch_1):\PP4025\" )
				( pinPairRef "@baseboard_fab2_lib.baseboard_fab2(sch_1):\PP4026\" )
				( objectStatus "M_A_MA<5>" )
			)
			( signal "@baseboard_fab2_lib.baseboard_fab2(sch_1):m_a_ma(6)"
				( pinPairRef "@baseboard_fab2_lib.baseboard_fab2(sch_1):\PP4027\" )
				( pinPairRef "@baseboard_fab2_lib.baseboard_fab2(sch_1):\PP4028\" )
				( objectStatus "M_A_MA<6>" )
			)
			( signal "@baseboard_fab2_lib.baseboard_fab2(sch_1):m_a_ma(7)"
				( pinPairRef "@baseboard_fab2_lib.baseboard_fab2(sch_1):\PP4021\" )
				( pinPairRef "@baseboard_fab2_lib.baseboard_fab2(sch_1):\PP4022\" )
				( objectStatus "M_A_MA<7>" )
			)
			( signal "@baseboard_fab2_lib.baseboard_fab2(sch_1):m_a_ma(8)"
				( pinPairRef "@baseboard_fab2_lib.baseboard_fab2(sch_1):\PP4023\" )
				( pinPairRef "@baseboard_fab2_lib.baseboard_fab2(sch_1):\PP4024\" )
				( objectStatus "M_A_MA<8>" )
			)
			( signal "@baseboard_fab2_lib.baseboard_fab2(sch_1):m_a_ma(9)"
				( pinPairRef "@baseboard_fab2_lib.baseboard_fab2(sch_1):\PP4017\" )
				( pinPairRef "@baseboard_fab2_lib.baseboard_fab2(sch_1):\PP4018\" )
				( attribute "NO_TEST" "1"
					( Origin gBackEnd )
				)
				( objectStatus "M_A_MA<9>" )
			)
			( signal "@baseboard_fab2_lib.baseboard_fab2(sch_1):m_a_ma(12)"
				( pinPairRef "@baseboard_fab2_lib.baseboard_fab2(sch_1):\PP4019\" )
				( pinPairRef "@baseboard_fab2_lib.baseboard_fab2(sch_1):\PP4020\" )
				( attribute "NO_TEST" "1"
					( Origin gBackEnd )
				)
				( objectStatus "M_A_MA<12>" )
			)
			( signal "@baseboard_fab2_lib.baseboard_fab2(sch_1):m_a_bg(1)"
				( pinPairRef "@baseboard_fab2_lib.baseboard_fab2(sch_1):\PP4013\" )
				( pinPairRef "@baseboard_fab2_lib.baseboard_fab2(sch_1):\PP4014\" )
				( attribute "NO_TEST" "1"
					( Origin gBackEnd )
				)
				( objectStatus "M_A_BG<1>" )
			)
			( signal "@baseboard_fab2_lib.baseboard_fab2(sch_1):m_a_ma(11)"
				( pinPairRef "@baseboard_fab2_lib.baseboard_fab2(sch_1):\PP4015\" )
				( pinPairRef "@baseboard_fab2_lib.baseboard_fab2(sch_1):\PP4016\" )
				( objectStatus "M_A_MA<11>" )
			)
			( signal "@baseboard_fab2_lib.baseboard_fab2(sch_1):m_a_act_n"
				( pinPairRef "@baseboard_fab2_lib.baseboard_fab2(sch_1):\PP4009\" )
				( pinPairRef "@baseboard_fab2_lib.baseboard_fab2(sch_1):\PP4010\" )
				( objectStatus "M_A_ACT_N" )
			)
			( signal "@baseboard_fab2_lib.baseboard_fab2(sch_1):m_a_bg(0)"
				( pinPairRef "@baseboard_fab2_lib.baseboard_fab2(sch_1):\PP4011\" )
				( pinPairRef "@baseboard_fab2_lib.baseboard_fab2(sch_1):\PP4012\" )
				( objectStatus "M_A_BG<0>" )
			)
			( signal "@baseboard_fab2_lib.baseboard_fab2(sch_1):m_a_cs_n(0)"
				( pinPairRef "@baseboard_fab2_lib.baseboard_fab2(sch_1):\PP4007\" )
				( objectStatus "M_A_CS_N<0>" )
			)
			( signal "@baseboard_fab2_lib.baseboard_fab2(sch_1):m_a_odt(0)"
				( pinPairRef "@baseboard_fab2_lib.baseboard_fab2(sch_1):\PP4008\" )
				( objectStatus "M_A_ODT<0>" )
			)
			( signal "@baseboard_fab2_lib.baseboard_fab2(sch_1):m_a_cke(0)"
				( pinPairRef "@baseboard_fab2_lib.baseboard_fab2(sch_1):\PP4006\" )
				( objectStatus "M_A_CKE<0>" )
			)
			( signal "@baseboard_fab2_lib.baseboard_fab2(sch_1):m_a_cs_n(2)"
				( pinPairRef "@baseboard_fab2_lib.baseboard_fab2(sch_1):\PP4005\" )
				( objectStatus "M_A_CS_N<2>" )
			)
			( signal "@baseboard_fab2_lib.baseboard_fab2(sch_1):m_a_cs_n(3)"
				( pinPairRef "@baseboard_fab2_lib.baseboard_fab2(sch_1):\PP4004\" )
				( objectStatus "M_A_CS_N<3>" )
			)
			( signal "@baseboard_fab2_lib.baseboard_fab2(sch_1):m_a_cs_n(1)"
				( pinPairRef "@baseboard_fab2_lib.baseboard_fab2(sch_1):\PP4002\" )
				( objectStatus "M_A_CS_N<1>" )
			)
			( signal "@baseboard_fab2_lib.baseboard_fab2(sch_1):m_a_odt(1)"
				( pinPairRef "@baseboard_fab2_lib.baseboard_fab2(sch_1):\PP4003\" )
				( objectStatus "M_A_ODT<1>" )
			)
			( signal "@baseboard_fab2_lib.baseboard_fab2(sch_1):m_a_cke(1)"
				( pinPairRef "@baseboard_fab2_lib.baseboard_fab2(sch_1):\PP4001\" )
				( objectStatus "M_A_CKE<1>" )
			)
			( signal "@baseboard_fab2_lib.baseboard_fab2(sch_1):m_a_cs_n(4)"
				( pinPairRef "@baseboard_fab2_lib.baseboard_fab2(sch_1):\PP3999\" )
				( objectStatus "M_A_CS_N<4>" )
			)
			( signal "@baseboard_fab2_lib.baseboard_fab2(sch_1):m_a_odt(2)"
				( pinPairRef "@baseboard_fab2_lib.baseboard_fab2(sch_1):\PP4000\" )
				( objectStatus "M_A_ODT<2>" )
			)
			( signal "@baseboard_fab2_lib.baseboard_fab2(sch_1):m_a_cke(2)"
				( pinPairRef "@baseboard_fab2_lib.baseboard_fab2(sch_1):\PP3998\" )
				( objectStatus "M_A_CKE<2>" )
			)
			( signal "@baseboard_fab2_lib.baseboard_fab2(sch_1):m_a_cs_n(6)"
				( pinPairRef "@baseboard_fab2_lib.baseboard_fab2(sch_1):\PP3996\" )
				( objectStatus "M_A_CS_N<6>" )
			)
			( signal "@baseboard_fab2_lib.baseboard_fab2(sch_1):m_a_cs_n(7)"
				( pinPairRef "@baseboard_fab2_lib.baseboard_fab2(sch_1):\PP3997\" )
				( objectStatus "M_A_CS_N<7>" )
			)
			( signal "@baseboard_fab2_lib.baseboard_fab2(sch_1):m_a_cs_n(5)"
				( pinPairRef "@baseboard_fab2_lib.baseboard_fab2(sch_1):\PP3994\" )
				( objectStatus "M_A_CS_N<5>" )
			)
			( signal "@baseboard_fab2_lib.baseboard_fab2(sch_1):m_a_odt(3)"
				( pinPairRef "@baseboard_fab2_lib.baseboard_fab2(sch_1):\PP3995\" )
				( objectStatus "M_A_ODT<3>" )
			)
			( signal "@baseboard_fab2_lib.baseboard_fab2(sch_1):m_a_cke(3)"
				( pinPairRef "@baseboard_fab2_lib.baseboard_fab2(sch_1):\PP3993\" )
				( objectStatus "M_A_CKE<3>" )
			)
			( signal "@baseboard_fab2_lib.baseboard_fab2(sch_1):m_a_clk_dn(0)"
				( objectStatus "M_A_CLK_DN<0>" )
			)
			( signal "@baseboard_fab2_lib.baseboard_fab2(sch_1):m_a_clk_dp(0)"
				( electricalCSetRef "@crescent_city_bb_fab1_lib.crescent_city_bb_fab1(sch_1):\M_A_CLK_DP_0_\" )
				( attribute "RELATIVE_PROPAGATION_DELAY_SCOPE" "G"
					( Parent
						( matchGroupRef "@crescent_city_bb_fab1_lib.crescent_city_bb_fab1(sch_1):\MG_DDR_FAR_DIMM-CLK0_CLS_DDR_A_CAC-CLKS\" )
					)
					( Origin gBackEnd )
				)
				( attribute "RELATIVE_PROPAGATION_DELAY_PATH_TYPE" "L:S"
					( Parent
						( matchGroupRef "@crescent_city_bb_fab1_lib.crescent_city_bb_fab1(sch_1):\MG_DDR_FAR_DIMM-CLK0_CLS_DDR_A_CAC-CLKS\" )
					)
					( Origin gBackEnd )
				)
				( attribute "RELATIVE_PROPAGATION_DELAY" "TARGET,TARGET"
					( Parent
						( matchGroupRef "@crescent_city_bb_fab1_lib.crescent_city_bb_fab1(sch_1):\MG_DDR_FAR_DIMM-CLK0_CLS_DDR_A_CAC-CLKS\" )
					)
					( Units "uMatchProp" "ns" 1.000000)
					( Origin gBackEnd )
				)
				( objectStatus "M_A_CLK_DP<0>" )
			)
			( signal "@baseboard_fab2_lib.baseboard_fab2(sch_1):m_a_clk_dn(2)"
				( electricalCSetRef "@crescent_city_bb_fab1_lib.crescent_city_bb_fab1(sch_1):\DDR_CLK1\" )
				( attribute "RELATIVE_PROPAGATION_DELAY_SCOPE" "G"
					( Parent
						( matchGroupRef "@crescent_city_bb_fab1_lib.crescent_city_bb_fab1(sch_1):\MG_DDR_NEAR_DIMM-CLK1_CLS_DDR_A_CAC-CLKS\" )
					)
					( Origin gBackEnd )
				)
				( attribute "RELATIVE_PROPAGATION_DELAY_PATH_TYPE" "L:S"
					( Parent
						( matchGroupRef "@crescent_city_bb_fab1_lib.crescent_city_bb_fab1(sch_1):\MG_DDR_NEAR_DIMM-CLK1_CLS_DDR_A_CAC-CLKS\" )
					)
					( Origin gBackEnd )
				)
				( attribute "RELATIVE_PROPAGATION_DELAY" "TARGET,TARGET"
					( Parent
						( matchGroupRef "@crescent_city_bb_fab1_lib.crescent_city_bb_fab1(sch_1):\MG_DDR_NEAR_DIMM-CLK1_CLS_DDR_A_CAC-CLKS\" )
					)
					( Units "uMatchProp" "ns" 1.000000)
					( Origin gBackEnd )
				)
				( objectStatus "M_A_CLK_DN<2>" )
			)
			( signal "@baseboard_fab2_lib.baseboard_fab2(sch_1):m_a_clk_dp(2)"
				( objectStatus "M_A_CLK_DP<2>" )
			)
			( signal "@baseboard_fab2_lib.baseboard_fab2(sch_1):vsense_pvddq_abc_p"
				( objectStatus "VSENSE_PVDDQ_ABC_P" )
			)
			( signal "@baseboard_fab2_lib.baseboard_fab2(sch_1):vsense_pvddq_abc_n"
				( objectStatus "VSENSE_PVDDQ_ABC_N" )
			)
			( signal "@baseboard_fab2_lib.baseboard_fab2(sch_1):vsense_pvddq_def_p"
				( objectStatus "VSENSE_PVDDQ_DEF_P" )
			)
			( signal "@baseboard_fab2_lib.baseboard_fab2(sch_1):vsense_pvddq_def_n"
				( objectStatus "VSENSE_PVDDQ_DEF_N" )
			)
			( signal "@baseboard_fab2_lib.baseboard_fab2(sch_1):vsense_pvddq_ghj_p"
				( objectStatus "VSENSE_PVDDQ_GHJ_P" )
			)
			( signal "@baseboard_fab2_lib.baseboard_fab2(sch_1):vsense_pvddq_ghj_n"
				( objectStatus "VSENSE_PVDDQ_GHJ_N" )
			)
			( signal "@baseboard_fab2_lib.baseboard_fab2(sch_1):vsense_pvcciomcp_cpu0_skt_vsen"
				( objectStatus "VSENSE_PVCCIOMCP_CPU0_SKT_VSEN" )
			)
			( signal "@baseboard_fab2_lib.baseboard_fab2(sch_1):vsense_pvcciomcp_cpu0_skt_vrtn"
				( objectStatus "VSENSE_PVCCIOMCP_CPU0_SKT_VRTN" )
			)
			( signal "@baseboard_fab2_lib.baseboard_fab2(sch_1):vsense_pvcciomcp_cpu1_skt_vsen"
				( objectStatus "VSENSE_PVCCIOMCP_CPU1_SKT_VSEN" )
			)
			( signal "@baseboard_fab2_lib.baseboard_fab2(sch_1):vsense_pvcciomcp_cpu1_skt_vrtn"
				( objectStatus "VSENSE_PVCCIOMCP_CPU1_SKT_VRTN" )
			)
			( signal "@baseboard_fab2_lib.baseboard_fab2(sch_1):vsense_pvsa_cpu1_skt_vrtn"
				( objectStatus "VSENSE_PVSA_CPU1_SKT_VRTN" )
			)
			( signal "@baseboard_fab2_lib.baseboard_fab2(sch_1):vsense_pvsa_cpu1_n"
				( objectStatus "VSENSE_PVSA_CPU1_N" )
			)
			( signal "@baseboard_fab2_lib.baseboard_fab2(sch_1):vsense_pvsa_cpu1_skt_vsen"
				( objectStatus "VSENSE_PVSA_CPU1_SKT_VSEN" )
			)
			( signal "@baseboard_fab2_lib.baseboard_fab2(sch_1):vsense_pvsa_cpu1_p"
				( objectStatus "VSENSE_PVSA_CPU1_P" )
			)
			( signal "@baseboard_fab2_lib.baseboard_fab2(sch_1):vsense_pvnn_pch_stby_avsn"
				( objectStatus "VSENSE_PVNN_PCH_STBY_AVSN" )
			)
			( signal "@baseboard_fab2_lib.baseboard_fab2(sch_1):vsense_pvnn_pch_stby_avsp"
				( objectStatus "VSENSE_PVNN_PCH_STBY_AVSP" )
			)
			( signal "@baseboard_fab2_lib.baseboard_fab2(sch_1):vsense_pvsa_cpu0_n"
				( objectStatus "VSENSE_PVSA_CPU0_N" )
			)
			( signal "@baseboard_fab2_lib.baseboard_fab2(sch_1):vsense_pvsa_cpu0_skt_vrtn"
				( objectStatus "VSENSE_PVSA_CPU0_SKT_VRTN" )
			)
			( signal "@baseboard_fab2_lib.baseboard_fab2(sch_1):vsense_pvsa_cpu0_skt_vsen"
				( objectStatus "VSENSE_PVSA_CPU0_SKT_VSEN" )
			)
			( signal "@baseboard_fab2_lib.baseboard_fab2(sch_1):vsense_pvsa_cpu0_p"
				( objectStatus "VSENSE_PVSA_CPU0_P" )
			)
			( signal "@baseboard_fab2_lib.baseboard_fab2(sch_1):vsense_pvccmcp_cpu1_skt_vrtn"
				( objectStatus "VSENSE_PVCCMCP_CPU1_SKT_VRTN" )
			)
			( signal "@baseboard_fab2_lib.baseboard_fab2(sch_1):vsense_pvccmcp_cpu1_skt_vsen"
				( objectStatus "VSENSE_PVCCMCP_CPU1_SKT_VSEN" )
			)
			( signal "@baseboard_fab2_lib.baseboard_fab2(sch_1):vsense_pvccmcp_cpu0_skt_vrtn"
				( objectStatus "VSENSE_PVCCMCP_CPU0_SKT_VRTN" )
			)
			( signal "@baseboard_fab2_lib.baseboard_fab2(sch_1):vsense_pvccmcp_cpu0_skt_vsen"
				( objectStatus "VSENSE_PVCCMCP_CPU0_SKT_VSEN" )
			)
			( signal "@baseboard_fab2_lib.baseboard_fab2(sch_1):vsense_pvccio_cpu1_skt_vrtn"
				( objectStatus "VSENSE_PVCCIO_CPU1_SKT_VRTN" )
			)
			( signal "@baseboard_fab2_lib.baseboard_fab2(sch_1):vsense_pvccio_cpu1_skt_vsen"
				( objectStatus "VSENSE_PVCCIO_CPU1_SKT_VSEN" )
			)
			( signal "@baseboard_fab2_lib.baseboard_fab2(sch_1):vsense_pvccin_cpu1_n"
				( objectStatus "VSENSE_PVCCIN_CPU1_N" )
			)
			( signal "@baseboard_fab2_lib.baseboard_fab2(sch_1):vsense_pvccin_cpu1_skt_vrtn"
				( objectStatus "VSENSE_PVCCIN_CPU1_SKT_VRTN" )
			)
			( signal "@baseboard_fab2_lib.baseboard_fab2(sch_1):vsense_pvccin_cpu1_skt_vsen"
				( objectStatus "VSENSE_PVCCIN_CPU1_SKT_VSEN" )
			)
			( signal "@baseboard_fab2_lib.baseboard_fab2(sch_1):vsense_pvccin_cpu1_p"
				( objectStatus "VSENSE_PVCCIN_CPU1_P" )
			)
			( signal "@baseboard_fab2_lib.baseboard_fab2(sch_1):vsense_p1v05_pch_stby_avsn"
				( objectStatus "VSENSE_P1V05_PCH_STBY_AVSN" )
			)
			( signal "@baseboard_fab2_lib.baseboard_fab2(sch_1):vsense_p1v05_pch_stby_avsp"
				( objectStatus "VSENSE_P1V05_PCH_STBY_AVSP" )
			)
			( signal "@baseboard_fab2_lib.baseboard_fab2(sch_1):vr_p1v05_pch_stby_avsp"
				( objectStatus "VR_P1V05_PCH_STBY_AVSP" )
			)
			( signal "@baseboard_fab2_lib.baseboard_fab2(sch_1):vsense_pvddq_klm_n"
				( objectStatus "VSENSE_PVDDQ_KLM_N" )
			)
			( signal "@baseboard_fab2_lib.baseboard_fab2(sch_1):vsense_pvddq_klm_p"
				( objectStatus "VSENSE_PVDDQ_KLM_P" )
			)
			( signal "@baseboard_fab2_lib.baseboard_fab2(sch_1):vsense_pvccio_cpu0_avsn"
				( objectStatus "VSENSE_PVCCIO_CPU0_AVSN" )
			)
			( signal "@baseboard_fab2_lib.baseboard_fab2(sch_1):vsense_pvccio_cpu0_skt_vrtn"
				( objectStatus "VSENSE_PVCCIO_CPU0_SKT_VRTN" )
			)
			( signal "@baseboard_fab2_lib.baseboard_fab2(sch_1):vsense_pvccio_cpu0_skt_vsen"
				( objectStatus "VSENSE_PVCCIO_CPU0_SKT_VSEN" )
			)
			( signal "@baseboard_fab2_lib.baseboard_fab2(sch_1):vsense_pvccio_cpu0_avsp"
				( objectStatus "VSENSE_PVCCIO_CPU0_AVSP" )
			)
			( signal "@baseboard_fab2_lib.baseboard_fab2(sch_1):vsense_pvccin_cpu0_n"
				( objectStatus "VSENSE_PVCCIN_CPU0_N" )
			)
			( signal "@baseboard_fab2_lib.baseboard_fab2(sch_1):vsense_pvccin_cpu0_p"
				( objectStatus "VSENSE_PVCCIN_CPU0_P" )
			)
			( signal "@baseboard_fab2_lib.baseboard_fab2(sch_1):vsense_pvnn_pch_stby_fpk"
				( objectStatus "VSENSE_PVNN_PCH_STBY_FPK" )
			)
			( signal "@baseboard_fab2_lib.baseboard_fab2(sch_1):vsense_pvnn_pch_stby_qat"
				( objectStatus "VSENSE_PVNN_PCH_STBY_QAT" )
			)
			( signal "@baseboard_fab2_lib.baseboard_fab2(sch_1):vsense_pvccin_cpu0_skt_vrtn"
				( objectStatus "VSENSE_PVCCIN_CPU0_SKT_VRTN" )
			)
			( signal "@baseboard_fab2_lib.baseboard_fab2(sch_1):vsense_pvccin_cpu0_skt_vsen"
				( objectStatus "VSENSE_PVCCIN_CPU0_SKT_VSEN" )
			)
			( signal "@baseboard_fab2_lib.baseboard_fab2(sch_1):vsense_p1v8mcp_cpu0_skt_vsen"
				( objectStatus "VSENSE_P1V8MCP_CPU0_SKT_VSEN" )
			)
			( signal "@baseboard_fab2_lib.baseboard_fab2(sch_1):vsense_p1v8mcp_cpu0_skt_vrtn"
				( objectStatus "VSENSE_P1V8MCP_CPU0_SKT_VRTN" )
			)
			( signal "@baseboard_fab2_lib.baseboard_fab2(sch_1):vsense_p1v8mcp_cpu1_skt_vsen"
				( objectStatus "VSENSE_P1V8MCP_CPU1_SKT_VSEN" )
			)
			( signal "@baseboard_fab2_lib.baseboard_fab2(sch_1):vsense_p1v8mcp_cpu1_skt_vrtn"
				( objectStatus "VSENSE_P1V8MCP_CPU1_SKT_VRTN" )
			)
			( signal "@baseboard_fab2_lib.baseboard_fab2(sch_1):vsense_rgnd_p3v3_stby"
				( objectStatus "VSENSE_RGND_P3V3_STBY" )
			)
			( signal "@baseboard_fab2_lib.baseboard_fab2(sch_1):m_f_ecc(0)"
				( pinPairRef "@baseboard_fab2_lib.baseboard_fab2(sch_1):\PP4059\" )
				( pinPairRef "@baseboard_fab2_lib.baseboard_fab2(sch_1):\PP4061\" )
				( objectStatus "M_F_ECC<0>" )
			)
			( signal "@baseboard_fab2_lib.baseboard_fab2(sch_1):m_f_ecc(1)"
				( pinPairRef "@baseboard_fab2_lib.baseboard_fab2(sch_1):\PP4062\" )
				( pinPairRef "@baseboard_fab2_lib.baseboard_fab2(sch_1):\PP4064\" )
				( attribute "NO_TEST" "1"
					( Origin gBackEnd )
				)
				( objectStatus "M_F_ECC<1>" )
			)
			( signal "@baseboard_fab2_lib.baseboard_fab2(sch_1):m_f_ecc(2)"
				( pinPairRef "@baseboard_fab2_lib.baseboard_fab2(sch_1):\PP4065\" )
				( pinPairRef "@baseboard_fab2_lib.baseboard_fab2(sch_1):\PP4067\" )
				( attribute "NO_TEST" "1"
					( Origin gBackEnd )
				)
				( objectStatus "M_F_ECC<2>" )
			)
			( signal "@baseboard_fab2_lib.baseboard_fab2(sch_1):m_f_ecc(3)"
				( pinPairRef "@baseboard_fab2_lib.baseboard_fab2(sch_1):\PP4068\" )
				( pinPairRef "@baseboard_fab2_lib.baseboard_fab2(sch_1):\PP4070\" )
				( objectStatus "M_F_ECC<3>" )
			)
			( signal "@baseboard_fab2_lib.baseboard_fab2(sch_1):m_f_ecc(4)"
				( pinPairRef "@baseboard_fab2_lib.baseboard_fab2(sch_1):\PP4071\" )
				( pinPairRef "@baseboard_fab2_lib.baseboard_fab2(sch_1):\PP4073\" )
				( attribute "NO_TEST" "1"
					( Origin gBackEnd )
				)
				( objectStatus "M_F_ECC<4>" )
			)
			( signal "@baseboard_fab2_lib.baseboard_fab2(sch_1):m_f_ecc(5)"
				( pinPairRef "@baseboard_fab2_lib.baseboard_fab2(sch_1):\PP4074\" )
				( pinPairRef "@baseboard_fab2_lib.baseboard_fab2(sch_1):\PP4076\" )
				( objectStatus "M_F_ECC<5>" )
			)
			( signal "@baseboard_fab2_lib.baseboard_fab2(sch_1):m_f_ecc(6)"
				( pinPairRef "@baseboard_fab2_lib.baseboard_fab2(sch_1):\PP4077\" )
				( pinPairRef "@baseboard_fab2_lib.baseboard_fab2(sch_1):\PP4079\" )
				( objectStatus "M_F_ECC<6>" )
			)
			( signal "@baseboard_fab2_lib.baseboard_fab2(sch_1):m_f_ecc(7)"
				( pinPairRef "@baseboard_fab2_lib.baseboard_fab2(sch_1):\PP4080\" )
				( pinPairRef "@baseboard_fab2_lib.baseboard_fab2(sch_1):\PP4082\" )
				( attribute "NO_TEST" "1"
					( Origin gBackEnd )
				)
				( objectStatus "M_F_ECC<7>" )
			)
			( signal "@baseboard_fab2_lib.baseboard_fab2(sch_1):m_g_ecc(0)"
				( pinPairRef "@baseboard_fab2_lib.baseboard_fab2(sch_1):\PP2947\" )
				( pinPairRef "@baseboard_fab2_lib.baseboard_fab2(sch_1):\PP2948\" )
				( attribute "NO_TEST" "1"
					( Origin gBackEnd )
				)
				( objectStatus "M_G_ECC<0>" )
			)
			( signal "@baseboard_fab2_lib.baseboard_fab2(sch_1):m_g_ecc(1)"
				( pinPairRef "@baseboard_fab2_lib.baseboard_fab2(sch_1):\PP2950\" )
				( pinPairRef "@baseboard_fab2_lib.baseboard_fab2(sch_1):\PP2951\" )
				( attribute "NO_TEST" "1"
					( Origin gBackEnd )
				)
				( objectStatus "M_G_ECC<1>" )
			)
			( signal "@baseboard_fab2_lib.baseboard_fab2(sch_1):m_g_ecc(2)"
				( pinPairRef "@baseboard_fab2_lib.baseboard_fab2(sch_1):\PP2953\" )
				( pinPairRef "@baseboard_fab2_lib.baseboard_fab2(sch_1):\PP2954\" )
				( objectStatus "M_G_ECC<2>" )
			)
			( signal "@baseboard_fab2_lib.baseboard_fab2(sch_1):m_g_ecc(3)"
				( pinPairRef "@baseboard_fab2_lib.baseboard_fab2(sch_1):\PP2956\" )
				( pinPairRef "@baseboard_fab2_lib.baseboard_fab2(sch_1):\PP2957\" )
				( attribute "NO_TEST" "1"
					( Origin gBackEnd )
				)
				( objectStatus "M_G_ECC<3>" )
			)
			( signal "@baseboard_fab2_lib.baseboard_fab2(sch_1):m_g_ecc(4)"
				( pinPairRef "@baseboard_fab2_lib.baseboard_fab2(sch_1):\PP2959\" )
				( pinPairRef "@baseboard_fab2_lib.baseboard_fab2(sch_1):\PP2960\" )
				( objectStatus "M_G_ECC<4>" )
			)
			( signal "@baseboard_fab2_lib.baseboard_fab2(sch_1):m_g_ecc(5)"
				( pinPairRef "@baseboard_fab2_lib.baseboard_fab2(sch_1):\PP2962\" )
				( pinPairRef "@baseboard_fab2_lib.baseboard_fab2(sch_1):\PP2963\" )
				( attribute "NO_TEST" "1"
					( Origin gBackEnd )
				)
				( objectStatus "M_G_ECC<5>" )
			)
			( signal "@baseboard_fab2_lib.baseboard_fab2(sch_1):m_g_ecc(6)"
				( pinPairRef "@baseboard_fab2_lib.baseboard_fab2(sch_1):\PP2965\" )
				( pinPairRef "@baseboard_fab2_lib.baseboard_fab2(sch_1):\PP2966\" )
				( attribute "NO_TEST" "1"
					( Origin gBackEnd )
				)
				( objectStatus "M_G_ECC<6>" )
			)
			( signal "@baseboard_fab2_lib.baseboard_fab2(sch_1):m_g_ecc(7)"
				( pinPairRef "@baseboard_fab2_lib.baseboard_fab2(sch_1):\PP2968\" )
				( pinPairRef "@baseboard_fab2_lib.baseboard_fab2(sch_1):\PP2969\" )
				( attribute "NO_TEST" "1"
					( Origin gBackEnd )
				)
				( objectStatus "M_G_ECC<7>" )
			)
			( signal "@baseboard_fab2_lib.baseboard_fab2(sch_1):m_h_ecc(0)"
				( pinPairRef "@baseboard_fab2_lib.baseboard_fab2(sch_1):\PP2731\" )
				( pinPairRef "@baseboard_fab2_lib.baseboard_fab2(sch_1):\PP2732\" )
				( attribute "NO_TEST" "1"
					( Origin gBackEnd )
				)
				( objectStatus "M_H_ECC<0>" )
			)
			( signal "@baseboard_fab2_lib.baseboard_fab2(sch_1):m_h_ecc(1)"
				( pinPairRef "@baseboard_fab2_lib.baseboard_fab2(sch_1):\PP2734\" )
				( pinPairRef "@baseboard_fab2_lib.baseboard_fab2(sch_1):\PP2735\" )
				( attribute "NO_TEST" "1"
					( Origin gBackEnd )
				)
				( objectStatus "M_H_ECC<1>" )
			)
			( signal "@baseboard_fab2_lib.baseboard_fab2(sch_1):m_h_ecc(2)"
				( pinPairRef "@baseboard_fab2_lib.baseboard_fab2(sch_1):\PP2737\" )
				( pinPairRef "@baseboard_fab2_lib.baseboard_fab2(sch_1):\PP2738\" )
				( objectStatus "M_H_ECC<2>" )
			)
			( signal "@baseboard_fab2_lib.baseboard_fab2(sch_1):m_h_ecc(3)"
				( pinPairRef "@baseboard_fab2_lib.baseboard_fab2(sch_1):\PP2740\" )
				( pinPairRef "@baseboard_fab2_lib.baseboard_fab2(sch_1):\PP2741\" )
				( objectStatus "M_H_ECC<3>" )
			)
			( signal "@baseboard_fab2_lib.baseboard_fab2(sch_1):m_h_ecc(4)"
				( pinPairRef "@baseboard_fab2_lib.baseboard_fab2(sch_1):\PP2743\" )
				( pinPairRef "@baseboard_fab2_lib.baseboard_fab2(sch_1):\PP2744\" )
				( attribute "NO_TEST" "1"
					( Origin gBackEnd )
				)
				( objectStatus "M_H_ECC<4>" )
			)
			( signal "@baseboard_fab2_lib.baseboard_fab2(sch_1):m_h_ecc(5)"
				( pinPairRef "@baseboard_fab2_lib.baseboard_fab2(sch_1):\PP2746\" )
				( pinPairRef "@baseboard_fab2_lib.baseboard_fab2(sch_1):\PP2747\" )
				( attribute "NO_TEST" "1"
					( Origin gBackEnd )
				)
				( objectStatus "M_H_ECC<5>" )
			)
			( signal "@baseboard_fab2_lib.baseboard_fab2(sch_1):m_h_ecc(6)"
				( pinPairRef "@baseboard_fab2_lib.baseboard_fab2(sch_1):\PP2749\" )
				( pinPairRef "@baseboard_fab2_lib.baseboard_fab2(sch_1):\PP2750\" )
				( attribute "NO_TEST" "1"
					( Origin gBackEnd )
				)
				( objectStatus "M_H_ECC<6>" )
			)
			( signal "@baseboard_fab2_lib.baseboard_fab2(sch_1):m_h_ecc(7)"
				( pinPairRef "@baseboard_fab2_lib.baseboard_fab2(sch_1):\PP2752\" )
				( pinPairRef "@baseboard_fab2_lib.baseboard_fab2(sch_1):\PP2753\" )
				( attribute "NO_TEST" "1"
					( Origin gBackEnd )
				)
				( objectStatus "M_H_ECC<7>" )
			)
			( signal "@baseboard_fab2_lib.baseboard_fab2(sch_1):m_j_ecc(0)"
				( pinPairRef "@baseboard_fab2_lib.baseboard_fab2(sch_1):\PP2515\" )
				( pinPairRef "@baseboard_fab2_lib.baseboard_fab2(sch_1):\PP2516\" )
				( objectStatus "M_J_ECC<0>" )
			)
			( signal "@baseboard_fab2_lib.baseboard_fab2(sch_1):m_j_ecc(1)"
				( pinPairRef "@baseboard_fab2_lib.baseboard_fab2(sch_1):\PP2518\" )
				( pinPairRef "@baseboard_fab2_lib.baseboard_fab2(sch_1):\PP2519\" )
				( attribute "NO_TEST" "1"
					( Origin gBackEnd )
				)
				( objectStatus "M_J_ECC<1>" )
			)
			( signal "@baseboard_fab2_lib.baseboard_fab2(sch_1):m_j_ecc(2)"
				( pinPairRef "@baseboard_fab2_lib.baseboard_fab2(sch_1):\PP2521\" )
				( pinPairRef "@baseboard_fab2_lib.baseboard_fab2(sch_1):\PP2522\" )
				( attribute "NO_TEST" "1"
					( Origin gBackEnd )
				)
				( objectStatus "M_J_ECC<2>" )
			)
			( signal "@baseboard_fab2_lib.baseboard_fab2(sch_1):m_j_ecc(3)"
				( pinPairRef "@baseboard_fab2_lib.baseboard_fab2(sch_1):\PP2524\" )
				( pinPairRef "@baseboard_fab2_lib.baseboard_fab2(sch_1):\PP2525\" )
				( objectStatus "M_J_ECC<3>" )
			)
			( signal "@baseboard_fab2_lib.baseboard_fab2(sch_1):m_j_ecc(4)"
				( pinPairRef "@baseboard_fab2_lib.baseboard_fab2(sch_1):\PP2527\" )
				( pinPairRef "@baseboard_fab2_lib.baseboard_fab2(sch_1):\PP2528\" )
				( attribute "NO_TEST" "1"
					( Origin gBackEnd )
				)
				( objectStatus "M_J_ECC<4>" )
			)
			( signal "@baseboard_fab2_lib.baseboard_fab2(sch_1):m_j_ecc(5)"
				( pinPairRef "@baseboard_fab2_lib.baseboard_fab2(sch_1):\PP2530\" )
				( pinPairRef "@baseboard_fab2_lib.baseboard_fab2(sch_1):\PP2531\" )
				( objectStatus "M_J_ECC<5>" )
			)
			( signal "@baseboard_fab2_lib.baseboard_fab2(sch_1):m_j_ecc(6)"
				( pinPairRef "@baseboard_fab2_lib.baseboard_fab2(sch_1):\PP2533\" )
				( pinPairRef "@baseboard_fab2_lib.baseboard_fab2(sch_1):\PP2534\" )
				( objectStatus "M_J_ECC<6>" )
			)
			( signal "@baseboard_fab2_lib.baseboard_fab2(sch_1):m_j_ecc(7)"
				( pinPairRef "@baseboard_fab2_lib.baseboard_fab2(sch_1):\PP2536\" )
				( pinPairRef "@baseboard_fab2_lib.baseboard_fab2(sch_1):\PP2537\" )
				( attribute "NO_TEST" "1"
					( Origin gBackEnd )
				)
				( objectStatus "M_J_ECC<7>" )
			)
			( signal "@baseboard_fab2_lib.baseboard_fab2(sch_1):m_k_ecc(0)"
				( pinPairRef "@baseboard_fab2_lib.baseboard_fab2(sch_1):\PP2299\" )
				( pinPairRef "@baseboard_fab2_lib.baseboard_fab2(sch_1):\PP2300\" )
				( objectStatus "M_K_ECC<0>" )
			)
			( signal "@baseboard_fab2_lib.baseboard_fab2(sch_1):m_k_ecc(1)"
				( pinPairRef "@baseboard_fab2_lib.baseboard_fab2(sch_1):\PP2302\" )
				( pinPairRef "@baseboard_fab2_lib.baseboard_fab2(sch_1):\PP2303\" )
				( attribute "NO_TEST" "1"
					( Origin gBackEnd )
				)
				( objectStatus "M_K_ECC<1>" )
			)
			( signal "@baseboard_fab2_lib.baseboard_fab2(sch_1):m_k_ecc(2)"
				( pinPairRef "@baseboard_fab2_lib.baseboard_fab2(sch_1):\PP2305\" )
				( pinPairRef "@baseboard_fab2_lib.baseboard_fab2(sch_1):\PP2306\" )
				( attribute "NO_TEST" "1"
					( Origin gBackEnd )
				)
				( objectStatus "M_K_ECC<2>" )
			)
			( signal "@baseboard_fab2_lib.baseboard_fab2(sch_1):m_k_ecc(3)"
				( pinPairRef "@baseboard_fab2_lib.baseboard_fab2(sch_1):\PP2308\" )
				( pinPairRef "@baseboard_fab2_lib.baseboard_fab2(sch_1):\PP2309\" )
				( objectStatus "M_K_ECC<3>" )
			)
			( signal "@baseboard_fab2_lib.baseboard_fab2(sch_1):m_k_ecc(4)"
				( pinPairRef "@baseboard_fab2_lib.baseboard_fab2(sch_1):\PP2311\" )
				( pinPairRef "@baseboard_fab2_lib.baseboard_fab2(sch_1):\PP2312\" )
				( attribute "NO_TEST" "1"
					( Origin gBackEnd )
				)
				( objectStatus "M_K_ECC<4>" )
			)
			( signal "@baseboard_fab2_lib.baseboard_fab2(sch_1):m_k_ecc(5)"
				( pinPairRef "@baseboard_fab2_lib.baseboard_fab2(sch_1):\PP2314\" )
				( pinPairRef "@baseboard_fab2_lib.baseboard_fab2(sch_1):\PP2315\" )
				( objectStatus "M_K_ECC<5>" )
			)
			( signal "@baseboard_fab2_lib.baseboard_fab2(sch_1):m_k_ecc(6)"
				( pinPairRef "@baseboard_fab2_lib.baseboard_fab2(sch_1):\PP2317\" )
				( pinPairRef "@baseboard_fab2_lib.baseboard_fab2(sch_1):\PP2318\" )
				( objectStatus "M_K_ECC<6>" )
			)
			( signal "@baseboard_fab2_lib.baseboard_fab2(sch_1):m_k_ecc(7)"
				( pinPairRef "@baseboard_fab2_lib.baseboard_fab2(sch_1):\PP2320\" )
				( pinPairRef "@baseboard_fab2_lib.baseboard_fab2(sch_1):\PP2321\" )
				( attribute "NO_TEST" "1"
					( Origin gBackEnd )
				)
				( objectStatus "M_K_ECC<7>" )
			)
			( signal "@baseboard_fab2_lib.baseboard_fab2(sch_1):m_l_ecc(0)"
				( pinPairRef "@baseboard_fab2_lib.baseboard_fab2(sch_1):\PP2083\" )
				( pinPairRef "@baseboard_fab2_lib.baseboard_fab2(sch_1):\PP2084\" )
				( attribute "NO_TEST" "1"
					( Origin gBackEnd )
				)
				( objectStatus "M_L_ECC<0>" )
			)
			( signal "@baseboard_fab2_lib.baseboard_fab2(sch_1):m_l_ecc(1)"
				( pinPairRef "@baseboard_fab2_lib.baseboard_fab2(sch_1):\PP2086\" )
				( pinPairRef "@baseboard_fab2_lib.baseboard_fab2(sch_1):\PP2087\" )
				( attribute "NO_TEST" "1"
					( Origin gBackEnd )
				)
				( objectStatus "M_L_ECC<1>" )
			)
			( signal "@baseboard_fab2_lib.baseboard_fab2(sch_1):m_l_ecc(2)"
				( pinPairRef "@baseboard_fab2_lib.baseboard_fab2(sch_1):\PP2089\" )
				( pinPairRef "@baseboard_fab2_lib.baseboard_fab2(sch_1):\PP2090\" )
				( attribute "NO_TEST" "1"
					( Origin gBackEnd )
				)
				( objectStatus "M_L_ECC<2>" )
			)
			( signal "@baseboard_fab2_lib.baseboard_fab2(sch_1):m_l_ecc(3)"
				( pinPairRef "@baseboard_fab2_lib.baseboard_fab2(sch_1):\PP2092\" )
				( pinPairRef "@baseboard_fab2_lib.baseboard_fab2(sch_1):\PP2093\" )
				( attribute "NO_TEST" "1"
					( Origin gBackEnd )
				)
				( objectStatus "M_L_ECC<3>" )
			)
			( signal "@baseboard_fab2_lib.baseboard_fab2(sch_1):m_l_ecc(4)"
				( pinPairRef "@baseboard_fab2_lib.baseboard_fab2(sch_1):\PP2095\" )
				( pinPairRef "@baseboard_fab2_lib.baseboard_fab2(sch_1):\PP2096\" )
				( attribute "NO_TEST" "1"
					( Origin gBackEnd )
				)
				( objectStatus "M_L_ECC<4>" )
			)
			( signal "@baseboard_fab2_lib.baseboard_fab2(sch_1):m_l_ecc(5)"
				( pinPairRef "@baseboard_fab2_lib.baseboard_fab2(sch_1):\PP2098\" )
				( pinPairRef "@baseboard_fab2_lib.baseboard_fab2(sch_1):\PP2099\" )
				( attribute "NO_TEST" "1"
					( Origin gBackEnd )
				)
				( objectStatus "M_L_ECC<5>" )
			)
			( signal "@baseboard_fab2_lib.baseboard_fab2(sch_1):m_l_ecc(6)"
				( pinPairRef "@baseboard_fab2_lib.baseboard_fab2(sch_1):\PP2101\" )
				( pinPairRef "@baseboard_fab2_lib.baseboard_fab2(sch_1):\PP2102\" )
				( attribute "NO_TEST" "1"
					( Origin gBackEnd )
				)
				( objectStatus "M_L_ECC<6>" )
			)
			( signal "@baseboard_fab2_lib.baseboard_fab2(sch_1):m_l_ecc(7)"
				( pinPairRef "@baseboard_fab2_lib.baseboard_fab2(sch_1):\PP2104\" )
				( pinPairRef "@baseboard_fab2_lib.baseboard_fab2(sch_1):\PP2105\" )
				( attribute "NO_TEST" "1"
					( Origin gBackEnd )
				)
				( objectStatus "M_L_ECC<7>" )
			)
			( signal "@baseboard_fab2_lib.baseboard_fab2(sch_1):m_m_ecc(0)"
				( pinPairRef "@baseboard_fab2_lib.baseboard_fab2(sch_1):\PP1867\" )
				( pinPairRef "@baseboard_fab2_lib.baseboard_fab2(sch_1):\PP1868\" )
				( objectStatus "M_M_ECC<0>" )
			)
			( signal "@baseboard_fab2_lib.baseboard_fab2(sch_1):m_m_ecc(1)"
				( pinPairRef "@baseboard_fab2_lib.baseboard_fab2(sch_1):\PP1870\" )
				( pinPairRef "@baseboard_fab2_lib.baseboard_fab2(sch_1):\PP1871\" )
				( attribute "NO_TEST" "1"
					( Origin gBackEnd )
				)
				( objectStatus "M_M_ECC<1>" )
			)
			( signal "@baseboard_fab2_lib.baseboard_fab2(sch_1):m_m_ecc(2)"
				( pinPairRef "@baseboard_fab2_lib.baseboard_fab2(sch_1):\PP1873\" )
				( pinPairRef "@baseboard_fab2_lib.baseboard_fab2(sch_1):\PP1874\" )
				( attribute "NO_TEST" "1"
					( Origin gBackEnd )
				)
				( objectStatus "M_M_ECC<2>" )
			)
			( signal "@baseboard_fab2_lib.baseboard_fab2(sch_1):m_m_ecc(3)"
				( pinPairRef "@baseboard_fab2_lib.baseboard_fab2(sch_1):\PP1876\" )
				( pinPairRef "@baseboard_fab2_lib.baseboard_fab2(sch_1):\PP1877\" )
				( objectStatus "M_M_ECC<3>" )
			)
			( signal "@baseboard_fab2_lib.baseboard_fab2(sch_1):m_m_ecc(4)"
				( pinPairRef "@baseboard_fab2_lib.baseboard_fab2(sch_1):\PP1879\" )
				( pinPairRef "@baseboard_fab2_lib.baseboard_fab2(sch_1):\PP1880\" )
				( attribute "NO_TEST" "1"
					( Origin gBackEnd )
				)
				( objectStatus "M_M_ECC<4>" )
			)
			( signal "@baseboard_fab2_lib.baseboard_fab2(sch_1):m_m_ecc(5)"
				( pinPairRef "@baseboard_fab2_lib.baseboard_fab2(sch_1):\PP1882\" )
				( pinPairRef "@baseboard_fab2_lib.baseboard_fab2(sch_1):\PP1883\" )
				( objectStatus "M_M_ECC<5>" )
			)
			( signal "@baseboard_fab2_lib.baseboard_fab2(sch_1):m_m_ecc(6)"
				( pinPairRef "@baseboard_fab2_lib.baseboard_fab2(sch_1):\PP1885\" )
				( pinPairRef "@baseboard_fab2_lib.baseboard_fab2(sch_1):\PP1886\" )
				( objectStatus "M_M_ECC<6>" )
			)
			( signal "@baseboard_fab2_lib.baseboard_fab2(sch_1):m_m_ecc(7)"
				( pinPairRef "@baseboard_fab2_lib.baseboard_fab2(sch_1):\PP1888\" )
				( pinPairRef "@baseboard_fab2_lib.baseboard_fab2(sch_1):\PP1889\" )
				( attribute "NO_TEST" "1"
					( Origin gBackEnd )
				)
				( objectStatus "M_M_ECC<7>" )
			)
			( signal "@baseboard_fab2_lib.baseboard_fab2(sch_1):m_f_dq(9)"
				( pinPairRef "@baseboard_fab2_lib.baseboard_fab2(sch_1):\PP4230\" )
				( pinPairRef "@baseboard_fab2_lib.baseboard_fab2(sch_1):\PP4232\" )
				( attribute "NO_TEST" "1"
					( Origin gBackEnd )
				)
				( objectStatus "M_F_DQ<9>" )
			)
			( signal "@baseboard_fab2_lib.baseboard_fab2(sch_1):m_f_dq(10)"
				( pinPairRef "@baseboard_fab2_lib.baseboard_fab2(sch_1):\PP4233\" )
				( pinPairRef "@baseboard_fab2_lib.baseboard_fab2(sch_1):\PP4235\" )
				( objectStatus "M_F_DQ<10>" )
			)
			( signal "@baseboard_fab2_lib.baseboard_fab2(sch_1):m_f_dq(11)"
				( pinPairRef "@baseboard_fab2_lib.baseboard_fab2(sch_1):\PP4236\" )
				( pinPairRef "@baseboard_fab2_lib.baseboard_fab2(sch_1):\PP4238\" )
				( attribute "NO_TEST" "1"
					( Origin gBackEnd )
				)
				( objectStatus "M_F_DQ<11>" )
			)
			( signal "@baseboard_fab2_lib.baseboard_fab2(sch_1):m_f_dq(12)"
				( pinPairRef "@baseboard_fab2_lib.baseboard_fab2(sch_1):\PP4239\" )
				( pinPairRef "@baseboard_fab2_lib.baseboard_fab2(sch_1):\PP4241\" )
				( attribute "NO_TEST" "1"
					( Origin gBackEnd )
				)
				( objectStatus "M_F_DQ<12>" )
			)
			( signal "@baseboard_fab2_lib.baseboard_fab2(sch_1):m_f_dq(13)"
				( pinPairRef "@baseboard_fab2_lib.baseboard_fab2(sch_1):\PP4242\" )
				( pinPairRef "@baseboard_fab2_lib.baseboard_fab2(sch_1):\PP4244\" )
				( objectStatus "M_F_DQ<13>" )
			)
			( signal "@baseboard_fab2_lib.baseboard_fab2(sch_1):m_f_dq(14)"
				( pinPairRef "@baseboard_fab2_lib.baseboard_fab2(sch_1):\PP4245\" )
				( pinPairRef "@baseboard_fab2_lib.baseboard_fab2(sch_1):\PP4247\" )
				( attribute "NO_TEST" "1"
					( Origin gBackEnd )
				)
				( objectStatus "M_F_DQ<14>" )
			)
			( signal "@baseboard_fab2_lib.baseboard_fab2(sch_1):m_f_dq(15)"
				( pinPairRef "@baseboard_fab2_lib.baseboard_fab2(sch_1):\PP4248\" )
				( pinPairRef "@baseboard_fab2_lib.baseboard_fab2(sch_1):\PP4250\" )
				( objectStatus "M_F_DQ<15>" )
			)
			( signal "@baseboard_fab2_lib.baseboard_fab2(sch_1):m_f_dq(16)"
				( pinPairRef "@baseboard_fab2_lib.baseboard_fab2(sch_1):\PP4203\" )
				( pinPairRef "@baseboard_fab2_lib.baseboard_fab2(sch_1):\PP4205\" )
				( attribute "NO_TEST" "1"
					( Origin gBackEnd )
				)
				( objectStatus "M_F_DQ<16>" )
			)
			( signal "@baseboard_fab2_lib.baseboard_fab2(sch_1):m_f_dq(17)"
				( pinPairRef "@baseboard_fab2_lib.baseboard_fab2(sch_1):\PP4206\" )
				( pinPairRef "@baseboard_fab2_lib.baseboard_fab2(sch_1):\PP4208\" )
				( objectStatus "M_F_DQ<17>" )
			)
			( signal "@baseboard_fab2_lib.baseboard_fab2(sch_1):m_f_dq(18)"
				( pinPairRef "@baseboard_fab2_lib.baseboard_fab2(sch_1):\PP4209\" )
				( pinPairRef "@baseboard_fab2_lib.baseboard_fab2(sch_1):\PP4211\" )
				( objectStatus "M_F_DQ<18>" )
			)
			( signal "@baseboard_fab2_lib.baseboard_fab2(sch_1):m_f_dq(19)"
				( pinPairRef "@baseboard_fab2_lib.baseboard_fab2(sch_1):\PP4212\" )
				( pinPairRef "@baseboard_fab2_lib.baseboard_fab2(sch_1):\PP4214\" )
				( attribute "NO_TEST" "1"
					( Origin gBackEnd )
				)
				( objectStatus "M_F_DQ<19>" )
			)
			( signal "@baseboard_fab2_lib.baseboard_fab2(sch_1):m_f_dq(20)"
				( pinPairRef "@baseboard_fab2_lib.baseboard_fab2(sch_1):\PP4215\" )
				( pinPairRef "@baseboard_fab2_lib.baseboard_fab2(sch_1):\PP4217\" )
				( objectStatus "M_F_DQ<20>" )
			)
			( signal "@baseboard_fab2_lib.baseboard_fab2(sch_1):m_f_dq(21)"
				( pinPairRef "@baseboard_fab2_lib.baseboard_fab2(sch_1):\PP4218\" )
				( pinPairRef "@baseboard_fab2_lib.baseboard_fab2(sch_1):\PP4220\" )
				( attribute "NO_TEST" "1"
					( Origin gBackEnd )
				)
				( objectStatus "M_F_DQ<21>" )
			)
			( signal "@baseboard_fab2_lib.baseboard_fab2(sch_1):m_f_dq(22)"
				( pinPairRef "@baseboard_fab2_lib.baseboard_fab2(sch_1):\PP4221\" )
				( pinPairRef "@baseboard_fab2_lib.baseboard_fab2(sch_1):\PP4223\" )
				( attribute "NO_TEST" "1"
					( Origin gBackEnd )
				)
				( objectStatus "M_F_DQ<22>" )
			)
			( signal "@baseboard_fab2_lib.baseboard_fab2(sch_1):m_f_dq(23)"
				( pinPairRef "@baseboard_fab2_lib.baseboard_fab2(sch_1):\PP4224\" )
				( pinPairRef "@baseboard_fab2_lib.baseboard_fab2(sch_1):\PP4226\" )
				( objectStatus "M_F_DQ<23>" )
			)
			( signal "@baseboard_fab2_lib.baseboard_fab2(sch_1):m_f_dq(24)"
				( pinPairRef "@baseboard_fab2_lib.baseboard_fab2(sch_1):\PP4179\" )
				( pinPairRef "@baseboard_fab2_lib.baseboard_fab2(sch_1):\PP4181\" )
				( attribute "NO_TEST" "1"
					( Origin gBackEnd )
				)
				( objectStatus "M_F_DQ<24>" )
			)
			( signal "@baseboard_fab2_lib.baseboard_fab2(sch_1):m_f_dq(25)"
				( pinPairRef "@baseboard_fab2_lib.baseboard_fab2(sch_1):\PP4182\" )
				( pinPairRef "@baseboard_fab2_lib.baseboard_fab2(sch_1):\PP4184\" )
				( objectStatus "M_F_DQ<25>" )
			)
			( signal "@baseboard_fab2_lib.baseboard_fab2(sch_1):m_f_dq(26)"
				( pinPairRef "@baseboard_fab2_lib.baseboard_fab2(sch_1):\PP4185\" )
				( pinPairRef "@baseboard_fab2_lib.baseboard_fab2(sch_1):\PP4187\" )
				( objectStatus "M_F_DQ<26>" )
			)
			( signal "@baseboard_fab2_lib.baseboard_fab2(sch_1):m_f_dq(27)"
				( pinPairRef "@baseboard_fab2_lib.baseboard_fab2(sch_1):\PP4188\" )
				( pinPairRef "@baseboard_fab2_lib.baseboard_fab2(sch_1):\PP4190\" )
				( attribute "NO_TEST" "1"
					( Origin gBackEnd )
				)
				( objectStatus "M_F_DQ<27>" )
			)
			( signal "@baseboard_fab2_lib.baseboard_fab2(sch_1):m_f_dq(28)"
				( pinPairRef "@baseboard_fab2_lib.baseboard_fab2(sch_1):\PP4191\" )
				( pinPairRef "@baseboard_fab2_lib.baseboard_fab2(sch_1):\PP4193\" )
				( objectStatus "M_F_DQ<28>" )
			)
			( signal "@baseboard_fab2_lib.baseboard_fab2(sch_1):m_f_dq(29)"
				( pinPairRef "@baseboard_fab2_lib.baseboard_fab2(sch_1):\PP4194\" )
				( pinPairRef "@baseboard_fab2_lib.baseboard_fab2(sch_1):\PP4196\" )
				( attribute "NO_TEST" "1"
					( Origin gBackEnd )
				)
				( objectStatus "M_F_DQ<29>" )
			)
			( signal "@baseboard_fab2_lib.baseboard_fab2(sch_1):m_f_dq(30)"
				( pinPairRef "@baseboard_fab2_lib.baseboard_fab2(sch_1):\PP4197\" )
				( pinPairRef "@baseboard_fab2_lib.baseboard_fab2(sch_1):\PP4199\" )
				( attribute "NO_TEST" "1"
					( Origin gBackEnd )
				)
				( objectStatus "M_F_DQ<30>" )
			)
			( signal "@baseboard_fab2_lib.baseboard_fab2(sch_1):m_f_dq(31)"
				( pinPairRef "@baseboard_fab2_lib.baseboard_fab2(sch_1):\PP4200\" )
				( pinPairRef "@baseboard_fab2_lib.baseboard_fab2(sch_1):\PP4202\" )
				( objectStatus "M_F_DQ<31>" )
			)
			( signal "@baseboard_fab2_lib.baseboard_fab2(sch_1):m_f_dq(32)"
				( pinPairRef "@baseboard_fab2_lib.baseboard_fab2(sch_1):\PP4155\" )
				( pinPairRef "@baseboard_fab2_lib.baseboard_fab2(sch_1):\PP4156\" )
				( objectStatus "M_F_DQ<32>" )
			)
			( signal "@baseboard_fab2_lib.baseboard_fab2(sch_1):m_f_dq(33)"
				( pinPairRef "@baseboard_fab2_lib.baseboard_fab2(sch_1):\PP4158\" )
				( pinPairRef "@baseboard_fab2_lib.baseboard_fab2(sch_1):\PP4159\" )
				( objectStatus "M_F_DQ<33>" )
			)
			( signal "@baseboard_fab2_lib.baseboard_fab2(sch_1):m_f_dq(34)"
				( pinPairRef "@baseboard_fab2_lib.baseboard_fab2(sch_1):\PP4161\" )
				( pinPairRef "@baseboard_fab2_lib.baseboard_fab2(sch_1):\PP4163\" )
				( attribute "NO_TEST" "1"
					( Origin gBackEnd )
				)
				( objectStatus "M_F_DQ<34>" )
			)
			( signal "@baseboard_fab2_lib.baseboard_fab2(sch_1):m_f_dq(35)"
				( pinPairRef "@baseboard_fab2_lib.baseboard_fab2(sch_1):\PP4164\" )
				( pinPairRef "@baseboard_fab2_lib.baseboard_fab2(sch_1):\PP4166\" )
				( objectStatus "M_F_DQ<35>" )
			)
			( signal "@baseboard_fab2_lib.baseboard_fab2(sch_1):m_f_dq(36)"
				( pinPairRef "@baseboard_fab2_lib.baseboard_fab2(sch_1):\PP4167\" )
				( pinPairRef "@baseboard_fab2_lib.baseboard_fab2(sch_1):\PP4168\" )
				( objectStatus "M_F_DQ<36>" )
			)
			( signal "@baseboard_fab2_lib.baseboard_fab2(sch_1):m_f_dq(37)"
				( pinPairRef "@baseboard_fab2_lib.baseboard_fab2(sch_1):\PP4170\" )
				( pinPairRef "@baseboard_fab2_lib.baseboard_fab2(sch_1):\PP4172\" )
				( attribute "NO_TEST" "1"
					( Origin gBackEnd )
				)
				( objectStatus "M_F_DQ<37>" )
			)
			( signal "@baseboard_fab2_lib.baseboard_fab2(sch_1):m_f_dq(38)"
				( pinPairRef "@baseboard_fab2_lib.baseboard_fab2(sch_1):\PP4173\" )
				( pinPairRef "@baseboard_fab2_lib.baseboard_fab2(sch_1):\PP4175\" )
				( objectStatus "M_F_DQ<38>" )
			)
			( signal "@baseboard_fab2_lib.baseboard_fab2(sch_1):m_f_dq(39)"
				( pinPairRef "@baseboard_fab2_lib.baseboard_fab2(sch_1):\PP4176\" )
				( pinPairRef "@baseboard_fab2_lib.baseboard_fab2(sch_1):\PP4178\" )
				( attribute "NO_TEST" "1"
					( Origin gBackEnd )
				)
				( objectStatus "M_F_DQ<39>" )
			)
			( signal "@baseboard_fab2_lib.baseboard_fab2(sch_1):m_f_dq(40)"
				( pinPairRef "@baseboard_fab2_lib.baseboard_fab2(sch_1):\PP4131\" )
				( pinPairRef "@baseboard_fab2_lib.baseboard_fab2(sch_1):\PP4133\" )
				( attribute "NO_TEST" "1"
					( Origin gBackEnd )
				)
				( objectStatus "M_F_DQ<40>" )
			)
			( signal "@baseboard_fab2_lib.baseboard_fab2(sch_1):m_f_dq(41)"
				( pinPairRef "@baseboard_fab2_lib.baseboard_fab2(sch_1):\PP4134\" )
				( pinPairRef "@baseboard_fab2_lib.baseboard_fab2(sch_1):\PP4136\" )
				( objectStatus "M_F_DQ<41>" )
			)
			( signal "@baseboard_fab2_lib.baseboard_fab2(sch_1):m_f_dq(42)"
				( pinPairRef "@baseboard_fab2_lib.baseboard_fab2(sch_1):\PP4137\" )
				( pinPairRef "@baseboard_fab2_lib.baseboard_fab2(sch_1):\PP4139\" )
				( objectStatus "M_F_DQ<42>" )
			)
			( signal "@baseboard_fab2_lib.baseboard_fab2(sch_1):m_f_dq(43)"
				( pinPairRef "@baseboard_fab2_lib.baseboard_fab2(sch_1):\PP4140\" )
				( pinPairRef "@baseboard_fab2_lib.baseboard_fab2(sch_1):\PP4142\" )
				( attribute "NO_TEST" "1"
					( Origin gBackEnd )
				)
				( objectStatus "M_F_DQ<43>" )
			)
			( signal "@baseboard_fab2_lib.baseboard_fab2(sch_1):m_f_dq(44)"
				( pinPairRef "@baseboard_fab2_lib.baseboard_fab2(sch_1):\PP4143\" )
				( pinPairRef "@baseboard_fab2_lib.baseboard_fab2(sch_1):\PP4145\" )
				( objectStatus "M_F_DQ<44>" )
			)
			( signal "@baseboard_fab2_lib.baseboard_fab2(sch_1):m_f_dq(45)"
				( pinPairRef "@baseboard_fab2_lib.baseboard_fab2(sch_1):\PP4146\" )
				( pinPairRef "@baseboard_fab2_lib.baseboard_fab2(sch_1):\PP4148\" )
				( attribute "NO_TEST" "1"
					( Origin gBackEnd )
				)
				( objectStatus "M_F_DQ<45>" )
			)
			( signal "@baseboard_fab2_lib.baseboard_fab2(sch_1):m_f_dq(46)"
				( pinPairRef "@baseboard_fab2_lib.baseboard_fab2(sch_1):\PP4149\" )
				( pinPairRef "@baseboard_fab2_lib.baseboard_fab2(sch_1):\PP4151\" )
				( attribute "NO_TEST" "1"
					( Origin gBackEnd )
				)
				( objectStatus "M_F_DQ<46>" )
			)
			( signal "@baseboard_fab2_lib.baseboard_fab2(sch_1):m_f_dq(47)"
				( pinPairRef "@baseboard_fab2_lib.baseboard_fab2(sch_1):\PP4152\" )
				( pinPairRef "@baseboard_fab2_lib.baseboard_fab2(sch_1):\PP4154\" )
				( objectStatus "M_F_DQ<47>" )
			)
			( signal "@baseboard_fab2_lib.baseboard_fab2(sch_1):m_f_dq(48)"
				( pinPairRef "@baseboard_fab2_lib.baseboard_fab2(sch_1):\PP4107\" )
				( pinPairRef "@baseboard_fab2_lib.baseboard_fab2(sch_1):\PP4109\" )
				( objectStatus "M_F_DQ<48>" )
			)
			( signal "@baseboard_fab2_lib.baseboard_fab2(sch_1):m_f_dq(49)"
				( pinPairRef "@baseboard_fab2_lib.baseboard_fab2(sch_1):\PP4110\" )
				( pinPairRef "@baseboard_fab2_lib.baseboard_fab2(sch_1):\PP4112\" )
				( attribute "NO_TEST" "1"
					( Origin gBackEnd )
				)
				( objectStatus "M_F_DQ<49>" )
			)
			( signal "@baseboard_fab2_lib.baseboard_fab2(sch_1):m_f_dq(50)"
				( pinPairRef "@baseboard_fab2_lib.baseboard_fab2(sch_1):\PP4113\" )
				( pinPairRef "@baseboard_fab2_lib.baseboard_fab2(sch_1):\PP4115\" )
				( attribute "NO_TEST" "1"
					( Origin gBackEnd )
				)
				( objectStatus "M_F_DQ<50>" )
			)
			( signal "@baseboard_fab2_lib.baseboard_fab2(sch_1):m_f_dq(51)"
				( pinPairRef "@baseboard_fab2_lib.baseboard_fab2(sch_1):\PP4116\" )
				( pinPairRef "@baseboard_fab2_lib.baseboard_fab2(sch_1):\PP4118\" )
				( objectStatus "M_F_DQ<51>" )
			)
			( signal "@baseboard_fab2_lib.baseboard_fab2(sch_1):m_f_dq(52)"
				( pinPairRef "@baseboard_fab2_lib.baseboard_fab2(sch_1):\PP4119\" )
				( pinPairRef "@baseboard_fab2_lib.baseboard_fab2(sch_1):\PP4121\" )
				( attribute "NO_TEST" "1"
					( Origin gBackEnd )
				)
				( objectStatus "M_F_DQ<52>" )
			)
			( signal "@baseboard_fab2_lib.baseboard_fab2(sch_1):m_f_dq(53)"
				( pinPairRef "@baseboard_fab2_lib.baseboard_fab2(sch_1):\PP4122\" )
				( pinPairRef "@baseboard_fab2_lib.baseboard_fab2(sch_1):\PP4124\" )
				( objectStatus "M_F_DQ<53>" )
			)
			( signal "@baseboard_fab2_lib.baseboard_fab2(sch_1):m_f_dq(54)"
				( pinPairRef "@baseboard_fab2_lib.baseboard_fab2(sch_1):\PP4125\" )
				( pinPairRef "@baseboard_fab2_lib.baseboard_fab2(sch_1):\PP4127\" )
				( objectStatus "M_F_DQ<54>" )
			)
			( signal "@baseboard_fab2_lib.baseboard_fab2(sch_1):m_f_dq(55)"
				( pinPairRef "@baseboard_fab2_lib.baseboard_fab2(sch_1):\PP4128\" )
				( pinPairRef "@baseboard_fab2_lib.baseboard_fab2(sch_1):\PP4130\" )
				( attribute "NO_TEST" "1"
					( Origin gBackEnd )
				)
				( objectStatus "M_F_DQ<55>" )
			)
			( signal "@baseboard_fab2_lib.baseboard_fab2(sch_1):m_f_dq(56)"
				( pinPairRef "@baseboard_fab2_lib.baseboard_fab2(sch_1):\PP4083\" )
				( pinPairRef "@baseboard_fab2_lib.baseboard_fab2(sch_1):\PP4085\" )
				( objectStatus "M_F_DQ<56>" )
			)
			( signal "@baseboard_fab2_lib.baseboard_fab2(sch_1):m_f_dq(57)"
				( pinPairRef "@baseboard_fab2_lib.baseboard_fab2(sch_1):\PP4086\" )
				( pinPairRef "@baseboard_fab2_lib.baseboard_fab2(sch_1):\PP4088\" )
				( attribute "NO_TEST" "1"
					( Origin gBackEnd )
				)
				( objectStatus "M_F_DQ<57>" )
			)
			( signal "@baseboard_fab2_lib.baseboard_fab2(sch_1):m_f_dq(58)"
				( pinPairRef "@baseboard_fab2_lib.baseboard_fab2(sch_1):\PP4089\" )
				( pinPairRef "@baseboard_fab2_lib.baseboard_fab2(sch_1):\PP4091\" )
				( attribute "NO_TEST" "1"
					( Origin gBackEnd )
				)
				( objectStatus "M_F_DQ<58>" )
			)
			( signal "@baseboard_fab2_lib.baseboard_fab2(sch_1):m_f_dq(59)"
				( pinPairRef "@baseboard_fab2_lib.baseboard_fab2(sch_1):\PP4092\" )
				( pinPairRef "@baseboard_fab2_lib.baseboard_fab2(sch_1):\PP4094\" )
				( objectStatus "M_F_DQ<59>" )
			)
			( signal "@baseboard_fab2_lib.baseboard_fab2(sch_1):m_f_dq(60)"
				( pinPairRef "@baseboard_fab2_lib.baseboard_fab2(sch_1):\PP4095\" )
				( pinPairRef "@baseboard_fab2_lib.baseboard_fab2(sch_1):\PP4097\" )
				( attribute "NO_TEST" "1"
					( Origin gBackEnd )
				)
				( objectStatus "M_F_DQ<60>" )
			)
			( signal "@baseboard_fab2_lib.baseboard_fab2(sch_1):m_f_dq(61)"
				( pinPairRef "@baseboard_fab2_lib.baseboard_fab2(sch_1):\PP4098\" )
				( pinPairRef "@baseboard_fab2_lib.baseboard_fab2(sch_1):\PP4100\" )
				( objectStatus "M_F_DQ<61>" )
			)
			( signal "@baseboard_fab2_lib.baseboard_fab2(sch_1):m_f_dq(62)"
				( pinPairRef "@baseboard_fab2_lib.baseboard_fab2(sch_1):\PP4101\" )
				( pinPairRef "@baseboard_fab2_lib.baseboard_fab2(sch_1):\PP4103\" )
				( objectStatus "M_F_DQ<62>" )
			)
			( signal "@baseboard_fab2_lib.baseboard_fab2(sch_1):m_f_dq(63)"
				( pinPairRef "@baseboard_fab2_lib.baseboard_fab2(sch_1):\PP4104\" )
				( pinPairRef "@baseboard_fab2_lib.baseboard_fab2(sch_1):\PP4106\" )
				( attribute "NO_TEST" "1"
					( Origin gBackEnd )
				)
				( objectStatus "M_F_DQ<63>" )
			)
			( signal "@baseboard_fab2_lib.baseboard_fab2(sch_1):m_g_dq(10)"
				( pinPairRef "@baseboard_fab2_lib.baseboard_fab2(sch_1):\PP2905\" )
				( pinPairRef "@baseboard_fab2_lib.baseboard_fab2(sch_1):\PP2907\" )
				( objectStatus "M_G_DQ<10>" )
			)
			( signal "@baseboard_fab2_lib.baseboard_fab2(sch_1):m_h_dq(13)"
				( pinPairRef "@baseboard_fab2_lib.baseboard_fab2(sch_1):\PP2698\" )
				( pinPairRef "@baseboard_fab2_lib.baseboard_fab2(sch_1):\PP2700\" )
				( attribute "NO_TEST" "1"
					( Origin gBackEnd )
				)
				( objectStatus "M_H_DQ<13>" )
			)
			( signal "@baseboard_fab2_lib.baseboard_fab2(sch_1):m_h_dq(14)"
				( pinPairRef "@baseboard_fab2_lib.baseboard_fab2(sch_1):\PP2701\" )
				( pinPairRef "@baseboard_fab2_lib.baseboard_fab2(sch_1):\PP2703\" )
				( attribute "NO_TEST" "1"
					( Origin gBackEnd )
				)
				( objectStatus "M_H_DQ<14>" )
			)
			( signal "@baseboard_fab2_lib.baseboard_fab2(sch_1):m_h_dq(15)"
				( pinPairRef "@baseboard_fab2_lib.baseboard_fab2(sch_1):\PP2704\" )
				( pinPairRef "@baseboard_fab2_lib.baseboard_fab2(sch_1):\PP2706\" )
				( attribute "NO_TEST" "1"
					( Origin gBackEnd )
				)
				( objectStatus "M_H_DQ<15>" )
			)
			( signal "@baseboard_fab2_lib.baseboard_fab2(sch_1):m_h_dq(16)"
				( pinPairRef "@baseboard_fab2_lib.baseboard_fab2(sch_1):\PP2659\" )
				( pinPairRef "@baseboard_fab2_lib.baseboard_fab2(sch_1):\PP2661\" )
				( attribute "NO_TEST" "1"
					( Origin gBackEnd )
				)
				( objectStatus "M_H_DQ<16>" )
			)
			( signal "@baseboard_fab2_lib.baseboard_fab2(sch_1):m_a_ecc(0)"
				( pinPairRef "@baseboard_fab2_lib.baseboard_fab2(sch_1):\PP5139\" )
				( pinPairRef "@baseboard_fab2_lib.baseboard_fab2(sch_1):\PP5141\" )
				( attribute "NO_TEST" "1"
					( Origin gBackEnd )
				)
				( objectStatus "M_A_ECC<0>" )
			)
			( signal "@baseboard_fab2_lib.baseboard_fab2(sch_1):m_a_ecc(1)"
				( pinPairRef "@baseboard_fab2_lib.baseboard_fab2(sch_1):\PP5142\" )
				( pinPairRef "@baseboard_fab2_lib.baseboard_fab2(sch_1):\PP5144\" )
				( objectStatus "M_A_ECC<1>" )
			)
			( signal "@baseboard_fab2_lib.baseboard_fab2(sch_1):m_a_ecc(2)"
				( pinPairRef "@baseboard_fab2_lib.baseboard_fab2(sch_1):\PP5145\" )
				( pinPairRef "@baseboard_fab2_lib.baseboard_fab2(sch_1):\PP5147\" )
				( objectStatus "M_A_ECC<2>" )
			)
			( signal "@baseboard_fab2_lib.baseboard_fab2(sch_1):m_a_ecc(3)"
				( pinPairRef "@baseboard_fab2_lib.baseboard_fab2(sch_1):\PP5148\" )
				( pinPairRef "@baseboard_fab2_lib.baseboard_fab2(sch_1):\PP5150\" )
				( attribute "NO_TEST" "1"
					( Origin gBackEnd )
				)
				( objectStatus "M_A_ECC<3>" )
			)
			( signal "@baseboard_fab2_lib.baseboard_fab2(sch_1):m_a_ecc(4)"
				( pinPairRef "@baseboard_fab2_lib.baseboard_fab2(sch_1):\PP5151\" )
				( pinPairRef "@baseboard_fab2_lib.baseboard_fab2(sch_1):\PP5153\" )
				( objectStatus "M_A_ECC<4>" )
			)
			( signal "@baseboard_fab2_lib.baseboard_fab2(sch_1):m_a_ecc(5)"
				( pinPairRef "@baseboard_fab2_lib.baseboard_fab2(sch_1):\PP5154\" )
				( pinPairRef "@baseboard_fab2_lib.baseboard_fab2(sch_1):\PP5156\" )
				( attribute "NO_TEST" "1"
					( Origin gBackEnd )
				)
				( objectStatus "M_A_ECC<5>" )
			)
			( signal "@baseboard_fab2_lib.baseboard_fab2(sch_1):m_a_ecc(6)"
				( pinPairRef "@baseboard_fab2_lib.baseboard_fab2(sch_1):\PP5157\" )
				( pinPairRef "@baseboard_fab2_lib.baseboard_fab2(sch_1):\PP5159\" )
				( attribute "NO_TEST" "1"
					( Origin gBackEnd )
				)
				( objectStatus "M_A_ECC<6>" )
			)
			( signal "@baseboard_fab2_lib.baseboard_fab2(sch_1):m_a_ecc(7)"
				( pinPairRef "@baseboard_fab2_lib.baseboard_fab2(sch_1):\PP5160\" )
				( pinPairRef "@baseboard_fab2_lib.baseboard_fab2(sch_1):\PP5162\" )
				( objectStatus "M_A_ECC<7>" )
			)
			( signal "@baseboard_fab2_lib.baseboard_fab2(sch_1):m_b_ecc(0)"
				( pinPairRef "@baseboard_fab2_lib.baseboard_fab2(sch_1):\PP5115\" )
				( pinPairRef "@baseboard_fab2_lib.baseboard_fab2(sch_1):\PP5117\" )
				( attribute "NO_TEST" "1"
					( Origin gBackEnd )
				)
				( objectStatus "M_B_ECC<0>" )
			)
			( signal "@baseboard_fab2_lib.baseboard_fab2(sch_1):m_b_ecc(1)"
				( pinPairRef "@baseboard_fab2_lib.baseboard_fab2(sch_1):\PP5118\" )
				( pinPairRef "@baseboard_fab2_lib.baseboard_fab2(sch_1):\PP5120\" )
				( objectStatus "M_B_ECC<1>" )
			)
			( signal "@baseboard_fab2_lib.baseboard_fab2(sch_1):m_b_ecc(2)"
				( pinPairRef "@baseboard_fab2_lib.baseboard_fab2(sch_1):\PP5121\" )
				( pinPairRef "@baseboard_fab2_lib.baseboard_fab2(sch_1):\PP5123\" )
				( objectStatus "M_B_ECC<2>" )
			)
			( signal "@baseboard_fab2_lib.baseboard_fab2(sch_1):m_b_ecc(3)"
				( pinPairRef "@baseboard_fab2_lib.baseboard_fab2(sch_1):\PP5124\" )
				( pinPairRef "@baseboard_fab2_lib.baseboard_fab2(sch_1):\PP5126\" )
				( objectStatus "M_B_ECC<3>" )
			)
			( signal "@baseboard_fab2_lib.baseboard_fab2(sch_1):m_b_ecc(4)"
				( pinPairRef "@baseboard_fab2_lib.baseboard_fab2(sch_1):\PP5127\" )
				( pinPairRef "@baseboard_fab2_lib.baseboard_fab2(sch_1):\PP5129\" )
				( objectStatus "M_B_ECC<4>" )
			)
			( signal "@baseboard_fab2_lib.baseboard_fab2(sch_1):m_b_ecc(5)"
				( pinPairRef "@baseboard_fab2_lib.baseboard_fab2(sch_1):\PP5130\" )
				( pinPairRef "@baseboard_fab2_lib.baseboard_fab2(sch_1):\PP5132\" )
				( objectStatus "M_B_ECC<5>" )
			)
			( signal "@baseboard_fab2_lib.baseboard_fab2(sch_1):m_b_ecc(6)"
				( pinPairRef "@baseboard_fab2_lib.baseboard_fab2(sch_1):\PP5133\" )
				( pinPairRef "@baseboard_fab2_lib.baseboard_fab2(sch_1):\PP5135\" )
				( objectStatus "M_B_ECC<6>" )
			)
			( signal "@baseboard_fab2_lib.baseboard_fab2(sch_1):m_b_ecc(7)"
				( pinPairRef "@baseboard_fab2_lib.baseboard_fab2(sch_1):\PP5136\" )
				( pinPairRef "@baseboard_fab2_lib.baseboard_fab2(sch_1):\PP5138\" )
				( attribute "NO_TEST" "1"
					( Origin gBackEnd )
				)
				( objectStatus "M_B_ECC<7>" )
			)
			( signal "@baseboard_fab2_lib.baseboard_fab2(sch_1):m_c_ecc(0)"
				( pinPairRef "@baseboard_fab2_lib.baseboard_fab2(sch_1):\PP4899\" )
				( pinPairRef "@baseboard_fab2_lib.baseboard_fab2(sch_1):\PP4901\" )
				( objectStatus "M_C_ECC<0>" )
			)
			( signal "@baseboard_fab2_lib.baseboard_fab2(sch_1):m_c_ecc(1)"
				( pinPairRef "@baseboard_fab2_lib.baseboard_fab2(sch_1):\PP4902\" )
				( pinPairRef "@baseboard_fab2_lib.baseboard_fab2(sch_1):\PP4904\" )
				( attribute "NO_TEST" "1"
					( Origin gBackEnd )
				)
				( objectStatus "M_C_ECC<1>" )
			)
			( signal "@baseboard_fab2_lib.baseboard_fab2(sch_1):m_c_ecc(2)"
				( pinPairRef "@baseboard_fab2_lib.baseboard_fab2(sch_1):\PP4905\" )
				( pinPairRef "@baseboard_fab2_lib.baseboard_fab2(sch_1):\PP4907\" )
				( attribute "NO_TEST" "1"
					( Origin gBackEnd )
				)
				( objectStatus "M_C_ECC<2>" )
			)
			( signal "@baseboard_fab2_lib.baseboard_fab2(sch_1):m_c_ecc(3)"
				( pinPairRef "@baseboard_fab2_lib.baseboard_fab2(sch_1):\PP4908\" )
				( pinPairRef "@baseboard_fab2_lib.baseboard_fab2(sch_1):\PP4910\" )
				( objectStatus "M_C_ECC<3>" )
			)
			( signal "@baseboard_fab2_lib.baseboard_fab2(sch_1):m_c_ecc(4)"
				( pinPairRef "@baseboard_fab2_lib.baseboard_fab2(sch_1):\PP4911\" )
				( pinPairRef "@baseboard_fab2_lib.baseboard_fab2(sch_1):\PP4913\" )
				( attribute "NO_TEST" "1"
					( Origin gBackEnd )
				)
				( objectStatus "M_C_ECC<4>" )
			)
			( signal "@baseboard_fab2_lib.baseboard_fab2(sch_1):m_c_ecc(5)"
				( pinPairRef "@baseboard_fab2_lib.baseboard_fab2(sch_1):\PP4914\" )
				( pinPairRef "@baseboard_fab2_lib.baseboard_fab2(sch_1):\PP4916\" )
				( objectStatus "M_C_ECC<5>" )
			)
			( signal "@baseboard_fab2_lib.baseboard_fab2(sch_1):m_c_ecc(6)"
				( pinPairRef "@baseboard_fab2_lib.baseboard_fab2(sch_1):\PP4917\" )
				( pinPairRef "@baseboard_fab2_lib.baseboard_fab2(sch_1):\PP4919\" )
				( objectStatus "M_C_ECC<6>" )
			)
			( signal "@baseboard_fab2_lib.baseboard_fab2(sch_1):m_c_ecc(7)"
				( pinPairRef "@baseboard_fab2_lib.baseboard_fab2(sch_1):\PP4920\" )
				( pinPairRef "@baseboard_fab2_lib.baseboard_fab2(sch_1):\PP4922\" )
				( attribute "NO_TEST" "1"
					( Origin gBackEnd )
				)
				( objectStatus "M_C_ECC<7>" )
			)
			( signal "@baseboard_fab2_lib.baseboard_fab2(sch_1):m_d_ecc(0)"
				( pinPairRef "@baseboard_fab2_lib.baseboard_fab2(sch_1):\PP4491\" )
				( pinPairRef "@baseboard_fab2_lib.baseboard_fab2(sch_1):\PP4493\" )
				( objectStatus "M_D_ECC<0>" )
			)
			( signal "@baseboard_fab2_lib.baseboard_fab2(sch_1):m_d_ecc(1)"
				( pinPairRef "@baseboard_fab2_lib.baseboard_fab2(sch_1):\PP4494\" )
				( pinPairRef "@baseboard_fab2_lib.baseboard_fab2(sch_1):\PP4496\" )
				( attribute "NO_TEST" "1"
					( Origin gBackEnd )
				)
				( objectStatus "M_D_ECC<1>" )
			)
			( signal "@baseboard_fab2_lib.baseboard_fab2(sch_1):m_d_ecc(2)"
				( pinPairRef "@baseboard_fab2_lib.baseboard_fab2(sch_1):\PP4497\" )
				( pinPairRef "@baseboard_fab2_lib.baseboard_fab2(sch_1):\PP4499\" )
				( attribute "NO_TEST" "1"
					( Origin gBackEnd )
				)
				( objectStatus "M_D_ECC<2>" )
			)
			( signal "@baseboard_fab2_lib.baseboard_fab2(sch_1):m_d_ecc(3)"
				( pinPairRef "@baseboard_fab2_lib.baseboard_fab2(sch_1):\PP4500\" )
				( pinPairRef "@baseboard_fab2_lib.baseboard_fab2(sch_1):\PP4502\" )
				( objectStatus "M_D_ECC<3>" )
			)
			( signal "@baseboard_fab2_lib.baseboard_fab2(sch_1):m_d_ecc(4)"
				( pinPairRef "@baseboard_fab2_lib.baseboard_fab2(sch_1):\PP4503\" )
				( pinPairRef "@baseboard_fab2_lib.baseboard_fab2(sch_1):\PP4505\" )
				( attribute "NO_TEST" "1"
					( Origin gBackEnd )
				)
				( objectStatus "M_D_ECC<4>" )
			)
			( signal "@baseboard_fab2_lib.baseboard_fab2(sch_1):m_d_ecc(5)"
				( pinPairRef "@baseboard_fab2_lib.baseboard_fab2(sch_1):\PP4506\" )
				( pinPairRef "@baseboard_fab2_lib.baseboard_fab2(sch_1):\PP4508\" )
				( objectStatus "M_D_ECC<5>" )
			)
			( signal "@baseboard_fab2_lib.baseboard_fab2(sch_1):m_d_ecc(6)"
				( pinPairRef "@baseboard_fab2_lib.baseboard_fab2(sch_1):\PP4509\" )
				( pinPairRef "@baseboard_fab2_lib.baseboard_fab2(sch_1):\PP4511\" )
				( objectStatus "M_D_ECC<6>" )
			)
			( signal "@baseboard_fab2_lib.baseboard_fab2(sch_1):m_d_ecc(7)"
				( pinPairRef "@baseboard_fab2_lib.baseboard_fab2(sch_1):\PP4512\" )
				( pinPairRef "@baseboard_fab2_lib.baseboard_fab2(sch_1):\PP4514\" )
				( attribute "NO_TEST" "1"
					( Origin gBackEnd )
				)
				( objectStatus "M_D_ECC<7>" )
			)
			( signal "@baseboard_fab2_lib.baseboard_fab2(sch_1):m_e_ecc(0)"
				( pinPairRef "@baseboard_fab2_lib.baseboard_fab2(sch_1):\PP4275\" )
				( pinPairRef "@baseboard_fab2_lib.baseboard_fab2(sch_1):\PP4277\" )
				( attribute "NO_TEST" "1"
					( Origin gBackEnd )
				)
				( objectStatus "M_E_ECC<0>" )
			)
			( signal "@baseboard_fab2_lib.baseboard_fab2(sch_1):m_e_ecc(1)"
				( pinPairRef "@baseboard_fab2_lib.baseboard_fab2(sch_1):\PP4278\" )
				( pinPairRef "@baseboard_fab2_lib.baseboard_fab2(sch_1):\PP4280\" )
				( attribute "NO_TEST" "1"
					( Origin gBackEnd )
				)
				( objectStatus "M_E_ECC<1>" )
			)
			( signal "@baseboard_fab2_lib.baseboard_fab2(sch_1):m_e_ecc(2)"
				( pinPairRef "@baseboard_fab2_lib.baseboard_fab2(sch_1):\PP4281\" )
				( pinPairRef "@baseboard_fab2_lib.baseboard_fab2(sch_1):\PP4283\" )
				( attribute "NO_TEST" "1"
					( Origin gBackEnd )
				)
				( objectStatus "M_E_ECC<2>" )
			)
			( signal "@baseboard_fab2_lib.baseboard_fab2(sch_1):m_e_ecc(3)"
				( pinPairRef "@baseboard_fab2_lib.baseboard_fab2(sch_1):\PP4284\" )
				( pinPairRef "@baseboard_fab2_lib.baseboard_fab2(sch_1):\PP4286\" )
				( attribute "NO_TEST" "1"
					( Origin gBackEnd )
				)
				( objectStatus "M_E_ECC<3>" )
			)
			( signal "@baseboard_fab2_lib.baseboard_fab2(sch_1):m_e_ecc(4)"
				( pinPairRef "@baseboard_fab2_lib.baseboard_fab2(sch_1):\PP4287\" )
				( pinPairRef "@baseboard_fab2_lib.baseboard_fab2(sch_1):\PP4289\" )
				( attribute "NO_TEST" "1"
					( Origin gBackEnd )
				)
				( objectStatus "M_E_ECC<4>" )
			)
			( signal "@baseboard_fab2_lib.baseboard_fab2(sch_1):m_e_ecc(5)"
				( pinPairRef "@baseboard_fab2_lib.baseboard_fab2(sch_1):\PP4290\" )
				( pinPairRef "@baseboard_fab2_lib.baseboard_fab2(sch_1):\PP4292\" )
				( attribute "NO_TEST" "1"
					( Origin gBackEnd )
				)
				( objectStatus "M_E_ECC<5>" )
			)
			( signal "@baseboard_fab2_lib.baseboard_fab2(sch_1):m_e_ecc(6)"
				( pinPairRef "@baseboard_fab2_lib.baseboard_fab2(sch_1):\PP4293\" )
				( pinPairRef "@baseboard_fab2_lib.baseboard_fab2(sch_1):\PP4295\" )
				( attribute "NO_TEST" "1"
					( Origin gBackEnd )
				)
				( objectStatus "M_E_ECC<6>" )
			)
			( signal "@baseboard_fab2_lib.baseboard_fab2(sch_1):m_e_ecc(7)"
				( pinPairRef "@baseboard_fab2_lib.baseboard_fab2(sch_1):\PP4296\" )
				( pinPairRef "@baseboard_fab2_lib.baseboard_fab2(sch_1):\PP4298\" )
				( attribute "NO_TEST" "1"
					( Origin gBackEnd )
				)
				( objectStatus "M_E_ECC<7>" )
			)
			( signal "@baseboard_fab2_lib.baseboard_fab2(sch_1):m_d_dq(37)"
				( pinPairRef "@baseboard_fab2_lib.baseboard_fab2(sch_1):\PP4602\" )
				( pinPairRef "@baseboard_fab2_lib.baseboard_fab2(sch_1):\PP4604\" )
				( attribute "NO_TEST" "1"
					( Origin gBackEnd )
				)
				( objectStatus "M_D_DQ<37>" )
			)
			( signal "@baseboard_fab2_lib.baseboard_fab2(sch_1):m_d_dq(38)"
				( pinPairRef "@baseboard_fab2_lib.baseboard_fab2(sch_1):\PP4605\" )
				( pinPairRef "@baseboard_fab2_lib.baseboard_fab2(sch_1):\PP4607\" )
				( attribute "NO_TEST" "1"
					( Origin gBackEnd )
				)
				( objectStatus "M_D_DQ<38>" )
			)
			( signal "@baseboard_fab2_lib.baseboard_fab2(sch_1):m_d_dq(39)"
				( pinPairRef "@baseboard_fab2_lib.baseboard_fab2(sch_1):\PP4608\" )
				( pinPairRef "@baseboard_fab2_lib.baseboard_fab2(sch_1):\PP4610\" )
				( attribute "NO_TEST" "1"
					( Origin gBackEnd )
				)
				( objectStatus "M_D_DQ<39>" )
			)
			( signal "@baseboard_fab2_lib.baseboard_fab2(sch_1):m_d_dq(40)"
				( pinPairRef "@baseboard_fab2_lib.baseboard_fab2(sch_1):\PP4563\" )
				( pinPairRef "@baseboard_fab2_lib.baseboard_fab2(sch_1):\PP4565\" )
				( objectStatus "M_D_DQ<40>" )
			)
			( signal "@baseboard_fab2_lib.baseboard_fab2(sch_1):m_d_dq(41)"
				( pinPairRef "@baseboard_fab2_lib.baseboard_fab2(sch_1):\PP4566\" )
				( pinPairRef "@baseboard_fab2_lib.baseboard_fab2(sch_1):\PP4568\" )
				( attribute "NO_TEST" "1"
					( Origin gBackEnd )
				)
				( objectStatus "M_D_DQ<41>" )
			)
			( signal "@baseboard_fab2_lib.baseboard_fab2(sch_1):m_d_dq(42)"
				( pinPairRef "@baseboard_fab2_lib.baseboard_fab2(sch_1):\PP4569\" )
				( pinPairRef "@baseboard_fab2_lib.baseboard_fab2(sch_1):\PP4571\" )
				( attribute "NO_TEST" "1"
					( Origin gBackEnd )
				)
				( objectStatus "M_D_DQ<42>" )
			)
			( signal "@baseboard_fab2_lib.baseboard_fab2(sch_1):m_d_dq(43)"
				( pinPairRef "@baseboard_fab2_lib.baseboard_fab2(sch_1):\PP4572\" )
				( pinPairRef "@baseboard_fab2_lib.baseboard_fab2(sch_1):\PP4574\" )
				( objectStatus "M_D_DQ<43>" )
			)
			( signal "@baseboard_fab2_lib.baseboard_fab2(sch_1):m_d_dq(44)"
				( pinPairRef "@baseboard_fab2_lib.baseboard_fab2(sch_1):\PP4575\" )
				( pinPairRef "@baseboard_fab2_lib.baseboard_fab2(sch_1):\PP4577\" )
				( attribute "NO_TEST" "1"
					( Origin gBackEnd )
				)
				( objectStatus "M_D_DQ<44>" )
			)
			( signal "@baseboard_fab2_lib.baseboard_fab2(sch_1):m_d_dq(45)"
				( pinPairRef "@baseboard_fab2_lib.baseboard_fab2(sch_1):\PP4578\" )
				( pinPairRef "@baseboard_fab2_lib.baseboard_fab2(sch_1):\PP4580\" )
				( objectStatus "M_D_DQ<45>" )
			)
			( signal "@baseboard_fab2_lib.baseboard_fab2(sch_1):m_d_dq(46)"
				( pinPairRef "@baseboard_fab2_lib.baseboard_fab2(sch_1):\PP4581\" )
				( pinPairRef "@baseboard_fab2_lib.baseboard_fab2(sch_1):\PP4583\" )
				( objectStatus "M_D_DQ<46>" )
			)
			( signal "@baseboard_fab2_lib.baseboard_fab2(sch_1):m_d_dq(47)"
				( pinPairRef "@baseboard_fab2_lib.baseboard_fab2(sch_1):\PP4584\" )
				( pinPairRef "@baseboard_fab2_lib.baseboard_fab2(sch_1):\PP4586\" )
				( attribute "NO_TEST" "1"
					( Origin gBackEnd )
				)
				( objectStatus "M_D_DQ<47>" )
			)
			( signal "@baseboard_fab2_lib.baseboard_fab2(sch_1):m_d_dq(48)"
				( pinPairRef "@baseboard_fab2_lib.baseboard_fab2(sch_1):\PP4539\" )
				( pinPairRef "@baseboard_fab2_lib.baseboard_fab2(sch_1):\PP4541\" )
				( attribute "NO_TEST" "1"
					( Origin gBackEnd )
				)
				( objectStatus "M_D_DQ<48>" )
			)
			( signal "@baseboard_fab2_lib.baseboard_fab2(sch_1):m_d_dq(49)"
				( pinPairRef "@baseboard_fab2_lib.baseboard_fab2(sch_1):\PP4542\" )
				( pinPairRef "@baseboard_fab2_lib.baseboard_fab2(sch_1):\PP4544\" )
				( objectStatus "M_D_DQ<49>" )
			)
			( signal "@baseboard_fab2_lib.baseboard_fab2(sch_1):m_d_dq(50)"
				( pinPairRef "@baseboard_fab2_lib.baseboard_fab2(sch_1):\PP4545\" )
				( pinPairRef "@baseboard_fab2_lib.baseboard_fab2(sch_1):\PP4547\" )
				( objectStatus "M_D_DQ<50>" )
			)
			( signal "@baseboard_fab2_lib.baseboard_fab2(sch_1):m_d_dq(51)"
				( pinPairRef "@baseboard_fab2_lib.baseboard_fab2(sch_1):\PP4548\" )
				( pinPairRef "@baseboard_fab2_lib.baseboard_fab2(sch_1):\PP4550\" )
				( attribute "NO_TEST" "1"
					( Origin gBackEnd )
				)
				( objectStatus "M_D_DQ<51>" )
			)
			( signal "@baseboard_fab2_lib.baseboard_fab2(sch_1):m_d_dq(52)"
				( pinPairRef "@baseboard_fab2_lib.baseboard_fab2(sch_1):\PP4551\" )
				( pinPairRef "@baseboard_fab2_lib.baseboard_fab2(sch_1):\PP4553\" )
				( objectStatus "M_D_DQ<52>" )
			)
			( signal "@baseboard_fab2_lib.baseboard_fab2(sch_1):m_d_dq(53)"
				( pinPairRef "@baseboard_fab2_lib.baseboard_fab2(sch_1):\PP4554\" )
				( pinPairRef "@baseboard_fab2_lib.baseboard_fab2(sch_1):\PP4556\" )
				( attribute "NO_TEST" "1"
					( Origin gBackEnd )
				)
				( objectStatus "M_D_DQ<53>" )
			)
			( signal "@baseboard_fab2_lib.baseboard_fab2(sch_1):m_d_dq(54)"
				( pinPairRef "@baseboard_fab2_lib.baseboard_fab2(sch_1):\PP4557\" )
				( pinPairRef "@baseboard_fab2_lib.baseboard_fab2(sch_1):\PP4559\" )
				( attribute "NO_TEST" "1"
					( Origin gBackEnd )
				)
				( objectStatus "M_D_DQ<54>" )
			)
			( signal "@baseboard_fab2_lib.baseboard_fab2(sch_1):m_d_dq(55)"
				( pinPairRef "@baseboard_fab2_lib.baseboard_fab2(sch_1):\PP4560\" )
				( pinPairRef "@baseboard_fab2_lib.baseboard_fab2(sch_1):\PP4562\" )
				( objectStatus "M_D_DQ<55>" )
			)
			( signal "@baseboard_fab2_lib.baseboard_fab2(sch_1):m_d_dq(56)"
				( pinPairRef "@baseboard_fab2_lib.baseboard_fab2(sch_1):\PP4515\" )
				( pinPairRef "@baseboard_fab2_lib.baseboard_fab2(sch_1):\PP4517\" )
				( attribute "NO_TEST" "1"
					( Origin gBackEnd )
				)
				( objectStatus "M_D_DQ<56>" )
			)
			( signal "@baseboard_fab2_lib.baseboard_fab2(sch_1):m_d_dq(57)"
				( pinPairRef "@baseboard_fab2_lib.baseboard_fab2(sch_1):\PP4518\" )
				( pinPairRef "@baseboard_fab2_lib.baseboard_fab2(sch_1):\PP4520\" )
				( attribute "NO_TEST" "1"
					( Origin gBackEnd )
				)
				( objectStatus "M_D_DQ<57>" )
			)
			( signal "@baseboard_fab2_lib.baseboard_fab2(sch_1):m_d_dq(58)"
				( pinPairRef "@baseboard_fab2_lib.baseboard_fab2(sch_1):\PP4521\" )
				( pinPairRef "@baseboard_fab2_lib.baseboard_fab2(sch_1):\PP4522\" )
				( attribute "NO_TEST" "1"
					( Origin gBackEnd )
				)
				( objectStatus "M_D_DQ<58>" )
			)
			( signal "@baseboard_fab2_lib.baseboard_fab2(sch_1):m_d_dq(59)"
				( pinPairRef "@baseboard_fab2_lib.baseboard_fab2(sch_1):\PP4524\" )
				( pinPairRef "@baseboard_fab2_lib.baseboard_fab2(sch_1):\PP4525\" )
				( objectStatus "M_D_DQ<59>" )
			)
			( signal "@baseboard_fab2_lib.baseboard_fab2(sch_1):m_d_dq(60)"
				( pinPairRef "@baseboard_fab2_lib.baseboard_fab2(sch_1):\PP4527\" )
				( pinPairRef "@baseboard_fab2_lib.baseboard_fab2(sch_1):\PP4529\" )
				( objectStatus "M_D_DQ<60>" )
			)
			( signal "@baseboard_fab2_lib.baseboard_fab2(sch_1):m_d_dq(61)"
				( pinPairRef "@baseboard_fab2_lib.baseboard_fab2(sch_1):\PP4530\" )
				( pinPairRef "@baseboard_fab2_lib.baseboard_fab2(sch_1):\PP4532\" )
				( attribute "NO_TEST" "1"
					( Origin gBackEnd )
				)
				( objectStatus "M_D_DQ<61>" )
			)
			( signal "@baseboard_fab2_lib.baseboard_fab2(sch_1):m_d_dq(62)"
				( pinPairRef "@baseboard_fab2_lib.baseboard_fab2(sch_1):\PP4533\" )
				( pinPairRef "@baseboard_fab2_lib.baseboard_fab2(sch_1):\PP4535\" )
				( attribute "NO_TEST" "1"
					( Origin gBackEnd )
				)
				( objectStatus "M_D_DQ<62>" )
			)
			( signal "@baseboard_fab2_lib.baseboard_fab2(sch_1):m_d_dq(63)"
				( pinPairRef "@baseboard_fab2_lib.baseboard_fab2(sch_1):\PP4536\" )
				( pinPairRef "@baseboard_fab2_lib.baseboard_fab2(sch_1):\PP4538\" )
				( objectStatus "M_D_DQ<63>" )
			)
			( signal "@baseboard_fab2_lib.baseboard_fab2(sch_1):m_e_dq(0)"
				( pinPairRef "@baseboard_fab2_lib.baseboard_fab2(sch_1):\PP4467\" )
				( pinPairRef "@baseboard_fab2_lib.baseboard_fab2(sch_1):\PP4469\" )
				( attribute "NO_TEST" "1"
					( Origin gBackEnd )
				)
				( objectStatus "M_E_DQ<0>" )
			)
			( signal "@baseboard_fab2_lib.baseboard_fab2(sch_1):m_e_dq(1)"
				( pinPairRef "@baseboard_fab2_lib.baseboard_fab2(sch_1):\PP4470\" )
				( pinPairRef "@baseboard_fab2_lib.baseboard_fab2(sch_1):\PP4472\" )
				( objectStatus "M_E_DQ<1>" )
			)
			( signal "@baseboard_fab2_lib.baseboard_fab2(sch_1):m_e_dq(2)"
				( pinPairRef "@baseboard_fab2_lib.baseboard_fab2(sch_1):\PP4473\" )
				( pinPairRef "@baseboard_fab2_lib.baseboard_fab2(sch_1):\PP4475\" )
				( objectStatus "M_E_DQ<2>" )
			)
			( signal "@baseboard_fab2_lib.baseboard_fab2(sch_1):m_e_dq(3)"
				( pinPairRef "@baseboard_fab2_lib.baseboard_fab2(sch_1):\PP4476\" )
				( pinPairRef "@baseboard_fab2_lib.baseboard_fab2(sch_1):\PP4478\" )
				( attribute "NO_TEST" "1"
					( Origin gBackEnd )
				)
				( objectStatus "M_E_DQ<3>" )
			)
			( signal "@baseboard_fab2_lib.baseboard_fab2(sch_1):m_e_dq(4)"
				( pinPairRef "@baseboard_fab2_lib.baseboard_fab2(sch_1):\PP4479\" )
				( pinPairRef "@baseboard_fab2_lib.baseboard_fab2(sch_1):\PP4481\" )
				( objectStatus "M_E_DQ<4>" )
			)
			( signal "@baseboard_fab2_lib.baseboard_fab2(sch_1):m_e_dq(5)"
				( pinPairRef "@baseboard_fab2_lib.baseboard_fab2(sch_1):\PP4482\" )
				( pinPairRef "@baseboard_fab2_lib.baseboard_fab2(sch_1):\PP4484\" )
				( attribute "NO_TEST" "1"
					( Origin gBackEnd )
				)
				( objectStatus "M_E_DQ<5>" )
			)
			( signal "@baseboard_fab2_lib.baseboard_fab2(sch_1):m_e_dq(6)"
				( pinPairRef "@baseboard_fab2_lib.baseboard_fab2(sch_1):\PP4485\" )
				( pinPairRef "@baseboard_fab2_lib.baseboard_fab2(sch_1):\PP4487\" )
				( attribute "NO_TEST" "1"
					( Origin gBackEnd )
				)
				( objectStatus "M_E_DQ<6>" )
			)
			( signal "@baseboard_fab2_lib.baseboard_fab2(sch_1):m_e_dq(7)"
				( pinPairRef "@baseboard_fab2_lib.baseboard_fab2(sch_1):\PP4488\" )
				( pinPairRef "@baseboard_fab2_lib.baseboard_fab2(sch_1):\PP4490\" )
				( objectStatus "M_E_DQ<7>" )
			)
			( signal "@baseboard_fab2_lib.baseboard_fab2(sch_1):m_e_dq(8)"
				( pinPairRef "@baseboard_fab2_lib.baseboard_fab2(sch_1):\PP4443\" )
				( pinPairRef "@baseboard_fab2_lib.baseboard_fab2(sch_1):\PP4445\" )
				( attribute "NO_TEST" "1"
					( Origin gBackEnd )
				)
				( objectStatus "M_E_DQ<8>" )
			)
			( signal "@baseboard_fab2_lib.baseboard_fab2(sch_1):m_e_dq(9)"
				( pinPairRef "@baseboard_fab2_lib.baseboard_fab2(sch_1):\PP4446\" )
				( pinPairRef "@baseboard_fab2_lib.baseboard_fab2(sch_1):\PP4448\" )
				( attribute "NO_TEST" "1"
					( Origin gBackEnd )
				)
				( objectStatus "M_E_DQ<9>" )
			)
			( signal "@baseboard_fab2_lib.baseboard_fab2(sch_1):m_e_dq(10)"
				( pinPairRef "@baseboard_fab2_lib.baseboard_fab2(sch_1):\PP4449\" )
				( pinPairRef "@baseboard_fab2_lib.baseboard_fab2(sch_1):\PP4451\" )
				( attribute "NO_TEST" "1"
					( Origin gBackEnd )
				)
				( objectStatus "M_E_DQ<10>" )
			)
			( signal "@baseboard_fab2_lib.baseboard_fab2(sch_1):m_e_dq(11)"
				( pinPairRef "@baseboard_fab2_lib.baseboard_fab2(sch_1):\PP4452\" )
				( pinPairRef "@baseboard_fab2_lib.baseboard_fab2(sch_1):\PP4454\" )
				( attribute "NO_TEST" "1"
					( Origin gBackEnd )
				)
				( objectStatus "M_E_DQ<11>" )
			)
			( signal "@baseboard_fab2_lib.baseboard_fab2(sch_1):m_e_dq(12)"
				( pinPairRef "@baseboard_fab2_lib.baseboard_fab2(sch_1):\PP4455\" )
				( pinPairRef "@baseboard_fab2_lib.baseboard_fab2(sch_1):\PP4457\" )
				( attribute "NO_TEST" "1"
					( Origin gBackEnd )
				)
				( objectStatus "M_E_DQ<12>" )
			)
			( signal "@baseboard_fab2_lib.baseboard_fab2(sch_1):m_e_dq(13)"
				( pinPairRef "@baseboard_fab2_lib.baseboard_fab2(sch_1):\PP4458\" )
				( pinPairRef "@baseboard_fab2_lib.baseboard_fab2(sch_1):\PP4460\" )
				( objectStatus "M_E_DQ<13>" )
			)
			( signal "@baseboard_fab2_lib.baseboard_fab2(sch_1):m_e_dq(14)"
				( pinPairRef "@baseboard_fab2_lib.baseboard_fab2(sch_1):\PP4461\" )
				( pinPairRef "@baseboard_fab2_lib.baseboard_fab2(sch_1):\PP4463\" )
				( attribute "NO_TEST" "1"
					( Origin gBackEnd )
				)
				( objectStatus "M_E_DQ<14>" )
			)
			( signal "@baseboard_fab2_lib.baseboard_fab2(sch_1):m_e_dq(15)"
				( pinPairRef "@baseboard_fab2_lib.baseboard_fab2(sch_1):\PP4464\" )
				( pinPairRef "@baseboard_fab2_lib.baseboard_fab2(sch_1):\PP4466\" )
				( objectStatus "M_E_DQ<15>" )
			)
			( signal "@baseboard_fab2_lib.baseboard_fab2(sch_1):m_e_dq(16)"
				( pinPairRef "@baseboard_fab2_lib.baseboard_fab2(sch_1):\PP4419\" )
				( pinPairRef "@baseboard_fab2_lib.baseboard_fab2(sch_1):\PP4421\" )
				( objectStatus "M_E_DQ<16>" )
			)
			( signal "@baseboard_fab2_lib.baseboard_fab2(sch_1):m_e_dq(17)"
				( pinPairRef "@baseboard_fab2_lib.baseboard_fab2(sch_1):\PP4422\" )
				( pinPairRef "@baseboard_fab2_lib.baseboard_fab2(sch_1):\PP4424\" )
				( attribute "NO_TEST" "1"
					( Origin gBackEnd )
				)
				( objectStatus "M_E_DQ<17>" )
			)
			( signal "@baseboard_fab2_lib.baseboard_fab2(sch_1):m_e_dq(18)"
				( pinPairRef "@baseboard_fab2_lib.baseboard_fab2(sch_1):\PP4425\" )
				( pinPairRef "@baseboard_fab2_lib.baseboard_fab2(sch_1):\PP4427\" )
				( attribute "NO_TEST" "1"
					( Origin gBackEnd )
				)
				( objectStatus "M_E_DQ<18>" )
			)
			( signal "@baseboard_fab2_lib.baseboard_fab2(sch_1):m_e_dq(19)"
				( pinPairRef "@baseboard_fab2_lib.baseboard_fab2(sch_1):\PP4428\" )
				( pinPairRef "@baseboard_fab2_lib.baseboard_fab2(sch_1):\PP4430\" )
				( objectStatus "M_E_DQ<19>" )
			)
			( signal "@baseboard_fab2_lib.baseboard_fab2(sch_1):m_e_dq(20)"
				( pinPairRef "@baseboard_fab2_lib.baseboard_fab2(sch_1):\PP4431\" )
				( pinPairRef "@baseboard_fab2_lib.baseboard_fab2(sch_1):\PP4433\" )
				( attribute "NO_TEST" "1"
					( Origin gBackEnd )
				)
				( objectStatus "M_E_DQ<20>" )
			)
			( signal "@baseboard_fab2_lib.baseboard_fab2(sch_1):m_e_dq(21)"
				( pinPairRef "@baseboard_fab2_lib.baseboard_fab2(sch_1):\PP4434\" )
				( pinPairRef "@baseboard_fab2_lib.baseboard_fab2(sch_1):\PP4436\" )
				( objectStatus "M_E_DQ<21>" )
			)
			( signal "@baseboard_fab2_lib.baseboard_fab2(sch_1):m_e_dq(22)"
				( pinPairRef "@baseboard_fab2_lib.baseboard_fab2(sch_1):\PP4437\" )
				( pinPairRef "@baseboard_fab2_lib.baseboard_fab2(sch_1):\PP4439\" )
				( objectStatus "M_E_DQ<22>" )
			)
			( signal "@baseboard_fab2_lib.baseboard_fab2(sch_1):m_e_dq(23)"
				( pinPairRef "@baseboard_fab2_lib.baseboard_fab2(sch_1):\PP4440\" )
				( pinPairRef "@baseboard_fab2_lib.baseboard_fab2(sch_1):\PP4442\" )
				( attribute "NO_TEST" "1"
					( Origin gBackEnd )
				)
				( objectStatus "M_E_DQ<23>" )
			)
			( signal "@baseboard_fab2_lib.baseboard_fab2(sch_1):m_e_dq(24)"
				( pinPairRef "@baseboard_fab2_lib.baseboard_fab2(sch_1):\PP4299\" )
				( pinPairRef "@baseboard_fab2_lib.baseboard_fab2(sch_1):\PP4301\" )
				( attribute "NO_TEST" "1"
					( Origin gBackEnd )
				)
				( objectStatus "M_E_DQ<24>" )
			)
			( signal "@baseboard_fab2_lib.baseboard_fab2(sch_1):m_e_dq(25)"
				( pinPairRef "@baseboard_fab2_lib.baseboard_fab2(sch_1):\PP4302\" )
				( pinPairRef "@baseboard_fab2_lib.baseboard_fab2(sch_1):\PP4304\" )
				( attribute "NO_TEST" "1"
					( Origin gBackEnd )
				)
				( objectStatus "M_E_DQ<25>" )
			)
			( signal "@baseboard_fab2_lib.baseboard_fab2(sch_1):m_e_dq(26)"
				( pinPairRef "@baseboard_fab2_lib.baseboard_fab2(sch_1):\PP4305\" )
				( pinPairRef "@baseboard_fab2_lib.baseboard_fab2(sch_1):\PP4307\" )
				( attribute "NO_TEST" "1"
					( Origin gBackEnd )
				)
				( objectStatus "M_E_DQ<26>" )
			)
			( signal "@baseboard_fab2_lib.baseboard_fab2(sch_1):m_e_dq(27)"
				( pinPairRef "@baseboard_fab2_lib.baseboard_fab2(sch_1):\PP4308\" )
				( pinPairRef "@baseboard_fab2_lib.baseboard_fab2(sch_1):\PP4310\" )
				( attribute "NO_TEST" "1"
					( Origin gBackEnd )
				)
				( objectStatus "M_E_DQ<27>" )
			)
			( signal "@baseboard_fab2_lib.baseboard_fab2(sch_1):m_e_dq(28)"
				( pinPairRef "@baseboard_fab2_lib.baseboard_fab2(sch_1):\PP4311\" )
				( pinPairRef "@baseboard_fab2_lib.baseboard_fab2(sch_1):\PP4313\" )
				( attribute "NO_TEST" "1"
					( Origin gBackEnd )
				)
				( objectStatus "M_E_DQ<28>" )
			)
			( signal "@baseboard_fab2_lib.baseboard_fab2(sch_1):m_e_dq(29)"
				( pinPairRef "@baseboard_fab2_lib.baseboard_fab2(sch_1):\PP4314\" )
				( pinPairRef "@baseboard_fab2_lib.baseboard_fab2(sch_1):\PP4316\" )
				( attribute "NO_TEST" "1"
					( Origin gBackEnd )
				)
				( objectStatus "M_E_DQ<29>" )
			)
			( signal "@baseboard_fab2_lib.baseboard_fab2(sch_1):m_e_dq(30)"
				( pinPairRef "@baseboard_fab2_lib.baseboard_fab2(sch_1):\PP4317\" )
				( pinPairRef "@baseboard_fab2_lib.baseboard_fab2(sch_1):\PP4319\" )
				( attribute "NO_TEST" "1"
					( Origin gBackEnd )
				)
				( objectStatus "M_E_DQ<30>" )
			)
			( signal "@baseboard_fab2_lib.baseboard_fab2(sch_1):m_e_dq(31)"
				( pinPairRef "@baseboard_fab2_lib.baseboard_fab2(sch_1):\PP4320\" )
				( pinPairRef "@baseboard_fab2_lib.baseboard_fab2(sch_1):\PP4322\" )
				( attribute "NO_TEST" "1"
					( Origin gBackEnd )
				)
				( objectStatus "M_E_DQ<31>" )
			)
			( signal "@baseboard_fab2_lib.baseboard_fab2(sch_1):m_e_dq(32)"
				( pinPairRef "@baseboard_fab2_lib.baseboard_fab2(sch_1):\PP4395\" )
				( pinPairRef "@baseboard_fab2_lib.baseboard_fab2(sch_1):\PP4396\" )
				( attribute "NO_TEST" "1"
					( Origin gBackEnd )
				)
				( objectStatus "M_E_DQ<32>" )
			)
			( signal "@baseboard_fab2_lib.baseboard_fab2(sch_1):m_e_dq(33)"
				( pinPairRef "@baseboard_fab2_lib.baseboard_fab2(sch_1):\PP4398\" )
				( pinPairRef "@baseboard_fab2_lib.baseboard_fab2(sch_1):\PP4399\" )
				( objectStatus "M_E_DQ<33>" )
			)
			( signal "@baseboard_fab2_lib.baseboard_fab2(sch_1):m_e_dq(34)"
				( pinPairRef "@baseboard_fab2_lib.baseboard_fab2(sch_1):\PP4401\" )
				( pinPairRef "@baseboard_fab2_lib.baseboard_fab2(sch_1):\PP4403\" )
				( objectStatus "M_E_DQ<34>" )
			)
			( signal "@baseboard_fab2_lib.baseboard_fab2(sch_1):m_e_dq(35)"
				( pinPairRef "@baseboard_fab2_lib.baseboard_fab2(sch_1):\PP4404\" )
				( pinPairRef "@baseboard_fab2_lib.baseboard_fab2(sch_1):\PP4406\" )
				( attribute "NO_TEST" "1"
					( Origin gBackEnd )
				)
				( objectStatus "M_E_DQ<35>" )
			)
			( signal "@baseboard_fab2_lib.baseboard_fab2(sch_1):m_e_dq(36)"
				( pinPairRef "@baseboard_fab2_lib.baseboard_fab2(sch_1):\PP4407\" )
				( pinPairRef "@baseboard_fab2_lib.baseboard_fab2(sch_1):\PP4408\" )
				( objectStatus "M_E_DQ<36>" )
			)
			( signal "@baseboard_fab2_lib.baseboard_fab2(sch_1):m_e_dq(37)"
				( pinPairRef "@baseboard_fab2_lib.baseboard_fab2(sch_1):\PP4410\" )
				( pinPairRef "@baseboard_fab2_lib.baseboard_fab2(sch_1):\PP4411\" )
				( attribute "NO_TEST" "1"
					( Origin gBackEnd )
				)
				( objectStatus "M_E_DQ<37>" )
			)
			( signal "@baseboard_fab2_lib.baseboard_fab2(sch_1):m_e_dq(38)"
				( pinPairRef "@baseboard_fab2_lib.baseboard_fab2(sch_1):\PP4413\" )
				( pinPairRef "@baseboard_fab2_lib.baseboard_fab2(sch_1):\PP4415\" )
				( attribute "NO_TEST" "1"
					( Origin gBackEnd )
				)
				( objectStatus "M_E_DQ<38>" )
			)
			( signal "@baseboard_fab2_lib.baseboard_fab2(sch_1):m_e_dq(39)"
				( pinPairRef "@baseboard_fab2_lib.baseboard_fab2(sch_1):\PP4416\" )
				( pinPairRef "@baseboard_fab2_lib.baseboard_fab2(sch_1):\PP4418\" )
				( objectStatus "M_E_DQ<39>" )
			)
			( signal "@baseboard_fab2_lib.baseboard_fab2(sch_1):m_e_dq(40)"
				( pinPairRef "@baseboard_fab2_lib.baseboard_fab2(sch_1):\PP4371\" )
				( pinPairRef "@baseboard_fab2_lib.baseboard_fab2(sch_1):\PP4373\" )
				( attribute "NO_TEST" "1"
					( Origin gBackEnd )
				)
				( objectStatus "M_E_DQ<40>" )
			)
			( signal "@baseboard_fab2_lib.baseboard_fab2(sch_1):m_e_dq(41)"
				( pinPairRef "@baseboard_fab2_lib.baseboard_fab2(sch_1):\PP4374\" )
				( pinPairRef "@baseboard_fab2_lib.baseboard_fab2(sch_1):\PP4376\" )
				( attribute "NO_TEST" "1"
					( Origin gBackEnd )
				)
				( objectStatus "M_E_DQ<41>" )
			)
			( signal "@baseboard_fab2_lib.baseboard_fab2(sch_1):m_e_dq(42)"
				( pinPairRef "@baseboard_fab2_lib.baseboard_fab2(sch_1):\PP4377\" )
				( pinPairRef "@baseboard_fab2_lib.baseboard_fab2(sch_1):\PP4379\" )
				( attribute "NO_TEST" "1"
					( Origin gBackEnd )
				)
				( objectStatus "M_E_DQ<42>" )
			)
			( signal "@baseboard_fab2_lib.baseboard_fab2(sch_1):m_e_dq(43)"
				( pinPairRef "@baseboard_fab2_lib.baseboard_fab2(sch_1):\PP4380\" )
				( pinPairRef "@baseboard_fab2_lib.baseboard_fab2(sch_1):\PP4382\" )
				( attribute "NO_TEST" "1"
					( Origin gBackEnd )
				)
				( objectStatus "M_E_DQ<43>" )
			)
			( signal "@baseboard_fab2_lib.baseboard_fab2(sch_1):m_e_dq(44)"
				( pinPairRef "@baseboard_fab2_lib.baseboard_fab2(sch_1):\PP4383\" )
				( pinPairRef "@baseboard_fab2_lib.baseboard_fab2(sch_1):\PP4385\" )
				( attribute "NO_TEST" "1"
					( Origin gBackEnd )
				)
				( objectStatus "M_E_DQ<44>" )
			)
			( signal "@baseboard_fab2_lib.baseboard_fab2(sch_1):m_e_dq(45)"
				( pinPairRef "@baseboard_fab2_lib.baseboard_fab2(sch_1):\PP4386\" )
				( pinPairRef "@baseboard_fab2_lib.baseboard_fab2(sch_1):\PP4388\" )
				( attribute "NO_TEST" "1"
					( Origin gBackEnd )
				)
				( objectStatus "M_E_DQ<45>" )
			)
			( signal "@baseboard_fab2_lib.baseboard_fab2(sch_1):m_e_dq(46)"
				( pinPairRef "@baseboard_fab2_lib.baseboard_fab2(sch_1):\PP4389\" )
				( pinPairRef "@baseboard_fab2_lib.baseboard_fab2(sch_1):\PP4391\" )
				( attribute "NO_TEST" "1"
					( Origin gBackEnd )
				)
				( objectStatus "M_E_DQ<46>" )
			)
			( signal "@baseboard_fab2_lib.baseboard_fab2(sch_1):m_e_dq(47)"
				( pinPairRef "@baseboard_fab2_lib.baseboard_fab2(sch_1):\PP4392\" )
				( pinPairRef "@baseboard_fab2_lib.baseboard_fab2(sch_1):\PP4394\" )
				( attribute "NO_TEST" "1"
					( Origin gBackEnd )
				)
				( objectStatus "M_E_DQ<47>" )
			)
			( signal "@baseboard_fab2_lib.baseboard_fab2(sch_1):m_e_dq(48)"
				( pinPairRef "@baseboard_fab2_lib.baseboard_fab2(sch_1):\PP4347\" )
				( pinPairRef "@baseboard_fab2_lib.baseboard_fab2(sch_1):\PP4349\" )
				( attribute "NO_TEST" "1"
					( Origin gBackEnd )
				)
				( objectStatus "M_E_DQ<48>" )
			)
			( signal "@baseboard_fab2_lib.baseboard_fab2(sch_1):m_e_dq(49)"
				( pinPairRef "@baseboard_fab2_lib.baseboard_fab2(sch_1):\PP4350\" )
				( pinPairRef "@baseboard_fab2_lib.baseboard_fab2(sch_1):\PP4352\" )
				( attribute "NO_TEST" "1"
					( Origin gBackEnd )
				)
				( objectStatus "M_E_DQ<49>" )
			)
			( signal "@baseboard_fab2_lib.baseboard_fab2(sch_1):m_e_dq(50)"
				( pinPairRef "@baseboard_fab2_lib.baseboard_fab2(sch_1):\PP4353\" )
				( pinPairRef "@baseboard_fab2_lib.baseboard_fab2(sch_1):\PP4355\" )
				( attribute "NO_TEST" "1"
					( Origin gBackEnd )
				)
				( objectStatus "M_E_DQ<50>" )
			)
			( signal "@baseboard_fab2_lib.baseboard_fab2(sch_1):m_e_dq(51)"
				( pinPairRef "@baseboard_fab2_lib.baseboard_fab2(sch_1):\PP4356\" )
				( pinPairRef "@baseboard_fab2_lib.baseboard_fab2(sch_1):\PP4358\" )
				( attribute "NO_TEST" "1"
					( Origin gBackEnd )
				)
				( objectStatus "M_E_DQ<51>" )
			)
			( signal "@baseboard_fab2_lib.baseboard_fab2(sch_1):m_e_dq(52)"
				( pinPairRef "@baseboard_fab2_lib.baseboard_fab2(sch_1):\PP4359\" )
				( pinPairRef "@baseboard_fab2_lib.baseboard_fab2(sch_1):\PP4361\" )
				( attribute "NO_TEST" "1"
					( Origin gBackEnd )
				)
				( objectStatus "M_E_DQ<52>" )
			)
			( signal "@baseboard_fab2_lib.baseboard_fab2(sch_1):m_e_dq(53)"
				( pinPairRef "@baseboard_fab2_lib.baseboard_fab2(sch_1):\PP4362\" )
				( pinPairRef "@baseboard_fab2_lib.baseboard_fab2(sch_1):\PP4364\" )
				( attribute "NO_TEST" "1"
					( Origin gBackEnd )
				)
				( objectStatus "M_E_DQ<53>" )
			)
			( signal "@baseboard_fab2_lib.baseboard_fab2(sch_1):m_e_dq(54)"
				( pinPairRef "@baseboard_fab2_lib.baseboard_fab2(sch_1):\PP4365\" )
				( pinPairRef "@baseboard_fab2_lib.baseboard_fab2(sch_1):\PP4367\" )
				( attribute "NO_TEST" "1"
					( Origin gBackEnd )
				)
				( objectStatus "M_E_DQ<54>" )
			)
			( signal "@baseboard_fab2_lib.baseboard_fab2(sch_1):m_e_dq(55)"
				( pinPairRef "@baseboard_fab2_lib.baseboard_fab2(sch_1):\PP4368\" )
				( pinPairRef "@baseboard_fab2_lib.baseboard_fab2(sch_1):\PP4370\" )
				( attribute "NO_TEST" "1"
					( Origin gBackEnd )
				)
				( objectStatus "M_E_DQ<55>" )
			)
			( signal "@baseboard_fab2_lib.baseboard_fab2(sch_1):m_e_dq(56)"
				( pinPairRef "@baseboard_fab2_lib.baseboard_fab2(sch_1):\PP4323\" )
				( pinPairRef "@baseboard_fab2_lib.baseboard_fab2(sch_1):\PP4325\" )
				( objectStatus "M_E_DQ<56>" )
			)
			( signal "@baseboard_fab2_lib.baseboard_fab2(sch_1):m_e_dq(57)"
				( pinPairRef "@baseboard_fab2_lib.baseboard_fab2(sch_1):\PP4326\" )
				( pinPairRef "@baseboard_fab2_lib.baseboard_fab2(sch_1):\PP4328\" )
				( attribute "NO_TEST" "1"
					( Origin gBackEnd )
				)
				( objectStatus "M_E_DQ<57>" )
			)
			( signal "@baseboard_fab2_lib.baseboard_fab2(sch_1):m_e_dq(58)"
				( pinPairRef "@baseboard_fab2_lib.baseboard_fab2(sch_1):\PP4329\" )
				( pinPairRef "@baseboard_fab2_lib.baseboard_fab2(sch_1):\PP4331\" )
				( objectStatus "M_E_DQ<58>" )
			)
			( signal "@baseboard_fab2_lib.baseboard_fab2(sch_1):m_e_dq(59)"
				( pinPairRef "@baseboard_fab2_lib.baseboard_fab2(sch_1):\PP4332\" )
				( pinPairRef "@baseboard_fab2_lib.baseboard_fab2(sch_1):\PP4334\" )
				( objectStatus "M_E_DQ<59>" )
			)
			( signal "@baseboard_fab2_lib.baseboard_fab2(sch_1):m_e_dq(60)"
				( pinPairRef "@baseboard_fab2_lib.baseboard_fab2(sch_1):\PP4335\" )
				( pinPairRef "@baseboard_fab2_lib.baseboard_fab2(sch_1):\PP4337\" )
				( attribute "NO_TEST" "1"
					( Origin gBackEnd )
				)
				( objectStatus "M_E_DQ<60>" )
			)
			( signal "@baseboard_fab2_lib.baseboard_fab2(sch_1):m_e_dq(61)"
				( pinPairRef "@baseboard_fab2_lib.baseboard_fab2(sch_1):\PP4338\" )
				( pinPairRef "@baseboard_fab2_lib.baseboard_fab2(sch_1):\PP4340\" )
				( objectStatus "M_E_DQ<61>" )
			)
			( signal "@baseboard_fab2_lib.baseboard_fab2(sch_1):m_e_dq(62)"
				( pinPairRef "@baseboard_fab2_lib.baseboard_fab2(sch_1):\PP4341\" )
				( pinPairRef "@baseboard_fab2_lib.baseboard_fab2(sch_1):\PP4343\" )
				( attribute "NO_TEST" "1"
					( Origin gBackEnd )
				)
				( objectStatus "M_E_DQ<62>" )
			)
			( signal "@baseboard_fab2_lib.baseboard_fab2(sch_1):m_e_dq(63)"
				( pinPairRef "@baseboard_fab2_lib.baseboard_fab2(sch_1):\PP4344\" )
				( pinPairRef "@baseboard_fab2_lib.baseboard_fab2(sch_1):\PP4346\" )
				( attribute "NO_TEST" "1"
					( Origin gBackEnd )
				)
				( objectStatus "M_E_DQ<63>" )
			)
			( signal "@baseboard_fab2_lib.baseboard_fab2(sch_1):m_f_dq(0)"
				( pinPairRef "@baseboard_fab2_lib.baseboard_fab2(sch_1):\PP4251\" )
				( pinPairRef "@baseboard_fab2_lib.baseboard_fab2(sch_1):\PP4253\" )
				( attribute "NO_TEST" "1"
					( Origin gBackEnd )
				)
				( objectStatus "M_F_DQ<0>" )
			)
			( signal "@baseboard_fab2_lib.baseboard_fab2(sch_1):m_f_dq(1)"
				( pinPairRef "@baseboard_fab2_lib.baseboard_fab2(sch_1):\PP4254\" )
				( pinPairRef "@baseboard_fab2_lib.baseboard_fab2(sch_1):\PP4256\" )
				( objectStatus "M_F_DQ<1>" )
			)
			( signal "@baseboard_fab2_lib.baseboard_fab2(sch_1):m_f_dq(2)"
				( pinPairRef "@baseboard_fab2_lib.baseboard_fab2(sch_1):\PP4257\" )
				( pinPairRef "@baseboard_fab2_lib.baseboard_fab2(sch_1):\PP4259\" )
				( objectStatus "M_F_DQ<2>" )
			)
			( signal "@baseboard_fab2_lib.baseboard_fab2(sch_1):m_f_dq(3)"
				( pinPairRef "@baseboard_fab2_lib.baseboard_fab2(sch_1):\PP4260\" )
				( pinPairRef "@baseboard_fab2_lib.baseboard_fab2(sch_1):\PP4262\" )
				( attribute "NO_TEST" "1"
					( Origin gBackEnd )
				)
				( objectStatus "M_F_DQ<3>" )
			)
			( signal "@baseboard_fab2_lib.baseboard_fab2(sch_1):m_f_dq(4)"
				( pinPairRef "@baseboard_fab2_lib.baseboard_fab2(sch_1):\PP4263\" )
				( pinPairRef "@baseboard_fab2_lib.baseboard_fab2(sch_1):\PP4265\" )
				( objectStatus "M_F_DQ<4>" )
			)
			( signal "@baseboard_fab2_lib.baseboard_fab2(sch_1):m_f_dq(5)"
				( pinPairRef "@baseboard_fab2_lib.baseboard_fab2(sch_1):\PP4266\" )
				( pinPairRef "@baseboard_fab2_lib.baseboard_fab2(sch_1):\PP4268\" )
				( attribute "NO_TEST" "1"
					( Origin gBackEnd )
				)
				( objectStatus "M_F_DQ<5>" )
			)
			( signal "@baseboard_fab2_lib.baseboard_fab2(sch_1):m_f_dq(6)"
				( pinPairRef "@baseboard_fab2_lib.baseboard_fab2(sch_1):\PP4269\" )
				( pinPairRef "@baseboard_fab2_lib.baseboard_fab2(sch_1):\PP4271\" )
				( attribute "NO_TEST" "1"
					( Origin gBackEnd )
				)
				( objectStatus "M_F_DQ<6>" )
			)
			( signal "@baseboard_fab2_lib.baseboard_fab2(sch_1):m_f_dq(7)"
				( pinPairRef "@baseboard_fab2_lib.baseboard_fab2(sch_1):\PP4272\" )
				( pinPairRef "@baseboard_fab2_lib.baseboard_fab2(sch_1):\PP4274\" )
				( objectStatus "M_F_DQ<7>" )
			)
			( signal "@baseboard_fab2_lib.baseboard_fab2(sch_1):m_f_dq(8)"
				( pinPairRef "@baseboard_fab2_lib.baseboard_fab2(sch_1):\PP4227\" )
				( pinPairRef "@baseboard_fab2_lib.baseboard_fab2(sch_1):\PP4229\" )
				( objectStatus "M_F_DQ<8>" )
			)
			( signal "@baseboard_fab2_lib.baseboard_fab2(sch_1):m_c_dq(1)"
				( pinPairRef "@baseboard_fab2_lib.baseboard_fab2(sch_1):\PP4878\" )
				( pinPairRef "@baseboard_fab2_lib.baseboard_fab2(sch_1):\PP4880\" )
				( objectStatus "M_C_DQ<1>" )
			)
			( signal "@baseboard_fab2_lib.baseboard_fab2(sch_1):m_c_dq(2)"
				( pinPairRef "@baseboard_fab2_lib.baseboard_fab2(sch_1):\PP4881\" )
				( pinPairRef "@baseboard_fab2_lib.baseboard_fab2(sch_1):\PP4883\" )
				( objectStatus "M_C_DQ<2>" )
			)
			( signal "@baseboard_fab2_lib.baseboard_fab2(sch_1):m_c_dq(3)"
				( pinPairRef "@baseboard_fab2_lib.baseboard_fab2(sch_1):\PP4884\" )
				( pinPairRef "@baseboard_fab2_lib.baseboard_fab2(sch_1):\PP4886\" )
				( attribute "NO_TEST" "1"
					( Origin gBackEnd )
				)
				( objectStatus "M_C_DQ<3>" )
			)
			( signal "@baseboard_fab2_lib.baseboard_fab2(sch_1):m_c_dq(4)"
				( pinPairRef "@baseboard_fab2_lib.baseboard_fab2(sch_1):\PP4887\" )
				( pinPairRef "@baseboard_fab2_lib.baseboard_fab2(sch_1):\PP4889\" )
				( objectStatus "M_C_DQ<4>" )
			)
			( signal "@baseboard_fab2_lib.baseboard_fab2(sch_1):m_c_dq(5)"
				( pinPairRef "@baseboard_fab2_lib.baseboard_fab2(sch_1):\PP4890\" )
				( pinPairRef "@baseboard_fab2_lib.baseboard_fab2(sch_1):\PP4892\" )
				( attribute "NO_TEST" "1"
					( Origin gBackEnd )
				)
				( objectStatus "M_C_DQ<5>" )
			)
			( signal "@baseboard_fab2_lib.baseboard_fab2(sch_1):m_c_dq(6)"
				( pinPairRef "@baseboard_fab2_lib.baseboard_fab2(sch_1):\PP4893\" )
				( pinPairRef "@baseboard_fab2_lib.baseboard_fab2(sch_1):\PP4895\" )
				( attribute "NO_TEST" "1"
					( Origin gBackEnd )
				)
				( objectStatus "M_C_DQ<6>" )
			)
			( signal "@baseboard_fab2_lib.baseboard_fab2(sch_1):m_c_dq(7)"
				( pinPairRef "@baseboard_fab2_lib.baseboard_fab2(sch_1):\PP4896\" )
				( pinPairRef "@baseboard_fab2_lib.baseboard_fab2(sch_1):\PP4898\" )
				( objectStatus "M_C_DQ<7>" )
			)
			( signal "@baseboard_fab2_lib.baseboard_fab2(sch_1):m_c_dq(8)"
				( pinPairRef "@baseboard_fab2_lib.baseboard_fab2(sch_1):\PP4851\" )
				( pinPairRef "@baseboard_fab2_lib.baseboard_fab2(sch_1):\PP4853\" )
				( attribute "NO_TEST" "1"
					( Origin gBackEnd )
				)
				( objectStatus "M_C_DQ<8>" )
			)
			( signal "@baseboard_fab2_lib.baseboard_fab2(sch_1):m_c_dq(9)"
				( pinPairRef "@baseboard_fab2_lib.baseboard_fab2(sch_1):\PP4854\" )
				( pinPairRef "@baseboard_fab2_lib.baseboard_fab2(sch_1):\PP4856\" )
				( objectStatus "M_C_DQ<9>" )
			)
			( signal "@baseboard_fab2_lib.baseboard_fab2(sch_1):m_c_dq(10)"
				( pinPairRef "@baseboard_fab2_lib.baseboard_fab2(sch_1):\PP4857\" )
				( pinPairRef "@baseboard_fab2_lib.baseboard_fab2(sch_1):\PP4859\" )
				( objectStatus "M_C_DQ<10>" )
			)
			( signal "@baseboard_fab2_lib.baseboard_fab2(sch_1):m_c_dq(11)"
				( pinPairRef "@baseboard_fab2_lib.baseboard_fab2(sch_1):\PP4860\" )
				( pinPairRef "@baseboard_fab2_lib.baseboard_fab2(sch_1):\PP4862\" )
				( attribute "NO_TEST" "1"
					( Origin gBackEnd )
				)
				( objectStatus "M_C_DQ<11>" )
			)
			( signal "@baseboard_fab2_lib.baseboard_fab2(sch_1):m_c_dq(12)"
				( pinPairRef "@baseboard_fab2_lib.baseboard_fab2(sch_1):\PP4863\" )
				( pinPairRef "@baseboard_fab2_lib.baseboard_fab2(sch_1):\PP4865\" )
				( objectStatus "M_C_DQ<12>" )
			)
			( signal "@baseboard_fab2_lib.baseboard_fab2(sch_1):m_c_dq(13)"
				( pinPairRef "@baseboard_fab2_lib.baseboard_fab2(sch_1):\PP4866\" )
				( pinPairRef "@baseboard_fab2_lib.baseboard_fab2(sch_1):\PP4868\" )
				( attribute "NO_TEST" "1"
					( Origin gBackEnd )
				)
				( objectStatus "M_C_DQ<13>" )
			)
			( signal "@baseboard_fab2_lib.baseboard_fab2(sch_1):m_c_dq(14)"
				( pinPairRef "@baseboard_fab2_lib.baseboard_fab2(sch_1):\PP4869\" )
				( pinPairRef "@baseboard_fab2_lib.baseboard_fab2(sch_1):\PP4871\" )
				( attribute "NO_TEST" "1"
					( Origin gBackEnd )
				)
				( objectStatus "M_C_DQ<14>" )
			)
			( signal "@baseboard_fab2_lib.baseboard_fab2(sch_1):m_c_dq(15)"
				( pinPairRef "@baseboard_fab2_lib.baseboard_fab2(sch_1):\PP4872\" )
				( pinPairRef "@baseboard_fab2_lib.baseboard_fab2(sch_1):\PP4874\" )
				( objectStatus "M_C_DQ<15>" )
			)
			( signal "@baseboard_fab2_lib.baseboard_fab2(sch_1):m_c_dq(16)"
				( pinPairRef "@baseboard_fab2_lib.baseboard_fab2(sch_1):\PP4827\" )
				( pinPairRef "@baseboard_fab2_lib.baseboard_fab2(sch_1):\PP4829\" )
				( attribute "NO_TEST" "1"
					( Origin gBackEnd )
				)
				( objectStatus "M_C_DQ<16>" )
			)
			( signal "@baseboard_fab2_lib.baseboard_fab2(sch_1):m_c_dq(17)"
				( pinPairRef "@baseboard_fab2_lib.baseboard_fab2(sch_1):\PP4830\" )
				( pinPairRef "@baseboard_fab2_lib.baseboard_fab2(sch_1):\PP4832\" )
				( objectStatus "M_C_DQ<17>" )
			)
			( signal "@baseboard_fab2_lib.baseboard_fab2(sch_1):m_c_dq(18)"
				( pinPairRef "@baseboard_fab2_lib.baseboard_fab2(sch_1):\PP4833\" )
				( pinPairRef "@baseboard_fab2_lib.baseboard_fab2(sch_1):\PP4835\" )
				( objectStatus "M_C_DQ<18>" )
			)
			( signal "@baseboard_fab2_lib.baseboard_fab2(sch_1):m_c_dq(19)"
				( pinPairRef "@baseboard_fab2_lib.baseboard_fab2(sch_1):\PP4836\" )
				( pinPairRef "@baseboard_fab2_lib.baseboard_fab2(sch_1):\PP4838\" )
				( attribute "NO_TEST" "1"
					( Origin gBackEnd )
				)
				( objectStatus "M_C_DQ<19>" )
			)
			( signal "@baseboard_fab2_lib.baseboard_fab2(sch_1):m_c_dq(20)"
				( pinPairRef "@baseboard_fab2_lib.baseboard_fab2(sch_1):\PP4839\" )
				( pinPairRef "@baseboard_fab2_lib.baseboard_fab2(sch_1):\PP4841\" )
				( objectStatus "M_C_DQ<20>" )
			)
			( signal "@baseboard_fab2_lib.baseboard_fab2(sch_1):m_c_dq(21)"
				( pinPairRef "@baseboard_fab2_lib.baseboard_fab2(sch_1):\PP4842\" )
				( pinPairRef "@baseboard_fab2_lib.baseboard_fab2(sch_1):\PP4844\" )
				( attribute "NO_TEST" "1"
					( Origin gBackEnd )
				)
				( objectStatus "M_C_DQ<21>" )
			)
			( signal "@baseboard_fab2_lib.baseboard_fab2(sch_1):m_c_dq(22)"
				( pinPairRef "@baseboard_fab2_lib.baseboard_fab2(sch_1):\PP4845\" )
				( pinPairRef "@baseboard_fab2_lib.baseboard_fab2(sch_1):\PP4847\" )
				( attribute "NO_TEST" "1"
					( Origin gBackEnd )
				)
				( objectStatus "M_C_DQ<22>" )
			)
			( signal "@baseboard_fab2_lib.baseboard_fab2(sch_1):m_c_dq(23)"
				( pinPairRef "@baseboard_fab2_lib.baseboard_fab2(sch_1):\PP4848\" )
				( pinPairRef "@baseboard_fab2_lib.baseboard_fab2(sch_1):\PP4850\" )
				( objectStatus "M_C_DQ<23>" )
			)
			( signal "@baseboard_fab2_lib.baseboard_fab2(sch_1):m_c_dq(24)"
				( pinPairRef "@baseboard_fab2_lib.baseboard_fab2(sch_1):\PP4803\" )
				( pinPairRef "@baseboard_fab2_lib.baseboard_fab2(sch_1):\PP4805\" )
				( attribute "NO_TEST" "1"
					( Origin gBackEnd )
				)
				( objectStatus "M_C_DQ<24>" )
			)
			( signal "@baseboard_fab2_lib.baseboard_fab2(sch_1):m_c_dq(25)"
				( pinPairRef "@baseboard_fab2_lib.baseboard_fab2(sch_1):\PP4806\" )
				( pinPairRef "@baseboard_fab2_lib.baseboard_fab2(sch_1):\PP4808\" )
				( objectStatus "M_C_DQ<25>" )
			)
			( signal "@baseboard_fab2_lib.baseboard_fab2(sch_1):m_c_dq(26)"
				( pinPairRef "@baseboard_fab2_lib.baseboard_fab2(sch_1):\PP4809\" )
				( pinPairRef "@baseboard_fab2_lib.baseboard_fab2(sch_1):\PP4811\" )
				( objectStatus "M_C_DQ<26>" )
			)
			( signal "@baseboard_fab2_lib.baseboard_fab2(sch_1):m_c_dq(27)"
				( pinPairRef "@baseboard_fab2_lib.baseboard_fab2(sch_1):\PP4812\" )
				( pinPairRef "@baseboard_fab2_lib.baseboard_fab2(sch_1):\PP4814\" )
				( attribute "NO_TEST" "1"
					( Origin gBackEnd )
				)
				( objectStatus "M_C_DQ<27>" )
			)
			( signal "@baseboard_fab2_lib.baseboard_fab2(sch_1):m_c_dq(28)"
				( pinPairRef "@baseboard_fab2_lib.baseboard_fab2(sch_1):\PP4815\" )
				( pinPairRef "@baseboard_fab2_lib.baseboard_fab2(sch_1):\PP4817\" )
				( objectStatus "M_C_DQ<28>" )
			)
			( signal "@baseboard_fab2_lib.baseboard_fab2(sch_1):m_c_dq(29)"
				( pinPairRef "@baseboard_fab2_lib.baseboard_fab2(sch_1):\PP4818\" )
				( pinPairRef "@baseboard_fab2_lib.baseboard_fab2(sch_1):\PP4820\" )
				( attribute "NO_TEST" "1"
					( Origin gBackEnd )
				)
				( objectStatus "M_C_DQ<29>" )
			)
			( signal "@baseboard_fab2_lib.baseboard_fab2(sch_1):m_c_dq(30)"
				( pinPairRef "@baseboard_fab2_lib.baseboard_fab2(sch_1):\PP4821\" )
				( pinPairRef "@baseboard_fab2_lib.baseboard_fab2(sch_1):\PP4823\" )
				( attribute "NO_TEST" "1"
					( Origin gBackEnd )
				)
				( objectStatus "M_C_DQ<30>" )
			)
			( signal "@baseboard_fab2_lib.baseboard_fab2(sch_1):m_c_dq(31)"
				( pinPairRef "@baseboard_fab2_lib.baseboard_fab2(sch_1):\PP4824\" )
				( pinPairRef "@baseboard_fab2_lib.baseboard_fab2(sch_1):\PP4826\" )
				( objectStatus "M_C_DQ<31>" )
			)
			( signal "@baseboard_fab2_lib.baseboard_fab2(sch_1):m_c_dq(32)"
				( pinPairRef "@baseboard_fab2_lib.baseboard_fab2(sch_1):\PP4779\" )
				( pinPairRef "@baseboard_fab2_lib.baseboard_fab2(sch_1):\PP4781\" )
				( attribute "NO_TEST" "1"
					( Origin gBackEnd )
				)
				( objectStatus "M_C_DQ<32>" )
			)
			( signal "@baseboard_fab2_lib.baseboard_fab2(sch_1):m_c_dq(33)"
				( pinPairRef "@baseboard_fab2_lib.baseboard_fab2(sch_1):\PP4782\" )
				( pinPairRef "@baseboard_fab2_lib.baseboard_fab2(sch_1):\PP4784\" )
				( objectStatus "M_C_DQ<33>" )
			)
			( signal "@baseboard_fab2_lib.baseboard_fab2(sch_1):m_c_dq(34)"
				( pinPairRef "@baseboard_fab2_lib.baseboard_fab2(sch_1):\PP4785\" )
				( pinPairRef "@baseboard_fab2_lib.baseboard_fab2(sch_1):\PP4787\" )
				( objectStatus "M_C_DQ<34>" )
			)
			( signal "@baseboard_fab2_lib.baseboard_fab2(sch_1):m_c_dq(35)"
				( pinPairRef "@baseboard_fab2_lib.baseboard_fab2(sch_1):\PP4788\" )
				( pinPairRef "@baseboard_fab2_lib.baseboard_fab2(sch_1):\PP4790\" )
				( attribute "NO_TEST" "1"
					( Origin gBackEnd )
				)
				( objectStatus "M_C_DQ<35>" )
			)
			( signal "@baseboard_fab2_lib.baseboard_fab2(sch_1):m_c_dq(36)"
				( pinPairRef "@baseboard_fab2_lib.baseboard_fab2(sch_1):\PP4791\" )
				( pinPairRef "@baseboard_fab2_lib.baseboard_fab2(sch_1):\PP4793\" )
				( objectStatus "M_C_DQ<36>" )
			)
			( signal "@baseboard_fab2_lib.baseboard_fab2(sch_1):m_c_dq(37)"
				( pinPairRef "@baseboard_fab2_lib.baseboard_fab2(sch_1):\PP4794\" )
				( pinPairRef "@baseboard_fab2_lib.baseboard_fab2(sch_1):\PP4796\" )
				( attribute "NO_TEST" "1"
					( Origin gBackEnd )
				)
				( objectStatus "M_C_DQ<37>" )
			)
			( signal "@baseboard_fab2_lib.baseboard_fab2(sch_1):m_c_dq(38)"
				( pinPairRef "@baseboard_fab2_lib.baseboard_fab2(sch_1):\PP4797\" )
				( pinPairRef "@baseboard_fab2_lib.baseboard_fab2(sch_1):\PP4799\" )
				( attribute "NO_TEST" "1"
					( Origin gBackEnd )
				)
				( objectStatus "M_C_DQ<38>" )
			)
			( signal "@baseboard_fab2_lib.baseboard_fab2(sch_1):m_c_dq(39)"
				( pinPairRef "@baseboard_fab2_lib.baseboard_fab2(sch_1):\PP4800\" )
				( pinPairRef "@baseboard_fab2_lib.baseboard_fab2(sch_1):\PP4802\" )
				( objectStatus "M_C_DQ<39>" )
			)
			( signal "@baseboard_fab2_lib.baseboard_fab2(sch_1):m_c_dq(40)"
				( pinPairRef "@baseboard_fab2_lib.baseboard_fab2(sch_1):\PP4755\" )
				( pinPairRef "@baseboard_fab2_lib.baseboard_fab2(sch_1):\PP4757\" )
				( attribute "NO_TEST" "1"
					( Origin gBackEnd )
				)
				( objectStatus "M_C_DQ<40>" )
			)
			( signal "@baseboard_fab2_lib.baseboard_fab2(sch_1):m_c_dq(41)"
				( pinPairRef "@baseboard_fab2_lib.baseboard_fab2(sch_1):\PP4758\" )
				( pinPairRef "@baseboard_fab2_lib.baseboard_fab2(sch_1):\PP4760\" )
				( objectStatus "M_C_DQ<41>" )
			)
			( signal "@baseboard_fab2_lib.baseboard_fab2(sch_1):m_c_dq(42)"
				( pinPairRef "@baseboard_fab2_lib.baseboard_fab2(sch_1):\PP4761\" )
				( pinPairRef "@baseboard_fab2_lib.baseboard_fab2(sch_1):\PP4763\" )
				( objectStatus "M_C_DQ<42>" )
			)
			( signal "@baseboard_fab2_lib.baseboard_fab2(sch_1):m_c_dq(43)"
				( pinPairRef "@baseboard_fab2_lib.baseboard_fab2(sch_1):\PP4764\" )
				( pinPairRef "@baseboard_fab2_lib.baseboard_fab2(sch_1):\PP4766\" )
				( attribute "NO_TEST" "1"
					( Origin gBackEnd )
				)
				( objectStatus "M_C_DQ<43>" )
			)
			( signal "@baseboard_fab2_lib.baseboard_fab2(sch_1):m_c_dq(44)"
				( pinPairRef "@baseboard_fab2_lib.baseboard_fab2(sch_1):\PP4767\" )
				( pinPairRef "@baseboard_fab2_lib.baseboard_fab2(sch_1):\PP4769\" )
				( objectStatus "M_C_DQ<44>" )
			)
			( signal "@baseboard_fab2_lib.baseboard_fab2(sch_1):m_c_dq(45)"
				( pinPairRef "@baseboard_fab2_lib.baseboard_fab2(sch_1):\PP4770\" )
				( pinPairRef "@baseboard_fab2_lib.baseboard_fab2(sch_1):\PP4772\" )
				( attribute "NO_TEST" "1"
					( Origin gBackEnd )
				)
				( objectStatus "M_C_DQ<45>" )
			)
			( signal "@baseboard_fab2_lib.baseboard_fab2(sch_1):m_c_dq(46)"
				( pinPairRef "@baseboard_fab2_lib.baseboard_fab2(sch_1):\PP4773\" )
				( pinPairRef "@baseboard_fab2_lib.baseboard_fab2(sch_1):\PP4775\" )
				( attribute "NO_TEST" "1"
					( Origin gBackEnd )
				)
				( objectStatus "M_C_DQ<46>" )
			)
			( signal "@baseboard_fab2_lib.baseboard_fab2(sch_1):m_c_dq(47)"
				( pinPairRef "@baseboard_fab2_lib.baseboard_fab2(sch_1):\PP4776\" )
				( pinPairRef "@baseboard_fab2_lib.baseboard_fab2(sch_1):\PP4778\" )
				( objectStatus "M_C_DQ<47>" )
			)
			( signal "@baseboard_fab2_lib.baseboard_fab2(sch_1):m_c_dq(48)"
				( pinPairRef "@baseboard_fab2_lib.baseboard_fab2(sch_1):\PP4731\" )
				( pinPairRef "@baseboard_fab2_lib.baseboard_fab2(sch_1):\PP4733\" )
				( attribute "NO_TEST" "1"
					( Origin gBackEnd )
				)
				( objectStatus "M_C_DQ<48>" )
			)
			( signal "@baseboard_fab2_lib.baseboard_fab2(sch_1):m_c_dq(49)"
				( pinPairRef "@baseboard_fab2_lib.baseboard_fab2(sch_1):\PP4734\" )
				( pinPairRef "@baseboard_fab2_lib.baseboard_fab2(sch_1):\PP4736\" )
				( objectStatus "M_C_DQ<49>" )
			)
			( signal "@baseboard_fab2_lib.baseboard_fab2(sch_1):m_c_dq(50)"
				( pinPairRef "@baseboard_fab2_lib.baseboard_fab2(sch_1):\PP4737\" )
				( pinPairRef "@baseboard_fab2_lib.baseboard_fab2(sch_1):\PP4739\" )
				( objectStatus "M_C_DQ<50>" )
			)
			( signal "@baseboard_fab2_lib.baseboard_fab2(sch_1):m_c_dq(51)"
				( pinPairRef "@baseboard_fab2_lib.baseboard_fab2(sch_1):\PP4740\" )
				( pinPairRef "@baseboard_fab2_lib.baseboard_fab2(sch_1):\PP4742\" )
				( attribute "NO_TEST" "1"
					( Origin gBackEnd )
				)
				( objectStatus "M_C_DQ<51>" )
			)
			( signal "@baseboard_fab2_lib.baseboard_fab2(sch_1):m_c_dq(52)"
				( pinPairRef "@baseboard_fab2_lib.baseboard_fab2(sch_1):\PP4743\" )
				( pinPairRef "@baseboard_fab2_lib.baseboard_fab2(sch_1):\PP4745\" )
				( objectStatus "M_C_DQ<52>" )
			)
			( signal "@baseboard_fab2_lib.baseboard_fab2(sch_1):m_c_dq(53)"
				( pinPairRef "@baseboard_fab2_lib.baseboard_fab2(sch_1):\PP4746\" )
				( pinPairRef "@baseboard_fab2_lib.baseboard_fab2(sch_1):\PP4748\" )
				( attribute "NO_TEST" "1"
					( Origin gBackEnd )
				)
				( objectStatus "M_C_DQ<53>" )
			)
			( signal "@baseboard_fab2_lib.baseboard_fab2(sch_1):m_c_dq(54)"
				( pinPairRef "@baseboard_fab2_lib.baseboard_fab2(sch_1):\PP4749\" )
				( pinPairRef "@baseboard_fab2_lib.baseboard_fab2(sch_1):\PP4751\" )
				( attribute "NO_TEST" "1"
					( Origin gBackEnd )
				)
				( objectStatus "M_C_DQ<54>" )
			)
			( signal "@baseboard_fab2_lib.baseboard_fab2(sch_1):m_c_dq(55)"
				( pinPairRef "@baseboard_fab2_lib.baseboard_fab2(sch_1):\PP4752\" )
				( pinPairRef "@baseboard_fab2_lib.baseboard_fab2(sch_1):\PP4754\" )
				( objectStatus "M_C_DQ<55>" )
			)
			( signal "@baseboard_fab2_lib.baseboard_fab2(sch_1):m_c_dq(56)"
				( pinPairRef "@baseboard_fab2_lib.baseboard_fab2(sch_1):\PP4707\" )
				( pinPairRef "@baseboard_fab2_lib.baseboard_fab2(sch_1):\PP4709\" )
				( objectStatus "M_C_DQ<56>" )
			)
			( signal "@baseboard_fab2_lib.baseboard_fab2(sch_1):m_c_dq(57)"
				( pinPairRef "@baseboard_fab2_lib.baseboard_fab2(sch_1):\PP4710\" )
				( pinPairRef "@baseboard_fab2_lib.baseboard_fab2(sch_1):\PP4712\" )
				( attribute "NO_TEST" "1"
					( Origin gBackEnd )
				)
				( objectStatus "M_C_DQ<57>" )
			)
			( signal "@baseboard_fab2_lib.baseboard_fab2(sch_1):m_c_dq(58)"
				( pinPairRef "@baseboard_fab2_lib.baseboard_fab2(sch_1):\PP4713\" )
				( pinPairRef "@baseboard_fab2_lib.baseboard_fab2(sch_1):\PP4715\" )
				( attribute "NO_TEST" "1"
					( Origin gBackEnd )
				)
				( objectStatus "M_C_DQ<58>" )
			)
			( signal "@baseboard_fab2_lib.baseboard_fab2(sch_1):m_c_dq(59)"
				( pinPairRef "@baseboard_fab2_lib.baseboard_fab2(sch_1):\PP4716\" )
				( pinPairRef "@baseboard_fab2_lib.baseboard_fab2(sch_1):\PP4718\" )
				( objectStatus "M_C_DQ<59>" )
			)
			( signal "@baseboard_fab2_lib.baseboard_fab2(sch_1):m_c_dq(60)"
				( pinPairRef "@baseboard_fab2_lib.baseboard_fab2(sch_1):\PP4719\" )
				( pinPairRef "@baseboard_fab2_lib.baseboard_fab2(sch_1):\PP4721\" )
				( attribute "NO_TEST" "1"
					( Origin gBackEnd )
				)
				( objectStatus "M_C_DQ<60>" )
			)
			( signal "@baseboard_fab2_lib.baseboard_fab2(sch_1):m_c_dq(61)"
				( pinPairRef "@baseboard_fab2_lib.baseboard_fab2(sch_1):\PP4722\" )
				( pinPairRef "@baseboard_fab2_lib.baseboard_fab2(sch_1):\PP4724\" )
				( objectStatus "M_C_DQ<61>" )
			)
			( signal "@baseboard_fab2_lib.baseboard_fab2(sch_1):m_c_dq(62)"
				( pinPairRef "@baseboard_fab2_lib.baseboard_fab2(sch_1):\PP4725\" )
				( pinPairRef "@baseboard_fab2_lib.baseboard_fab2(sch_1):\PP4727\" )
				( objectStatus "M_C_DQ<62>" )
			)
			( signal "@baseboard_fab2_lib.baseboard_fab2(sch_1):m_c_dq(63)"
				( pinPairRef "@baseboard_fab2_lib.baseboard_fab2(sch_1):\PP4728\" )
				( pinPairRef "@baseboard_fab2_lib.baseboard_fab2(sch_1):\PP4730\" )
				( attribute "NO_TEST" "1"
					( Origin gBackEnd )
				)
				( objectStatus "M_C_DQ<63>" )
			)
			( signal "@baseboard_fab2_lib.baseboard_fab2(sch_1):m_d_dq(0)"
				( pinPairRef "@baseboard_fab2_lib.baseboard_fab2(sch_1):\PP4683\" )
				( pinPairRef "@baseboard_fab2_lib.baseboard_fab2(sch_1):\PP4685\" )
				( attribute "NO_TEST" "1"
					( Origin gBackEnd )
				)
				( objectStatus "M_D_DQ<0>" )
			)
			( signal "@baseboard_fab2_lib.baseboard_fab2(sch_1):m_d_dq(1)"
				( pinPairRef "@baseboard_fab2_lib.baseboard_fab2(sch_1):\PP4686\" )
				( pinPairRef "@baseboard_fab2_lib.baseboard_fab2(sch_1):\PP4688\" )
				( objectStatus "M_D_DQ<1>" )
			)
			( signal "@baseboard_fab2_lib.baseboard_fab2(sch_1):m_d_dq(2)"
				( pinPairRef "@baseboard_fab2_lib.baseboard_fab2(sch_1):\PP4689\" )
				( pinPairRef "@baseboard_fab2_lib.baseboard_fab2(sch_1):\PP4691\" )
				( objectStatus "M_D_DQ<2>" )
			)
			( signal "@baseboard_fab2_lib.baseboard_fab2(sch_1):m_d_dq(3)"
				( pinPairRef "@baseboard_fab2_lib.baseboard_fab2(sch_1):\PP4692\" )
				( pinPairRef "@baseboard_fab2_lib.baseboard_fab2(sch_1):\PP4694\" )
				( objectStatus "M_D_DQ<3>" )
			)
			( signal "@baseboard_fab2_lib.baseboard_fab2(sch_1):m_d_dq(4)"
				( pinPairRef "@baseboard_fab2_lib.baseboard_fab2(sch_1):\PP4695\" )
				( pinPairRef "@baseboard_fab2_lib.baseboard_fab2(sch_1):\PP4697\" )
				( objectStatus "M_D_DQ<4>" )
			)
			( signal "@baseboard_fab2_lib.baseboard_fab2(sch_1):m_d_dq(5)"
				( pinPairRef "@baseboard_fab2_lib.baseboard_fab2(sch_1):\PP4698\" )
				( pinPairRef "@baseboard_fab2_lib.baseboard_fab2(sch_1):\PP4700\" )
				( attribute "NO_TEST" "1"
					( Origin gBackEnd )
				)
				( objectStatus "M_D_DQ<5>" )
			)
			( signal "@baseboard_fab2_lib.baseboard_fab2(sch_1):m_d_dq(6)"
				( pinPairRef "@baseboard_fab2_lib.baseboard_fab2(sch_1):\PP4701\" )
				( pinPairRef "@baseboard_fab2_lib.baseboard_fab2(sch_1):\PP4703\" )
				( attribute "NO_TEST" "1"
					( Origin gBackEnd )
				)
				( objectStatus "M_D_DQ<6>" )
			)
			( signal "@baseboard_fab2_lib.baseboard_fab2(sch_1):m_d_dq(7)"
				( pinPairRef "@baseboard_fab2_lib.baseboard_fab2(sch_1):\PP4704\" )
				( pinPairRef "@baseboard_fab2_lib.baseboard_fab2(sch_1):\PP4706\" )
				( attribute "NO_TEST" "1"
					( Origin gBackEnd )
				)
				( objectStatus "M_D_DQ<7>" )
			)
			( signal "@baseboard_fab2_lib.baseboard_fab2(sch_1):m_d_dq(8)"
				( pinPairRef "@baseboard_fab2_lib.baseboard_fab2(sch_1):\PP4659\" )
				( pinPairRef "@baseboard_fab2_lib.baseboard_fab2(sch_1):\PP4661\" )
				( attribute "NO_TEST" "1"
					( Origin gBackEnd )
				)
				( objectStatus "M_D_DQ<8>" )
			)
			( signal "@baseboard_fab2_lib.baseboard_fab2(sch_1):m_d_dq(9)"
				( pinPairRef "@baseboard_fab2_lib.baseboard_fab2(sch_1):\PP4662\" )
				( pinPairRef "@baseboard_fab2_lib.baseboard_fab2(sch_1):\PP4664\" )
				( attribute "NO_TEST" "1"
					( Origin gBackEnd )
				)
				( objectStatus "M_D_DQ<9>" )
			)
			( signal "@baseboard_fab2_lib.baseboard_fab2(sch_1):m_d_dq(10)"
				( pinPairRef "@baseboard_fab2_lib.baseboard_fab2(sch_1):\PP4665\" )
				( pinPairRef "@baseboard_fab2_lib.baseboard_fab2(sch_1):\PP4667\" )
				( attribute "NO_TEST" "1"
					( Origin gBackEnd )
				)
				( objectStatus "M_D_DQ<10>" )
			)
			( signal "@baseboard_fab2_lib.baseboard_fab2(sch_1):m_d_dq(11)"
				( pinPairRef "@baseboard_fab2_lib.baseboard_fab2(sch_1):\PP4668\" )
				( pinPairRef "@baseboard_fab2_lib.baseboard_fab2(sch_1):\PP4670\" )
				( attribute "NO_TEST" "1"
					( Origin gBackEnd )
				)
				( objectStatus "M_D_DQ<11>" )
			)
			( signal "@baseboard_fab2_lib.baseboard_fab2(sch_1):m_d_dq(12)"
				( pinPairRef "@baseboard_fab2_lib.baseboard_fab2(sch_1):\PP4671\" )
				( pinPairRef "@baseboard_fab2_lib.baseboard_fab2(sch_1):\PP4673\" )
				( attribute "NO_TEST" "1"
					( Origin gBackEnd )
				)
				( objectStatus "M_D_DQ<12>" )
			)
			( signal "@baseboard_fab2_lib.baseboard_fab2(sch_1):m_d_dq(13)"
				( pinPairRef "@baseboard_fab2_lib.baseboard_fab2(sch_1):\PP4674\" )
				( pinPairRef "@baseboard_fab2_lib.baseboard_fab2(sch_1):\PP4676\" )
				( attribute "NO_TEST" "1"
					( Origin gBackEnd )
				)
				( objectStatus "M_D_DQ<13>" )
			)
			( signal "@baseboard_fab2_lib.baseboard_fab2(sch_1):m_d_dq(14)"
				( pinPairRef "@baseboard_fab2_lib.baseboard_fab2(sch_1):\PP4677\" )
				( pinPairRef "@baseboard_fab2_lib.baseboard_fab2(sch_1):\PP4679\" )
				( attribute "NO_TEST" "1"
					( Origin gBackEnd )
				)
				( objectStatus "M_D_DQ<14>" )
			)
			( signal "@baseboard_fab2_lib.baseboard_fab2(sch_1):m_d_dq(15)"
				( pinPairRef "@baseboard_fab2_lib.baseboard_fab2(sch_1):\PP4680\" )
				( pinPairRef "@baseboard_fab2_lib.baseboard_fab2(sch_1):\PP4682\" )
				( attribute "NO_TEST" "1"
					( Origin gBackEnd )
				)
				( objectStatus "M_D_DQ<15>" )
			)
			( signal "@baseboard_fab2_lib.baseboard_fab2(sch_1):m_d_dq(16)"
				( pinPairRef "@baseboard_fab2_lib.baseboard_fab2(sch_1):\PP4635\" )
				( pinPairRef "@baseboard_fab2_lib.baseboard_fab2(sch_1):\PP4637\" )
				( objectStatus "M_D_DQ<16>" )
			)
			( signal "@baseboard_fab2_lib.baseboard_fab2(sch_1):m_d_dq(17)"
				( pinPairRef "@baseboard_fab2_lib.baseboard_fab2(sch_1):\PP4638\" )
				( pinPairRef "@baseboard_fab2_lib.baseboard_fab2(sch_1):\PP4640\" )
				( attribute "NO_TEST" "1"
					( Origin gBackEnd )
				)
				( objectStatus "M_D_DQ<17>" )
			)
			( signal "@baseboard_fab2_lib.baseboard_fab2(sch_1):m_d_dq(18)"
				( pinPairRef "@baseboard_fab2_lib.baseboard_fab2(sch_1):\PP4641\" )
				( pinPairRef "@baseboard_fab2_lib.baseboard_fab2(sch_1):\PP4643\" )
				( attribute "NO_TEST" "1"
					( Origin gBackEnd )
				)
				( objectStatus "M_D_DQ<18>" )
			)
			( signal "@baseboard_fab2_lib.baseboard_fab2(sch_1):m_d_dq(19)"
				( pinPairRef "@baseboard_fab2_lib.baseboard_fab2(sch_1):\PP4644\" )
				( pinPairRef "@baseboard_fab2_lib.baseboard_fab2(sch_1):\PP4646\" )
				( objectStatus "M_D_DQ<19>" )
			)
			( signal "@baseboard_fab2_lib.baseboard_fab2(sch_1):m_d_dq(20)"
				( pinPairRef "@baseboard_fab2_lib.baseboard_fab2(sch_1):\PP4647\" )
				( pinPairRef "@baseboard_fab2_lib.baseboard_fab2(sch_1):\PP4649\" )
				( attribute "NO_TEST" "1"
					( Origin gBackEnd )
				)
				( objectStatus "M_D_DQ<20>" )
			)
			( signal "@baseboard_fab2_lib.baseboard_fab2(sch_1):m_d_dq(21)"
				( pinPairRef "@baseboard_fab2_lib.baseboard_fab2(sch_1):\PP4650\" )
				( pinPairRef "@baseboard_fab2_lib.baseboard_fab2(sch_1):\PP4652\" )
				( objectStatus "M_D_DQ<21>" )
			)
			( signal "@baseboard_fab2_lib.baseboard_fab2(sch_1):m_d_dq(22)"
				( pinPairRef "@baseboard_fab2_lib.baseboard_fab2(sch_1):\PP4653\" )
				( pinPairRef "@baseboard_fab2_lib.baseboard_fab2(sch_1):\PP4655\" )
				( objectStatus "M_D_DQ<22>" )
			)
			( signal "@baseboard_fab2_lib.baseboard_fab2(sch_1):m_d_dq(23)"
				( pinPairRef "@baseboard_fab2_lib.baseboard_fab2(sch_1):\PP4656\" )
				( pinPairRef "@baseboard_fab2_lib.baseboard_fab2(sch_1):\PP4658\" )
				( attribute "NO_TEST" "1"
					( Origin gBackEnd )
				)
				( objectStatus "M_D_DQ<23>" )
			)
			( signal "@baseboard_fab2_lib.baseboard_fab2(sch_1):m_d_dq(24)"
				( pinPairRef "@baseboard_fab2_lib.baseboard_fab2(sch_1):\PP4611\" )
				( pinPairRef "@baseboard_fab2_lib.baseboard_fab2(sch_1):\PP4613\" )
				( attribute "NO_TEST" "1"
					( Origin gBackEnd )
				)
				( objectStatus "M_D_DQ<24>" )
			)
			( signal "@baseboard_fab2_lib.baseboard_fab2(sch_1):m_d_dq(25)"
				( pinPairRef "@baseboard_fab2_lib.baseboard_fab2(sch_1):\PP4614\" )
				( pinPairRef "@baseboard_fab2_lib.baseboard_fab2(sch_1):\PP4616\" )
				( objectStatus "M_D_DQ<25>" )
			)
			( signal "@baseboard_fab2_lib.baseboard_fab2(sch_1):m_d_dq(26)"
				( pinPairRef "@baseboard_fab2_lib.baseboard_fab2(sch_1):\PP4617\" )
				( pinPairRef "@baseboard_fab2_lib.baseboard_fab2(sch_1):\PP4619\" )
				( objectStatus "M_D_DQ<26>" )
			)
			( signal "@baseboard_fab2_lib.baseboard_fab2(sch_1):m_d_dq(27)"
				( pinPairRef "@baseboard_fab2_lib.baseboard_fab2(sch_1):\PP4620\" )
				( pinPairRef "@baseboard_fab2_lib.baseboard_fab2(sch_1):\PP4622\" )
				( attribute "NO_TEST" "1"
					( Origin gBackEnd )
				)
				( objectStatus "M_D_DQ<27>" )
			)
			( signal "@baseboard_fab2_lib.baseboard_fab2(sch_1):m_d_dq(28)"
				( pinPairRef "@baseboard_fab2_lib.baseboard_fab2(sch_1):\PP4623\" )
				( pinPairRef "@baseboard_fab2_lib.baseboard_fab2(sch_1):\PP4625\" )
				( objectStatus "M_D_DQ<28>" )
			)
			( signal "@baseboard_fab2_lib.baseboard_fab2(sch_1):m_d_dq(29)"
				( pinPairRef "@baseboard_fab2_lib.baseboard_fab2(sch_1):\PP4626\" )
				( pinPairRef "@baseboard_fab2_lib.baseboard_fab2(sch_1):\PP4628\" )
				( attribute "NO_TEST" "1"
					( Origin gBackEnd )
				)
				( objectStatus "M_D_DQ<29>" )
			)
			( signal "@baseboard_fab2_lib.baseboard_fab2(sch_1):m_d_dq(30)"
				( pinPairRef "@baseboard_fab2_lib.baseboard_fab2(sch_1):\PP4629\" )
				( pinPairRef "@baseboard_fab2_lib.baseboard_fab2(sch_1):\PP4631\" )
				( attribute "NO_TEST" "1"
					( Origin gBackEnd )
				)
				( objectStatus "M_D_DQ<30>" )
			)
			( signal "@baseboard_fab2_lib.baseboard_fab2(sch_1):m_d_dq(31)"
				( pinPairRef "@baseboard_fab2_lib.baseboard_fab2(sch_1):\PP4632\" )
				( pinPairRef "@baseboard_fab2_lib.baseboard_fab2(sch_1):\PP4634\" )
				( objectStatus "M_D_DQ<31>" )
			)
			( signal "@baseboard_fab2_lib.baseboard_fab2(sch_1):m_d_dq(32)"
				( pinPairRef "@baseboard_fab2_lib.baseboard_fab2(sch_1):\PP4587\" )
				( pinPairRef "@baseboard_fab2_lib.baseboard_fab2(sch_1):\PP4589\" )
				( attribute "NO_TEST" "1"
					( Origin gBackEnd )
				)
				( objectStatus "M_D_DQ<32>" )
			)
			( signal "@baseboard_fab2_lib.baseboard_fab2(sch_1):m_d_dq(33)"
				( pinPairRef "@baseboard_fab2_lib.baseboard_fab2(sch_1):\PP4590\" )
				( pinPairRef "@baseboard_fab2_lib.baseboard_fab2(sch_1):\PP4592\" )
				( attribute "NO_TEST" "1"
					( Origin gBackEnd )
				)
				( objectStatus "M_D_DQ<33>" )
			)
			( signal "@baseboard_fab2_lib.baseboard_fab2(sch_1):m_d_dq(34)"
				( pinPairRef "@baseboard_fab2_lib.baseboard_fab2(sch_1):\PP4593\" )
				( pinPairRef "@baseboard_fab2_lib.baseboard_fab2(sch_1):\PP4595\" )
				( attribute "NO_TEST" "1"
					( Origin gBackEnd )
				)
				( objectStatus "M_D_DQ<34>" )
			)
			( signal "@baseboard_fab2_lib.baseboard_fab2(sch_1):m_d_dq(35)"
				( pinPairRef "@baseboard_fab2_lib.baseboard_fab2(sch_1):\PP4596\" )
				( pinPairRef "@baseboard_fab2_lib.baseboard_fab2(sch_1):\PP4598\" )
				( attribute "NO_TEST" "1"
					( Origin gBackEnd )
				)
				( objectStatus "M_D_DQ<35>" )
			)
			( signal "@baseboard_fab2_lib.baseboard_fab2(sch_1):m_d_dq(36)"
				( pinPairRef "@baseboard_fab2_lib.baseboard_fab2(sch_1):\PP4599\" )
				( pinPairRef "@baseboard_fab2_lib.baseboard_fab2(sch_1):\PP4601\" )
				( attribute "NO_TEST" "1"
					( Origin gBackEnd )
				)
				( objectStatus "M_D_DQ<36>" )
			)
			( signal "@baseboard_fab2_lib.baseboard_fab2(sch_1):m_m_dq(29)"
				( pinPairRef "@baseboard_fab2_lib.baseboard_fab2(sch_1):\PP1786\" )
				( pinPairRef "@baseboard_fab2_lib.baseboard_fab2(sch_1):\PP1787\" )
				( objectStatus "M_M_DQ<29>" )
			)
			( signal "@baseboard_fab2_lib.baseboard_fab2(sch_1):m_m_dq(30)"
				( pinPairRef "@baseboard_fab2_lib.baseboard_fab2(sch_1):\PP1789\" )
				( pinPairRef "@baseboard_fab2_lib.baseboard_fab2(sch_1):\PP1790\" )
				( objectStatus "M_M_DQ<30>" )
			)
			( signal "@baseboard_fab2_lib.baseboard_fab2(sch_1):m_m_dq(31)"
				( pinPairRef "@baseboard_fab2_lib.baseboard_fab2(sch_1):\PP1792\" )
				( pinPairRef "@baseboard_fab2_lib.baseboard_fab2(sch_1):\PP1793\" )
				( attribute "NO_TEST" "1"
					( Origin gBackEnd )
				)
				( objectStatus "M_M_DQ<31>" )
			)
			( signal "@baseboard_fab2_lib.baseboard_fab2(sch_1):m_m_dq(32)"
				( pinPairRef "@baseboard_fab2_lib.baseboard_fab2(sch_1):\PP1747\" )
				( pinPairRef "@baseboard_fab2_lib.baseboard_fab2(sch_1):\PP1749\" )
				( attribute "NO_TEST" "1"
					( Origin gBackEnd )
				)
				( objectStatus "M_M_DQ<32>" )
			)
			( signal "@baseboard_fab2_lib.baseboard_fab2(sch_1):m_m_dq(33)"
				( pinPairRef "@baseboard_fab2_lib.baseboard_fab2(sch_1):\PP1750\" )
				( pinPairRef "@baseboard_fab2_lib.baseboard_fab2(sch_1):\PP1752\" )
				( attribute "NO_TEST" "1"
					( Origin gBackEnd )
				)
				( objectStatus "M_M_DQ<33>" )
			)
			( signal "@baseboard_fab2_lib.baseboard_fab2(sch_1):m_m_dq(34)"
				( pinPairRef "@baseboard_fab2_lib.baseboard_fab2(sch_1):\PP1753\" )
				( pinPairRef "@baseboard_fab2_lib.baseboard_fab2(sch_1):\PP1755\" )
				( objectStatus "M_M_DQ<34>" )
			)
			( signal "@baseboard_fab2_lib.baseboard_fab2(sch_1):m_m_dq(35)"
				( pinPairRef "@baseboard_fab2_lib.baseboard_fab2(sch_1):\PP1756\" )
				( pinPairRef "@baseboard_fab2_lib.baseboard_fab2(sch_1):\PP1758\" )
				( attribute "NO_TEST" "1"
					( Origin gBackEnd )
				)
				( objectStatus "M_M_DQ<35>" )
			)
			( signal "@baseboard_fab2_lib.baseboard_fab2(sch_1):m_m_dq(36)"
				( pinPairRef "@baseboard_fab2_lib.baseboard_fab2(sch_1):\PP1759\" )
				( pinPairRef "@baseboard_fab2_lib.baseboard_fab2(sch_1):\PP1761\" )
				( objectStatus "M_M_DQ<36>" )
			)
			( signal "@baseboard_fab2_lib.baseboard_fab2(sch_1):m_m_dq(37)"
				( pinPairRef "@baseboard_fab2_lib.baseboard_fab2(sch_1):\PP1762\" )
				( pinPairRef "@baseboard_fab2_lib.baseboard_fab2(sch_1):\PP1764\" )
				( objectStatus "M_M_DQ<37>" )
			)
			( signal "@baseboard_fab2_lib.baseboard_fab2(sch_1):m_m_dq(38)"
				( pinPairRef "@baseboard_fab2_lib.baseboard_fab2(sch_1):\PP1765\" )
				( pinPairRef "@baseboard_fab2_lib.baseboard_fab2(sch_1):\PP1767\" )
				( attribute "NO_TEST" "1"
					( Origin gBackEnd )
				)
				( objectStatus "M_M_DQ<38>" )
			)
			( signal "@baseboard_fab2_lib.baseboard_fab2(sch_1):m_m_dq(39)"
				( pinPairRef "@baseboard_fab2_lib.baseboard_fab2(sch_1):\PP1768\" )
				( pinPairRef "@baseboard_fab2_lib.baseboard_fab2(sch_1):\PP1770\" )
				( attribute "NO_TEST" "1"
					( Origin gBackEnd )
				)
				( objectStatus "M_M_DQ<39>" )
			)
			( signal "@baseboard_fab2_lib.baseboard_fab2(sch_1):m_m_dq(40)"
				( pinPairRef "@baseboard_fab2_lib.baseboard_fab2(sch_1):\PP1723\" )
				( pinPairRef "@baseboard_fab2_lib.baseboard_fab2(sch_1):\PP1725\" )
				( objectStatus "M_M_DQ<40>" )
			)
			( signal "@baseboard_fab2_lib.baseboard_fab2(sch_1):m_m_dq(41)"
				( pinPairRef "@baseboard_fab2_lib.baseboard_fab2(sch_1):\PP1726\" )
				( pinPairRef "@baseboard_fab2_lib.baseboard_fab2(sch_1):\PP1728\" )
				( attribute "NO_TEST" "1"
					( Origin gBackEnd )
				)
				( objectStatus "M_M_DQ<41>" )
			)
			( signal "@baseboard_fab2_lib.baseboard_fab2(sch_1):m_m_dq(42)"
				( pinPairRef "@baseboard_fab2_lib.baseboard_fab2(sch_1):\PP1729\" )
				( pinPairRef "@baseboard_fab2_lib.baseboard_fab2(sch_1):\PP1731\" )
				( attribute "NO_TEST" "1"
					( Origin gBackEnd )
				)
				( objectStatus "M_M_DQ<42>" )
			)
			( signal "@baseboard_fab2_lib.baseboard_fab2(sch_1):m_m_dq(43)"
				( pinPairRef "@baseboard_fab2_lib.baseboard_fab2(sch_1):\PP1732\" )
				( pinPairRef "@baseboard_fab2_lib.baseboard_fab2(sch_1):\PP1734\" )
				( objectStatus "M_M_DQ<43>" )
			)
			( signal "@baseboard_fab2_lib.baseboard_fab2(sch_1):m_m_dq(44)"
				( pinPairRef "@baseboard_fab2_lib.baseboard_fab2(sch_1):\PP1735\" )
				( pinPairRef "@baseboard_fab2_lib.baseboard_fab2(sch_1):\PP1737\" )
				( attribute "NO_TEST" "1"
					( Origin gBackEnd )
				)
				( objectStatus "M_M_DQ<44>" )
			)
			( signal "@baseboard_fab2_lib.baseboard_fab2(sch_1):m_m_dq(45)"
				( pinPairRef "@baseboard_fab2_lib.baseboard_fab2(sch_1):\PP1738\" )
				( pinPairRef "@baseboard_fab2_lib.baseboard_fab2(sch_1):\PP1740\" )
				( objectStatus "M_M_DQ<45>" )
			)
			( signal "@baseboard_fab2_lib.baseboard_fab2(sch_1):m_m_dq(46)"
				( pinPairRef "@baseboard_fab2_lib.baseboard_fab2(sch_1):\PP1741\" )
				( pinPairRef "@baseboard_fab2_lib.baseboard_fab2(sch_1):\PP1743\" )
				( objectStatus "M_M_DQ<46>" )
			)
			( signal "@baseboard_fab2_lib.baseboard_fab2(sch_1):m_m_dq(47)"
				( pinPairRef "@baseboard_fab2_lib.baseboard_fab2(sch_1):\PP1744\" )
				( pinPairRef "@baseboard_fab2_lib.baseboard_fab2(sch_1):\PP1746\" )
				( attribute "NO_TEST" "1"
					( Origin gBackEnd )
				)
				( objectStatus "M_M_DQ<47>" )
			)
			( signal "@baseboard_fab2_lib.baseboard_fab2(sch_1):m_m_dq(48)"
				( pinPairRef "@baseboard_fab2_lib.baseboard_fab2(sch_1):\PP1699\" )
				( pinPairRef "@baseboard_fab2_lib.baseboard_fab2(sch_1):\PP1701\" )
				( objectStatus "M_M_DQ<48>" )
			)
			( signal "@baseboard_fab2_lib.baseboard_fab2(sch_1):m_m_dq(49)"
				( pinPairRef "@baseboard_fab2_lib.baseboard_fab2(sch_1):\PP1702\" )
				( pinPairRef "@baseboard_fab2_lib.baseboard_fab2(sch_1):\PP1704\" )
				( attribute "NO_TEST" "1"
					( Origin gBackEnd )
				)
				( objectStatus "M_M_DQ<49>" )
			)
			( signal "@baseboard_fab2_lib.baseboard_fab2(sch_1):m_m_dq(50)"
				( pinPairRef "@baseboard_fab2_lib.baseboard_fab2(sch_1):\PP1705\" )
				( pinPairRef "@baseboard_fab2_lib.baseboard_fab2(sch_1):\PP1707\" )
				( attribute "NO_TEST" "1"
					( Origin gBackEnd )
				)
				( objectStatus "M_M_DQ<50>" )
			)
			( signal "@baseboard_fab2_lib.baseboard_fab2(sch_1):m_m_dq(51)"
				( pinPairRef "@baseboard_fab2_lib.baseboard_fab2(sch_1):\PP1708\" )
				( pinPairRef "@baseboard_fab2_lib.baseboard_fab2(sch_1):\PP1710\" )
				( objectStatus "M_M_DQ<51>" )
			)
			( signal "@baseboard_fab2_lib.baseboard_fab2(sch_1):m_m_dq(52)"
				( pinPairRef "@baseboard_fab2_lib.baseboard_fab2(sch_1):\PP1711\" )
				( pinPairRef "@baseboard_fab2_lib.baseboard_fab2(sch_1):\PP1713\" )
				( attribute "NO_TEST" "1"
					( Origin gBackEnd )
				)
				( objectStatus "M_M_DQ<52>" )
			)
			( signal "@baseboard_fab2_lib.baseboard_fab2(sch_1):m_m_dq(53)"
				( pinPairRef "@baseboard_fab2_lib.baseboard_fab2(sch_1):\PP1714\" )
				( pinPairRef "@baseboard_fab2_lib.baseboard_fab2(sch_1):\PP1716\" )
				( objectStatus "M_M_DQ<53>" )
			)
			( signal "@baseboard_fab2_lib.baseboard_fab2(sch_1):m_m_dq(54)"
				( pinPairRef "@baseboard_fab2_lib.baseboard_fab2(sch_1):\PP1717\" )
				( pinPairRef "@baseboard_fab2_lib.baseboard_fab2(sch_1):\PP1719\" )
				( objectStatus "M_M_DQ<54>" )
			)
			( signal "@baseboard_fab2_lib.baseboard_fab2(sch_1):m_m_dq(55)"
				( pinPairRef "@baseboard_fab2_lib.baseboard_fab2(sch_1):\PP1720\" )
				( pinPairRef "@baseboard_fab2_lib.baseboard_fab2(sch_1):\PP1722\" )
				( attribute "NO_TEST" "1"
					( Origin gBackEnd )
				)
				( objectStatus "M_M_DQ<55>" )
			)
			( signal "@baseboard_fab2_lib.baseboard_fab2(sch_1):m_m_dq(56)"
				( pinPairRef "@baseboard_fab2_lib.baseboard_fab2(sch_1):\PP1675\" )
				( pinPairRef "@baseboard_fab2_lib.baseboard_fab2(sch_1):\PP1677\" )
				( objectStatus "M_M_DQ<56>" )
			)
			( signal "@baseboard_fab2_lib.baseboard_fab2(sch_1):m_m_dq(57)"
				( pinPairRef "@baseboard_fab2_lib.baseboard_fab2(sch_1):\PP1678\" )
				( pinPairRef "@baseboard_fab2_lib.baseboard_fab2(sch_1):\PP1680\" )
				( attribute "NO_TEST" "1"
					( Origin gBackEnd )
				)
				( objectStatus "M_M_DQ<57>" )
			)
			( signal "@baseboard_fab2_lib.baseboard_fab2(sch_1):m_m_dq(58)"
				( pinPairRef "@baseboard_fab2_lib.baseboard_fab2(sch_1):\PP1681\" )
				( pinPairRef "@baseboard_fab2_lib.baseboard_fab2(sch_1):\PP1683\" )
				( attribute "NO_TEST" "1"
					( Origin gBackEnd )
				)
				( objectStatus "M_M_DQ<58>" )
			)
			( signal "@baseboard_fab2_lib.baseboard_fab2(sch_1):m_m_dq(59)"
				( pinPairRef "@baseboard_fab2_lib.baseboard_fab2(sch_1):\PP1684\" )
				( pinPairRef "@baseboard_fab2_lib.baseboard_fab2(sch_1):\PP1686\" )
				( objectStatus "M_M_DQ<59>" )
			)
			( signal "@baseboard_fab2_lib.baseboard_fab2(sch_1):m_m_dq(60)"
				( pinPairRef "@baseboard_fab2_lib.baseboard_fab2(sch_1):\PP1687\" )
				( pinPairRef "@baseboard_fab2_lib.baseboard_fab2(sch_1):\PP1689\" )
				( attribute "NO_TEST" "1"
					( Origin gBackEnd )
				)
				( objectStatus "M_M_DQ<60>" )
			)
			( signal "@baseboard_fab2_lib.baseboard_fab2(sch_1):m_m_dq(61)"
				( pinPairRef "@baseboard_fab2_lib.baseboard_fab2(sch_1):\PP1690\" )
				( pinPairRef "@baseboard_fab2_lib.baseboard_fab2(sch_1):\PP1692\" )
				( objectStatus "M_M_DQ<61>" )
			)
			( signal "@baseboard_fab2_lib.baseboard_fab2(sch_1):m_m_dq(62)"
				( pinPairRef "@baseboard_fab2_lib.baseboard_fab2(sch_1):\PP1693\" )
				( pinPairRef "@baseboard_fab2_lib.baseboard_fab2(sch_1):\PP1694\" )
				( objectStatus "M_M_DQ<62>" )
			)
			( signal "@baseboard_fab2_lib.baseboard_fab2(sch_1):m_m_dq(63)"
				( pinPairRef "@baseboard_fab2_lib.baseboard_fab2(sch_1):\PP1696\" )
				( pinPairRef "@baseboard_fab2_lib.baseboard_fab2(sch_1):\PP1698\" )
				( attribute "NO_TEST" "1"
					( Origin gBackEnd )
				)
				( objectStatus "M_M_DQ<63>" )
			)
			( signal "@baseboard_fab2_lib.baseboard_fab2(sch_1):m_b_dq(0)"
				( pinPairRef "@baseboard_fab2_lib.baseboard_fab2(sch_1):\PP5091\" )
				( pinPairRef "@baseboard_fab2_lib.baseboard_fab2(sch_1):\PP5093\" )
				( attribute "NO_TEST" "1"
					( Origin gBackEnd )
				)
				( objectStatus "M_B_DQ<0>" )
			)
			( signal "@baseboard_fab2_lib.baseboard_fab2(sch_1):m_b_dq(1)"
				( pinPairRef "@baseboard_fab2_lib.baseboard_fab2(sch_1):\PP5094\" )
				( pinPairRef "@baseboard_fab2_lib.baseboard_fab2(sch_1):\PP5096\" )
				( attribute "NO_TEST" "1"
					( Origin gBackEnd )
				)
				( objectStatus "M_B_DQ<1>" )
			)
			( signal "@baseboard_fab2_lib.baseboard_fab2(sch_1):m_b_dq(2)"
				( pinPairRef "@baseboard_fab2_lib.baseboard_fab2(sch_1):\PP5097\" )
				( pinPairRef "@baseboard_fab2_lib.baseboard_fab2(sch_1):\PP5099\" )
				( attribute "NO_TEST" "1"
					( Origin gBackEnd )
				)
				( objectStatus "M_B_DQ<2>" )
			)
			( signal "@baseboard_fab2_lib.baseboard_fab2(sch_1):m_b_dq(3)"
				( pinPairRef "@baseboard_fab2_lib.baseboard_fab2(sch_1):\PP5100\" )
				( pinPairRef "@baseboard_fab2_lib.baseboard_fab2(sch_1):\PP5102\" )
				( objectStatus "M_B_DQ<3>" )
			)
			( signal "@baseboard_fab2_lib.baseboard_fab2(sch_1):m_b_dq(4)"
				( pinPairRef "@baseboard_fab2_lib.baseboard_fab2(sch_1):\PP5103\" )
				( pinPairRef "@baseboard_fab2_lib.baseboard_fab2(sch_1):\PP5105\" )
				( objectStatus "M_B_DQ<4>" )
			)
			( signal "@baseboard_fab2_lib.baseboard_fab2(sch_1):m_b_dq(5)"
				( pinPairRef "@baseboard_fab2_lib.baseboard_fab2(sch_1):\PP5106\" )
				( pinPairRef "@baseboard_fab2_lib.baseboard_fab2(sch_1):\PP5108\" )
				( attribute "NO_TEST" "1"
					( Origin gBackEnd )
				)
				( objectStatus "M_B_DQ<5>" )
			)
			( signal "@baseboard_fab2_lib.baseboard_fab2(sch_1):m_b_dq(6)"
				( pinPairRef "@baseboard_fab2_lib.baseboard_fab2(sch_1):\PP5109\" )
				( pinPairRef "@baseboard_fab2_lib.baseboard_fab2(sch_1):\PP5111\" )
				( objectStatus "M_B_DQ<6>" )
			)
			( signal "@baseboard_fab2_lib.baseboard_fab2(sch_1):m_b_dq(7)"
				( pinPairRef "@baseboard_fab2_lib.baseboard_fab2(sch_1):\PP5112\" )
				( pinPairRef "@baseboard_fab2_lib.baseboard_fab2(sch_1):\PP5114\" )
				( attribute "NO_TEST" "1"
					( Origin gBackEnd )
				)
				( objectStatus "M_B_DQ<7>" )
			)
			( signal "@baseboard_fab2_lib.baseboard_fab2(sch_1):m_b_dq(8)"
				( pinPairRef "@baseboard_fab2_lib.baseboard_fab2(sch_1):\PP5067\" )
				( pinPairRef "@baseboard_fab2_lib.baseboard_fab2(sch_1):\PP5069\" )
				( attribute "NO_TEST" "1"
					( Origin gBackEnd )
				)
				( objectStatus "M_B_DQ<8>" )
			)
			( signal "@baseboard_fab2_lib.baseboard_fab2(sch_1):m_b_dq(9)"
				( pinPairRef "@baseboard_fab2_lib.baseboard_fab2(sch_1):\PP5070\" )
				( pinPairRef "@baseboard_fab2_lib.baseboard_fab2(sch_1):\PP5072\" )
				( objectStatus "M_B_DQ<9>" )
			)
			( signal "@baseboard_fab2_lib.baseboard_fab2(sch_1):m_b_dq(10)"
				( pinPairRef "@baseboard_fab2_lib.baseboard_fab2(sch_1):\PP5073\" )
				( pinPairRef "@baseboard_fab2_lib.baseboard_fab2(sch_1):\PP5075\" )
				( objectStatus "M_B_DQ<10>" )
			)
			( signal "@baseboard_fab2_lib.baseboard_fab2(sch_1):m_b_dq(11)"
				( pinPairRef "@baseboard_fab2_lib.baseboard_fab2(sch_1):\PP5076\" )
				( pinPairRef "@baseboard_fab2_lib.baseboard_fab2(sch_1):\PP5078\" )
				( attribute "NO_TEST" "1"
					( Origin gBackEnd )
				)
				( objectStatus "M_B_DQ<11>" )
			)
			( signal "@baseboard_fab2_lib.baseboard_fab2(sch_1):m_b_dq(12)"
				( pinPairRef "@baseboard_fab2_lib.baseboard_fab2(sch_1):\PP5079\" )
				( pinPairRef "@baseboard_fab2_lib.baseboard_fab2(sch_1):\PP5081\" )
				( objectStatus "M_B_DQ<12>" )
			)
			( signal "@baseboard_fab2_lib.baseboard_fab2(sch_1):m_b_dq(13)"
				( pinPairRef "@baseboard_fab2_lib.baseboard_fab2(sch_1):\PP5082\" )
				( pinPairRef "@baseboard_fab2_lib.baseboard_fab2(sch_1):\PP5084\" )
				( attribute "NO_TEST" "1"
					( Origin gBackEnd )
				)
				( objectStatus "M_B_DQ<13>" )
			)
			( signal "@baseboard_fab2_lib.baseboard_fab2(sch_1):m_b_dq(14)"
				( pinPairRef "@baseboard_fab2_lib.baseboard_fab2(sch_1):\PP5085\" )
				( pinPairRef "@baseboard_fab2_lib.baseboard_fab2(sch_1):\PP5087\" )
				( attribute "NO_TEST" "1"
					( Origin gBackEnd )
				)
				( objectStatus "M_B_DQ<14>" )
			)
			( signal "@baseboard_fab2_lib.baseboard_fab2(sch_1):m_b_dq(15)"
				( pinPairRef "@baseboard_fab2_lib.baseboard_fab2(sch_1):\PP5088\" )
				( pinPairRef "@baseboard_fab2_lib.baseboard_fab2(sch_1):\PP5090\" )
				( objectStatus "M_B_DQ<15>" )
			)
			( signal "@baseboard_fab2_lib.baseboard_fab2(sch_1):m_b_dq(16)"
				( pinPairRef "@baseboard_fab2_lib.baseboard_fab2(sch_1):\PP5043\" )
				( pinPairRef "@baseboard_fab2_lib.baseboard_fab2(sch_1):\PP5045\" )
				( attribute "NO_TEST" "1"
					( Origin gBackEnd )
				)
				( objectStatus "M_B_DQ<16>" )
			)
			( signal "@baseboard_fab2_lib.baseboard_fab2(sch_1):m_b_dq(17)"
				( pinPairRef "@baseboard_fab2_lib.baseboard_fab2(sch_1):\PP5046\" )
				( pinPairRef "@baseboard_fab2_lib.baseboard_fab2(sch_1):\PP5048\" )
				( attribute "NO_TEST" "1"
					( Origin gBackEnd )
				)
				( objectStatus "M_B_DQ<17>" )
			)
			( signal "@baseboard_fab2_lib.baseboard_fab2(sch_1):m_b_dq(18)"
				( pinPairRef "@baseboard_fab2_lib.baseboard_fab2(sch_1):\PP5049\" )
				( pinPairRef "@baseboard_fab2_lib.baseboard_fab2(sch_1):\PP5051\" )
				( objectStatus "M_B_DQ<18>" )
			)
			( signal "@baseboard_fab2_lib.baseboard_fab2(sch_1):m_b_dq(19)"
				( pinPairRef "@baseboard_fab2_lib.baseboard_fab2(sch_1):\PP5052\" )
				( pinPairRef "@baseboard_fab2_lib.baseboard_fab2(sch_1):\PP5054\" )
				( attribute "NO_TEST" "1"
					( Origin gBackEnd )
				)
				( objectStatus "M_B_DQ<19>" )
			)
			( signal "@baseboard_fab2_lib.baseboard_fab2(sch_1):m_b_dq(20)"
				( pinPairRef "@baseboard_fab2_lib.baseboard_fab2(sch_1):\PP5055\" )
				( pinPairRef "@baseboard_fab2_lib.baseboard_fab2(sch_1):\PP5057\" )
				( attribute "NO_TEST" "1"
					( Origin gBackEnd )
				)
				( objectStatus "M_B_DQ<20>" )
			)
			( signal "@baseboard_fab2_lib.baseboard_fab2(sch_1):m_b_dq(21)"
				( pinPairRef "@baseboard_fab2_lib.baseboard_fab2(sch_1):\PP5058\" )
				( pinPairRef "@baseboard_fab2_lib.baseboard_fab2(sch_1):\PP5060\" )
				( objectStatus "M_B_DQ<21>" )
			)
			( signal "@baseboard_fab2_lib.baseboard_fab2(sch_1):m_b_dq(22)"
				( pinPairRef "@baseboard_fab2_lib.baseboard_fab2(sch_1):\PP5061\" )
				( pinPairRef "@baseboard_fab2_lib.baseboard_fab2(sch_1):\PP5063\" )
				( attribute "NO_TEST" "1"
					( Origin gBackEnd )
				)
				( objectStatus "M_B_DQ<22>" )
			)
			( signal "@baseboard_fab2_lib.baseboard_fab2(sch_1):m_b_dq(23)"
				( pinPairRef "@baseboard_fab2_lib.baseboard_fab2(sch_1):\PP5064\" )
				( pinPairRef "@baseboard_fab2_lib.baseboard_fab2(sch_1):\PP5066\" )
				( attribute "NO_TEST" "1"
					( Origin gBackEnd )
				)
				( objectStatus "M_B_DQ<23>" )
			)
			( signal "@baseboard_fab2_lib.baseboard_fab2(sch_1):m_b_dq(24)"
				( pinPairRef "@baseboard_fab2_lib.baseboard_fab2(sch_1):\PP5019\" )
				( pinPairRef "@baseboard_fab2_lib.baseboard_fab2(sch_1):\PP5021\" )
				( objectStatus "M_B_DQ<24>" )
			)
			( signal "@baseboard_fab2_lib.baseboard_fab2(sch_1):m_b_dq(25)"
				( pinPairRef "@baseboard_fab2_lib.baseboard_fab2(sch_1):\PP5022\" )
				( pinPairRef "@baseboard_fab2_lib.baseboard_fab2(sch_1):\PP5024\" )
				( objectStatus "M_B_DQ<25>" )
			)
			( signal "@baseboard_fab2_lib.baseboard_fab2(sch_1):m_b_dq(26)"
				( pinPairRef "@baseboard_fab2_lib.baseboard_fab2(sch_1):\PP5025\" )
				( pinPairRef "@baseboard_fab2_lib.baseboard_fab2(sch_1):\PP5027\" )
				( objectStatus "M_B_DQ<26>" )
			)
			( signal "@baseboard_fab2_lib.baseboard_fab2(sch_1):m_b_dq(27)"
				( pinPairRef "@baseboard_fab2_lib.baseboard_fab2(sch_1):\PP5028\" )
				( pinPairRef "@baseboard_fab2_lib.baseboard_fab2(sch_1):\PP5030\" )
				( objectStatus "M_B_DQ<27>" )
			)
			( signal "@baseboard_fab2_lib.baseboard_fab2(sch_1):m_b_dq(28)"
				( pinPairRef "@baseboard_fab2_lib.baseboard_fab2(sch_1):\PP5031\" )
				( pinPairRef "@baseboard_fab2_lib.baseboard_fab2(sch_1):\PP5033\" )
				( objectStatus "M_B_DQ<28>" )
			)
			( signal "@baseboard_fab2_lib.baseboard_fab2(sch_1):m_b_dq(29)"
				( pinPairRef "@baseboard_fab2_lib.baseboard_fab2(sch_1):\PP5034\" )
				( pinPairRef "@baseboard_fab2_lib.baseboard_fab2(sch_1):\PP5036\" )
				( objectStatus "M_B_DQ<29>" )
			)
			( signal "@baseboard_fab2_lib.baseboard_fab2(sch_1):m_b_dq(30)"
				( pinPairRef "@baseboard_fab2_lib.baseboard_fab2(sch_1):\PP5037\" )
				( pinPairRef "@baseboard_fab2_lib.baseboard_fab2(sch_1):\PP5039\" )
				( objectStatus "M_B_DQ<30>" )
			)
			( signal "@baseboard_fab2_lib.baseboard_fab2(sch_1):m_b_dq(31)"
				( pinPairRef "@baseboard_fab2_lib.baseboard_fab2(sch_1):\PP5040\" )
				( pinPairRef "@baseboard_fab2_lib.baseboard_fab2(sch_1):\PP5042\" )
				( objectStatus "M_B_DQ<31>" )
			)
			( signal "@baseboard_fab2_lib.baseboard_fab2(sch_1):m_b_dq(32)"
				( pinPairRef "@baseboard_fab2_lib.baseboard_fab2(sch_1):\PP4995\" )
				( pinPairRef "@baseboard_fab2_lib.baseboard_fab2(sch_1):\PP4997\" )
				( attribute "NO_TEST" "1"
					( Origin gBackEnd )
				)
				( objectStatus "M_B_DQ<32>" )
			)
			( signal "@baseboard_fab2_lib.baseboard_fab2(sch_1):m_b_dq(33)"
				( pinPairRef "@baseboard_fab2_lib.baseboard_fab2(sch_1):\PP4998\" )
				( pinPairRef "@baseboard_fab2_lib.baseboard_fab2(sch_1):\PP5000\" )
				( objectStatus "M_B_DQ<33>" )
			)
			( signal "@baseboard_fab2_lib.baseboard_fab2(sch_1):m_b_dq(34)"
				( pinPairRef "@baseboard_fab2_lib.baseboard_fab2(sch_1):\PP5001\" )
				( pinPairRef "@baseboard_fab2_lib.baseboard_fab2(sch_1):\PP5003\" )
				( objectStatus "M_B_DQ<34>" )
			)
			( signal "@baseboard_fab2_lib.baseboard_fab2(sch_1):m_b_dq(35)"
				( pinPairRef "@baseboard_fab2_lib.baseboard_fab2(sch_1):\PP5004\" )
				( pinPairRef "@baseboard_fab2_lib.baseboard_fab2(sch_1):\PP5006\" )
				( attribute "NO_TEST" "1"
					( Origin gBackEnd )
				)
				( objectStatus "M_B_DQ<35>" )
			)
			( signal "@baseboard_fab2_lib.baseboard_fab2(sch_1):m_b_dq(36)"
				( pinPairRef "@baseboard_fab2_lib.baseboard_fab2(sch_1):\PP5007\" )
				( pinPairRef "@baseboard_fab2_lib.baseboard_fab2(sch_1):\PP5009\" )
				( attribute "NO_TEST" "1"
					( Origin gBackEnd )
				)
				( objectStatus "M_B_DQ<36>" )
			)
			( signal "@baseboard_fab2_lib.baseboard_fab2(sch_1):m_b_dq(37)"
				( pinPairRef "@baseboard_fab2_lib.baseboard_fab2(sch_1):\PP5010\" )
				( pinPairRef "@baseboard_fab2_lib.baseboard_fab2(sch_1):\PP5012\" )
				( objectStatus "M_B_DQ<37>" )
			)
			( signal "@baseboard_fab2_lib.baseboard_fab2(sch_1):m_b_dq(38)"
				( pinPairRef "@baseboard_fab2_lib.baseboard_fab2(sch_1):\PP5013\" )
				( pinPairRef "@baseboard_fab2_lib.baseboard_fab2(sch_1):\PP5015\" )
				( attribute "NO_TEST" "1"
					( Origin gBackEnd )
				)
				( objectStatus "M_B_DQ<38>" )
			)
			( signal "@baseboard_fab2_lib.baseboard_fab2(sch_1):m_b_dq(39)"
				( pinPairRef "@baseboard_fab2_lib.baseboard_fab2(sch_1):\PP5016\" )
				( pinPairRef "@baseboard_fab2_lib.baseboard_fab2(sch_1):\PP5018\" )
				( objectStatus "M_B_DQ<39>" )
			)
			( signal "@baseboard_fab2_lib.baseboard_fab2(sch_1):m_b_dq(40)"
				( pinPairRef "@baseboard_fab2_lib.baseboard_fab2(sch_1):\PP4971\" )
				( pinPairRef "@baseboard_fab2_lib.baseboard_fab2(sch_1):\PP4973\" )
				( attribute "NO_TEST" "1"
					( Origin gBackEnd )
				)
				( objectStatus "M_B_DQ<40>" )
			)
			( signal "@baseboard_fab2_lib.baseboard_fab2(sch_1):m_b_dq(41)"
				( pinPairRef "@baseboard_fab2_lib.baseboard_fab2(sch_1):\PP4974\" )
				( pinPairRef "@baseboard_fab2_lib.baseboard_fab2(sch_1):\PP4976\" )
				( objectStatus "M_B_DQ<41>" )
			)
			( signal "@baseboard_fab2_lib.baseboard_fab2(sch_1):m_b_dq(42)"
				( pinPairRef "@baseboard_fab2_lib.baseboard_fab2(sch_1):\PP4977\" )
				( pinPairRef "@baseboard_fab2_lib.baseboard_fab2(sch_1):\PP4979\" )
				( objectStatus "M_B_DQ<42>" )
			)
			( signal "@baseboard_fab2_lib.baseboard_fab2(sch_1):m_b_dq(43)"
				( pinPairRef "@baseboard_fab2_lib.baseboard_fab2(sch_1):\PP4980\" )
				( pinPairRef "@baseboard_fab2_lib.baseboard_fab2(sch_1):\PP4982\" )
				( objectStatus "M_B_DQ<43>" )
			)
			( signal "@baseboard_fab2_lib.baseboard_fab2(sch_1):m_b_dq(44)"
				( pinPairRef "@baseboard_fab2_lib.baseboard_fab2(sch_1):\PP4983\" )
				( pinPairRef "@baseboard_fab2_lib.baseboard_fab2(sch_1):\PP4985\" )
				( attribute "NO_TEST" "1"
					( Origin gBackEnd )
				)
				( objectStatus "M_B_DQ<44>" )
			)
			( signal "@baseboard_fab2_lib.baseboard_fab2(sch_1):m_b_dq(45)"
				( pinPairRef "@baseboard_fab2_lib.baseboard_fab2(sch_1):\PP4986\" )
				( pinPairRef "@baseboard_fab2_lib.baseboard_fab2(sch_1):\PP4988\" )
				( objectStatus "M_B_DQ<45>" )
			)
			( signal "@baseboard_fab2_lib.baseboard_fab2(sch_1):m_b_dq(46)"
				( pinPairRef "@baseboard_fab2_lib.baseboard_fab2(sch_1):\PP4989\" )
				( pinPairRef "@baseboard_fab2_lib.baseboard_fab2(sch_1):\PP4991\" )
				( objectStatus "M_B_DQ<46>" )
			)
			( signal "@baseboard_fab2_lib.baseboard_fab2(sch_1):m_b_dq(47)"
				( pinPairRef "@baseboard_fab2_lib.baseboard_fab2(sch_1):\PP4992\" )
				( pinPairRef "@baseboard_fab2_lib.baseboard_fab2(sch_1):\PP4994\" )
				( objectStatus "M_B_DQ<47>" )
			)
			( signal "@baseboard_fab2_lib.baseboard_fab2(sch_1):m_b_dq(48)"
				( pinPairRef "@baseboard_fab2_lib.baseboard_fab2(sch_1):\PP4947\" )
				( pinPairRef "@baseboard_fab2_lib.baseboard_fab2(sch_1):\PP4949\" )
				( attribute "NO_TEST" "1"
					( Origin gBackEnd )
				)
				( objectStatus "M_B_DQ<48>" )
			)
			( signal "@baseboard_fab2_lib.baseboard_fab2(sch_1):m_b_dq(49)"
				( pinPairRef "@baseboard_fab2_lib.baseboard_fab2(sch_1):\PP4950\" )
				( pinPairRef "@baseboard_fab2_lib.baseboard_fab2(sch_1):\PP4952\" )
				( objectStatus "M_B_DQ<49>" )
			)
			( signal "@baseboard_fab2_lib.baseboard_fab2(sch_1):m_b_dq(50)"
				( pinPairRef "@baseboard_fab2_lib.baseboard_fab2(sch_1):\PP4953\" )
				( pinPairRef "@baseboard_fab2_lib.baseboard_fab2(sch_1):\PP4955\" )
				( objectStatus "M_B_DQ<50>" )
			)
			( signal "@baseboard_fab2_lib.baseboard_fab2(sch_1):m_b_dq(51)"
				( pinPairRef "@baseboard_fab2_lib.baseboard_fab2(sch_1):\PP4956\" )
				( pinPairRef "@baseboard_fab2_lib.baseboard_fab2(sch_1):\PP4958\" )
				( objectStatus "M_B_DQ<51>" )
			)
			( signal "@baseboard_fab2_lib.baseboard_fab2(sch_1):m_b_dq(52)"
				( pinPairRef "@baseboard_fab2_lib.baseboard_fab2(sch_1):\PP4959\" )
				( pinPairRef "@baseboard_fab2_lib.baseboard_fab2(sch_1):\PP4961\" )
				( objectStatus "M_B_DQ<52>" )
			)
			( signal "@baseboard_fab2_lib.baseboard_fab2(sch_1):m_b_dq(53)"
				( pinPairRef "@baseboard_fab2_lib.baseboard_fab2(sch_1):\PP4962\" )
				( pinPairRef "@baseboard_fab2_lib.baseboard_fab2(sch_1):\PP4964\" )
				( objectStatus "M_B_DQ<53>" )
			)
			( signal "@baseboard_fab2_lib.baseboard_fab2(sch_1):m_b_dq(54)"
				( pinPairRef "@baseboard_fab2_lib.baseboard_fab2(sch_1):\PP4965\" )
				( pinPairRef "@baseboard_fab2_lib.baseboard_fab2(sch_1):\PP4967\" )
				( objectStatus "M_B_DQ<54>" )
			)
			( signal "@baseboard_fab2_lib.baseboard_fab2(sch_1):m_b_dq(55)"
				( pinPairRef "@baseboard_fab2_lib.baseboard_fab2(sch_1):\PP4968\" )
				( pinPairRef "@baseboard_fab2_lib.baseboard_fab2(sch_1):\PP4970\" )
				( objectStatus "M_B_DQ<55>" )
			)
			( signal "@baseboard_fab2_lib.baseboard_fab2(sch_1):m_b_dq(56)"
				( pinPairRef "@baseboard_fab2_lib.baseboard_fab2(sch_1):\PP4923\" )
				( pinPairRef "@baseboard_fab2_lib.baseboard_fab2(sch_1):\PP4925\" )
				( attribute "NO_TEST" "1"
					( Origin gBackEnd )
				)
				( objectStatus "M_B_DQ<56>" )
			)
			( signal "@baseboard_fab2_lib.baseboard_fab2(sch_1):m_b_dq(57)"
				( pinPairRef "@baseboard_fab2_lib.baseboard_fab2(sch_1):\PP4926\" )
				( pinPairRef "@baseboard_fab2_lib.baseboard_fab2(sch_1):\PP4928\" )
				( objectStatus "M_B_DQ<57>" )
			)
			( signal "@baseboard_fab2_lib.baseboard_fab2(sch_1):m_b_dq(58)"
				( pinPairRef "@baseboard_fab2_lib.baseboard_fab2(sch_1):\PP4929\" )
				( pinPairRef "@baseboard_fab2_lib.baseboard_fab2(sch_1):\PP4931\" )
				( objectStatus "M_B_DQ<58>" )
			)
			( signal "@baseboard_fab2_lib.baseboard_fab2(sch_1):m_b_dq(59)"
				( pinPairRef "@baseboard_fab2_lib.baseboard_fab2(sch_1):\PP4932\" )
				( pinPairRef "@baseboard_fab2_lib.baseboard_fab2(sch_1):\PP4934\" )
				( attribute "NO_TEST" "1"
					( Origin gBackEnd )
				)
				( objectStatus "M_B_DQ<59>" )
			)
			( signal "@baseboard_fab2_lib.baseboard_fab2(sch_1):m_b_dq(60)"
				( pinPairRef "@baseboard_fab2_lib.baseboard_fab2(sch_1):\PP4935\" )
				( pinPairRef "@baseboard_fab2_lib.baseboard_fab2(sch_1):\PP4937\" )
				( objectStatus "M_B_DQ<60>" )
			)
			( signal "@baseboard_fab2_lib.baseboard_fab2(sch_1):m_b_dq(61)"
				( pinPairRef "@baseboard_fab2_lib.baseboard_fab2(sch_1):\PP4938\" )
				( pinPairRef "@baseboard_fab2_lib.baseboard_fab2(sch_1):\PP4940\" )
				( attribute "NO_TEST" "1"
					( Origin gBackEnd )
				)
				( objectStatus "M_B_DQ<61>" )
			)
			( signal "@baseboard_fab2_lib.baseboard_fab2(sch_1):m_b_dq(62)"
				( pinPairRef "@baseboard_fab2_lib.baseboard_fab2(sch_1):\PP4941\" )
				( pinPairRef "@baseboard_fab2_lib.baseboard_fab2(sch_1):\PP4943\" )
				( attribute "NO_TEST" "1"
					( Origin gBackEnd )
				)
				( objectStatus "M_B_DQ<62>" )
			)
			( signal "@baseboard_fab2_lib.baseboard_fab2(sch_1):m_b_dq(63)"
				( pinPairRef "@baseboard_fab2_lib.baseboard_fab2(sch_1):\PP4944\" )
				( pinPairRef "@baseboard_fab2_lib.baseboard_fab2(sch_1):\PP4946\" )
				( objectStatus "M_B_DQ<63>" )
			)
			( signal "@baseboard_fab2_lib.baseboard_fab2(sch_1):m_c_dq(0)"
				( pinPairRef "@baseboard_fab2_lib.baseboard_fab2(sch_1):\PP4875\" )
				( pinPairRef "@baseboard_fab2_lib.baseboard_fab2(sch_1):\PP4877\" )
				( attribute "NO_TEST" "1"
					( Origin gBackEnd )
				)
				( objectStatus "M_C_DQ<0>" )
			)
			( signal "@baseboard_fab2_lib.baseboard_fab2(sch_1):m_k_dq(57)"
				( pinPairRef "@baseboard_fab2_lib.baseboard_fab2(sch_1):\PP2110\" )
				( pinPairRef "@baseboard_fab2_lib.baseboard_fab2(sch_1):\PP2112\" )
				( objectStatus "M_K_DQ<57>" )
			)
			( signal "@baseboard_fab2_lib.baseboard_fab2(sch_1):m_k_dq(58)"
				( pinPairRef "@baseboard_fab2_lib.baseboard_fab2(sch_1):\PP2113\" )
				( pinPairRef "@baseboard_fab2_lib.baseboard_fab2(sch_1):\PP2115\" )
				( attribute "NO_TEST" "1"
					( Origin gBackEnd )
				)
				( objectStatus "M_K_DQ<58>" )
			)
			( signal "@baseboard_fab2_lib.baseboard_fab2(sch_1):m_k_dq(59)"
				( pinPairRef "@baseboard_fab2_lib.baseboard_fab2(sch_1):\PP2116\" )
				( pinPairRef "@baseboard_fab2_lib.baseboard_fab2(sch_1):\PP2118\" )
				( objectStatus "M_K_DQ<59>" )
			)
			( signal "@baseboard_fab2_lib.baseboard_fab2(sch_1):m_k_dq(60)"
				( pinPairRef "@baseboard_fab2_lib.baseboard_fab2(sch_1):\PP2119\" )
				( pinPairRef "@baseboard_fab2_lib.baseboard_fab2(sch_1):\PP2121\" )
				( objectStatus "M_K_DQ<60>" )
			)
			( signal "@baseboard_fab2_lib.baseboard_fab2(sch_1):m_k_dq(61)"
				( pinPairRef "@baseboard_fab2_lib.baseboard_fab2(sch_1):\PP2122\" )
				( pinPairRef "@baseboard_fab2_lib.baseboard_fab2(sch_1):\PP2124\" )
				( attribute "NO_TEST" "1"
					( Origin gBackEnd )
				)
				( objectStatus "M_K_DQ<61>" )
			)
			( signal "@baseboard_fab2_lib.baseboard_fab2(sch_1):m_k_dq(62)"
				( pinPairRef "@baseboard_fab2_lib.baseboard_fab2(sch_1):\PP2125\" )
				( pinPairRef "@baseboard_fab2_lib.baseboard_fab2(sch_1):\PP2127\" )
				( attribute "NO_TEST" "1"
					( Origin gBackEnd )
				)
				( objectStatus "M_K_DQ<62>" )
			)
			( signal "@baseboard_fab2_lib.baseboard_fab2(sch_1):m_k_dq(63)"
				( pinPairRef "@baseboard_fab2_lib.baseboard_fab2(sch_1):\PP2128\" )
				( pinPairRef "@baseboard_fab2_lib.baseboard_fab2(sch_1):\PP2130\" )
				( objectStatus "M_K_DQ<63>" )
			)
			( signal "@baseboard_fab2_lib.baseboard_fab2(sch_1):m_l_dq(0)"
				( pinPairRef "@baseboard_fab2_lib.baseboard_fab2(sch_1):\PP2059\" )
				( pinPairRef "@baseboard_fab2_lib.baseboard_fab2(sch_1):\PP2060\" )
				( attribute "NO_TEST" "1"
					( Origin gBackEnd )
				)
				( objectStatus "M_L_DQ<0>" )
			)
			( signal "@baseboard_fab2_lib.baseboard_fab2(sch_1):m_l_dq(1)"
				( pinPairRef "@baseboard_fab2_lib.baseboard_fab2(sch_1):\PP2062\" )
				( pinPairRef "@baseboard_fab2_lib.baseboard_fab2(sch_1):\PP2063\" )
				( objectStatus "M_L_DQ<1>" )
			)
			( signal "@baseboard_fab2_lib.baseboard_fab2(sch_1):m_l_dq(2)"
				( pinPairRef "@baseboard_fab2_lib.baseboard_fab2(sch_1):\PP2065\" )
				( pinPairRef "@baseboard_fab2_lib.baseboard_fab2(sch_1):\PP2066\" )
				( objectStatus "M_L_DQ<2>" )
			)
			( signal "@baseboard_fab2_lib.baseboard_fab2(sch_1):m_l_dq(3)"
				( pinPairRef "@baseboard_fab2_lib.baseboard_fab2(sch_1):\PP2068\" )
				( pinPairRef "@baseboard_fab2_lib.baseboard_fab2(sch_1):\PP2069\" )
				( attribute "NO_TEST" "1"
					( Origin gBackEnd )
				)
				( objectStatus "M_L_DQ<3>" )
			)
			( signal "@baseboard_fab2_lib.baseboard_fab2(sch_1):m_l_dq(4)"
				( pinPairRef "@baseboard_fab2_lib.baseboard_fab2(sch_1):\PP2071\" )
				( pinPairRef "@baseboard_fab2_lib.baseboard_fab2(sch_1):\PP2072\" )
				( objectStatus "M_L_DQ<4>" )
			)
			( signal "@baseboard_fab2_lib.baseboard_fab2(sch_1):m_l_dq(5)"
				( pinPairRef "@baseboard_fab2_lib.baseboard_fab2(sch_1):\PP2074\" )
				( pinPairRef "@baseboard_fab2_lib.baseboard_fab2(sch_1):\PP2075\" )
				( attribute "NO_TEST" "1"
					( Origin gBackEnd )
				)
				( objectStatus "M_L_DQ<5>" )
			)
			( signal "@baseboard_fab2_lib.baseboard_fab2(sch_1):m_l_dq(6)"
				( pinPairRef "@baseboard_fab2_lib.baseboard_fab2(sch_1):\PP2077\" )
				( pinPairRef "@baseboard_fab2_lib.baseboard_fab2(sch_1):\PP2078\" )
				( attribute "NO_TEST" "1"
					( Origin gBackEnd )
				)
				( objectStatus "M_L_DQ<6>" )
			)
			( signal "@baseboard_fab2_lib.baseboard_fab2(sch_1):m_l_dq(7)"
				( pinPairRef "@baseboard_fab2_lib.baseboard_fab2(sch_1):\PP2080\" )
				( pinPairRef "@baseboard_fab2_lib.baseboard_fab2(sch_1):\PP2081\" )
				( objectStatus "M_L_DQ<7>" )
			)
			( signal "@baseboard_fab2_lib.baseboard_fab2(sch_1):m_l_dq(8)"
				( pinPairRef "@baseboard_fab2_lib.baseboard_fab2(sch_1):\PP2035\" )
				( pinPairRef "@baseboard_fab2_lib.baseboard_fab2(sch_1):\PP2036\" )
				( attribute "NO_TEST" "1"
					( Origin gBackEnd )
				)
				( objectStatus "M_L_DQ<8>" )
			)
			( signal "@baseboard_fab2_lib.baseboard_fab2(sch_1):m_l_dq(9)"
				( pinPairRef "@baseboard_fab2_lib.baseboard_fab2(sch_1):\PP2038\" )
				( pinPairRef "@baseboard_fab2_lib.baseboard_fab2(sch_1):\PP2039\" )
				( attribute "NO_TEST" "1"
					( Origin gBackEnd )
				)
				( objectStatus "M_L_DQ<9>" )
			)
			( signal "@baseboard_fab2_lib.baseboard_fab2(sch_1):m_l_dq(10)"
				( pinPairRef "@baseboard_fab2_lib.baseboard_fab2(sch_1):\PP2041\" )
				( pinPairRef "@baseboard_fab2_lib.baseboard_fab2(sch_1):\PP2042\" )
				( attribute "NO_TEST" "1"
					( Origin gBackEnd )
				)
				( objectStatus "M_L_DQ<10>" )
			)
			( signal "@baseboard_fab2_lib.baseboard_fab2(sch_1):m_l_dq(11)"
				( pinPairRef "@baseboard_fab2_lib.baseboard_fab2(sch_1):\PP2044\" )
				( pinPairRef "@baseboard_fab2_lib.baseboard_fab2(sch_1):\PP2045\" )
				( objectStatus "M_L_DQ<11>" )
			)
			( signal "@baseboard_fab2_lib.baseboard_fab2(sch_1):m_l_dq(12)"
				( pinPairRef "@baseboard_fab2_lib.baseboard_fab2(sch_1):\PP2047\" )
				( pinPairRef "@baseboard_fab2_lib.baseboard_fab2(sch_1):\PP2048\" )
				( attribute "NO_TEST" "1"
					( Origin gBackEnd )
				)
				( objectStatus "M_L_DQ<12>" )
			)
			( signal "@baseboard_fab2_lib.baseboard_fab2(sch_1):m_l_dq(13)"
				( pinPairRef "@baseboard_fab2_lib.baseboard_fab2(sch_1):\PP2050\" )
				( pinPairRef "@baseboard_fab2_lib.baseboard_fab2(sch_1):\PP2051\" )
				( objectStatus "M_L_DQ<13>" )
			)
			( signal "@baseboard_fab2_lib.baseboard_fab2(sch_1):m_l_dq(14)"
				( pinPairRef "@baseboard_fab2_lib.baseboard_fab2(sch_1):\PP2053\" )
				( pinPairRef "@baseboard_fab2_lib.baseboard_fab2(sch_1):\PP2054\" )
				( objectStatus "M_L_DQ<14>" )
			)
			( signal "@baseboard_fab2_lib.baseboard_fab2(sch_1):m_l_dq(15)"
				( pinPairRef "@baseboard_fab2_lib.baseboard_fab2(sch_1):\PP2056\" )
				( pinPairRef "@baseboard_fab2_lib.baseboard_fab2(sch_1):\PP2057\" )
				( attribute "NO_TEST" "1"
					( Origin gBackEnd )
				)
				( objectStatus "M_L_DQ<15>" )
			)
			( signal "@baseboard_fab2_lib.baseboard_fab2(sch_1):m_l_dq(16)"
				( pinPairRef "@baseboard_fab2_lib.baseboard_fab2(sch_1):\PP2011\" )
				( pinPairRef "@baseboard_fab2_lib.baseboard_fab2(sch_1):\PP2012\" )
				( attribute "NO_TEST" "1"
					( Origin gBackEnd )
				)
				( objectStatus "M_L_DQ<16>" )
			)
			( signal "@baseboard_fab2_lib.baseboard_fab2(sch_1):m_l_dq(17)"
				( pinPairRef "@baseboard_fab2_lib.baseboard_fab2(sch_1):\PP2014\" )
				( pinPairRef "@baseboard_fab2_lib.baseboard_fab2(sch_1):\PP2015\" )
				( objectStatus "M_L_DQ<17>" )
			)
			( signal "@baseboard_fab2_lib.baseboard_fab2(sch_1):m_l_dq(18)"
				( pinPairRef "@baseboard_fab2_lib.baseboard_fab2(sch_1):\PP2017\" )
				( pinPairRef "@baseboard_fab2_lib.baseboard_fab2(sch_1):\PP2018\" )
				( objectStatus "M_L_DQ<18>" )
			)
			( signal "@baseboard_fab2_lib.baseboard_fab2(sch_1):m_l_dq(19)"
				( pinPairRef "@baseboard_fab2_lib.baseboard_fab2(sch_1):\PP2020\" )
				( pinPairRef "@baseboard_fab2_lib.baseboard_fab2(sch_1):\PP2021\" )
				( attribute "NO_TEST" "1"
					( Origin gBackEnd )
				)
				( objectStatus "M_L_DQ<19>" )
			)
			( signal "@baseboard_fab2_lib.baseboard_fab2(sch_1):m_l_dq(20)"
				( pinPairRef "@baseboard_fab2_lib.baseboard_fab2(sch_1):\PP2023\" )
				( pinPairRef "@baseboard_fab2_lib.baseboard_fab2(sch_1):\PP2024\" )
				( objectStatus "M_L_DQ<20>" )
			)
			( signal "@baseboard_fab2_lib.baseboard_fab2(sch_1):m_l_dq(21)"
				( pinPairRef "@baseboard_fab2_lib.baseboard_fab2(sch_1):\PP2026\" )
				( pinPairRef "@baseboard_fab2_lib.baseboard_fab2(sch_1):\PP2027\" )
				( attribute "NO_TEST" "1"
					( Origin gBackEnd )
				)
				( objectStatus "M_L_DQ<21>" )
			)
			( signal "@baseboard_fab2_lib.baseboard_fab2(sch_1):m_l_dq(22)"
				( pinPairRef "@baseboard_fab2_lib.baseboard_fab2(sch_1):\PP2029\" )
				( pinPairRef "@baseboard_fab2_lib.baseboard_fab2(sch_1):\PP2030\" )
				( attribute "NO_TEST" "1"
					( Origin gBackEnd )
				)
				( objectStatus "M_L_DQ<22>" )
			)
			( signal "@baseboard_fab2_lib.baseboard_fab2(sch_1):m_l_dq(23)"
				( pinPairRef "@baseboard_fab2_lib.baseboard_fab2(sch_1):\PP2032\" )
				( pinPairRef "@baseboard_fab2_lib.baseboard_fab2(sch_1):\PP2033\" )
				( objectStatus "M_L_DQ<23>" )
			)
			( signal "@baseboard_fab2_lib.baseboard_fab2(sch_1):m_l_dq(24)"
				( pinPairRef "@baseboard_fab2_lib.baseboard_fab2(sch_1):\PP1987\" )
				( pinPairRef "@baseboard_fab2_lib.baseboard_fab2(sch_1):\PP1988\" )
				( attribute "NO_TEST" "1"
					( Origin gBackEnd )
				)
				( objectStatus "M_L_DQ<24>" )
			)
			( signal "@baseboard_fab2_lib.baseboard_fab2(sch_1):m_l_dq(25)"
				( pinPairRef "@baseboard_fab2_lib.baseboard_fab2(sch_1):\PP1990\" )
				( pinPairRef "@baseboard_fab2_lib.baseboard_fab2(sch_1):\PP1991\" )
				( attribute "NO_TEST" "1"
					( Origin gBackEnd )
				)
				( objectStatus "M_L_DQ<25>" )
			)
			( signal "@baseboard_fab2_lib.baseboard_fab2(sch_1):m_l_dq(26)"
				( pinPairRef "@baseboard_fab2_lib.baseboard_fab2(sch_1):\PP1993\" )
				( pinPairRef "@baseboard_fab2_lib.baseboard_fab2(sch_1):\PP1994\" )
				( attribute "NO_TEST" "1"
					( Origin gBackEnd )
				)
				( objectStatus "M_L_DQ<26>" )
			)
			( signal "@baseboard_fab2_lib.baseboard_fab2(sch_1):m_l_dq(27)"
				( pinPairRef "@baseboard_fab2_lib.baseboard_fab2(sch_1):\PP1996\" )
				( pinPairRef "@baseboard_fab2_lib.baseboard_fab2(sch_1):\PP1997\" )
				( attribute "NO_TEST" "1"
					( Origin gBackEnd )
				)
				( objectStatus "M_L_DQ<27>" )
			)
			( signal "@baseboard_fab2_lib.baseboard_fab2(sch_1):m_l_dq(28)"
				( pinPairRef "@baseboard_fab2_lib.baseboard_fab2(sch_1):\PP1999\" )
				( pinPairRef "@baseboard_fab2_lib.baseboard_fab2(sch_1):\PP2000\" )
				( attribute "NO_TEST" "1"
					( Origin gBackEnd )
				)
				( objectStatus "M_L_DQ<28>" )
			)
			( signal "@baseboard_fab2_lib.baseboard_fab2(sch_1):m_l_dq(29)"
				( pinPairRef "@baseboard_fab2_lib.baseboard_fab2(sch_1):\PP2002\" )
				( pinPairRef "@baseboard_fab2_lib.baseboard_fab2(sch_1):\PP2003\" )
				( attribute "NO_TEST" "1"
					( Origin gBackEnd )
				)
				( objectStatus "M_L_DQ<29>" )
			)
			( signal "@baseboard_fab2_lib.baseboard_fab2(sch_1):m_l_dq(30)"
				( pinPairRef "@baseboard_fab2_lib.baseboard_fab2(sch_1):\PP2005\" )
				( pinPairRef "@baseboard_fab2_lib.baseboard_fab2(sch_1):\PP2006\" )
				( attribute "NO_TEST" "1"
					( Origin gBackEnd )
				)
				( objectStatus "M_L_DQ<30>" )
			)
			( signal "@baseboard_fab2_lib.baseboard_fab2(sch_1):m_l_dq(31)"
				( pinPairRef "@baseboard_fab2_lib.baseboard_fab2(sch_1):\PP2008\" )
				( pinPairRef "@baseboard_fab2_lib.baseboard_fab2(sch_1):\PP2009\" )
				( attribute "NO_TEST" "1"
					( Origin gBackEnd )
				)
				( objectStatus "M_L_DQ<31>" )
			)
			( signal "@baseboard_fab2_lib.baseboard_fab2(sch_1):m_l_dq(32)"
				( pinPairRef "@baseboard_fab2_lib.baseboard_fab2(sch_1):\PP1963\" )
				( pinPairRef "@baseboard_fab2_lib.baseboard_fab2(sch_1):\PP1965\" )
				( attribute "NO_TEST" "1"
					( Origin gBackEnd )
				)
				( objectStatus "M_L_DQ<32>" )
			)
			( signal "@baseboard_fab2_lib.baseboard_fab2(sch_1):m_l_dq(33)"
				( pinPairRef "@baseboard_fab2_lib.baseboard_fab2(sch_1):\PP1966\" )
				( pinPairRef "@baseboard_fab2_lib.baseboard_fab2(sch_1):\PP1968\" )
				( objectStatus "M_L_DQ<33>" )
			)
			( signal "@baseboard_fab2_lib.baseboard_fab2(sch_1):m_l_dq(34)"
				( pinPairRef "@baseboard_fab2_lib.baseboard_fab2(sch_1):\PP1969\" )
				( pinPairRef "@baseboard_fab2_lib.baseboard_fab2(sch_1):\PP1971\" )
				( attribute "NO_TEST" "1"
					( Origin gBackEnd )
				)
				( objectStatus "M_L_DQ<34>" )
			)
			( signal "@baseboard_fab2_lib.baseboard_fab2(sch_1):m_l_dq(35)"
				( pinPairRef "@baseboard_fab2_lib.baseboard_fab2(sch_1):\PP1972\" )
				( pinPairRef "@baseboard_fab2_lib.baseboard_fab2(sch_1):\PP1974\" )
				( objectStatus "M_L_DQ<35>" )
			)
			( signal "@baseboard_fab2_lib.baseboard_fab2(sch_1):m_l_dq(36)"
				( pinPairRef "@baseboard_fab2_lib.baseboard_fab2(sch_1):\PP1975\" )
				( pinPairRef "@baseboard_fab2_lib.baseboard_fab2(sch_1):\PP1977\" )
				( objectStatus "M_L_DQ<36>" )
			)
			( signal "@baseboard_fab2_lib.baseboard_fab2(sch_1):m_l_dq(37)"
				( pinPairRef "@baseboard_fab2_lib.baseboard_fab2(sch_1):\PP1978\" )
				( pinPairRef "@baseboard_fab2_lib.baseboard_fab2(sch_1):\PP1980\" )
				( attribute "NO_TEST" "1"
					( Origin gBackEnd )
				)
				( objectStatus "M_L_DQ<37>" )
			)
			( signal "@baseboard_fab2_lib.baseboard_fab2(sch_1):m_l_dq(38)"
				( pinPairRef "@baseboard_fab2_lib.baseboard_fab2(sch_1):\PP1981\" )
				( pinPairRef "@baseboard_fab2_lib.baseboard_fab2(sch_1):\PP1983\" )
				( objectStatus "M_L_DQ<38>" )
			)
			( signal "@baseboard_fab2_lib.baseboard_fab2(sch_1):m_l_dq(39)"
				( pinPairRef "@baseboard_fab2_lib.baseboard_fab2(sch_1):\PP1984\" )
				( pinPairRef "@baseboard_fab2_lib.baseboard_fab2(sch_1):\PP1986\" )
				( attribute "NO_TEST" "1"
					( Origin gBackEnd )
				)
				( objectStatus "M_L_DQ<39>" )
			)
			( signal "@baseboard_fab2_lib.baseboard_fab2(sch_1):m_l_dq(40)"
				( pinPairRef "@baseboard_fab2_lib.baseboard_fab2(sch_1):\PP1939\" )
				( pinPairRef "@baseboard_fab2_lib.baseboard_fab2(sch_1):\PP1941\" )
				( attribute "NO_TEST" "1"
					( Origin gBackEnd )
				)
				( objectStatus "M_L_DQ<40>" )
			)
			( signal "@baseboard_fab2_lib.baseboard_fab2(sch_1):m_l_dq(41)"
				( pinPairRef "@baseboard_fab2_lib.baseboard_fab2(sch_1):\PP1942\" )
				( pinPairRef "@baseboard_fab2_lib.baseboard_fab2(sch_1):\PP1944\" )
				( attribute "NO_TEST" "1"
					( Origin gBackEnd )
				)
				( objectStatus "M_L_DQ<41>" )
			)
			( signal "@baseboard_fab2_lib.baseboard_fab2(sch_1):m_l_dq(42)"
				( pinPairRef "@baseboard_fab2_lib.baseboard_fab2(sch_1):\PP1945\" )
				( pinPairRef "@baseboard_fab2_lib.baseboard_fab2(sch_1):\PP1947\" )
				( attribute "NO_TEST" "1"
					( Origin gBackEnd )
				)
				( objectStatus "M_L_DQ<42>" )
			)
			( signal "@baseboard_fab2_lib.baseboard_fab2(sch_1):m_l_dq(43)"
				( pinPairRef "@baseboard_fab2_lib.baseboard_fab2(sch_1):\PP1948\" )
				( pinPairRef "@baseboard_fab2_lib.baseboard_fab2(sch_1):\PP1950\" )
				( attribute "NO_TEST" "1"
					( Origin gBackEnd )
				)
				( objectStatus "M_L_DQ<43>" )
			)
			( signal "@baseboard_fab2_lib.baseboard_fab2(sch_1):m_l_dq(44)"
				( pinPairRef "@baseboard_fab2_lib.baseboard_fab2(sch_1):\PP1951\" )
				( pinPairRef "@baseboard_fab2_lib.baseboard_fab2(sch_1):\PP1953\" )
				( attribute "NO_TEST" "1"
					( Origin gBackEnd )
				)
				( objectStatus "M_L_DQ<44>" )
			)
			( signal "@baseboard_fab2_lib.baseboard_fab2(sch_1):m_l_dq(45)"
				( pinPairRef "@baseboard_fab2_lib.baseboard_fab2(sch_1):\PP1954\" )
				( pinPairRef "@baseboard_fab2_lib.baseboard_fab2(sch_1):\PP1956\" )
				( attribute "NO_TEST" "1"
					( Origin gBackEnd )
				)
				( objectStatus "M_L_DQ<45>" )
			)
			( signal "@baseboard_fab2_lib.baseboard_fab2(sch_1):m_l_dq(46)"
				( pinPairRef "@baseboard_fab2_lib.baseboard_fab2(sch_1):\PP1957\" )
				( pinPairRef "@baseboard_fab2_lib.baseboard_fab2(sch_1):\PP1959\" )
				( attribute "NO_TEST" "1"
					( Origin gBackEnd )
				)
				( objectStatus "M_L_DQ<46>" )
			)
			( signal "@baseboard_fab2_lib.baseboard_fab2(sch_1):m_l_dq(47)"
				( pinPairRef "@baseboard_fab2_lib.baseboard_fab2(sch_1):\PP1960\" )
				( pinPairRef "@baseboard_fab2_lib.baseboard_fab2(sch_1):\PP1962\" )
				( attribute "NO_TEST" "1"
					( Origin gBackEnd )
				)
				( objectStatus "M_L_DQ<47>" )
			)
			( signal "@baseboard_fab2_lib.baseboard_fab2(sch_1):m_l_dq(48)"
				( pinPairRef "@baseboard_fab2_lib.baseboard_fab2(sch_1):\PP1915\" )
				( pinPairRef "@baseboard_fab2_lib.baseboard_fab2(sch_1):\PP1917\" )
				( attribute "NO_TEST" "1"
					( Origin gBackEnd )
				)
				( objectStatus "M_L_DQ<48>" )
			)
			( signal "@baseboard_fab2_lib.baseboard_fab2(sch_1):m_l_dq(49)"
				( pinPairRef "@baseboard_fab2_lib.baseboard_fab2(sch_1):\PP1918\" )
				( pinPairRef "@baseboard_fab2_lib.baseboard_fab2(sch_1):\PP1920\" )
				( attribute "NO_TEST" "1"
					( Origin gBackEnd )
				)
				( objectStatus "M_L_DQ<49>" )
			)
			( signal "@baseboard_fab2_lib.baseboard_fab2(sch_1):m_l_dq(50)"
				( pinPairRef "@baseboard_fab2_lib.baseboard_fab2(sch_1):\PP1921\" )
				( pinPairRef "@baseboard_fab2_lib.baseboard_fab2(sch_1):\PP1923\" )
				( attribute "NO_TEST" "1"
					( Origin gBackEnd )
				)
				( objectStatus "M_L_DQ<50>" )
			)
			( signal "@baseboard_fab2_lib.baseboard_fab2(sch_1):m_l_dq(51)"
				( pinPairRef "@baseboard_fab2_lib.baseboard_fab2(sch_1):\PP1924\" )
				( pinPairRef "@baseboard_fab2_lib.baseboard_fab2(sch_1):\PP1926\" )
				( attribute "NO_TEST" "1"
					( Origin gBackEnd )
				)
				( objectStatus "M_L_DQ<51>" )
			)
			( signal "@baseboard_fab2_lib.baseboard_fab2(sch_1):m_l_dq(52)"
				( pinPairRef "@baseboard_fab2_lib.baseboard_fab2(sch_1):\PP1927\" )
				( pinPairRef "@baseboard_fab2_lib.baseboard_fab2(sch_1):\PP1929\" )
				( attribute "NO_TEST" "1"
					( Origin gBackEnd )
				)
				( objectStatus "M_L_DQ<52>" )
			)
			( signal "@baseboard_fab2_lib.baseboard_fab2(sch_1):m_l_dq(53)"
				( pinPairRef "@baseboard_fab2_lib.baseboard_fab2(sch_1):\PP1930\" )
				( pinPairRef "@baseboard_fab2_lib.baseboard_fab2(sch_1):\PP1932\" )
				( attribute "NO_TEST" "1"
					( Origin gBackEnd )
				)
				( objectStatus "M_L_DQ<53>" )
			)
			( signal "@baseboard_fab2_lib.baseboard_fab2(sch_1):m_l_dq(54)"
				( pinPairRef "@baseboard_fab2_lib.baseboard_fab2(sch_1):\PP1933\" )
				( pinPairRef "@baseboard_fab2_lib.baseboard_fab2(sch_1):\PP1935\" )
				( attribute "NO_TEST" "1"
					( Origin gBackEnd )
				)
				( objectStatus "M_L_DQ<54>" )
			)
			( signal "@baseboard_fab2_lib.baseboard_fab2(sch_1):m_l_dq(55)"
				( pinPairRef "@baseboard_fab2_lib.baseboard_fab2(sch_1):\PP1936\" )
				( pinPairRef "@baseboard_fab2_lib.baseboard_fab2(sch_1):\PP1938\" )
				( attribute "NO_TEST" "1"
					( Origin gBackEnd )
				)
				( objectStatus "M_L_DQ<55>" )
			)
			( signal "@baseboard_fab2_lib.baseboard_fab2(sch_1):m_l_dq(56)"
				( pinPairRef "@baseboard_fab2_lib.baseboard_fab2(sch_1):\PP1891\" )
				( pinPairRef "@baseboard_fab2_lib.baseboard_fab2(sch_1):\PP1893\" )
				( objectStatus "M_L_DQ<56>" )
			)
			( signal "@baseboard_fab2_lib.baseboard_fab2(sch_1):m_l_dq(57)"
				( pinPairRef "@baseboard_fab2_lib.baseboard_fab2(sch_1):\PP1894\" )
				( pinPairRef "@baseboard_fab2_lib.baseboard_fab2(sch_1):\PP1896\" )
				( attribute "NO_TEST" "1"
					( Origin gBackEnd )
				)
				( objectStatus "M_L_DQ<57>" )
			)
			( signal "@baseboard_fab2_lib.baseboard_fab2(sch_1):m_l_dq(58)"
				( pinPairRef "@baseboard_fab2_lib.baseboard_fab2(sch_1):\PP1897\" )
				( pinPairRef "@baseboard_fab2_lib.baseboard_fab2(sch_1):\PP1899\" )
				( objectStatus "M_L_DQ<58>" )
			)
			( signal "@baseboard_fab2_lib.baseboard_fab2(sch_1):m_l_dq(59)"
				( pinPairRef "@baseboard_fab2_lib.baseboard_fab2(sch_1):\PP1900\" )
				( pinPairRef "@baseboard_fab2_lib.baseboard_fab2(sch_1):\PP1902\" )
				( objectStatus "M_L_DQ<59>" )
			)
			( signal "@baseboard_fab2_lib.baseboard_fab2(sch_1):m_l_dq(60)"
				( pinPairRef "@baseboard_fab2_lib.baseboard_fab2(sch_1):\PP1903\" )
				( pinPairRef "@baseboard_fab2_lib.baseboard_fab2(sch_1):\PP1905\" )
				( attribute "NO_TEST" "1"
					( Origin gBackEnd )
				)
				( objectStatus "M_L_DQ<60>" )
			)
			( signal "@baseboard_fab2_lib.baseboard_fab2(sch_1):m_l_dq(61)"
				( pinPairRef "@baseboard_fab2_lib.baseboard_fab2(sch_1):\PP1906\" )
				( pinPairRef "@baseboard_fab2_lib.baseboard_fab2(sch_1):\PP1908\" )
				( objectStatus "M_L_DQ<61>" )
			)
			( signal "@baseboard_fab2_lib.baseboard_fab2(sch_1):m_l_dq(62)"
				( pinPairRef "@baseboard_fab2_lib.baseboard_fab2(sch_1):\PP1909\" )
				( pinPairRef "@baseboard_fab2_lib.baseboard_fab2(sch_1):\PP1911\" )
				( attribute "NO_TEST" "1"
					( Origin gBackEnd )
				)
				( objectStatus "M_L_DQ<62>" )
			)
			( signal "@baseboard_fab2_lib.baseboard_fab2(sch_1):m_l_dq(63)"
				( pinPairRef "@baseboard_fab2_lib.baseboard_fab2(sch_1):\PP1912\" )
				( pinPairRef "@baseboard_fab2_lib.baseboard_fab2(sch_1):\PP1914\" )
				( attribute "NO_TEST" "1"
					( Origin gBackEnd )
				)
				( objectStatus "M_L_DQ<63>" )
			)
			( signal "@baseboard_fab2_lib.baseboard_fab2(sch_1):m_m_dq(0)"
				( pinPairRef "@baseboard_fab2_lib.baseboard_fab2(sch_1):\PP1843\" )
				( pinPairRef "@baseboard_fab2_lib.baseboard_fab2(sch_1):\PP1844\" )
				( attribute "NO_TEST" "1"
					( Origin gBackEnd )
				)
				( objectStatus "M_M_DQ<0>" )
			)
			( signal "@baseboard_fab2_lib.baseboard_fab2(sch_1):m_m_dq(1)"
				( pinPairRef "@baseboard_fab2_lib.baseboard_fab2(sch_1):\PP1846\" )
				( pinPairRef "@baseboard_fab2_lib.baseboard_fab2(sch_1):\PP1847\" )
				( objectStatus "M_M_DQ<1>" )
			)
			( signal "@baseboard_fab2_lib.baseboard_fab2(sch_1):m_m_dq(2)"
				( pinPairRef "@baseboard_fab2_lib.baseboard_fab2(sch_1):\PP1849\" )
				( pinPairRef "@baseboard_fab2_lib.baseboard_fab2(sch_1):\PP1850\" )
				( objectStatus "M_M_DQ<2>" )
			)
			( signal "@baseboard_fab2_lib.baseboard_fab2(sch_1):m_m_dq(3)"
				( pinPairRef "@baseboard_fab2_lib.baseboard_fab2(sch_1):\PP1852\" )
				( pinPairRef "@baseboard_fab2_lib.baseboard_fab2(sch_1):\PP1853\" )
				( attribute "NO_TEST" "1"
					( Origin gBackEnd )
				)
				( objectStatus "M_M_DQ<3>" )
			)
			( signal "@baseboard_fab2_lib.baseboard_fab2(sch_1):m_m_dq(4)"
				( pinPairRef "@baseboard_fab2_lib.baseboard_fab2(sch_1):\PP1855\" )
				( pinPairRef "@baseboard_fab2_lib.baseboard_fab2(sch_1):\PP1856\" )
				( objectStatus "M_M_DQ<4>" )
			)
			( signal "@baseboard_fab2_lib.baseboard_fab2(sch_1):m_m_dq(5)"
				( pinPairRef "@baseboard_fab2_lib.baseboard_fab2(sch_1):\PP1858\" )
				( pinPairRef "@baseboard_fab2_lib.baseboard_fab2(sch_1):\PP1859\" )
				( attribute "NO_TEST" "1"
					( Origin gBackEnd )
				)
				( objectStatus "M_M_DQ<5>" )
			)
			( signal "@baseboard_fab2_lib.baseboard_fab2(sch_1):m_m_dq(6)"
				( pinPairRef "@baseboard_fab2_lib.baseboard_fab2(sch_1):\PP1861\" )
				( pinPairRef "@baseboard_fab2_lib.baseboard_fab2(sch_1):\PP1862\" )
				( attribute "NO_TEST" "1"
					( Origin gBackEnd )
				)
				( objectStatus "M_M_DQ<6>" )
			)
			( signal "@baseboard_fab2_lib.baseboard_fab2(sch_1):m_m_dq(7)"
				( pinPairRef "@baseboard_fab2_lib.baseboard_fab2(sch_1):\PP1864\" )
				( pinPairRef "@baseboard_fab2_lib.baseboard_fab2(sch_1):\PP1865\" )
				( objectStatus "M_M_DQ<7>" )
			)
			( signal "@baseboard_fab2_lib.baseboard_fab2(sch_1):m_m_dq(8)"
				( pinPairRef "@baseboard_fab2_lib.baseboard_fab2(sch_1):\PP1819\" )
				( pinPairRef "@baseboard_fab2_lib.baseboard_fab2(sch_1):\PP1820\" )
				( attribute "NO_TEST" "1"
					( Origin gBackEnd )
				)
				( objectStatus "M_M_DQ<8>" )
			)
			( signal "@baseboard_fab2_lib.baseboard_fab2(sch_1):m_m_dq(9)"
				( pinPairRef "@baseboard_fab2_lib.baseboard_fab2(sch_1):\PP1822\" )
				( pinPairRef "@baseboard_fab2_lib.baseboard_fab2(sch_1):\PP1823\" )
				( objectStatus "M_M_DQ<9>" )
			)
			( signal "@baseboard_fab2_lib.baseboard_fab2(sch_1):m_m_dq(10)"
				( pinPairRef "@baseboard_fab2_lib.baseboard_fab2(sch_1):\PP1825\" )
				( pinPairRef "@baseboard_fab2_lib.baseboard_fab2(sch_1):\PP1826\" )
				( attribute "NO_TEST" "1"
					( Origin gBackEnd )
				)
				( objectStatus "M_M_DQ<10>" )
			)
			( signal "@baseboard_fab2_lib.baseboard_fab2(sch_1):m_m_dq(11)"
				( pinPairRef "@baseboard_fab2_lib.baseboard_fab2(sch_1):\PP1828\" )
				( pinPairRef "@baseboard_fab2_lib.baseboard_fab2(sch_1):\PP1829\" )
				( objectStatus "M_M_DQ<11>" )
			)
			( signal "@baseboard_fab2_lib.baseboard_fab2(sch_1):m_m_dq(12)"
				( pinPairRef "@baseboard_fab2_lib.baseboard_fab2(sch_1):\PP1831\" )
				( pinPairRef "@baseboard_fab2_lib.baseboard_fab2(sch_1):\PP1832\" )
				( objectStatus "M_M_DQ<12>" )
			)
			( signal "@baseboard_fab2_lib.baseboard_fab2(sch_1):m_m_dq(13)"
				( pinPairRef "@baseboard_fab2_lib.baseboard_fab2(sch_1):\PP1834\" )
				( pinPairRef "@baseboard_fab2_lib.baseboard_fab2(sch_1):\PP1835\" )
				( attribute "NO_TEST" "1"
					( Origin gBackEnd )
				)
				( objectStatus "M_M_DQ<13>" )
			)
			( signal "@baseboard_fab2_lib.baseboard_fab2(sch_1):m_m_dq(14)"
				( pinPairRef "@baseboard_fab2_lib.baseboard_fab2(sch_1):\PP1837\" )
				( pinPairRef "@baseboard_fab2_lib.baseboard_fab2(sch_1):\PP1838\" )
				( objectStatus "M_M_DQ<14>" )
			)
			( signal "@baseboard_fab2_lib.baseboard_fab2(sch_1):m_m_dq(15)"
				( pinPairRef "@baseboard_fab2_lib.baseboard_fab2(sch_1):\PP1840\" )
				( pinPairRef "@baseboard_fab2_lib.baseboard_fab2(sch_1):\PP1841\" )
				( attribute "NO_TEST" "1"
					( Origin gBackEnd )
				)
				( objectStatus "M_M_DQ<15>" )
			)
			( signal "@baseboard_fab2_lib.baseboard_fab2(sch_1):m_m_dq(16)"
				( pinPairRef "@baseboard_fab2_lib.baseboard_fab2(sch_1):\PP1795\" )
				( pinPairRef "@baseboard_fab2_lib.baseboard_fab2(sch_1):\PP1796\" )
				( objectStatus "M_M_DQ<16>" )
			)
			( signal "@baseboard_fab2_lib.baseboard_fab2(sch_1):m_m_dq(17)"
				( pinPairRef "@baseboard_fab2_lib.baseboard_fab2(sch_1):\PP1798\" )
				( pinPairRef "@baseboard_fab2_lib.baseboard_fab2(sch_1):\PP1799\" )
				( attribute "NO_TEST" "1"
					( Origin gBackEnd )
				)
				( objectStatus "M_M_DQ<17>" )
			)
			( signal "@baseboard_fab2_lib.baseboard_fab2(sch_1):m_m_dq(18)"
				( pinPairRef "@baseboard_fab2_lib.baseboard_fab2(sch_1):\PP1801\" )
				( pinPairRef "@baseboard_fab2_lib.baseboard_fab2(sch_1):\PP1802\" )
				( attribute "NO_TEST" "1"
					( Origin gBackEnd )
				)
				( objectStatus "M_M_DQ<18>" )
			)
			( signal "@baseboard_fab2_lib.baseboard_fab2(sch_1):m_m_dq(19)"
				( pinPairRef "@baseboard_fab2_lib.baseboard_fab2(sch_1):\PP1804\" )
				( pinPairRef "@baseboard_fab2_lib.baseboard_fab2(sch_1):\PP1805\" )
				( objectStatus "M_M_DQ<19>" )
			)
			( signal "@baseboard_fab2_lib.baseboard_fab2(sch_1):m_m_dq(20)"
				( pinPairRef "@baseboard_fab2_lib.baseboard_fab2(sch_1):\PP1807\" )
				( pinPairRef "@baseboard_fab2_lib.baseboard_fab2(sch_1):\PP1808\" )
				( attribute "NO_TEST" "1"
					( Origin gBackEnd )
				)
				( objectStatus "M_M_DQ<20>" )
			)
			( signal "@baseboard_fab2_lib.baseboard_fab2(sch_1):m_m_dq(21)"
				( pinPairRef "@baseboard_fab2_lib.baseboard_fab2(sch_1):\PP1810\" )
				( pinPairRef "@baseboard_fab2_lib.baseboard_fab2(sch_1):\PP1811\" )
				( objectStatus "M_M_DQ<21>" )
			)
			( signal "@baseboard_fab2_lib.baseboard_fab2(sch_1):m_m_dq(22)"
				( pinPairRef "@baseboard_fab2_lib.baseboard_fab2(sch_1):\PP1813\" )
				( pinPairRef "@baseboard_fab2_lib.baseboard_fab2(sch_1):\PP1814\" )
				( objectStatus "M_M_DQ<22>" )
			)
			( signal "@baseboard_fab2_lib.baseboard_fab2(sch_1):m_m_dq(23)"
				( pinPairRef "@baseboard_fab2_lib.baseboard_fab2(sch_1):\PP1816\" )
				( pinPairRef "@baseboard_fab2_lib.baseboard_fab2(sch_1):\PP1817\" )
				( attribute "NO_TEST" "1"
					( Origin gBackEnd )
				)
				( objectStatus "M_M_DQ<23>" )
			)
			( signal "@baseboard_fab2_lib.baseboard_fab2(sch_1):m_m_dq(24)"
				( pinPairRef "@baseboard_fab2_lib.baseboard_fab2(sch_1):\PP1771\" )
				( pinPairRef "@baseboard_fab2_lib.baseboard_fab2(sch_1):\PP1772\" )
				( objectStatus "M_M_DQ<24>" )
			)
			( signal "@baseboard_fab2_lib.baseboard_fab2(sch_1):m_m_dq(25)"
				( pinPairRef "@baseboard_fab2_lib.baseboard_fab2(sch_1):\PP1774\" )
				( pinPairRef "@baseboard_fab2_lib.baseboard_fab2(sch_1):\PP1775\" )
				( attribute "NO_TEST" "1"
					( Origin gBackEnd )
				)
				( objectStatus "M_M_DQ<25>" )
			)
			( signal "@baseboard_fab2_lib.baseboard_fab2(sch_1):m_m_dq(26)"
				( pinPairRef "@baseboard_fab2_lib.baseboard_fab2(sch_1):\PP1777\" )
				( pinPairRef "@baseboard_fab2_lib.baseboard_fab2(sch_1):\PP1778\" )
				( attribute "NO_TEST" "1"
					( Origin gBackEnd )
				)
				( objectStatus "M_M_DQ<26>" )
			)
			( signal "@baseboard_fab2_lib.baseboard_fab2(sch_1):m_m_dq(27)"
				( pinPairRef "@baseboard_fab2_lib.baseboard_fab2(sch_1):\PP1780\" )
				( pinPairRef "@baseboard_fab2_lib.baseboard_fab2(sch_1):\PP1781\" )
				( objectStatus "M_M_DQ<27>" )
			)
			( signal "@baseboard_fab2_lib.baseboard_fab2(sch_1):m_m_dq(28)"
				( pinPairRef "@baseboard_fab2_lib.baseboard_fab2(sch_1):\PP1783\" )
				( pinPairRef "@baseboard_fab2_lib.baseboard_fab2(sch_1):\PP1784\" )
				( attribute "NO_TEST" "1"
					( Origin gBackEnd )
				)
				( objectStatus "M_M_DQ<28>" )
			)
			( signal "@baseboard_fab2_lib.baseboard_fab2(sch_1):m_j_dq(21)"
				( pinPairRef "@baseboard_fab2_lib.baseboard_fab2(sch_1):\PP2458\" )
				( pinPairRef "@baseboard_fab2_lib.baseboard_fab2(sch_1):\PP2459\" )
				( attribute "NO_TEST" "1"
					( Origin gBackEnd )
				)
				( objectStatus "M_J_DQ<21>" )
			)
			( signal "@baseboard_fab2_lib.baseboard_fab2(sch_1):m_j_dq(22)"
				( pinPairRef "@baseboard_fab2_lib.baseboard_fab2(sch_1):\PP2461\" )
				( pinPairRef "@baseboard_fab2_lib.baseboard_fab2(sch_1):\PP2462\" )
				( attribute "NO_TEST" "1"
					( Origin gBackEnd )
				)
				( objectStatus "M_J_DQ<22>" )
			)
			( signal "@baseboard_fab2_lib.baseboard_fab2(sch_1):m_j_dq(23)"
				( pinPairRef "@baseboard_fab2_lib.baseboard_fab2(sch_1):\PP2464\" )
				( pinPairRef "@baseboard_fab2_lib.baseboard_fab2(sch_1):\PP2465\" )
				( attribute "NO_TEST" "1"
					( Origin gBackEnd )
				)
				( objectStatus "M_J_DQ<23>" )
			)
			( signal "@baseboard_fab2_lib.baseboard_fab2(sch_1):m_j_dq(24)"
				( pinPairRef "@baseboard_fab2_lib.baseboard_fab2(sch_1):\PP2419\" )
				( pinPairRef "@baseboard_fab2_lib.baseboard_fab2(sch_1):\PP2420\" )
				( objectStatus "M_J_DQ<24>" )
			)
			( signal "@baseboard_fab2_lib.baseboard_fab2(sch_1):m_j_dq(25)"
				( pinPairRef "@baseboard_fab2_lib.baseboard_fab2(sch_1):\PP2422\" )
				( pinPairRef "@baseboard_fab2_lib.baseboard_fab2(sch_1):\PP2423\" )
				( attribute "NO_TEST" "1"
					( Origin gBackEnd )
				)
				( objectStatus "M_J_DQ<25>" )
			)
			( signal "@baseboard_fab2_lib.baseboard_fab2(sch_1):m_j_dq(26)"
				( pinPairRef "@baseboard_fab2_lib.baseboard_fab2(sch_1):\PP2425\" )
				( pinPairRef "@baseboard_fab2_lib.baseboard_fab2(sch_1):\PP2426\" )
				( attribute "NO_TEST" "1"
					( Origin gBackEnd )
				)
				( objectStatus "M_J_DQ<26>" )
			)
			( signal "@baseboard_fab2_lib.baseboard_fab2(sch_1):m_j_dq(27)"
				( pinPairRef "@baseboard_fab2_lib.baseboard_fab2(sch_1):\PP2428\" )
				( pinPairRef "@baseboard_fab2_lib.baseboard_fab2(sch_1):\PP2429\" )
				( objectStatus "M_J_DQ<27>" )
			)
			( signal "@baseboard_fab2_lib.baseboard_fab2(sch_1):m_j_dq(28)"
				( pinPairRef "@baseboard_fab2_lib.baseboard_fab2(sch_1):\PP2431\" )
				( pinPairRef "@baseboard_fab2_lib.baseboard_fab2(sch_1):\PP2432\" )
				( attribute "NO_TEST" "1"
					( Origin gBackEnd )
				)
				( objectStatus "M_J_DQ<28>" )
			)
			( signal "@baseboard_fab2_lib.baseboard_fab2(sch_1):m_j_dq(29)"
				( pinPairRef "@baseboard_fab2_lib.baseboard_fab2(sch_1):\PP2434\" )
				( pinPairRef "@baseboard_fab2_lib.baseboard_fab2(sch_1):\PP2435\" )
				( objectStatus "M_J_DQ<29>" )
			)
			( signal "@baseboard_fab2_lib.baseboard_fab2(sch_1):m_j_dq(30)"
				( pinPairRef "@baseboard_fab2_lib.baseboard_fab2(sch_1):\PP2437\" )
				( pinPairRef "@baseboard_fab2_lib.baseboard_fab2(sch_1):\PP2438\" )
				( objectStatus "M_J_DQ<30>" )
			)
			( signal "@baseboard_fab2_lib.baseboard_fab2(sch_1):m_j_dq(31)"
				( pinPairRef "@baseboard_fab2_lib.baseboard_fab2(sch_1):\PP2440\" )
				( pinPairRef "@baseboard_fab2_lib.baseboard_fab2(sch_1):\PP2441\" )
				( attribute "NO_TEST" "1"
					( Origin gBackEnd )
				)
				( objectStatus "M_J_DQ<31>" )
			)
			( signal "@baseboard_fab2_lib.baseboard_fab2(sch_1):m_j_dq(32)"
				( pinPairRef "@baseboard_fab2_lib.baseboard_fab2(sch_1):\PP2395\" )
				( pinPairRef "@baseboard_fab2_lib.baseboard_fab2(sch_1):\PP2397\" )
				( attribute "NO_TEST" "1"
					( Origin gBackEnd )
				)
				( objectStatus "M_J_DQ<32>" )
			)
			( signal "@baseboard_fab2_lib.baseboard_fab2(sch_1):m_j_dq(33)"
				( pinPairRef "@baseboard_fab2_lib.baseboard_fab2(sch_1):\PP2398\" )
				( pinPairRef "@baseboard_fab2_lib.baseboard_fab2(sch_1):\PP2400\" )
				( attribute "NO_TEST" "1"
					( Origin gBackEnd )
				)
				( objectStatus "M_J_DQ<33>" )
			)
			( signal "@baseboard_fab2_lib.baseboard_fab2(sch_1):m_j_dq(34)"
				( pinPairRef "@baseboard_fab2_lib.baseboard_fab2(sch_1):\PP2401\" )
				( pinPairRef "@baseboard_fab2_lib.baseboard_fab2(sch_1):\PP2403\" )
				( objectStatus "M_J_DQ<34>" )
			)
			( signal "@baseboard_fab2_lib.baseboard_fab2(sch_1):m_j_dq(35)"
				( pinPairRef "@baseboard_fab2_lib.baseboard_fab2(sch_1):\PP2404\" )
				( pinPairRef "@baseboard_fab2_lib.baseboard_fab2(sch_1):\PP2406\" )
				( attribute "NO_TEST" "1"
					( Origin gBackEnd )
				)
				( objectStatus "M_J_DQ<35>" )
			)
			( signal "@baseboard_fab2_lib.baseboard_fab2(sch_1):m_j_dq(36)"
				( pinPairRef "@baseboard_fab2_lib.baseboard_fab2(sch_1):\PP2407\" )
				( pinPairRef "@baseboard_fab2_lib.baseboard_fab2(sch_1):\PP2409\" )
				( objectStatus "M_J_DQ<36>" )
			)
			( signal "@baseboard_fab2_lib.baseboard_fab2(sch_1):m_j_dq(37)"
				( pinPairRef "@baseboard_fab2_lib.baseboard_fab2(sch_1):\PP2410\" )
				( pinPairRef "@baseboard_fab2_lib.baseboard_fab2(sch_1):\PP2412\" )
				( attribute "NO_TEST" "1"
					( Origin gBackEnd )
				)
				( objectStatus "M_J_DQ<37>" )
			)
			( signal "@baseboard_fab2_lib.baseboard_fab2(sch_1):m_j_dq(38)"
				( pinPairRef "@baseboard_fab2_lib.baseboard_fab2(sch_1):\PP2413\" )
				( pinPairRef "@baseboard_fab2_lib.baseboard_fab2(sch_1):\PP2415\" )
				( attribute "NO_TEST" "1"
					( Origin gBackEnd )
				)
				( objectStatus "M_J_DQ<38>" )
			)
			( signal "@baseboard_fab2_lib.baseboard_fab2(sch_1):m_j_dq(39)"
				( pinPairRef "@baseboard_fab2_lib.baseboard_fab2(sch_1):\PP2416\" )
				( pinPairRef "@baseboard_fab2_lib.baseboard_fab2(sch_1):\PP2418\" )
				( attribute "NO_TEST" "1"
					( Origin gBackEnd )
				)
				( objectStatus "M_J_DQ<39>" )
			)
			( signal "@baseboard_fab2_lib.baseboard_fab2(sch_1):m_j_dq(40)"
				( pinPairRef "@baseboard_fab2_lib.baseboard_fab2(sch_1):\PP2371\" )
				( pinPairRef "@baseboard_fab2_lib.baseboard_fab2(sch_1):\PP2373\" )
				( attribute "NO_TEST" "1"
					( Origin gBackEnd )
				)
				( objectStatus "M_J_DQ<40>" )
			)
			( signal "@baseboard_fab2_lib.baseboard_fab2(sch_1):m_j_dq(41)"
				( pinPairRef "@baseboard_fab2_lib.baseboard_fab2(sch_1):\PP2374\" )
				( pinPairRef "@baseboard_fab2_lib.baseboard_fab2(sch_1):\PP2376\" )
				( attribute "NO_TEST" "1"
					( Origin gBackEnd )
				)
				( objectStatus "M_J_DQ<41>" )
			)
			( signal "@baseboard_fab2_lib.baseboard_fab2(sch_1):m_j_dq(42)"
				( pinPairRef "@baseboard_fab2_lib.baseboard_fab2(sch_1):\PP2377\" )
				( pinPairRef "@baseboard_fab2_lib.baseboard_fab2(sch_1):\PP2379\" )
				( objectStatus "M_J_DQ<42>" )
			)
			( signal "@baseboard_fab2_lib.baseboard_fab2(sch_1):m_j_dq(43)"
				( pinPairRef "@baseboard_fab2_lib.baseboard_fab2(sch_1):\PP2380\" )
				( pinPairRef "@baseboard_fab2_lib.baseboard_fab2(sch_1):\PP2382\" )
				( attribute "NO_TEST" "1"
					( Origin gBackEnd )
				)
				( objectStatus "M_J_DQ<43>" )
			)
			( signal "@baseboard_fab2_lib.baseboard_fab2(sch_1):m_j_dq(44)"
				( pinPairRef "@baseboard_fab2_lib.baseboard_fab2(sch_1):\PP2383\" )
				( pinPairRef "@baseboard_fab2_lib.baseboard_fab2(sch_1):\PP2385\" )
				( objectStatus "M_J_DQ<44>" )
			)
			( signal "@baseboard_fab2_lib.baseboard_fab2(sch_1):m_j_dq(45)"
				( pinPairRef "@baseboard_fab2_lib.baseboard_fab2(sch_1):\PP2386\" )
				( pinPairRef "@baseboard_fab2_lib.baseboard_fab2(sch_1):\PP2388\" )
				( attribute "NO_TEST" "1"
					( Origin gBackEnd )
				)
				( objectStatus "M_J_DQ<45>" )
			)
			( signal "@baseboard_fab2_lib.baseboard_fab2(sch_1):m_j_dq(46)"
				( pinPairRef "@baseboard_fab2_lib.baseboard_fab2(sch_1):\PP2389\" )
				( pinPairRef "@baseboard_fab2_lib.baseboard_fab2(sch_1):\PP2391\" )
				( attribute "NO_TEST" "1"
					( Origin gBackEnd )
				)
				( objectStatus "M_J_DQ<46>" )
			)
			( signal "@baseboard_fab2_lib.baseboard_fab2(sch_1):m_j_dq(47)"
				( pinPairRef "@baseboard_fab2_lib.baseboard_fab2(sch_1):\PP2392\" )
				( pinPairRef "@baseboard_fab2_lib.baseboard_fab2(sch_1):\PP2394\" )
				( attribute "NO_TEST" "1"
					( Origin gBackEnd )
				)
				( objectStatus "M_J_DQ<47>" )
			)
			( signal "@baseboard_fab2_lib.baseboard_fab2(sch_1):m_j_dq(48)"
				( pinPairRef "@baseboard_fab2_lib.baseboard_fab2(sch_1):\PP2347\" )
				( pinPairRef "@baseboard_fab2_lib.baseboard_fab2(sch_1):\PP2349\" )
				( objectStatus "M_J_DQ<48>" )
			)
			( signal "@baseboard_fab2_lib.baseboard_fab2(sch_1):m_j_dq(49)"
				( pinPairRef "@baseboard_fab2_lib.baseboard_fab2(sch_1):\PP2350\" )
				( pinPairRef "@baseboard_fab2_lib.baseboard_fab2(sch_1):\PP2352\" )
				( attribute "NO_TEST" "1"
					( Origin gBackEnd )
				)
				( objectStatus "M_J_DQ<49>" )
			)
			( signal "@baseboard_fab2_lib.baseboard_fab2(sch_1):m_j_dq(50)"
				( pinPairRef "@baseboard_fab2_lib.baseboard_fab2(sch_1):\PP2353\" )
				( pinPairRef "@baseboard_fab2_lib.baseboard_fab2(sch_1):\PP2355\" )
				( attribute "NO_TEST" "1"
					( Origin gBackEnd )
				)
				( objectStatus "M_J_DQ<50>" )
			)
			( signal "@baseboard_fab2_lib.baseboard_fab2(sch_1):m_j_dq(51)"
				( pinPairRef "@baseboard_fab2_lib.baseboard_fab2(sch_1):\PP2356\" )
				( pinPairRef "@baseboard_fab2_lib.baseboard_fab2(sch_1):\PP2358\" )
				( objectStatus "M_J_DQ<51>" )
			)
			( signal "@baseboard_fab2_lib.baseboard_fab2(sch_1):m_j_dq(52)"
				( pinPairRef "@baseboard_fab2_lib.baseboard_fab2(sch_1):\PP2359\" )
				( pinPairRef "@baseboard_fab2_lib.baseboard_fab2(sch_1):\PP2361\" )
				( attribute "NO_TEST" "1"
					( Origin gBackEnd )
				)
				( objectStatus "M_J_DQ<52>" )
			)
			( signal "@baseboard_fab2_lib.baseboard_fab2(sch_1):m_j_dq(53)"
				( pinPairRef "@baseboard_fab2_lib.baseboard_fab2(sch_1):\PP2362\" )
				( pinPairRef "@baseboard_fab2_lib.baseboard_fab2(sch_1):\PP2364\" )
				( objectStatus "M_J_DQ<53>" )
			)
			( signal "@baseboard_fab2_lib.baseboard_fab2(sch_1):m_j_dq(54)"
				( pinPairRef "@baseboard_fab2_lib.baseboard_fab2(sch_1):\PP2365\" )
				( pinPairRef "@baseboard_fab2_lib.baseboard_fab2(sch_1):\PP2367\" )
				( objectStatus "M_J_DQ<54>" )
			)
			( signal "@baseboard_fab2_lib.baseboard_fab2(sch_1):m_j_dq(55)"
				( pinPairRef "@baseboard_fab2_lib.baseboard_fab2(sch_1):\PP2368\" )
				( pinPairRef "@baseboard_fab2_lib.baseboard_fab2(sch_1):\PP2370\" )
				( attribute "NO_TEST" "1"
					( Origin gBackEnd )
				)
				( objectStatus "M_J_DQ<55>" )
			)
			( signal "@baseboard_fab2_lib.baseboard_fab2(sch_1):m_j_dq(56)"
				( pinPairRef "@baseboard_fab2_lib.baseboard_fab2(sch_1):\PP2323\" )
				( pinPairRef "@baseboard_fab2_lib.baseboard_fab2(sch_1):\PP2325\" )
				( objectStatus "M_J_DQ<56>" )
			)
			( signal "@baseboard_fab2_lib.baseboard_fab2(sch_1):m_j_dq(57)"
				( pinPairRef "@baseboard_fab2_lib.baseboard_fab2(sch_1):\PP2326\" )
				( pinPairRef "@baseboard_fab2_lib.baseboard_fab2(sch_1):\PP2328\" )
				( attribute "NO_TEST" "1"
					( Origin gBackEnd )
				)
				( objectStatus "M_J_DQ<57>" )
			)
			( signal "@baseboard_fab2_lib.baseboard_fab2(sch_1):m_j_dq(58)"
				( pinPairRef "@baseboard_fab2_lib.baseboard_fab2(sch_1):\PP2329\" )
				( pinPairRef "@baseboard_fab2_lib.baseboard_fab2(sch_1):\PP2331\" )
				( attribute "NO_TEST" "1"
					( Origin gBackEnd )
				)
				( objectStatus "M_J_DQ<58>" )
			)
			( signal "@baseboard_fab2_lib.baseboard_fab2(sch_1):m_j_dq(59)"
				( pinPairRef "@baseboard_fab2_lib.baseboard_fab2(sch_1):\PP2332\" )
				( pinPairRef "@baseboard_fab2_lib.baseboard_fab2(sch_1):\PP2334\" )
				( objectStatus "M_J_DQ<59>" )
			)
			( signal "@baseboard_fab2_lib.baseboard_fab2(sch_1):m_j_dq(60)"
				( pinPairRef "@baseboard_fab2_lib.baseboard_fab2(sch_1):\PP2335\" )
				( pinPairRef "@baseboard_fab2_lib.baseboard_fab2(sch_1):\PP2337\" )
				( attribute "NO_TEST" "1"
					( Origin gBackEnd )
				)
				( objectStatus "M_J_DQ<60>" )
			)
			( signal "@baseboard_fab2_lib.baseboard_fab2(sch_1):m_j_dq(61)"
				( pinPairRef "@baseboard_fab2_lib.baseboard_fab2(sch_1):\PP2338\" )
				( pinPairRef "@baseboard_fab2_lib.baseboard_fab2(sch_1):\PP2340\" )
				( objectStatus "M_J_DQ<61>" )
			)
			( signal "@baseboard_fab2_lib.baseboard_fab2(sch_1):m_j_dq(62)"
				( pinPairRef "@baseboard_fab2_lib.baseboard_fab2(sch_1):\PP2341\" )
				( pinPairRef "@baseboard_fab2_lib.baseboard_fab2(sch_1):\PP2343\" )
				( objectStatus "M_J_DQ<62>" )
			)
			( signal "@baseboard_fab2_lib.baseboard_fab2(sch_1):m_j_dq(63)"
				( pinPairRef "@baseboard_fab2_lib.baseboard_fab2(sch_1):\PP2344\" )
				( pinPairRef "@baseboard_fab2_lib.baseboard_fab2(sch_1):\PP2346\" )
				( attribute "NO_TEST" "1"
					( Origin gBackEnd )
				)
				( objectStatus "M_J_DQ<63>" )
			)
			( signal "@baseboard_fab2_lib.baseboard_fab2(sch_1):m_k_dq(0)"
				( pinPairRef "@baseboard_fab2_lib.baseboard_fab2(sch_1):\PP2275\" )
				( pinPairRef "@baseboard_fab2_lib.baseboard_fab2(sch_1):\PP2276\" )
				( attribute "NO_TEST" "1"
					( Origin gBackEnd )
				)
				( objectStatus "M_K_DQ<0>" )
			)
			( signal "@baseboard_fab2_lib.baseboard_fab2(sch_1):m_k_dq(1)"
				( pinPairRef "@baseboard_fab2_lib.baseboard_fab2(sch_1):\PP2278\" )
				( pinPairRef "@baseboard_fab2_lib.baseboard_fab2(sch_1):\PP2279\" )
				( attribute "NO_TEST" "1"
					( Origin gBackEnd )
				)
				( objectStatus "M_K_DQ<1>" )
			)
			( signal "@baseboard_fab2_lib.baseboard_fab2(sch_1):m_k_dq(2)"
				( pinPairRef "@baseboard_fab2_lib.baseboard_fab2(sch_1):\PP2281\" )
				( pinPairRef "@baseboard_fab2_lib.baseboard_fab2(sch_1):\PP2282\" )
				( attribute "NO_TEST" "1"
					( Origin gBackEnd )
				)
				( objectStatus "M_K_DQ<2>" )
			)
			( signal "@baseboard_fab2_lib.baseboard_fab2(sch_1):m_k_dq(3)"
				( pinPairRef "@baseboard_fab2_lib.baseboard_fab2(sch_1):\PP2284\" )
				( pinPairRef "@baseboard_fab2_lib.baseboard_fab2(sch_1):\PP2285\" )
				( attribute "NO_TEST" "1"
					( Origin gBackEnd )
				)
				( objectStatus "M_K_DQ<3>" )
			)
			( signal "@baseboard_fab2_lib.baseboard_fab2(sch_1):m_k_dq(4)"
				( pinPairRef "@baseboard_fab2_lib.baseboard_fab2(sch_1):\PP2287\" )
				( pinPairRef "@baseboard_fab2_lib.baseboard_fab2(sch_1):\PP2288\" )
				( objectStatus "M_K_DQ<4>" )
			)
			( signal "@baseboard_fab2_lib.baseboard_fab2(sch_1):m_k_dq(5)"
				( pinPairRef "@baseboard_fab2_lib.baseboard_fab2(sch_1):\PP2290\" )
				( pinPairRef "@baseboard_fab2_lib.baseboard_fab2(sch_1):\PP2291\" )
				( objectStatus "M_K_DQ<5>" )
			)
			( signal "@baseboard_fab2_lib.baseboard_fab2(sch_1):m_k_dq(6)"
				( pinPairRef "@baseboard_fab2_lib.baseboard_fab2(sch_1):\PP2293\" )
				( pinPairRef "@baseboard_fab2_lib.baseboard_fab2(sch_1):\PP2294\" )
				( objectStatus "M_K_DQ<6>" )
			)
			( signal "@baseboard_fab2_lib.baseboard_fab2(sch_1):m_k_dq(7)"
				( pinPairRef "@baseboard_fab2_lib.baseboard_fab2(sch_1):\PP2296\" )
				( pinPairRef "@baseboard_fab2_lib.baseboard_fab2(sch_1):\PP2297\" )
				( objectStatus "M_K_DQ<7>" )
			)
			( signal "@baseboard_fab2_lib.baseboard_fab2(sch_1):m_k_dq(8)"
				( pinPairRef "@baseboard_fab2_lib.baseboard_fab2(sch_1):\PP2251\" )
				( pinPairRef "@baseboard_fab2_lib.baseboard_fab2(sch_1):\PP2252\" )
				( attribute "NO_TEST" "1"
					( Origin gBackEnd )
				)
				( objectStatus "M_K_DQ<8>" )
			)
			( signal "@baseboard_fab2_lib.baseboard_fab2(sch_1):m_k_dq(9)"
				( pinPairRef "@baseboard_fab2_lib.baseboard_fab2(sch_1):\PP2254\" )
				( pinPairRef "@baseboard_fab2_lib.baseboard_fab2(sch_1):\PP2255\" )
				( attribute "NO_TEST" "1"
					( Origin gBackEnd )
				)
				( objectStatus "M_K_DQ<9>" )
			)
			( signal "@baseboard_fab2_lib.baseboard_fab2(sch_1):m_k_dq(10)"
				( pinPairRef "@baseboard_fab2_lib.baseboard_fab2(sch_1):\PP2257\" )
				( pinPairRef "@baseboard_fab2_lib.baseboard_fab2(sch_1):\PP2258\" )
				( attribute "NO_TEST" "1"
					( Origin gBackEnd )
				)
				( objectStatus "M_K_DQ<10>" )
			)
			( signal "@baseboard_fab2_lib.baseboard_fab2(sch_1):m_k_dq(11)"
				( pinPairRef "@baseboard_fab2_lib.baseboard_fab2(sch_1):\PP2260\" )
				( pinPairRef "@baseboard_fab2_lib.baseboard_fab2(sch_1):\PP2261\" )
				( attribute "NO_TEST" "1"
					( Origin gBackEnd )
				)
				( objectStatus "M_K_DQ<11>" )
			)
			( signal "@baseboard_fab2_lib.baseboard_fab2(sch_1):m_k_dq(12)"
				( pinPairRef "@baseboard_fab2_lib.baseboard_fab2(sch_1):\PP2263\" )
				( pinPairRef "@baseboard_fab2_lib.baseboard_fab2(sch_1):\PP2264\" )
				( attribute "NO_TEST" "1"
					( Origin gBackEnd )
				)
				( objectStatus "M_K_DQ<12>" )
			)
			( signal "@baseboard_fab2_lib.baseboard_fab2(sch_1):m_k_dq(13)"
				( pinPairRef "@baseboard_fab2_lib.baseboard_fab2(sch_1):\PP2266\" )
				( pinPairRef "@baseboard_fab2_lib.baseboard_fab2(sch_1):\PP2267\" )
				( attribute "NO_TEST" "1"
					( Origin gBackEnd )
				)
				( objectStatus "M_K_DQ<13>" )
			)
			( signal "@baseboard_fab2_lib.baseboard_fab2(sch_1):m_k_dq(14)"
				( pinPairRef "@baseboard_fab2_lib.baseboard_fab2(sch_1):\PP2269\" )
				( pinPairRef "@baseboard_fab2_lib.baseboard_fab2(sch_1):\PP2270\" )
				( attribute "NO_TEST" "1"
					( Origin gBackEnd )
				)
				( objectStatus "M_K_DQ<14>" )
			)
			( signal "@baseboard_fab2_lib.baseboard_fab2(sch_1):m_k_dq(15)"
				( pinPairRef "@baseboard_fab2_lib.baseboard_fab2(sch_1):\PP2272\" )
				( pinPairRef "@baseboard_fab2_lib.baseboard_fab2(sch_1):\PP2273\" )
				( attribute "NO_TEST" "1"
					( Origin gBackEnd )
				)
				( objectStatus "M_K_DQ<15>" )
			)
			( signal "@baseboard_fab2_lib.baseboard_fab2(sch_1):m_k_dq(16)"
				( pinPairRef "@baseboard_fab2_lib.baseboard_fab2(sch_1):\PP2227\" )
				( pinPairRef "@baseboard_fab2_lib.baseboard_fab2(sch_1):\PP2228\" )
				( attribute "NO_TEST" "1"
					( Origin gBackEnd )
				)
				( objectStatus "M_K_DQ<16>" )
			)
			( signal "@baseboard_fab2_lib.baseboard_fab2(sch_1):m_k_dq(17)"
				( pinPairRef "@baseboard_fab2_lib.baseboard_fab2(sch_1):\PP2230\" )
				( pinPairRef "@baseboard_fab2_lib.baseboard_fab2(sch_1):\PP2231\" )
				( objectStatus "M_K_DQ<17>" )
			)
			( signal "@baseboard_fab2_lib.baseboard_fab2(sch_1):m_k_dq(18)"
				( pinPairRef "@baseboard_fab2_lib.baseboard_fab2(sch_1):\PP2233\" )
				( pinPairRef "@baseboard_fab2_lib.baseboard_fab2(sch_1):\PP2234\" )
				( objectStatus "M_K_DQ<18>" )
			)
			( signal "@baseboard_fab2_lib.baseboard_fab2(sch_1):m_k_dq(19)"
				( pinPairRef "@baseboard_fab2_lib.baseboard_fab2(sch_1):\PP2236\" )
				( pinPairRef "@baseboard_fab2_lib.baseboard_fab2(sch_1):\PP2237\" )
				( attribute "NO_TEST" "1"
					( Origin gBackEnd )
				)
				( objectStatus "M_K_DQ<19>" )
			)
			( signal "@baseboard_fab2_lib.baseboard_fab2(sch_1):m_k_dq(20)"
				( pinPairRef "@baseboard_fab2_lib.baseboard_fab2(sch_1):\PP2239\" )
				( pinPairRef "@baseboard_fab2_lib.baseboard_fab2(sch_1):\PP2240\" )
				( objectStatus "M_K_DQ<20>" )
			)
			( signal "@baseboard_fab2_lib.baseboard_fab2(sch_1):m_k_dq(21)"
				( pinPairRef "@baseboard_fab2_lib.baseboard_fab2(sch_1):\PP2242\" )
				( pinPairRef "@baseboard_fab2_lib.baseboard_fab2(sch_1):\PP2243\" )
				( attribute "NO_TEST" "1"
					( Origin gBackEnd )
				)
				( objectStatus "M_K_DQ<21>" )
			)
			( signal "@baseboard_fab2_lib.baseboard_fab2(sch_1):m_k_dq(22)"
				( pinPairRef "@baseboard_fab2_lib.baseboard_fab2(sch_1):\PP2245\" )
				( pinPairRef "@baseboard_fab2_lib.baseboard_fab2(sch_1):\PP2246\" )
				( attribute "NO_TEST" "1"
					( Origin gBackEnd )
				)
				( objectStatus "M_K_DQ<22>" )
			)
			( signal "@baseboard_fab2_lib.baseboard_fab2(sch_1):m_k_dq(23)"
				( pinPairRef "@baseboard_fab2_lib.baseboard_fab2(sch_1):\PP2248\" )
				( pinPairRef "@baseboard_fab2_lib.baseboard_fab2(sch_1):\PP2249\" )
				( objectStatus "M_K_DQ<23>" )
			)
			( signal "@baseboard_fab2_lib.baseboard_fab2(sch_1):m_k_dq(24)"
				( pinPairRef "@baseboard_fab2_lib.baseboard_fab2(sch_1):\PP2203\" )
				( pinPairRef "@baseboard_fab2_lib.baseboard_fab2(sch_1):\PP2204\" )
				( objectStatus "M_K_DQ<24>" )
			)
			( signal "@baseboard_fab2_lib.baseboard_fab2(sch_1):m_k_dq(25)"
				( pinPairRef "@baseboard_fab2_lib.baseboard_fab2(sch_1):\PP2206\" )
				( pinPairRef "@baseboard_fab2_lib.baseboard_fab2(sch_1):\PP2207\" )
				( attribute "NO_TEST" "1"
					( Origin gBackEnd )
				)
				( objectStatus "M_K_DQ<25>" )
			)
			( signal "@baseboard_fab2_lib.baseboard_fab2(sch_1):m_k_dq(26)"
				( pinPairRef "@baseboard_fab2_lib.baseboard_fab2(sch_1):\PP2209\" )
				( pinPairRef "@baseboard_fab2_lib.baseboard_fab2(sch_1):\PP2210\" )
				( attribute "NO_TEST" "1"
					( Origin gBackEnd )
				)
				( objectStatus "M_K_DQ<26>" )
			)
			( signal "@baseboard_fab2_lib.baseboard_fab2(sch_1):m_k_dq(27)"
				( pinPairRef "@baseboard_fab2_lib.baseboard_fab2(sch_1):\PP2212\" )
				( pinPairRef "@baseboard_fab2_lib.baseboard_fab2(sch_1):\PP2213\" )
				( objectStatus "M_K_DQ<27>" )
			)
			( signal "@baseboard_fab2_lib.baseboard_fab2(sch_1):m_k_dq(28)"
				( pinPairRef "@baseboard_fab2_lib.baseboard_fab2(sch_1):\PP2215\" )
				( pinPairRef "@baseboard_fab2_lib.baseboard_fab2(sch_1):\PP2216\" )
				( attribute "NO_TEST" "1"
					( Origin gBackEnd )
				)
				( objectStatus "M_K_DQ<28>" )
			)
			( signal "@baseboard_fab2_lib.baseboard_fab2(sch_1):m_k_dq(29)"
				( pinPairRef "@baseboard_fab2_lib.baseboard_fab2(sch_1):\PP2218\" )
				( pinPairRef "@baseboard_fab2_lib.baseboard_fab2(sch_1):\PP2219\" )
				( objectStatus "M_K_DQ<29>" )
			)
			( signal "@baseboard_fab2_lib.baseboard_fab2(sch_1):m_k_dq(30)"
				( pinPairRef "@baseboard_fab2_lib.baseboard_fab2(sch_1):\PP2221\" )
				( pinPairRef "@baseboard_fab2_lib.baseboard_fab2(sch_1):\PP2222\" )
				( objectStatus "M_K_DQ<30>" )
			)
			( signal "@baseboard_fab2_lib.baseboard_fab2(sch_1):m_k_dq(31)"
				( pinPairRef "@baseboard_fab2_lib.baseboard_fab2(sch_1):\PP2224\" )
				( pinPairRef "@baseboard_fab2_lib.baseboard_fab2(sch_1):\PP2225\" )
				( attribute "NO_TEST" "1"
					( Origin gBackEnd )
				)
				( objectStatus "M_K_DQ<31>" )
			)
			( signal "@baseboard_fab2_lib.baseboard_fab2(sch_1):m_k_dq(32)"
				( pinPairRef "@baseboard_fab2_lib.baseboard_fab2(sch_1):\PP2179\" )
				( pinPairRef "@baseboard_fab2_lib.baseboard_fab2(sch_1):\PP2181\" )
				( attribute "NO_TEST" "1"
					( Origin gBackEnd )
				)
				( objectStatus "M_K_DQ<32>" )
			)
			( signal "@baseboard_fab2_lib.baseboard_fab2(sch_1):m_k_dq(33)"
				( pinPairRef "@baseboard_fab2_lib.baseboard_fab2(sch_1):\PP2182\" )
				( pinPairRef "@baseboard_fab2_lib.baseboard_fab2(sch_1):\PP2184\" )
				( attribute "NO_TEST" "1"
					( Origin gBackEnd )
				)
				( objectStatus "M_K_DQ<33>" )
			)
			( signal "@baseboard_fab2_lib.baseboard_fab2(sch_1):m_k_dq(34)"
				( pinPairRef "@baseboard_fab2_lib.baseboard_fab2(sch_1):\PP2185\" )
				( pinPairRef "@baseboard_fab2_lib.baseboard_fab2(sch_1):\PP2187\" )
				( attribute "NO_TEST" "1"
					( Origin gBackEnd )
				)
				( objectStatus "M_K_DQ<34>" )
			)
			( signal "@baseboard_fab2_lib.baseboard_fab2(sch_1):m_k_dq(35)"
				( pinPairRef "@baseboard_fab2_lib.baseboard_fab2(sch_1):\PP2188\" )
				( pinPairRef "@baseboard_fab2_lib.baseboard_fab2(sch_1):\PP2190\" )
				( attribute "NO_TEST" "1"
					( Origin gBackEnd )
				)
				( objectStatus "M_K_DQ<35>" )
			)
			( signal "@baseboard_fab2_lib.baseboard_fab2(sch_1):m_k_dq(36)"
				( pinPairRef "@baseboard_fab2_lib.baseboard_fab2(sch_1):\PP2191\" )
				( pinPairRef "@baseboard_fab2_lib.baseboard_fab2(sch_1):\PP2193\" )
				( attribute "NO_TEST" "1"
					( Origin gBackEnd )
				)
				( objectStatus "M_K_DQ<36>" )
			)
			( signal "@baseboard_fab2_lib.baseboard_fab2(sch_1):m_k_dq(37)"
				( pinPairRef "@baseboard_fab2_lib.baseboard_fab2(sch_1):\PP2194\" )
				( pinPairRef "@baseboard_fab2_lib.baseboard_fab2(sch_1):\PP2196\" )
				( attribute "NO_TEST" "1"
					( Origin gBackEnd )
				)
				( objectStatus "M_K_DQ<37>" )
			)
			( signal "@baseboard_fab2_lib.baseboard_fab2(sch_1):m_k_dq(38)"
				( pinPairRef "@baseboard_fab2_lib.baseboard_fab2(sch_1):\PP2197\" )
				( pinPairRef "@baseboard_fab2_lib.baseboard_fab2(sch_1):\PP2199\" )
				( attribute "NO_TEST" "1"
					( Origin gBackEnd )
				)
				( objectStatus "M_K_DQ<38>" )
			)
			( signal "@baseboard_fab2_lib.baseboard_fab2(sch_1):m_k_dq(39)"
				( pinPairRef "@baseboard_fab2_lib.baseboard_fab2(sch_1):\PP2200\" )
				( pinPairRef "@baseboard_fab2_lib.baseboard_fab2(sch_1):\PP2202\" )
				( attribute "NO_TEST" "1"
					( Origin gBackEnd )
				)
				( objectStatus "M_K_DQ<39>" )
			)
			( signal "@baseboard_fab2_lib.baseboard_fab2(sch_1):m_k_dq(40)"
				( pinPairRef "@baseboard_fab2_lib.baseboard_fab2(sch_1):\PP2155\" )
				( pinPairRef "@baseboard_fab2_lib.baseboard_fab2(sch_1):\PP2157\" )
				( attribute "NO_TEST" "1"
					( Origin gBackEnd )
				)
				( objectStatus "M_K_DQ<40>" )
			)
			( signal "@baseboard_fab2_lib.baseboard_fab2(sch_1):m_k_dq(41)"
				( pinPairRef "@baseboard_fab2_lib.baseboard_fab2(sch_1):\PP2158\" )
				( pinPairRef "@baseboard_fab2_lib.baseboard_fab2(sch_1):\PP2160\" )
				( objectStatus "M_K_DQ<41>" )
			)
			( signal "@baseboard_fab2_lib.baseboard_fab2(sch_1):m_k_dq(42)"
				( pinPairRef "@baseboard_fab2_lib.baseboard_fab2(sch_1):\PP2161\" )
				( pinPairRef "@baseboard_fab2_lib.baseboard_fab2(sch_1):\PP2163\" )
				( objectStatus "M_K_DQ<42>" )
			)
			( signal "@baseboard_fab2_lib.baseboard_fab2(sch_1):m_k_dq(43)"
				( pinPairRef "@baseboard_fab2_lib.baseboard_fab2(sch_1):\PP2164\" )
				( pinPairRef "@baseboard_fab2_lib.baseboard_fab2(sch_1):\PP2166\" )
				( attribute "NO_TEST" "1"
					( Origin gBackEnd )
				)
				( objectStatus "M_K_DQ<43>" )
			)
			( signal "@baseboard_fab2_lib.baseboard_fab2(sch_1):m_k_dq(44)"
				( pinPairRef "@baseboard_fab2_lib.baseboard_fab2(sch_1):\PP2167\" )
				( pinPairRef "@baseboard_fab2_lib.baseboard_fab2(sch_1):\PP2169\" )
				( objectStatus "M_K_DQ<44>" )
			)
			( signal "@baseboard_fab2_lib.baseboard_fab2(sch_1):m_k_dq(45)"
				( pinPairRef "@baseboard_fab2_lib.baseboard_fab2(sch_1):\PP2170\" )
				( pinPairRef "@baseboard_fab2_lib.baseboard_fab2(sch_1):\PP2172\" )
				( attribute "NO_TEST" "1"
					( Origin gBackEnd )
				)
				( objectStatus "M_K_DQ<45>" )
			)
			( signal "@baseboard_fab2_lib.baseboard_fab2(sch_1):m_k_dq(46)"
				( pinPairRef "@baseboard_fab2_lib.baseboard_fab2(sch_1):\PP2173\" )
				( pinPairRef "@baseboard_fab2_lib.baseboard_fab2(sch_1):\PP2175\" )
				( attribute "NO_TEST" "1"
					( Origin gBackEnd )
				)
				( objectStatus "M_K_DQ<46>" )
			)
			( signal "@baseboard_fab2_lib.baseboard_fab2(sch_1):m_k_dq(47)"
				( pinPairRef "@baseboard_fab2_lib.baseboard_fab2(sch_1):\PP2176\" )
				( pinPairRef "@baseboard_fab2_lib.baseboard_fab2(sch_1):\PP2178\" )
				( objectStatus "M_K_DQ<47>" )
			)
			( signal "@baseboard_fab2_lib.baseboard_fab2(sch_1):m_k_dq(48)"
				( pinPairRef "@baseboard_fab2_lib.baseboard_fab2(sch_1):\PP2131\" )
				( pinPairRef "@baseboard_fab2_lib.baseboard_fab2(sch_1):\PP2133\" )
				( attribute "NO_TEST" "1"
					( Origin gBackEnd )
				)
				( objectStatus "M_K_DQ<48>" )
			)
			( signal "@baseboard_fab2_lib.baseboard_fab2(sch_1):m_k_dq(49)"
				( pinPairRef "@baseboard_fab2_lib.baseboard_fab2(sch_1):\PP2134\" )
				( pinPairRef "@baseboard_fab2_lib.baseboard_fab2(sch_1):\PP2136\" )
				( attribute "NO_TEST" "1"
					( Origin gBackEnd )
				)
				( objectStatus "M_K_DQ<49>" )
			)
			( signal "@baseboard_fab2_lib.baseboard_fab2(sch_1):m_k_dq(50)"
				( pinPairRef "@baseboard_fab2_lib.baseboard_fab2(sch_1):\PP2137\" )
				( pinPairRef "@baseboard_fab2_lib.baseboard_fab2(sch_1):\PP2139\" )
				( objectStatus "M_K_DQ<50>" )
			)
			( signal "@baseboard_fab2_lib.baseboard_fab2(sch_1):m_k_dq(51)"
				( pinPairRef "@baseboard_fab2_lib.baseboard_fab2(sch_1):\PP2140\" )
				( pinPairRef "@baseboard_fab2_lib.baseboard_fab2(sch_1):\PP2142\" )
				( attribute "NO_TEST" "1"
					( Origin gBackEnd )
				)
				( objectStatus "M_K_DQ<51>" )
			)
			( signal "@baseboard_fab2_lib.baseboard_fab2(sch_1):m_k_dq(52)"
				( pinPairRef "@baseboard_fab2_lib.baseboard_fab2(sch_1):\PP2143\" )
				( pinPairRef "@baseboard_fab2_lib.baseboard_fab2(sch_1):\PP2145\" )
				( objectStatus "M_K_DQ<52>" )
			)
			( signal "@baseboard_fab2_lib.baseboard_fab2(sch_1):m_k_dq(53)"
				( pinPairRef "@baseboard_fab2_lib.baseboard_fab2(sch_1):\PP2146\" )
				( pinPairRef "@baseboard_fab2_lib.baseboard_fab2(sch_1):\PP2148\" )
				( attribute "NO_TEST" "1"
					( Origin gBackEnd )
				)
				( objectStatus "M_K_DQ<53>" )
			)
			( signal "@baseboard_fab2_lib.baseboard_fab2(sch_1):m_k_dq(54)"
				( pinPairRef "@baseboard_fab2_lib.baseboard_fab2(sch_1):\PP2149\" )
				( pinPairRef "@baseboard_fab2_lib.baseboard_fab2(sch_1):\PP2151\" )
				( attribute "NO_TEST" "1"
					( Origin gBackEnd )
				)
				( objectStatus "M_K_DQ<54>" )
			)
			( signal "@baseboard_fab2_lib.baseboard_fab2(sch_1):m_k_dq(55)"
				( pinPairRef "@baseboard_fab2_lib.baseboard_fab2(sch_1):\PP2152\" )
				( pinPairRef "@baseboard_fab2_lib.baseboard_fab2(sch_1):\PP2154\" )
				( attribute "NO_TEST" "1"
					( Origin gBackEnd )
				)
				( objectStatus "M_K_DQ<55>" )
			)
			( signal "@baseboard_fab2_lib.baseboard_fab2(sch_1):m_k_dq(56)"
				( pinPairRef "@baseboard_fab2_lib.baseboard_fab2(sch_1):\PP2107\" )
				( pinPairRef "@baseboard_fab2_lib.baseboard_fab2(sch_1):\PP2109\" )
				( attribute "NO_TEST" "1"
					( Origin gBackEnd )
				)
				( objectStatus "M_K_DQ<56>" )
			)
			( signal "@baseboard_fab2_lib.baseboard_fab2(sch_1):m_g_dq(45)"
				( pinPairRef "@baseboard_fab2_lib.baseboard_fab2(sch_1):\PP2818\" )
				( pinPairRef "@baseboard_fab2_lib.baseboard_fab2(sch_1):\PP2820\" )
				( objectStatus "M_G_DQ<45>" )
			)
			( signal "@baseboard_fab2_lib.baseboard_fab2(sch_1):m_g_dq(46)"
				( pinPairRef "@baseboard_fab2_lib.baseboard_fab2(sch_1):\PP2821\" )
				( pinPairRef "@baseboard_fab2_lib.baseboard_fab2(sch_1):\PP2823\" )
				( attribute "NO_TEST" "1"
					( Origin gBackEnd )
				)
				( objectStatus "M_G_DQ<46>" )
			)
			( signal "@baseboard_fab2_lib.baseboard_fab2(sch_1):m_g_dq(47)"
				( pinPairRef "@baseboard_fab2_lib.baseboard_fab2(sch_1):\PP2824\" )
				( pinPairRef "@baseboard_fab2_lib.baseboard_fab2(sch_1):\PP2826\" )
				( attribute "NO_TEST" "1"
					( Origin gBackEnd )
				)
				( objectStatus "M_G_DQ<47>" )
			)
			( signal "@baseboard_fab2_lib.baseboard_fab2(sch_1):m_g_dq(48)"
				( pinPairRef "@baseboard_fab2_lib.baseboard_fab2(sch_1):\PP2779\" )
				( pinPairRef "@baseboard_fab2_lib.baseboard_fab2(sch_1):\PP2781\" )
				( objectStatus "M_G_DQ<48>" )
			)
			( signal "@baseboard_fab2_lib.baseboard_fab2(sch_1):m_g_dq(49)"
				( pinPairRef "@baseboard_fab2_lib.baseboard_fab2(sch_1):\PP2782\" )
				( pinPairRef "@baseboard_fab2_lib.baseboard_fab2(sch_1):\PP2784\" )
				( attribute "NO_TEST" "1"
					( Origin gBackEnd )
				)
				( objectStatus "M_G_DQ<49>" )
			)
			( signal "@baseboard_fab2_lib.baseboard_fab2(sch_1):m_g_dq(50)"
				( pinPairRef "@baseboard_fab2_lib.baseboard_fab2(sch_1):\PP2785\" )
				( pinPairRef "@baseboard_fab2_lib.baseboard_fab2(sch_1):\PP2787\" )
				( attribute "NO_TEST" "1"
					( Origin gBackEnd )
				)
				( objectStatus "M_G_DQ<50>" )
			)
			( signal "@baseboard_fab2_lib.baseboard_fab2(sch_1):m_g_dq(51)"
				( pinPairRef "@baseboard_fab2_lib.baseboard_fab2(sch_1):\PP2788\" )
				( pinPairRef "@baseboard_fab2_lib.baseboard_fab2(sch_1):\PP2790\" )
				( objectStatus "M_G_DQ<51>" )
			)
			( signal "@baseboard_fab2_lib.baseboard_fab2(sch_1):m_g_dq(52)"
				( pinPairRef "@baseboard_fab2_lib.baseboard_fab2(sch_1):\PP2791\" )
				( pinPairRef "@baseboard_fab2_lib.baseboard_fab2(sch_1):\PP2793\" )
				( attribute "NO_TEST" "1"
					( Origin gBackEnd )
				)
				( objectStatus "M_G_DQ<52>" )
			)
			( signal "@baseboard_fab2_lib.baseboard_fab2(sch_1):m_g_dq(53)"
				( pinPairRef "@baseboard_fab2_lib.baseboard_fab2(sch_1):\PP2794\" )
				( pinPairRef "@baseboard_fab2_lib.baseboard_fab2(sch_1):\PP2796\" )
				( objectStatus "M_G_DQ<53>" )
			)
			( signal "@baseboard_fab2_lib.baseboard_fab2(sch_1):m_g_dq(54)"
				( pinPairRef "@baseboard_fab2_lib.baseboard_fab2(sch_1):\PP2797\" )
				( pinPairRef "@baseboard_fab2_lib.baseboard_fab2(sch_1):\PP2799\" )
				( objectStatus "M_G_DQ<54>" )
			)
			( signal "@baseboard_fab2_lib.baseboard_fab2(sch_1):m_g_dq(55)"
				( pinPairRef "@baseboard_fab2_lib.baseboard_fab2(sch_1):\PP2800\" )
				( pinPairRef "@baseboard_fab2_lib.baseboard_fab2(sch_1):\PP2802\" )
				( attribute "NO_TEST" "1"
					( Origin gBackEnd )
				)
				( objectStatus "M_G_DQ<55>" )
			)
			( signal "@baseboard_fab2_lib.baseboard_fab2(sch_1):m_g_dq(56)"
				( pinPairRef "@baseboard_fab2_lib.baseboard_fab2(sch_1):\PP2755\" )
				( pinPairRef "@baseboard_fab2_lib.baseboard_fab2(sch_1):\PP2757\" )
				( objectStatus "M_G_DQ<56>" )
			)
			( signal "@baseboard_fab2_lib.baseboard_fab2(sch_1):m_g_dq(57)"
				( pinPairRef "@baseboard_fab2_lib.baseboard_fab2(sch_1):\PP2758\" )
				( pinPairRef "@baseboard_fab2_lib.baseboard_fab2(sch_1):\PP2760\" )
				( attribute "NO_TEST" "1"
					( Origin gBackEnd )
				)
				( objectStatus "M_G_DQ<57>" )
			)
			( signal "@baseboard_fab2_lib.baseboard_fab2(sch_1):m_g_dq(58)"
				( pinPairRef "@baseboard_fab2_lib.baseboard_fab2(sch_1):\PP2761\" )
				( pinPairRef "@baseboard_fab2_lib.baseboard_fab2(sch_1):\PP2763\" )
				( attribute "NO_TEST" "1"
					( Origin gBackEnd )
				)
				( objectStatus "M_G_DQ<58>" )
			)
			( signal "@baseboard_fab2_lib.baseboard_fab2(sch_1):m_g_dq(59)"
				( pinPairRef "@baseboard_fab2_lib.baseboard_fab2(sch_1):\PP2764\" )
				( pinPairRef "@baseboard_fab2_lib.baseboard_fab2(sch_1):\PP2766\" )
				( objectStatus "M_G_DQ<59>" )
			)
			( signal "@baseboard_fab2_lib.baseboard_fab2(sch_1):m_g_dq(60)"
				( pinPairRef "@baseboard_fab2_lib.baseboard_fab2(sch_1):\PP2767\" )
				( pinPairRef "@baseboard_fab2_lib.baseboard_fab2(sch_1):\PP2769\" )
				( attribute "NO_TEST" "1"
					( Origin gBackEnd )
				)
				( objectStatus "M_G_DQ<60>" )
			)
			( signal "@baseboard_fab2_lib.baseboard_fab2(sch_1):m_g_dq(61)"
				( pinPairRef "@baseboard_fab2_lib.baseboard_fab2(sch_1):\PP2770\" )
				( pinPairRef "@baseboard_fab2_lib.baseboard_fab2(sch_1):\PP2772\" )
				( objectStatus "M_G_DQ<61>" )
			)
			( signal "@baseboard_fab2_lib.baseboard_fab2(sch_1):m_g_dq(62)"
				( pinPairRef "@baseboard_fab2_lib.baseboard_fab2(sch_1):\PP2773\" )
				( pinPairRef "@baseboard_fab2_lib.baseboard_fab2(sch_1):\PP2775\" )
				( objectStatus "M_G_DQ<62>" )
			)
			( signal "@baseboard_fab2_lib.baseboard_fab2(sch_1):m_g_dq(63)"
				( pinPairRef "@baseboard_fab2_lib.baseboard_fab2(sch_1):\PP2776\" )
				( pinPairRef "@baseboard_fab2_lib.baseboard_fab2(sch_1):\PP2778\" )
				( attribute "NO_TEST" "1"
					( Origin gBackEnd )
				)
				( objectStatus "M_G_DQ<63>" )
			)
			( signal "@baseboard_fab2_lib.baseboard_fab2(sch_1):m_h_dq(0)"
				( pinPairRef "@baseboard_fab2_lib.baseboard_fab2(sch_1):\PP2707\" )
				( pinPairRef "@baseboard_fab2_lib.baseboard_fab2(sch_1):\PP2708\" )
				( attribute "NO_TEST" "1"
					( Origin gBackEnd )
				)
				( objectStatus "M_H_DQ<0>" )
			)
			( signal "@baseboard_fab2_lib.baseboard_fab2(sch_1):m_h_dq(1)"
				( pinPairRef "@baseboard_fab2_lib.baseboard_fab2(sch_1):\PP2710\" )
				( pinPairRef "@baseboard_fab2_lib.baseboard_fab2(sch_1):\PP2711\" )
				( attribute "NO_TEST" "1"
					( Origin gBackEnd )
				)
				( objectStatus "M_H_DQ<1>" )
			)
			( signal "@baseboard_fab2_lib.baseboard_fab2(sch_1):m_h_dq(2)"
				( pinPairRef "@baseboard_fab2_lib.baseboard_fab2(sch_1):\PP2713\" )
				( pinPairRef "@baseboard_fab2_lib.baseboard_fab2(sch_1):\PP2714\" )
				( objectStatus "M_H_DQ<2>" )
			)
			( signal "@baseboard_fab2_lib.baseboard_fab2(sch_1):m_h_dq(3)"
				( pinPairRef "@baseboard_fab2_lib.baseboard_fab2(sch_1):\PP2716\" )
				( pinPairRef "@baseboard_fab2_lib.baseboard_fab2(sch_1):\PP2717\" )
				( attribute "NO_TEST" "1"
					( Origin gBackEnd )
				)
				( objectStatus "M_H_DQ<3>" )
			)
			( signal "@baseboard_fab2_lib.baseboard_fab2(sch_1):m_h_dq(4)"
				( pinPairRef "@baseboard_fab2_lib.baseboard_fab2(sch_1):\PP2719\" )
				( pinPairRef "@baseboard_fab2_lib.baseboard_fab2(sch_1):\PP2720\" )
				( attribute "NO_TEST" "1"
					( Origin gBackEnd )
				)
				( objectStatus "M_H_DQ<4>" )
			)
			( signal "@baseboard_fab2_lib.baseboard_fab2(sch_1):m_h_dq(5)"
				( pinPairRef "@baseboard_fab2_lib.baseboard_fab2(sch_1):\PP2722\" )
				( pinPairRef "@baseboard_fab2_lib.baseboard_fab2(sch_1):\PP2723\" )
				( objectStatus "M_H_DQ<5>" )
			)
			( signal "@baseboard_fab2_lib.baseboard_fab2(sch_1):m_h_dq(6)"
				( pinPairRef "@baseboard_fab2_lib.baseboard_fab2(sch_1):\PP2725\" )
				( pinPairRef "@baseboard_fab2_lib.baseboard_fab2(sch_1):\PP2726\" )
				( attribute "NO_TEST" "1"
					( Origin gBackEnd )
				)
				( objectStatus "M_H_DQ<6>" )
			)
			( signal "@baseboard_fab2_lib.baseboard_fab2(sch_1):m_h_dq(7)"
				( pinPairRef "@baseboard_fab2_lib.baseboard_fab2(sch_1):\PP2728\" )
				( pinPairRef "@baseboard_fab2_lib.baseboard_fab2(sch_1):\PP2729\" )
				( attribute "NO_TEST" "1"
					( Origin gBackEnd )
				)
				( objectStatus "M_H_DQ<7>" )
			)
			( signal "@baseboard_fab2_lib.baseboard_fab2(sch_1):m_h_dq(8)"
				( pinPairRef "@baseboard_fab2_lib.baseboard_fab2(sch_1):\PP2683\" )
				( pinPairRef "@baseboard_fab2_lib.baseboard_fab2(sch_1):\PP2684\" )
				( attribute "NO_TEST" "1"
					( Origin gBackEnd )
				)
				( objectStatus "M_H_DQ<8>" )
			)
			( signal "@baseboard_fab2_lib.baseboard_fab2(sch_1):m_h_dq(9)"
				( pinPairRef "@baseboard_fab2_lib.baseboard_fab2(sch_1):\PP2686\" )
				( pinPairRef "@baseboard_fab2_lib.baseboard_fab2(sch_1):\PP2687\" )
				( attribute "NO_TEST" "1"
					( Origin gBackEnd )
				)
				( objectStatus "M_H_DQ<9>" )
			)
			( signal "@baseboard_fab2_lib.baseboard_fab2(sch_1):m_h_dq(10)"
				( pinPairRef "@baseboard_fab2_lib.baseboard_fab2(sch_1):\PP2689\" )
				( pinPairRef "@baseboard_fab2_lib.baseboard_fab2(sch_1):\PP2690\" )
				( attribute "NO_TEST" "1"
					( Origin gBackEnd )
				)
				( objectStatus "M_H_DQ<10>" )
			)
			( signal "@baseboard_fab2_lib.baseboard_fab2(sch_1):m_h_dq(11)"
				( pinPairRef "@baseboard_fab2_lib.baseboard_fab2(sch_1):\PP2692\" )
				( pinPairRef "@baseboard_fab2_lib.baseboard_fab2(sch_1):\PP2693\" )
				( objectStatus "M_H_DQ<11>" )
			)
			( signal "@baseboard_fab2_lib.baseboard_fab2(sch_1):m_h_dq(12)"
				( pinPairRef "@baseboard_fab2_lib.baseboard_fab2(sch_1):\PP2695\" )
				( pinPairRef "@baseboard_fab2_lib.baseboard_fab2(sch_1):\PP2696\" )
				( objectStatus "M_H_DQ<12>" )
			)
			( signal "@baseboard_fab2_lib.baseboard_fab2(sch_1):m_h_dq(17)"
				( pinPairRef "@baseboard_fab2_lib.baseboard_fab2(sch_1):\PP2662\" )
				( pinPairRef "@baseboard_fab2_lib.baseboard_fab2(sch_1):\PP2663\" )
				( attribute "NO_TEST" "1"
					( Origin gBackEnd )
				)
				( objectStatus "M_H_DQ<17>" )
			)
			( signal "@baseboard_fab2_lib.baseboard_fab2(sch_1):m_h_dq(18)"
				( pinPairRef "@baseboard_fab2_lib.baseboard_fab2(sch_1):\PP2665\" )
				( pinPairRef "@baseboard_fab2_lib.baseboard_fab2(sch_1):\PP2666\" )
				( objectStatus "M_H_DQ<18>" )
			)
			( signal "@baseboard_fab2_lib.baseboard_fab2(sch_1):m_h_dq(19)"
				( pinPairRef "@baseboard_fab2_lib.baseboard_fab2(sch_1):\PP2668\" )
				( pinPairRef "@baseboard_fab2_lib.baseboard_fab2(sch_1):\PP2669\" )
				( attribute "NO_TEST" "1"
					( Origin gBackEnd )
				)
				( objectStatus "M_H_DQ<19>" )
			)
			( signal "@baseboard_fab2_lib.baseboard_fab2(sch_1):m_h_dq(20)"
				( pinPairRef "@baseboard_fab2_lib.baseboard_fab2(sch_1):\PP2671\" )
				( pinPairRef "@baseboard_fab2_lib.baseboard_fab2(sch_1):\PP2672\" )
				( attribute "NO_TEST" "1"
					( Origin gBackEnd )
				)
				( objectStatus "M_H_DQ<20>" )
			)
			( signal "@baseboard_fab2_lib.baseboard_fab2(sch_1):m_h_dq(21)"
				( pinPairRef "@baseboard_fab2_lib.baseboard_fab2(sch_1):\PP2674\" )
				( pinPairRef "@baseboard_fab2_lib.baseboard_fab2(sch_1):\PP2675\" )
				( objectStatus "M_H_DQ<21>" )
			)
			( signal "@baseboard_fab2_lib.baseboard_fab2(sch_1):m_h_dq(22)"
				( pinPairRef "@baseboard_fab2_lib.baseboard_fab2(sch_1):\PP2677\" )
				( pinPairRef "@baseboard_fab2_lib.baseboard_fab2(sch_1):\PP2678\" )
				( attribute "NO_TEST" "1"
					( Origin gBackEnd )
				)
				( objectStatus "M_H_DQ<22>" )
			)
			( signal "@baseboard_fab2_lib.baseboard_fab2(sch_1):m_h_dq(23)"
				( pinPairRef "@baseboard_fab2_lib.baseboard_fab2(sch_1):\PP2680\" )
				( pinPairRef "@baseboard_fab2_lib.baseboard_fab2(sch_1):\PP2681\" )
				( attribute "NO_TEST" "1"
					( Origin gBackEnd )
				)
				( objectStatus "M_H_DQ<23>" )
			)
			( signal "@baseboard_fab2_lib.baseboard_fab2(sch_1):m_h_dq(24)"
				( pinPairRef "@baseboard_fab2_lib.baseboard_fab2(sch_1):\PP2635\" )
				( pinPairRef "@baseboard_fab2_lib.baseboard_fab2(sch_1):\PP2636\" )
				( objectStatus "M_H_DQ<24>" )
			)
			( signal "@baseboard_fab2_lib.baseboard_fab2(sch_1):m_h_dq(25)"
				( pinPairRef "@baseboard_fab2_lib.baseboard_fab2(sch_1):\PP2638\" )
				( pinPairRef "@baseboard_fab2_lib.baseboard_fab2(sch_1):\PP2639\" )
				( objectStatus "M_H_DQ<25>" )
			)
			( signal "@baseboard_fab2_lib.baseboard_fab2(sch_1):m_h_dq(26)"
				( pinPairRef "@baseboard_fab2_lib.baseboard_fab2(sch_1):\PP2641\" )
				( pinPairRef "@baseboard_fab2_lib.baseboard_fab2(sch_1):\PP2642\" )
				( objectStatus "M_H_DQ<26>" )
			)
			( signal "@baseboard_fab2_lib.baseboard_fab2(sch_1):m_h_dq(27)"
				( pinPairRef "@baseboard_fab2_lib.baseboard_fab2(sch_1):\PP2644\" )
				( pinPairRef "@baseboard_fab2_lib.baseboard_fab2(sch_1):\PP2645\" )
				( objectStatus "M_H_DQ<27>" )
			)
			( signal "@baseboard_fab2_lib.baseboard_fab2(sch_1):m_h_dq(28)"
				( pinPairRef "@baseboard_fab2_lib.baseboard_fab2(sch_1):\PP2647\" )
				( pinPairRef "@baseboard_fab2_lib.baseboard_fab2(sch_1):\PP2648\" )
				( objectStatus "M_H_DQ<28>" )
			)
			( signal "@baseboard_fab2_lib.baseboard_fab2(sch_1):m_h_dq(29)"
				( pinPairRef "@baseboard_fab2_lib.baseboard_fab2(sch_1):\PP2650\" )
				( pinPairRef "@baseboard_fab2_lib.baseboard_fab2(sch_1):\PP2651\" )
				( objectStatus "M_H_DQ<29>" )
			)
			( signal "@baseboard_fab2_lib.baseboard_fab2(sch_1):m_h_dq(30)"
				( pinPairRef "@baseboard_fab2_lib.baseboard_fab2(sch_1):\PP2653\" )
				( pinPairRef "@baseboard_fab2_lib.baseboard_fab2(sch_1):\PP2654\" )
				( objectStatus "M_H_DQ<30>" )
			)
			( signal "@baseboard_fab2_lib.baseboard_fab2(sch_1):m_h_dq(31)"
				( pinPairRef "@baseboard_fab2_lib.baseboard_fab2(sch_1):\PP2656\" )
				( pinPairRef "@baseboard_fab2_lib.baseboard_fab2(sch_1):\PP2657\" )
				( objectStatus "M_H_DQ<31>" )
			)
			( signal "@baseboard_fab2_lib.baseboard_fab2(sch_1):m_h_dq(32)"
				( pinPairRef "@baseboard_fab2_lib.baseboard_fab2(sch_1):\PP2611\" )
				( pinPairRef "@baseboard_fab2_lib.baseboard_fab2(sch_1):\PP2613\" )
				( attribute "NO_TEST" "1"
					( Origin gBackEnd )
				)
				( objectStatus "M_H_DQ<32>" )
			)
			( signal "@baseboard_fab2_lib.baseboard_fab2(sch_1):m_h_dq(33)"
				( pinPairRef "@baseboard_fab2_lib.baseboard_fab2(sch_1):\PP2614\" )
				( pinPairRef "@baseboard_fab2_lib.baseboard_fab2(sch_1):\PP2616\" )
				( attribute "NO_TEST" "1"
					( Origin gBackEnd )
				)
				( objectStatus "M_H_DQ<33>" )
			)
			( signal "@baseboard_fab2_lib.baseboard_fab2(sch_1):m_h_dq(34)"
				( pinPairRef "@baseboard_fab2_lib.baseboard_fab2(sch_1):\PP2617\" )
				( pinPairRef "@baseboard_fab2_lib.baseboard_fab2(sch_1):\PP2619\" )
				( objectStatus "M_H_DQ<34>" )
			)
			( signal "@baseboard_fab2_lib.baseboard_fab2(sch_1):m_h_dq(35)"
				( pinPairRef "@baseboard_fab2_lib.baseboard_fab2(sch_1):\PP2620\" )
				( pinPairRef "@baseboard_fab2_lib.baseboard_fab2(sch_1):\PP2622\" )
				( attribute "NO_TEST" "1"
					( Origin gBackEnd )
				)
				( objectStatus "M_H_DQ<35>" )
			)
			( signal "@baseboard_fab2_lib.baseboard_fab2(sch_1):m_h_dq(36)"
				( pinPairRef "@baseboard_fab2_lib.baseboard_fab2(sch_1):\PP2623\" )
				( pinPairRef "@baseboard_fab2_lib.baseboard_fab2(sch_1):\PP2625\" )
				( attribute "NO_TEST" "1"
					( Origin gBackEnd )
				)
				( objectStatus "M_H_DQ<36>" )
			)
			( signal "@baseboard_fab2_lib.baseboard_fab2(sch_1):m_h_dq(37)"
				( pinPairRef "@baseboard_fab2_lib.baseboard_fab2(sch_1):\PP2626\" )
				( pinPairRef "@baseboard_fab2_lib.baseboard_fab2(sch_1):\PP2628\" )
				( objectStatus "M_H_DQ<37>" )
			)
			( signal "@baseboard_fab2_lib.baseboard_fab2(sch_1):m_h_dq(38)"
				( pinPairRef "@baseboard_fab2_lib.baseboard_fab2(sch_1):\PP2629\" )
				( pinPairRef "@baseboard_fab2_lib.baseboard_fab2(sch_1):\PP2631\" )
				( attribute "NO_TEST" "1"
					( Origin gBackEnd )
				)
				( objectStatus "M_H_DQ<38>" )
			)
			( signal "@baseboard_fab2_lib.baseboard_fab2(sch_1):m_h_dq(39)"
				( pinPairRef "@baseboard_fab2_lib.baseboard_fab2(sch_1):\PP2632\" )
				( pinPairRef "@baseboard_fab2_lib.baseboard_fab2(sch_1):\PP2634\" )
				( attribute "NO_TEST" "1"
					( Origin gBackEnd )
				)
				( objectStatus "M_H_DQ<39>" )
			)
			( signal "@baseboard_fab2_lib.baseboard_fab2(sch_1):m_h_dq(40)"
				( pinPairRef "@baseboard_fab2_lib.baseboard_fab2(sch_1):\PP2587\" )
				( pinPairRef "@baseboard_fab2_lib.baseboard_fab2(sch_1):\PP2589\" )
				( attribute "NO_TEST" "1"
					( Origin gBackEnd )
				)
				( objectStatus "M_H_DQ<40>" )
			)
			( signal "@baseboard_fab2_lib.baseboard_fab2(sch_1):m_h_dq(41)"
				( pinPairRef "@baseboard_fab2_lib.baseboard_fab2(sch_1):\PP2590\" )
				( pinPairRef "@baseboard_fab2_lib.baseboard_fab2(sch_1):\PP2592\" )
				( objectStatus "M_H_DQ<41>" )
			)
			( signal "@baseboard_fab2_lib.baseboard_fab2(sch_1):m_h_dq(42)"
				( pinPairRef "@baseboard_fab2_lib.baseboard_fab2(sch_1):\PP2593\" )
				( pinPairRef "@baseboard_fab2_lib.baseboard_fab2(sch_1):\PP2595\" )
				( objectStatus "M_H_DQ<42>" )
			)
			( signal "@baseboard_fab2_lib.baseboard_fab2(sch_1):m_h_dq(43)"
				( pinPairRef "@baseboard_fab2_lib.baseboard_fab2(sch_1):\PP2596\" )
				( pinPairRef "@baseboard_fab2_lib.baseboard_fab2(sch_1):\PP2598\" )
				( objectStatus "M_H_DQ<43>" )
			)
			( signal "@baseboard_fab2_lib.baseboard_fab2(sch_1):m_h_dq(44)"
				( pinPairRef "@baseboard_fab2_lib.baseboard_fab2(sch_1):\PP2599\" )
				( pinPairRef "@baseboard_fab2_lib.baseboard_fab2(sch_1):\PP2601\" )
				( attribute "NO_TEST" "1"
					( Origin gBackEnd )
				)
				( objectStatus "M_H_DQ<44>" )
			)
			( signal "@baseboard_fab2_lib.baseboard_fab2(sch_1):m_h_dq(45)"
				( pinPairRef "@baseboard_fab2_lib.baseboard_fab2(sch_1):\PP2602\" )
				( pinPairRef "@baseboard_fab2_lib.baseboard_fab2(sch_1):\PP2604\" )
				( objectStatus "M_H_DQ<45>" )
			)
			( signal "@baseboard_fab2_lib.baseboard_fab2(sch_1):m_h_dq(46)"
				( pinPairRef "@baseboard_fab2_lib.baseboard_fab2(sch_1):\PP2605\" )
				( pinPairRef "@baseboard_fab2_lib.baseboard_fab2(sch_1):\PP2607\" )
				( objectStatus "M_H_DQ<46>" )
			)
			( signal "@baseboard_fab2_lib.baseboard_fab2(sch_1):m_h_dq(47)"
				( pinPairRef "@baseboard_fab2_lib.baseboard_fab2(sch_1):\PP2608\" )
				( pinPairRef "@baseboard_fab2_lib.baseboard_fab2(sch_1):\PP2610\" )
				( objectStatus "M_H_DQ<47>" )
			)
			( signal "@baseboard_fab2_lib.baseboard_fab2(sch_1):m_h_dq(48)"
				( pinPairRef "@baseboard_fab2_lib.baseboard_fab2(sch_1):\PP2563\" )
				( pinPairRef "@baseboard_fab2_lib.baseboard_fab2(sch_1):\PP2565\" )
				( attribute "NO_TEST" "1"
					( Origin gBackEnd )
				)
				( objectStatus "M_H_DQ<48>" )
			)
			( signal "@baseboard_fab2_lib.baseboard_fab2(sch_1):m_h_dq(49)"
				( pinPairRef "@baseboard_fab2_lib.baseboard_fab2(sch_1):\PP2566\" )
				( pinPairRef "@baseboard_fab2_lib.baseboard_fab2(sch_1):\PP2568\" )
				( objectStatus "M_H_DQ<49>" )
			)
			( signal "@baseboard_fab2_lib.baseboard_fab2(sch_1):m_h_dq(50)"
				( pinPairRef "@baseboard_fab2_lib.baseboard_fab2(sch_1):\PP2569\" )
				( pinPairRef "@baseboard_fab2_lib.baseboard_fab2(sch_1):\PP2571\" )
				( objectStatus "M_H_DQ<50>" )
			)
			( signal "@baseboard_fab2_lib.baseboard_fab2(sch_1):m_h_dq(51)"
				( pinPairRef "@baseboard_fab2_lib.baseboard_fab2(sch_1):\PP2572\" )
				( pinPairRef "@baseboard_fab2_lib.baseboard_fab2(sch_1):\PP2574\" )
				( objectStatus "M_H_DQ<51>" )
			)
			( signal "@baseboard_fab2_lib.baseboard_fab2(sch_1):m_h_dq(52)"
				( pinPairRef "@baseboard_fab2_lib.baseboard_fab2(sch_1):\PP2575\" )
				( pinPairRef "@baseboard_fab2_lib.baseboard_fab2(sch_1):\PP2577\" )
				( objectStatus "M_H_DQ<52>" )
			)
			( signal "@baseboard_fab2_lib.baseboard_fab2(sch_1):m_h_dq(53)"
				( pinPairRef "@baseboard_fab2_lib.baseboard_fab2(sch_1):\PP2578\" )
				( pinPairRef "@baseboard_fab2_lib.baseboard_fab2(sch_1):\PP2580\" )
				( objectStatus "M_H_DQ<53>" )
			)
			( signal "@baseboard_fab2_lib.baseboard_fab2(sch_1):m_h_dq(54)"
				( pinPairRef "@baseboard_fab2_lib.baseboard_fab2(sch_1):\PP2581\" )
				( pinPairRef "@baseboard_fab2_lib.baseboard_fab2(sch_1):\PP2583\" )
				( objectStatus "M_H_DQ<54>" )
			)
			( signal "@baseboard_fab2_lib.baseboard_fab2(sch_1):m_h_dq(55)"
				( pinPairRef "@baseboard_fab2_lib.baseboard_fab2(sch_1):\PP2584\" )
				( pinPairRef "@baseboard_fab2_lib.baseboard_fab2(sch_1):\PP2586\" )
				( objectStatus "M_H_DQ<55>" )
			)
			( signal "@baseboard_fab2_lib.baseboard_fab2(sch_1):m_h_dq(56)"
				( pinPairRef "@baseboard_fab2_lib.baseboard_fab2(sch_1):\PP2539\" )
				( pinPairRef "@baseboard_fab2_lib.baseboard_fab2(sch_1):\PP2541\" )
				( attribute "NO_TEST" "1"
					( Origin gBackEnd )
				)
				( objectStatus "M_H_DQ<56>" )
			)
			( signal "@baseboard_fab2_lib.baseboard_fab2(sch_1):m_h_dq(57)"
				( pinPairRef "@baseboard_fab2_lib.baseboard_fab2(sch_1):\PP2542\" )
				( pinPairRef "@baseboard_fab2_lib.baseboard_fab2(sch_1):\PP2544\" )
				( objectStatus "M_H_DQ<57>" )
			)
			( signal "@baseboard_fab2_lib.baseboard_fab2(sch_1):m_h_dq(58)"
				( pinPairRef "@baseboard_fab2_lib.baseboard_fab2(sch_1):\PP2545\" )
				( pinPairRef "@baseboard_fab2_lib.baseboard_fab2(sch_1):\PP2547\" )
				( objectStatus "M_H_DQ<58>" )
			)
			( signal "@baseboard_fab2_lib.baseboard_fab2(sch_1):m_h_dq(59)"
				( pinPairRef "@baseboard_fab2_lib.baseboard_fab2(sch_1):\PP2548\" )
				( pinPairRef "@baseboard_fab2_lib.baseboard_fab2(sch_1):\PP2550\" )
				( attribute "NO_TEST" "1"
					( Origin gBackEnd )
				)
				( objectStatus "M_H_DQ<59>" )
			)
			( signal "@baseboard_fab2_lib.baseboard_fab2(sch_1):m_h_dq(60)"
				( pinPairRef "@baseboard_fab2_lib.baseboard_fab2(sch_1):\PP2551\" )
				( pinPairRef "@baseboard_fab2_lib.baseboard_fab2(sch_1):\PP2553\" )
				( objectStatus "M_H_DQ<60>" )
			)
			( signal "@baseboard_fab2_lib.baseboard_fab2(sch_1):m_h_dq(61)"
				( pinPairRef "@baseboard_fab2_lib.baseboard_fab2(sch_1):\PP2554\" )
				( pinPairRef "@baseboard_fab2_lib.baseboard_fab2(sch_1):\PP2556\" )
				( attribute "NO_TEST" "1"
					( Origin gBackEnd )
				)
				( objectStatus "M_H_DQ<61>" )
			)
			( signal "@baseboard_fab2_lib.baseboard_fab2(sch_1):m_h_dq(62)"
				( pinPairRef "@baseboard_fab2_lib.baseboard_fab2(sch_1):\PP2557\" )
				( pinPairRef "@baseboard_fab2_lib.baseboard_fab2(sch_1):\PP2559\" )
				( attribute "NO_TEST" "1"
					( Origin gBackEnd )
				)
				( objectStatus "M_H_DQ<62>" )
			)
			( signal "@baseboard_fab2_lib.baseboard_fab2(sch_1):m_h_dq(63)"
				( pinPairRef "@baseboard_fab2_lib.baseboard_fab2(sch_1):\PP2560\" )
				( pinPairRef "@baseboard_fab2_lib.baseboard_fab2(sch_1):\PP2562\" )
				( objectStatus "M_H_DQ<63>" )
			)
			( signal "@baseboard_fab2_lib.baseboard_fab2(sch_1):m_j_dq(0)"
				( pinPairRef "@baseboard_fab2_lib.baseboard_fab2(sch_1):\PP2491\" )
				( pinPairRef "@baseboard_fab2_lib.baseboard_fab2(sch_1):\PP2492\" )
				( attribute "NO_TEST" "1"
					( Origin gBackEnd )
				)
				( objectStatus "M_J_DQ<0>" )
			)
			( signal "@baseboard_fab2_lib.baseboard_fab2(sch_1):m_j_dq(1)"
				( pinPairRef "@baseboard_fab2_lib.baseboard_fab2(sch_1):\PP2494\" )
				( pinPairRef "@baseboard_fab2_lib.baseboard_fab2(sch_1):\PP2495\" )
				( objectStatus "M_J_DQ<1>" )
			)
			( signal "@baseboard_fab2_lib.baseboard_fab2(sch_1):m_j_dq(2)"
				( pinPairRef "@baseboard_fab2_lib.baseboard_fab2(sch_1):\PP2497\" )
				( pinPairRef "@baseboard_fab2_lib.baseboard_fab2(sch_1):\PP2498\" )
				( objectStatus "M_J_DQ<2>" )
			)
			( signal "@baseboard_fab2_lib.baseboard_fab2(sch_1):m_j_dq(3)"
				( pinPairRef "@baseboard_fab2_lib.baseboard_fab2(sch_1):\PP2500\" )
				( pinPairRef "@baseboard_fab2_lib.baseboard_fab2(sch_1):\PP2501\" )
				( attribute "NO_TEST" "1"
					( Origin gBackEnd )
				)
				( objectStatus "M_J_DQ<3>" )
			)
			( signal "@baseboard_fab2_lib.baseboard_fab2(sch_1):m_j_dq(4)"
				( pinPairRef "@baseboard_fab2_lib.baseboard_fab2(sch_1):\PP2503\" )
				( pinPairRef "@baseboard_fab2_lib.baseboard_fab2(sch_1):\PP2504\" )
				( objectStatus "M_J_DQ<4>" )
			)
			( signal "@baseboard_fab2_lib.baseboard_fab2(sch_1):m_j_dq(5)"
				( pinPairRef "@baseboard_fab2_lib.baseboard_fab2(sch_1):\PP2506\" )
				( pinPairRef "@baseboard_fab2_lib.baseboard_fab2(sch_1):\PP2507\" )
				( attribute "NO_TEST" "1"
					( Origin gBackEnd )
				)
				( objectStatus "M_J_DQ<5>" )
			)
			( signal "@baseboard_fab2_lib.baseboard_fab2(sch_1):m_j_dq(6)"
				( pinPairRef "@baseboard_fab2_lib.baseboard_fab2(sch_1):\PP2509\" )
				( pinPairRef "@baseboard_fab2_lib.baseboard_fab2(sch_1):\PP2510\" )
				( attribute "NO_TEST" "1"
					( Origin gBackEnd )
				)
				( objectStatus "M_J_DQ<6>" )
			)
			( signal "@baseboard_fab2_lib.baseboard_fab2(sch_1):m_j_dq(7)"
				( pinPairRef "@baseboard_fab2_lib.baseboard_fab2(sch_1):\PP2512\" )
				( pinPairRef "@baseboard_fab2_lib.baseboard_fab2(sch_1):\PP2513\" )
				( objectStatus "M_J_DQ<7>" )
			)
			( signal "@baseboard_fab2_lib.baseboard_fab2(sch_1):m_j_dq(8)"
				( pinPairRef "@baseboard_fab2_lib.baseboard_fab2(sch_1):\PP2467\" )
				( pinPairRef "@baseboard_fab2_lib.baseboard_fab2(sch_1):\PP2468\" )
				( attribute "NO_TEST" "1"
					( Origin gBackEnd )
				)
				( objectStatus "M_J_DQ<8>" )
			)
			( signal "@baseboard_fab2_lib.baseboard_fab2(sch_1):m_j_dq(9)"
				( pinPairRef "@baseboard_fab2_lib.baseboard_fab2(sch_1):\PP2470\" )
				( pinPairRef "@baseboard_fab2_lib.baseboard_fab2(sch_1):\PP2471\" )
				( objectStatus "M_J_DQ<9>" )
			)
			( signal "@baseboard_fab2_lib.baseboard_fab2(sch_1):m_j_dq(10)"
				( pinPairRef "@baseboard_fab2_lib.baseboard_fab2(sch_1):\PP2473\" )
				( pinPairRef "@baseboard_fab2_lib.baseboard_fab2(sch_1):\PP2474\" )
				( objectStatus "M_J_DQ<10>" )
			)
			( signal "@baseboard_fab2_lib.baseboard_fab2(sch_1):m_j_dq(11)"
				( pinPairRef "@baseboard_fab2_lib.baseboard_fab2(sch_1):\PP2476\" )
				( pinPairRef "@baseboard_fab2_lib.baseboard_fab2(sch_1):\PP2477\" )
				( attribute "NO_TEST" "1"
					( Origin gBackEnd )
				)
				( objectStatus "M_J_DQ<11>" )
			)
			( signal "@baseboard_fab2_lib.baseboard_fab2(sch_1):m_j_dq(12)"
				( pinPairRef "@baseboard_fab2_lib.baseboard_fab2(sch_1):\PP2479\" )
				( pinPairRef "@baseboard_fab2_lib.baseboard_fab2(sch_1):\PP2480\" )
				( objectStatus "M_J_DQ<12>" )
			)
			( signal "@baseboard_fab2_lib.baseboard_fab2(sch_1):m_j_dq(13)"
				( pinPairRef "@baseboard_fab2_lib.baseboard_fab2(sch_1):\PP2482\" )
				( pinPairRef "@baseboard_fab2_lib.baseboard_fab2(sch_1):\PP2483\" )
				( attribute "NO_TEST" "1"
					( Origin gBackEnd )
				)
				( objectStatus "M_J_DQ<13>" )
			)
			( signal "@baseboard_fab2_lib.baseboard_fab2(sch_1):m_j_dq(14)"
				( pinPairRef "@baseboard_fab2_lib.baseboard_fab2(sch_1):\PP2485\" )
				( pinPairRef "@baseboard_fab2_lib.baseboard_fab2(sch_1):\PP2486\" )
				( attribute "NO_TEST" "1"
					( Origin gBackEnd )
				)
				( objectStatus "M_J_DQ<14>" )
			)
			( signal "@baseboard_fab2_lib.baseboard_fab2(sch_1):m_j_dq(15)"
				( pinPairRef "@baseboard_fab2_lib.baseboard_fab2(sch_1):\PP2488\" )
				( pinPairRef "@baseboard_fab2_lib.baseboard_fab2(sch_1):\PP2489\" )
				( objectStatus "M_J_DQ<15>" )
			)
			( signal "@baseboard_fab2_lib.baseboard_fab2(sch_1):m_j_dq(16)"
				( pinPairRef "@baseboard_fab2_lib.baseboard_fab2(sch_1):\PP2443\" )
				( pinPairRef "@baseboard_fab2_lib.baseboard_fab2(sch_1):\PP2444\" )
				( attribute "NO_TEST" "1"
					( Origin gBackEnd )
				)
				( objectStatus "M_J_DQ<16>" )
			)
			( signal "@baseboard_fab2_lib.baseboard_fab2(sch_1):m_j_dq(17)"
				( pinPairRef "@baseboard_fab2_lib.baseboard_fab2(sch_1):\PP2446\" )
				( pinPairRef "@baseboard_fab2_lib.baseboard_fab2(sch_1):\PP2447\" )
				( attribute "NO_TEST" "1"
					( Origin gBackEnd )
				)
				( objectStatus "M_J_DQ<17>" )
			)
			( signal "@baseboard_fab2_lib.baseboard_fab2(sch_1):m_j_dq(18)"
				( pinPairRef "@baseboard_fab2_lib.baseboard_fab2(sch_1):\PP2449\" )
				( pinPairRef "@baseboard_fab2_lib.baseboard_fab2(sch_1):\PP2450\" )
				( objectStatus "M_J_DQ<18>" )
			)
			( signal "@baseboard_fab2_lib.baseboard_fab2(sch_1):m_j_dq(19)"
				( pinPairRef "@baseboard_fab2_lib.baseboard_fab2(sch_1):\PP2452\" )
				( pinPairRef "@baseboard_fab2_lib.baseboard_fab2(sch_1):\PP2453\" )
				( attribute "NO_TEST" "1"
					( Origin gBackEnd )
				)
				( objectStatus "M_J_DQ<19>" )
			)
			( signal "@baseboard_fab2_lib.baseboard_fab2(sch_1):m_j_dq(20)"
				( pinPairRef "@baseboard_fab2_lib.baseboard_fab2(sch_1):\PP2455\" )
				( pinPairRef "@baseboard_fab2_lib.baseboard_fab2(sch_1):\PP2456\" )
				( objectStatus "M_J_DQ<20>" )
			)
			( signal "@baseboard_fab2_lib.baseboard_fab2(sch_1):m_a_dq(8)"
				( pinPairRef "@baseboard_fab2_lib.baseboard_fab2(sch_1):\PP5319\" )
				( pinPairRef "@baseboard_fab2_lib.baseboard_fab2(sch_1):\PP5321\" )
				( objectStatus "M_A_DQ<8>" )
			)
			( signal "@baseboard_fab2_lib.baseboard_fab2(sch_1):m_a_dq(9)"
				( pinPairRef "@baseboard_fab2_lib.baseboard_fab2(sch_1):\PP5322\" )
				( pinPairRef "@baseboard_fab2_lib.baseboard_fab2(sch_1):\PP5324\" )
				( attribute "NO_TEST" "1"
					( Origin gBackEnd )
				)
				( objectStatus "M_A_DQ<9>" )
			)
			( signal "@baseboard_fab2_lib.baseboard_fab2(sch_1):m_a_dq(10)"
				( pinPairRef "@baseboard_fab2_lib.baseboard_fab2(sch_1):\PP5325\" )
				( pinPairRef "@baseboard_fab2_lib.baseboard_fab2(sch_1):\PP5327\" )
				( objectStatus "M_A_DQ<10>" )
			)
			( signal "@baseboard_fab2_lib.baseboard_fab2(sch_1):m_a_dq(11)"
				( pinPairRef "@baseboard_fab2_lib.baseboard_fab2(sch_1):\PP5328\" )
				( pinPairRef "@baseboard_fab2_lib.baseboard_fab2(sch_1):\PP5330\" )
				( objectStatus "M_A_DQ<11>" )
			)
			( signal "@baseboard_fab2_lib.baseboard_fab2(sch_1):m_a_dq(12)"
				( pinPairRef "@baseboard_fab2_lib.baseboard_fab2(sch_1):\PP5331\" )
				( pinPairRef "@baseboard_fab2_lib.baseboard_fab2(sch_1):\PP5333\" )
				( attribute "NO_TEST" "1"
					( Origin gBackEnd )
				)
				( objectStatus "M_A_DQ<12>" )
			)
			( signal "@baseboard_fab2_lib.baseboard_fab2(sch_1):m_a_dq(13)"
				( pinPairRef "@baseboard_fab2_lib.baseboard_fab2(sch_1):\PP5334\" )
				( pinPairRef "@baseboard_fab2_lib.baseboard_fab2(sch_1):\PP5336\" )
				( objectStatus "M_A_DQ<13>" )
			)
			( signal "@baseboard_fab2_lib.baseboard_fab2(sch_1):m_a_dq(14)"
				( pinPairRef "@baseboard_fab2_lib.baseboard_fab2(sch_1):\PP5337\" )
				( pinPairRef "@baseboard_fab2_lib.baseboard_fab2(sch_1):\PP5339\" )
				( objectStatus "M_A_DQ<14>" )
			)
			( signal "@baseboard_fab2_lib.baseboard_fab2(sch_1):m_a_dq(15)"
				( pinPairRef "@baseboard_fab2_lib.baseboard_fab2(sch_1):\PP5340\" )
				( pinPairRef "@baseboard_fab2_lib.baseboard_fab2(sch_1):\PP5342\" )
				( objectStatus "M_A_DQ<15>" )
			)
			( signal "@baseboard_fab2_lib.baseboard_fab2(sch_1):m_a_dq(16)"
				( pinPairRef "@baseboard_fab2_lib.baseboard_fab2(sch_1):\PP5295\" )
				( pinPairRef "@baseboard_fab2_lib.baseboard_fab2(sch_1):\PP5297\" )
				( objectStatus "M_A_DQ<16>" )
			)
			( signal "@baseboard_fab2_lib.baseboard_fab2(sch_1):m_a_dq(17)"
				( pinPairRef "@baseboard_fab2_lib.baseboard_fab2(sch_1):\PP5298\" )
				( pinPairRef "@baseboard_fab2_lib.baseboard_fab2(sch_1):\PP5300\" )
				( attribute "NO_TEST" "1"
					( Origin gBackEnd )
				)
				( objectStatus "M_A_DQ<17>" )
			)
			( signal "@baseboard_fab2_lib.baseboard_fab2(sch_1):m_a_dq(18)"
				( pinPairRef "@baseboard_fab2_lib.baseboard_fab2(sch_1):\PP5301\" )
				( pinPairRef "@baseboard_fab2_lib.baseboard_fab2(sch_1):\PP5303\" )
				( attribute "NO_TEST" "1"
					( Origin gBackEnd )
				)
				( objectStatus "M_A_DQ<18>" )
			)
			( signal "@baseboard_fab2_lib.baseboard_fab2(sch_1):m_a_dq(19)"
				( pinPairRef "@baseboard_fab2_lib.baseboard_fab2(sch_1):\PP5304\" )
				( pinPairRef "@baseboard_fab2_lib.baseboard_fab2(sch_1):\PP5306\" )
				( objectStatus "M_A_DQ<19>" )
			)
			( signal "@baseboard_fab2_lib.baseboard_fab2(sch_1):m_a_dq(20)"
				( pinPairRef "@baseboard_fab2_lib.baseboard_fab2(sch_1):\PP5307\" )
				( pinPairRef "@baseboard_fab2_lib.baseboard_fab2(sch_1):\PP5309\" )
				( attribute "NO_TEST" "1"
					( Origin gBackEnd )
				)
				( objectStatus "M_A_DQ<20>" )
			)
			( signal "@baseboard_fab2_lib.baseboard_fab2(sch_1):m_a_dq(21)"
				( pinPairRef "@baseboard_fab2_lib.baseboard_fab2(sch_1):\PP5310\" )
				( pinPairRef "@baseboard_fab2_lib.baseboard_fab2(sch_1):\PP5312\" )
				( objectStatus "M_A_DQ<21>" )
			)
			( signal "@baseboard_fab2_lib.baseboard_fab2(sch_1):m_a_dq(22)"
				( pinPairRef "@baseboard_fab2_lib.baseboard_fab2(sch_1):\PP5313\" )
				( pinPairRef "@baseboard_fab2_lib.baseboard_fab2(sch_1):\PP5315\" )
				( objectStatus "M_A_DQ<22>" )
			)
			( signal "@baseboard_fab2_lib.baseboard_fab2(sch_1):m_a_dq(23)"
				( pinPairRef "@baseboard_fab2_lib.baseboard_fab2(sch_1):\PP5316\" )
				( pinPairRef "@baseboard_fab2_lib.baseboard_fab2(sch_1):\PP5318\" )
				( attribute "NO_TEST" "1"
					( Origin gBackEnd )
				)
				( objectStatus "M_A_DQ<23>" )
			)
			( signal "@baseboard_fab2_lib.baseboard_fab2(sch_1):m_a_dq(24)"
				( pinPairRef "@baseboard_fab2_lib.baseboard_fab2(sch_1):\PP5271\" )
				( pinPairRef "@baseboard_fab2_lib.baseboard_fab2(sch_1):\PP5273\" )
				( attribute "NO_TEST" "1"
					( Origin gBackEnd )
				)
				( objectStatus "M_A_DQ<24>" )
			)
			( signal "@baseboard_fab2_lib.baseboard_fab2(sch_1):m_a_dq(25)"
				( pinPairRef "@baseboard_fab2_lib.baseboard_fab2(sch_1):\PP5274\" )
				( pinPairRef "@baseboard_fab2_lib.baseboard_fab2(sch_1):\PP5276\" )
				( objectStatus "M_A_DQ<25>" )
			)
			( signal "@baseboard_fab2_lib.baseboard_fab2(sch_1):m_a_dq(26)"
				( pinPairRef "@baseboard_fab2_lib.baseboard_fab2(sch_1):\PP5277\" )
				( pinPairRef "@baseboard_fab2_lib.baseboard_fab2(sch_1):\PP5279\" )
				( objectStatus "M_A_DQ<26>" )
			)
			( signal "@baseboard_fab2_lib.baseboard_fab2(sch_1):m_a_dq(27)"
				( pinPairRef "@baseboard_fab2_lib.baseboard_fab2(sch_1):\PP5280\" )
				( pinPairRef "@baseboard_fab2_lib.baseboard_fab2(sch_1):\PP5282\" )
				( attribute "NO_TEST" "1"
					( Origin gBackEnd )
				)
				( objectStatus "M_A_DQ<27>" )
			)
			( signal "@baseboard_fab2_lib.baseboard_fab2(sch_1):m_a_dq(28)"
				( pinPairRef "@baseboard_fab2_lib.baseboard_fab2(sch_1):\PP5283\" )
				( pinPairRef "@baseboard_fab2_lib.baseboard_fab2(sch_1):\PP5285\" )
				( objectStatus "M_A_DQ<28>" )
			)
			( signal "@baseboard_fab2_lib.baseboard_fab2(sch_1):m_a_dq(29)"
				( pinPairRef "@baseboard_fab2_lib.baseboard_fab2(sch_1):\PP5286\" )
				( pinPairRef "@baseboard_fab2_lib.baseboard_fab2(sch_1):\PP5288\" )
				( attribute "NO_TEST" "1"
					( Origin gBackEnd )
				)
				( objectStatus "M_A_DQ<29>" )
			)
			( signal "@baseboard_fab2_lib.baseboard_fab2(sch_1):m_a_dq(30)"
				( pinPairRef "@baseboard_fab2_lib.baseboard_fab2(sch_1):\PP5289\" )
				( pinPairRef "@baseboard_fab2_lib.baseboard_fab2(sch_1):\PP5291\" )
				( attribute "NO_TEST" "1"
					( Origin gBackEnd )
				)
				( objectStatus "M_A_DQ<30>" )
			)
			( signal "@baseboard_fab2_lib.baseboard_fab2(sch_1):m_a_dq(31)"
				( pinPairRef "@baseboard_fab2_lib.baseboard_fab2(sch_1):\PP5292\" )
				( pinPairRef "@baseboard_fab2_lib.baseboard_fab2(sch_1):\PP5294\" )
				( objectStatus "M_A_DQ<31>" )
			)
			( signal "@baseboard_fab2_lib.baseboard_fab2(sch_1):m_a_dq(32)"
				( pinPairRef "@baseboard_fab2_lib.baseboard_fab2(sch_1):\PP5247\" )
				( pinPairRef "@baseboard_fab2_lib.baseboard_fab2(sch_1):\PP5249\" )
				( objectStatus "M_A_DQ<32>" )
			)
			( signal "@baseboard_fab2_lib.baseboard_fab2(sch_1):m_a_dq(33)"
				( pinPairRef "@baseboard_fab2_lib.baseboard_fab2(sch_1):\PP5250\" )
				( pinPairRef "@baseboard_fab2_lib.baseboard_fab2(sch_1):\PP5252\" )
				( attribute "NO_TEST" "1"
					( Origin gBackEnd )
				)
				( objectStatus "M_A_DQ<33>" )
			)
			( signal "@baseboard_fab2_lib.baseboard_fab2(sch_1):m_a_dq(34)"
				( pinPairRef "@baseboard_fab2_lib.baseboard_fab2(sch_1):\PP5253\" )
				( pinPairRef "@baseboard_fab2_lib.baseboard_fab2(sch_1):\PP5255\" )
				( objectStatus "M_A_DQ<34>" )
			)
			( signal "@baseboard_fab2_lib.baseboard_fab2(sch_1):m_a_dq(35)"
				( pinPairRef "@baseboard_fab2_lib.baseboard_fab2(sch_1):\PP5256\" )
				( pinPairRef "@baseboard_fab2_lib.baseboard_fab2(sch_1):\PP5258\" )
				( objectStatus "M_A_DQ<35>" )
			)
			( signal "@baseboard_fab2_lib.baseboard_fab2(sch_1):m_a_dq(36)"
				( pinPairRef "@baseboard_fab2_lib.baseboard_fab2(sch_1):\PP5259\" )
				( pinPairRef "@baseboard_fab2_lib.baseboard_fab2(sch_1):\PP5261\" )
				( attribute "NO_TEST" "1"
					( Origin gBackEnd )
				)
				( objectStatus "M_A_DQ<36>" )
			)
			( signal "@baseboard_fab2_lib.baseboard_fab2(sch_1):m_a_dq(37)"
				( pinPairRef "@baseboard_fab2_lib.baseboard_fab2(sch_1):\PP5262\" )
				( pinPairRef "@baseboard_fab2_lib.baseboard_fab2(sch_1):\PP5264\" )
				( attribute "NO_TEST" "1"
					( Origin gBackEnd )
				)
				( objectStatus "M_A_DQ<37>" )
			)
			( signal "@baseboard_fab2_lib.baseboard_fab2(sch_1):m_a_dq(38)"
				( pinPairRef "@baseboard_fab2_lib.baseboard_fab2(sch_1):\PP5265\" )
				( pinPairRef "@baseboard_fab2_lib.baseboard_fab2(sch_1):\PP5267\" )
				( attribute "NO_TEST" "1"
					( Origin gBackEnd )
				)
				( objectStatus "M_A_DQ<38>" )
			)
			( signal "@baseboard_fab2_lib.baseboard_fab2(sch_1):m_a_dq(39)"
				( pinPairRef "@baseboard_fab2_lib.baseboard_fab2(sch_1):\PP5268\" )
				( pinPairRef "@baseboard_fab2_lib.baseboard_fab2(sch_1):\PP5270\" )
				( objectStatus "M_A_DQ<39>" )
			)
			( signal "@baseboard_fab2_lib.baseboard_fab2(sch_1):m_a_dq(40)"
				( pinPairRef "@baseboard_fab2_lib.baseboard_fab2(sch_1):\PP5223\" )
				( pinPairRef "@baseboard_fab2_lib.baseboard_fab2(sch_1):\PP5225\" )
				( objectStatus "M_A_DQ<40>" )
			)
			( signal "@baseboard_fab2_lib.baseboard_fab2(sch_1):m_a_dq(41)"
				( pinPairRef "@baseboard_fab2_lib.baseboard_fab2(sch_1):\PP5226\" )
				( pinPairRef "@baseboard_fab2_lib.baseboard_fab2(sch_1):\PP5228\" )
				( attribute "NO_TEST" "1"
					( Origin gBackEnd )
				)
				( objectStatus "M_A_DQ<41>" )
			)
			( signal "@baseboard_fab2_lib.baseboard_fab2(sch_1):m_a_dq(42)"
				( pinPairRef "@baseboard_fab2_lib.baseboard_fab2(sch_1):\PP5229\" )
				( pinPairRef "@baseboard_fab2_lib.baseboard_fab2(sch_1):\PP5231\" )
				( attribute "NO_TEST" "1"
					( Origin gBackEnd )
				)
				( objectStatus "M_A_DQ<42>" )
			)
			( signal "@baseboard_fab2_lib.baseboard_fab2(sch_1):m_a_dq(43)"
				( pinPairRef "@baseboard_fab2_lib.baseboard_fab2(sch_1):\PP5232\" )
				( pinPairRef "@baseboard_fab2_lib.baseboard_fab2(sch_1):\PP5234\" )
				( objectStatus "M_A_DQ<43>" )
			)
			( signal "@baseboard_fab2_lib.baseboard_fab2(sch_1):m_a_dq(44)"
				( pinPairRef "@baseboard_fab2_lib.baseboard_fab2(sch_1):\PP5235\" )
				( pinPairRef "@baseboard_fab2_lib.baseboard_fab2(sch_1):\PP5237\" )
				( attribute "NO_TEST" "1"
					( Origin gBackEnd )
				)
				( objectStatus "M_A_DQ<44>" )
			)
			( signal "@baseboard_fab2_lib.baseboard_fab2(sch_1):m_a_dq(45)"
				( pinPairRef "@baseboard_fab2_lib.baseboard_fab2(sch_1):\PP5238\" )
				( pinPairRef "@baseboard_fab2_lib.baseboard_fab2(sch_1):\PP5240\" )
				( objectStatus "M_A_DQ<45>" )
			)
			( signal "@baseboard_fab2_lib.baseboard_fab2(sch_1):m_a_dq(46)"
				( pinPairRef "@baseboard_fab2_lib.baseboard_fab2(sch_1):\PP5241\" )
				( pinPairRef "@baseboard_fab2_lib.baseboard_fab2(sch_1):\PP5243\" )
				( objectStatus "M_A_DQ<46>" )
			)
			( signal "@baseboard_fab2_lib.baseboard_fab2(sch_1):m_a_dq(47)"
				( pinPairRef "@baseboard_fab2_lib.baseboard_fab2(sch_1):\PP5244\" )
				( pinPairRef "@baseboard_fab2_lib.baseboard_fab2(sch_1):\PP5246\" )
				( attribute "NO_TEST" "1"
					( Origin gBackEnd )
				)
				( objectStatus "M_A_DQ<47>" )
			)
			( signal "@baseboard_fab2_lib.baseboard_fab2(sch_1):m_a_dq(48)"
				( pinPairRef "@baseboard_fab2_lib.baseboard_fab2(sch_1):\PP5199\" )
				( pinPairRef "@baseboard_fab2_lib.baseboard_fab2(sch_1):\PP5201\" )
				( objectStatus "M_A_DQ<48>" )
			)
			( signal "@baseboard_fab2_lib.baseboard_fab2(sch_1):m_a_dq(49)"
				( pinPairRef "@baseboard_fab2_lib.baseboard_fab2(sch_1):\PP5202\" )
				( pinPairRef "@baseboard_fab2_lib.baseboard_fab2(sch_1):\PP5204\" )
				( attribute "NO_TEST" "1"
					( Origin gBackEnd )
				)
				( objectStatus "M_A_DQ<49>" )
			)
			( signal "@baseboard_fab2_lib.baseboard_fab2(sch_1):m_a_dq(50)"
				( pinPairRef "@baseboard_fab2_lib.baseboard_fab2(sch_1):\PP5205\" )
				( pinPairRef "@baseboard_fab2_lib.baseboard_fab2(sch_1):\PP5207\" )
				( attribute "NO_TEST" "1"
					( Origin gBackEnd )
				)
				( objectStatus "M_A_DQ<50>" )
			)
			( signal "@baseboard_fab2_lib.baseboard_fab2(sch_1):m_a_dq(51)"
				( pinPairRef "@baseboard_fab2_lib.baseboard_fab2(sch_1):\PP5208\" )
				( pinPairRef "@baseboard_fab2_lib.baseboard_fab2(sch_1):\PP5210\" )
				( objectStatus "M_A_DQ<51>" )
			)
			( signal "@baseboard_fab2_lib.baseboard_fab2(sch_1):m_a_dq(52)"
				( pinPairRef "@baseboard_fab2_lib.baseboard_fab2(sch_1):\PP5211\" )
				( pinPairRef "@baseboard_fab2_lib.baseboard_fab2(sch_1):\PP5213\" )
				( attribute "NO_TEST" "1"
					( Origin gBackEnd )
				)
				( objectStatus "M_A_DQ<52>" )
			)
			( signal "@baseboard_fab2_lib.baseboard_fab2(sch_1):m_a_dq(53)"
				( pinPairRef "@baseboard_fab2_lib.baseboard_fab2(sch_1):\PP5214\" )
				( pinPairRef "@baseboard_fab2_lib.baseboard_fab2(sch_1):\PP5216\" )
				( objectStatus "M_A_DQ<53>" )
			)
			( signal "@baseboard_fab2_lib.baseboard_fab2(sch_1):m_a_dq(54)"
				( pinPairRef "@baseboard_fab2_lib.baseboard_fab2(sch_1):\PP5217\" )
				( pinPairRef "@baseboard_fab2_lib.baseboard_fab2(sch_1):\PP5219\" )
				( objectStatus "M_A_DQ<54>" )
			)
			( signal "@baseboard_fab2_lib.baseboard_fab2(sch_1):m_a_dq(55)"
				( pinPairRef "@baseboard_fab2_lib.baseboard_fab2(sch_1):\PP5220\" )
				( pinPairRef "@baseboard_fab2_lib.baseboard_fab2(sch_1):\PP5222\" )
				( attribute "NO_TEST" "1"
					( Origin gBackEnd )
				)
				( objectStatus "M_A_DQ<55>" )
			)
			( signal "@baseboard_fab2_lib.baseboard_fab2(sch_1):m_a_dq(56)"
				( pinPairRef "@baseboard_fab2_lib.baseboard_fab2(sch_1):\PP5163\" )
				( pinPairRef "@baseboard_fab2_lib.baseboard_fab2(sch_1):\PP5165\" )
				( objectStatus "M_A_DQ<56>" )
			)
			( signal "@baseboard_fab2_lib.baseboard_fab2(sch_1):m_a_dq(57)"
				( pinPairRef "@baseboard_fab2_lib.baseboard_fab2(sch_1):\PP5166\" )
				( pinPairRef "@baseboard_fab2_lib.baseboard_fab2(sch_1):\PP5168\" )
				( attribute "NO_TEST" "1"
					( Origin gBackEnd )
				)
				( objectStatus "M_A_DQ<57>" )
			)
			( signal "@baseboard_fab2_lib.baseboard_fab2(sch_1):m_a_dq(58)"
				( pinPairRef "@baseboard_fab2_lib.baseboard_fab2(sch_1):\PP5169\" )
				( pinPairRef "@baseboard_fab2_lib.baseboard_fab2(sch_1):\PP5171\" )
				( attribute "NO_TEST" "1"
					( Origin gBackEnd )
				)
				( objectStatus "M_A_DQ<58>" )
			)
			( signal "@baseboard_fab2_lib.baseboard_fab2(sch_1):m_a_dq(59)"
				( pinPairRef "@baseboard_fab2_lib.baseboard_fab2(sch_1):\PP5172\" )
				( pinPairRef "@baseboard_fab2_lib.baseboard_fab2(sch_1):\PP5174\" )
				( attribute "NO_TEST" "1"
					( Origin gBackEnd )
				)
				( objectStatus "M_A_DQ<59>" )
			)
			( signal "@baseboard_fab2_lib.baseboard_fab2(sch_1):m_a_dq(60)"
				( pinPairRef "@baseboard_fab2_lib.baseboard_fab2(sch_1):\PP5175\" )
				( pinPairRef "@baseboard_fab2_lib.baseboard_fab2(sch_1):\PP5177\" )
				( attribute "NO_TEST" "1"
					( Origin gBackEnd )
				)
				( objectStatus "M_A_DQ<60>" )
			)
			( signal "@baseboard_fab2_lib.baseboard_fab2(sch_1):m_a_dq(61)"
				( pinPairRef "@baseboard_fab2_lib.baseboard_fab2(sch_1):\PP5178\" )
				( pinPairRef "@baseboard_fab2_lib.baseboard_fab2(sch_1):\PP5180\" )
				( objectStatus "M_A_DQ<61>" )
			)
			( signal "@baseboard_fab2_lib.baseboard_fab2(sch_1):m_a_dq(62)"
				( pinPairRef "@baseboard_fab2_lib.baseboard_fab2(sch_1):\PP5181\" )
				( pinPairRef "@baseboard_fab2_lib.baseboard_fab2(sch_1):\PP5183\" )
				( attribute "NO_TEST" "1"
					( Origin gBackEnd )
				)
				( objectStatus "M_A_DQ<62>" )
			)
			( signal "@baseboard_fab2_lib.baseboard_fab2(sch_1):m_a_dq(63)"
				( pinPairRef "@baseboard_fab2_lib.baseboard_fab2(sch_1):\PP5184\" )
				( pinPairRef "@baseboard_fab2_lib.baseboard_fab2(sch_1):\PP5186\" )
				( objectStatus "M_A_DQ<63>" )
			)
			( signal "@baseboard_fab2_lib.baseboard_fab2(sch_1):m_g_dq(0)"
				( pinPairRef "@baseboard_fab2_lib.baseboard_fab2(sch_1):\PP2923\" )
				( pinPairRef "@baseboard_fab2_lib.baseboard_fab2(sch_1):\PP2924\" )
				( attribute "NO_TEST" "1"
					( Origin gBackEnd )
				)
				( objectStatus "M_G_DQ<0>" )
			)
			( signal "@baseboard_fab2_lib.baseboard_fab2(sch_1):m_g_dq(1)"
				( pinPairRef "@baseboard_fab2_lib.baseboard_fab2(sch_1):\PP2926\" )
				( pinPairRef "@baseboard_fab2_lib.baseboard_fab2(sch_1):\PP2927\" )
				( attribute "NO_TEST" "1"
					( Origin gBackEnd )
				)
				( objectStatus "M_G_DQ<1>" )
			)
			( signal "@baseboard_fab2_lib.baseboard_fab2(sch_1):m_g_dq(2)"
				( pinPairRef "@baseboard_fab2_lib.baseboard_fab2(sch_1):\PP2929\" )
				( pinPairRef "@baseboard_fab2_lib.baseboard_fab2(sch_1):\PP2930\" )
				( objectStatus "M_G_DQ<2>" )
			)
			( signal "@baseboard_fab2_lib.baseboard_fab2(sch_1):m_g_dq(3)"
				( pinPairRef "@baseboard_fab2_lib.baseboard_fab2(sch_1):\PP2932\" )
				( pinPairRef "@baseboard_fab2_lib.baseboard_fab2(sch_1):\PP2933\" )
				( objectStatus "M_G_DQ<3>" )
			)
			( signal "@baseboard_fab2_lib.baseboard_fab2(sch_1):m_g_dq(4)"
				( pinPairRef "@baseboard_fab2_lib.baseboard_fab2(sch_1):\PP2935\" )
				( pinPairRef "@baseboard_fab2_lib.baseboard_fab2(sch_1):\PP2936\" )
				( objectStatus "M_G_DQ<4>" )
			)
			( signal "@baseboard_fab2_lib.baseboard_fab2(sch_1):m_g_dq(5)"
				( pinPairRef "@baseboard_fab2_lib.baseboard_fab2(sch_1):\PP2938\" )
				( pinPairRef "@baseboard_fab2_lib.baseboard_fab2(sch_1):\PP2939\" )
				( objectStatus "M_G_DQ<5>" )
			)
			( signal "@baseboard_fab2_lib.baseboard_fab2(sch_1):m_g_dq(6)"
				( pinPairRef "@baseboard_fab2_lib.baseboard_fab2(sch_1):\PP2941\" )
				( pinPairRef "@baseboard_fab2_lib.baseboard_fab2(sch_1):\PP2942\" )
				( attribute "NO_TEST" "1"
					( Origin gBackEnd )
				)
				( objectStatus "M_G_DQ<6>" )
			)
			( signal "@baseboard_fab2_lib.baseboard_fab2(sch_1):m_g_dq(7)"
				( pinPairRef "@baseboard_fab2_lib.baseboard_fab2(sch_1):\PP2944\" )
				( pinPairRef "@baseboard_fab2_lib.baseboard_fab2(sch_1):\PP2945\" )
				( attribute "NO_TEST" "1"
					( Origin gBackEnd )
				)
				( objectStatus "M_G_DQ<7>" )
			)
			( signal "@baseboard_fab2_lib.baseboard_fab2(sch_1):m_g_dq(8)"
				( pinPairRef "@baseboard_fab2_lib.baseboard_fab2(sch_1):\PP2899\" )
				( pinPairRef "@baseboard_fab2_lib.baseboard_fab2(sch_1):\PP2900\" )
				( attribute "NO_TEST" "1"
					( Origin gBackEnd )
				)
				( objectStatus "M_G_DQ<8>" )
			)
			( signal "@baseboard_fab2_lib.baseboard_fab2(sch_1):m_g_dq(9)"
				( pinPairRef "@baseboard_fab2_lib.baseboard_fab2(sch_1):\PP2902\" )
				( pinPairRef "@baseboard_fab2_lib.baseboard_fab2(sch_1):\PP2903\" )
				( attribute "NO_TEST" "1"
					( Origin gBackEnd )
				)
				( objectStatus "M_G_DQ<9>" )
			)
			( signal "@baseboard_fab2_lib.baseboard_fab2(sch_1):m_g_dq(11)"
				( pinPairRef "@baseboard_fab2_lib.baseboard_fab2(sch_1):\PP2908\" )
				( pinPairRef "@baseboard_fab2_lib.baseboard_fab2(sch_1):\PP2909\" )
				( objectStatus "M_G_DQ<11>" )
			)
			( signal "@baseboard_fab2_lib.baseboard_fab2(sch_1):m_g_dq(12)"
				( pinPairRef "@baseboard_fab2_lib.baseboard_fab2(sch_1):\PP2911\" )
				( pinPairRef "@baseboard_fab2_lib.baseboard_fab2(sch_1):\PP2912\" )
				( attribute "NO_TEST" "1"
					( Origin gBackEnd )
				)
				( objectStatus "M_G_DQ<12>" )
			)
			( signal "@baseboard_fab2_lib.baseboard_fab2(sch_1):m_g_dq(13)"
				( pinPairRef "@baseboard_fab2_lib.baseboard_fab2(sch_1):\PP2914\" )
				( pinPairRef "@baseboard_fab2_lib.baseboard_fab2(sch_1):\PP2915\" )
				( objectStatus "M_G_DQ<13>" )
			)
			( signal "@baseboard_fab2_lib.baseboard_fab2(sch_1):m_g_dq(14)"
				( pinPairRef "@baseboard_fab2_lib.baseboard_fab2(sch_1):\PP2917\" )
				( pinPairRef "@baseboard_fab2_lib.baseboard_fab2(sch_1):\PP2918\" )
				( objectStatus "M_G_DQ<14>" )
			)
			( signal "@baseboard_fab2_lib.baseboard_fab2(sch_1):m_g_dq(15)"
				( pinPairRef "@baseboard_fab2_lib.baseboard_fab2(sch_1):\PP2920\" )
				( pinPairRef "@baseboard_fab2_lib.baseboard_fab2(sch_1):\PP2921\" )
				( objectStatus "M_G_DQ<15>" )
			)
			( signal "@baseboard_fab2_lib.baseboard_fab2(sch_1):m_g_dq(16)"
				( pinPairRef "@baseboard_fab2_lib.baseboard_fab2(sch_1):\PP2875\" )
				( pinPairRef "@baseboard_fab2_lib.baseboard_fab2(sch_1):\PP2876\" )
				( attribute "NO_TEST" "1"
					( Origin gBackEnd )
				)
				( objectStatus "M_G_DQ<16>" )
			)
			( signal "@baseboard_fab2_lib.baseboard_fab2(sch_1):m_g_dq(17)"
				( pinPairRef "@baseboard_fab2_lib.baseboard_fab2(sch_1):\PP2878\" )
				( pinPairRef "@baseboard_fab2_lib.baseboard_fab2(sch_1):\PP2879\" )
				( attribute "NO_TEST" "1"
					( Origin gBackEnd )
				)
				( objectStatus "M_G_DQ<17>" )
			)
			( signal "@baseboard_fab2_lib.baseboard_fab2(sch_1):m_g_dq(18)"
				( pinPairRef "@baseboard_fab2_lib.baseboard_fab2(sch_1):\PP2881\" )
				( pinPairRef "@baseboard_fab2_lib.baseboard_fab2(sch_1):\PP2882\" )
				( objectStatus "M_G_DQ<18>" )
			)
			( signal "@baseboard_fab2_lib.baseboard_fab2(sch_1):m_g_dq(19)"
				( pinPairRef "@baseboard_fab2_lib.baseboard_fab2(sch_1):\PP2884\" )
				( pinPairRef "@baseboard_fab2_lib.baseboard_fab2(sch_1):\PP2885\" )
				( attribute "NO_TEST" "1"
					( Origin gBackEnd )
				)
				( objectStatus "M_G_DQ<19>" )
			)
			( signal "@baseboard_fab2_lib.baseboard_fab2(sch_1):m_g_dq(20)"
				( pinPairRef "@baseboard_fab2_lib.baseboard_fab2(sch_1):\PP2887\" )
				( pinPairRef "@baseboard_fab2_lib.baseboard_fab2(sch_1):\PP2888\" )
				( attribute "NO_TEST" "1"
					( Origin gBackEnd )
				)
				( objectStatus "M_G_DQ<20>" )
			)
			( signal "@baseboard_fab2_lib.baseboard_fab2(sch_1):m_g_dq(21)"
				( pinPairRef "@baseboard_fab2_lib.baseboard_fab2(sch_1):\PP2890\" )
				( pinPairRef "@baseboard_fab2_lib.baseboard_fab2(sch_1):\PP2891\" )
				( objectStatus "M_G_DQ<21>" )
			)
			( signal "@baseboard_fab2_lib.baseboard_fab2(sch_1):m_g_dq(22)"
				( pinPairRef "@baseboard_fab2_lib.baseboard_fab2(sch_1):\PP2893\" )
				( pinPairRef "@baseboard_fab2_lib.baseboard_fab2(sch_1):\PP2894\" )
				( attribute "NO_TEST" "1"
					( Origin gBackEnd )
				)
				( objectStatus "M_G_DQ<22>" )
			)
			( signal "@baseboard_fab2_lib.baseboard_fab2(sch_1):m_g_dq(23)"
				( pinPairRef "@baseboard_fab2_lib.baseboard_fab2(sch_1):\PP2896\" )
				( pinPairRef "@baseboard_fab2_lib.baseboard_fab2(sch_1):\PP2897\" )
				( attribute "NO_TEST" "1"
					( Origin gBackEnd )
				)
				( objectStatus "M_G_DQ<23>" )
			)
			( signal "@baseboard_fab2_lib.baseboard_fab2(sch_1):m_g_dq(24)"
				( pinPairRef "@baseboard_fab2_lib.baseboard_fab2(sch_1):\PP2851\" )
				( pinPairRef "@baseboard_fab2_lib.baseboard_fab2(sch_1):\PP2852\" )
				( attribute "NO_TEST" "1"
					( Origin gBackEnd )
				)
				( objectStatus "M_G_DQ<24>" )
			)
			( signal "@baseboard_fab2_lib.baseboard_fab2(sch_1):m_g_dq(25)"
				( pinPairRef "@baseboard_fab2_lib.baseboard_fab2(sch_1):\PP2854\" )
				( pinPairRef "@baseboard_fab2_lib.baseboard_fab2(sch_1):\PP2855\" )
				( objectStatus "M_G_DQ<25>" )
			)
			( signal "@baseboard_fab2_lib.baseboard_fab2(sch_1):m_g_dq(26)"
				( pinPairRef "@baseboard_fab2_lib.baseboard_fab2(sch_1):\PP2857\" )
				( pinPairRef "@baseboard_fab2_lib.baseboard_fab2(sch_1):\PP2858\" )
				( objectStatus "M_G_DQ<26>" )
			)
			( signal "@baseboard_fab2_lib.baseboard_fab2(sch_1):m_g_dq(27)"
				( pinPairRef "@baseboard_fab2_lib.baseboard_fab2(sch_1):\PP2860\" )
				( pinPairRef "@baseboard_fab2_lib.baseboard_fab2(sch_1):\PP2861\" )
				( attribute "NO_TEST" "1"
					( Origin gBackEnd )
				)
				( objectStatus "M_G_DQ<27>" )
			)
			( signal "@baseboard_fab2_lib.baseboard_fab2(sch_1):m_g_dq(28)"
				( pinPairRef "@baseboard_fab2_lib.baseboard_fab2(sch_1):\PP2863\" )
				( pinPairRef "@baseboard_fab2_lib.baseboard_fab2(sch_1):\PP2864\" )
				( objectStatus "M_G_DQ<28>" )
			)
			( signal "@baseboard_fab2_lib.baseboard_fab2(sch_1):m_g_dq(29)"
				( pinPairRef "@baseboard_fab2_lib.baseboard_fab2(sch_1):\PP2866\" )
				( pinPairRef "@baseboard_fab2_lib.baseboard_fab2(sch_1):\PP2867\" )
				( attribute "NO_TEST" "1"
					( Origin gBackEnd )
				)
				( objectStatus "M_G_DQ<29>" )
			)
			( signal "@baseboard_fab2_lib.baseboard_fab2(sch_1):m_g_dq(30)"
				( pinPairRef "@baseboard_fab2_lib.baseboard_fab2(sch_1):\PP2869\" )
				( pinPairRef "@baseboard_fab2_lib.baseboard_fab2(sch_1):\PP2870\" )
				( attribute "NO_TEST" "1"
					( Origin gBackEnd )
				)
				( objectStatus "M_G_DQ<30>" )
			)
			( signal "@baseboard_fab2_lib.baseboard_fab2(sch_1):m_g_dq(31)"
				( pinPairRef "@baseboard_fab2_lib.baseboard_fab2(sch_1):\PP2872\" )
				( pinPairRef "@baseboard_fab2_lib.baseboard_fab2(sch_1):\PP2873\" )
				( objectStatus "M_G_DQ<31>" )
			)
			( signal "@baseboard_fab2_lib.baseboard_fab2(sch_1):m_g_dq(32)"
				( pinPairRef "@baseboard_fab2_lib.baseboard_fab2(sch_1):\PP2827\" )
				( pinPairRef "@baseboard_fab2_lib.baseboard_fab2(sch_1):\PP2829\" )
				( objectStatus "M_G_DQ<32>" )
			)
			( signal "@baseboard_fab2_lib.baseboard_fab2(sch_1):m_g_dq(33)"
				( pinPairRef "@baseboard_fab2_lib.baseboard_fab2(sch_1):\PP2830\" )
				( pinPairRef "@baseboard_fab2_lib.baseboard_fab2(sch_1):\PP2832\" )
				( attribute "NO_TEST" "1"
					( Origin gBackEnd )
				)
				( objectStatus "M_G_DQ<33>" )
			)
			( signal "@baseboard_fab2_lib.baseboard_fab2(sch_1):m_g_dq(34)"
				( pinPairRef "@baseboard_fab2_lib.baseboard_fab2(sch_1):\PP2833\" )
				( pinPairRef "@baseboard_fab2_lib.baseboard_fab2(sch_1):\PP2835\" )
				( objectStatus "M_G_DQ<34>" )
			)
			( signal "@baseboard_fab2_lib.baseboard_fab2(sch_1):m_g_dq(35)"
				( pinPairRef "@baseboard_fab2_lib.baseboard_fab2(sch_1):\PP2836\" )
				( pinPairRef "@baseboard_fab2_lib.baseboard_fab2(sch_1):\PP2838\" )
				( objectStatus "M_G_DQ<35>" )
			)
			( signal "@baseboard_fab2_lib.baseboard_fab2(sch_1):m_g_dq(36)"
				( pinPairRef "@baseboard_fab2_lib.baseboard_fab2(sch_1):\PP2839\" )
				( pinPairRef "@baseboard_fab2_lib.baseboard_fab2(sch_1):\PP2841\" )
				( attribute "NO_TEST" "1"
					( Origin gBackEnd )
				)
				( objectStatus "M_G_DQ<36>" )
			)
			( signal "@baseboard_fab2_lib.baseboard_fab2(sch_1):m_g_dq(37)"
				( pinPairRef "@baseboard_fab2_lib.baseboard_fab2(sch_1):\PP2842\" )
				( pinPairRef "@baseboard_fab2_lib.baseboard_fab2(sch_1):\PP2844\" )
				( attribute "NO_TEST" "1"
					( Origin gBackEnd )
				)
				( objectStatus "M_G_DQ<37>" )
			)
			( signal "@baseboard_fab2_lib.baseboard_fab2(sch_1):m_g_dq(38)"
				( pinPairRef "@baseboard_fab2_lib.baseboard_fab2(sch_1):\PP2845\" )
				( pinPairRef "@baseboard_fab2_lib.baseboard_fab2(sch_1):\PP2847\" )
				( attribute "NO_TEST" "1"
					( Origin gBackEnd )
				)
				( objectStatus "M_G_DQ<38>" )
			)
			( signal "@baseboard_fab2_lib.baseboard_fab2(sch_1):m_g_dq(39)"
				( pinPairRef "@baseboard_fab2_lib.baseboard_fab2(sch_1):\PP2848\" )
				( pinPairRef "@baseboard_fab2_lib.baseboard_fab2(sch_1):\PP2850\" )
				( objectStatus "M_G_DQ<39>" )
			)
			( signal "@baseboard_fab2_lib.baseboard_fab2(sch_1):m_g_dq(40)"
				( pinPairRef "@baseboard_fab2_lib.baseboard_fab2(sch_1):\PP2803\" )
				( pinPairRef "@baseboard_fab2_lib.baseboard_fab2(sch_1):\PP2805\" )
				( attribute "NO_TEST" "1"
					( Origin gBackEnd )
				)
				( objectStatus "M_G_DQ<40>" )
			)
			( signal "@baseboard_fab2_lib.baseboard_fab2(sch_1):m_g_dq(41)"
				( pinPairRef "@baseboard_fab2_lib.baseboard_fab2(sch_1):\PP2806\" )
				( pinPairRef "@baseboard_fab2_lib.baseboard_fab2(sch_1):\PP2808\" )
				( attribute "NO_TEST" "1"
					( Origin gBackEnd )
				)
				( objectStatus "M_G_DQ<41>" )
			)
			( signal "@baseboard_fab2_lib.baseboard_fab2(sch_1):m_g_dq(42)"
				( pinPairRef "@baseboard_fab2_lib.baseboard_fab2(sch_1):\PP2809\" )
				( pinPairRef "@baseboard_fab2_lib.baseboard_fab2(sch_1):\PP2811\" )
				( attribute "NO_TEST" "1"
					( Origin gBackEnd )
				)
				( objectStatus "M_G_DQ<42>" )
			)
			( signal "@baseboard_fab2_lib.baseboard_fab2(sch_1):m_g_dq(43)"
				( pinPairRef "@baseboard_fab2_lib.baseboard_fab2(sch_1):\PP2812\" )
				( pinPairRef "@baseboard_fab2_lib.baseboard_fab2(sch_1):\PP2814\" )
				( objectStatus "M_G_DQ<43>" )
			)
			( signal "@baseboard_fab2_lib.baseboard_fab2(sch_1):m_g_dq(44)"
				( pinPairRef "@baseboard_fab2_lib.baseboard_fab2(sch_1):\PP2815\" )
				( pinPairRef "@baseboard_fab2_lib.baseboard_fab2(sch_1):\PP2817\" )
				( attribute "NO_TEST" "1"
					( Origin gBackEnd )
				)
				( objectStatus "M_G_DQ<44>" )
			)
			( signal "@baseboard_fab2_lib.baseboard_fab2(sch_1):m_b_alert_n"
				( attribute "NO_TEST" "1"
					( Origin gBackEnd )
				)
				( objectStatus "M_B_ALERT_N" )
			)
			( signal "@baseboard_fab2_lib.baseboard_fab2(sch_1):m_c_alert_n"
				( attribute "NO_TEST" "1"
					( Origin gBackEnd )
				)
				( objectStatus "M_C_ALERT_N" )
			)
			( signal "@baseboard_fab2_lib.baseboard_fab2(sch_1):m_d_alert_n"
				( objectStatus "M_D_ALERT_N" )
			)
			( signal "@baseboard_fab2_lib.baseboard_fab2(sch_1):m_e_alert_n"
				( attribute "NO_TEST" "1"
					( Origin gBackEnd )
				)
				( objectStatus "M_E_ALERT_N" )
			)
			( signal "@baseboard_fab2_lib.baseboard_fab2(sch_1):m_f_alert_n"
				( attribute "NO_TEST" "1"
					( Origin gBackEnd )
				)
				( objectStatus "M_F_ALERT_N" )
			)
			( signal "@baseboard_fab2_lib.baseboard_fab2(sch_1):m_g_alert_n"
				( objectStatus "M_G_ALERT_N" )
			)
			( signal "@baseboard_fab2_lib.baseboard_fab2(sch_1):m_h_alert_n"
				( objectStatus "M_H_ALERT_N" )
			)
			( signal "@baseboard_fab2_lib.baseboard_fab2(sch_1):m_j_alert_n"
				( attribute "NO_TEST" "1"
					( Origin gBackEnd )
				)
				( objectStatus "M_J_ALERT_N" )
			)
			( signal "@baseboard_fab2_lib.baseboard_fab2(sch_1):m_k_alert_n"
				( objectStatus "M_K_ALERT_N" )
			)
			( signal "@baseboard_fab2_lib.baseboard_fab2(sch_1):m_l_alert_n"
				( objectStatus "M_L_ALERT_N" )
			)
			( signal "@baseboard_fab2_lib.baseboard_fab2(sch_1):m_m_alert_n"
				( objectStatus "M_M_ALERT_N" )
			)
			( signal "@baseboard_fab2_lib.baseboard_fab2(sch_1):m_a_dq(0)"
				( pinPairRef "@baseboard_fab2_lib.baseboard_fab2(sch_1):\PP5343\" )
				( pinPairRef "@baseboard_fab2_lib.baseboard_fab2(sch_1):\PP5345\" )
				( objectStatus "M_A_DQ<0>" )
			)
			( signal "@baseboard_fab2_lib.baseboard_fab2(sch_1):m_a_dq(1)"
				( pinPairRef "@baseboard_fab2_lib.baseboard_fab2(sch_1):\PP5346\" )
				( pinPairRef "@baseboard_fab2_lib.baseboard_fab2(sch_1):\PP5348\" )
				( attribute "NO_TEST" "1"
					( Origin gBackEnd )
				)
				( objectStatus "M_A_DQ<1>" )
			)
			( signal "@baseboard_fab2_lib.baseboard_fab2(sch_1):m_a_dq(2)"
				( pinPairRef "@baseboard_fab2_lib.baseboard_fab2(sch_1):\PP5349\" )
				( pinPairRef "@baseboard_fab2_lib.baseboard_fab2(sch_1):\PP5351\" )
				( objectStatus "M_A_DQ<2>" )
			)
			( signal "@baseboard_fab2_lib.baseboard_fab2(sch_1):m_a_dq(3)"
				( pinPairRef "@baseboard_fab2_lib.baseboard_fab2(sch_1):\PP5352\" )
				( pinPairRef "@baseboard_fab2_lib.baseboard_fab2(sch_1):\PP5354\" )
				( objectStatus "M_A_DQ<3>" )
			)
			( signal "@baseboard_fab2_lib.baseboard_fab2(sch_1):m_a_dq(4)"
				( pinPairRef "@baseboard_fab2_lib.baseboard_fab2(sch_1):\PP5355\" )
				( pinPairRef "@baseboard_fab2_lib.baseboard_fab2(sch_1):\PP5357\" )
				( attribute "NO_TEST" "1"
					( Origin gBackEnd )
				)
				( objectStatus "M_A_DQ<4>" )
			)
			( signal "@baseboard_fab2_lib.baseboard_fab2(sch_1):m_a_dq(5)"
				( pinPairRef "@baseboard_fab2_lib.baseboard_fab2(sch_1):\PP5358\" )
				( pinPairRef "@baseboard_fab2_lib.baseboard_fab2(sch_1):\PP5360\" )
				( objectStatus "M_A_DQ<5>" )
			)
			( signal "@baseboard_fab2_lib.baseboard_fab2(sch_1):m_a_dq(6)"
				( pinPairRef "@baseboard_fab2_lib.baseboard_fab2(sch_1):\PP5361\" )
				( pinPairRef "@baseboard_fab2_lib.baseboard_fab2(sch_1):\PP5363\" )
				( attribute "NO_TEST" "1"
					( Origin gBackEnd )
				)
				( objectStatus "M_A_DQ<6>" )
			)
			( signal "@baseboard_fab2_lib.baseboard_fab2(sch_1):m_a_dq(7)"
				( pinPairRef "@baseboard_fab2_lib.baseboard_fab2(sch_1):\PP5364\" )
				( pinPairRef "@baseboard_fab2_lib.baseboard_fab2(sch_1):\PP5366\" )
				( attribute "NO_TEST" "1"
					( Origin gBackEnd )
				)
				( objectStatus "M_A_DQ<7>" )
			)
			( signal "@baseboard_fab2_lib.baseboard_fab2(sch_1):m_a_alert_n"
				( objectStatus "M_A_ALERT_N" )
			)
			( signal "@baseboard_fab2_lib.baseboard_fab2(sch_1):m_h_dqs_dn(2)"
				( pinPairRef "@baseboard_fab2_lib.baseboard_fab2(sch_1):\PP841\" )
				( pinPairRef "@baseboard_fab2_lib.baseboard_fab2(sch_1):\PP842\" )
				( attribute "NO_TEST" "1"
					( Origin gBackEnd )
				)
				( objectStatus "M_H_DQS_DN<2>" )
			)
			( signal "@baseboard_fab2_lib.baseboard_fab2(sch_1):m_h_dqs_dp(2)"
				( pinPairRef "@baseboard_fab2_lib.baseboard_fab2(sch_1):\PP844\" )
				( pinPairRef "@baseboard_fab2_lib.baseboard_fab2(sch_1):\PP845\" )
				( objectStatus "M_H_DQS_DP<2>" )
			)
			( signal "@baseboard_fab2_lib.baseboard_fab2(sch_1):m_h_dqs_dn(3)"
				( pinPairRef "@baseboard_fab2_lib.baseboard_fab2(sch_1):\PP829\" )
				( pinPairRef "@baseboard_fab2_lib.baseboard_fab2(sch_1):\PP830\" )
				( objectStatus "M_H_DQS_DN<3>" )
			)
			( signal "@baseboard_fab2_lib.baseboard_fab2(sch_1):m_h_dqs_dp(3)"
				( pinPairRef "@baseboard_fab2_lib.baseboard_fab2(sch_1):\PP832\" )
				( pinPairRef "@baseboard_fab2_lib.baseboard_fab2(sch_1):\PP833\" )
				( objectStatus "M_H_DQS_DP<3>" )
			)
			( signal "@baseboard_fab2_lib.baseboard_fab2(sch_1):m_h_dqs_dn(4)"
				( pinPairRef "@baseboard_fab2_lib.baseboard_fab2(sch_1):\PP817\" )
				( pinPairRef "@baseboard_fab2_lib.baseboard_fab2(sch_1):\PP819\" )
				( objectStatus "M_H_DQS_DN<4>" )
			)
			( signal "@baseboard_fab2_lib.baseboard_fab2(sch_1):m_h_dqs_dp(4)"
				( pinPairRef "@baseboard_fab2_lib.baseboard_fab2(sch_1):\PP820\" )
				( pinPairRef "@baseboard_fab2_lib.baseboard_fab2(sch_1):\PP822\" )
				( attribute "NO_TEST" "1"
					( Origin gBackEnd )
				)
				( objectStatus "M_H_DQS_DP<4>" )
			)
			( signal "@baseboard_fab2_lib.baseboard_fab2(sch_1):m_h_dqs_dn(5)"
				( pinPairRef "@baseboard_fab2_lib.baseboard_fab2(sch_1):\PP805\" )
				( pinPairRef "@baseboard_fab2_lib.baseboard_fab2(sch_1):\PP807\" )
				( attribute "NO_TEST" "1"
					( Origin gBackEnd )
				)
				( objectStatus "M_H_DQS_DN<5>" )
			)
			( signal "@baseboard_fab2_lib.baseboard_fab2(sch_1):m_h_dqs_dp(5)"
				( pinPairRef "@baseboard_fab2_lib.baseboard_fab2(sch_1):\PP808\" )
				( pinPairRef "@baseboard_fab2_lib.baseboard_fab2(sch_1):\PP810\" )
				( attribute "NO_TEST" "1"
					( Origin gBackEnd )
				)
				( objectStatus "M_H_DQS_DP<5>" )
			)
			( signal "@baseboard_fab2_lib.baseboard_fab2(sch_1):m_h_dqs_dn(6)"
				( pinPairRef "@baseboard_fab2_lib.baseboard_fab2(sch_1):\PP793\" )
				( pinPairRef "@baseboard_fab2_lib.baseboard_fab2(sch_1):\PP795\" )
				( objectStatus "M_H_DQS_DN<6>" )
			)
			( signal "@baseboard_fab2_lib.baseboard_fab2(sch_1):m_h_dqs_dp(6)"
				( pinPairRef "@baseboard_fab2_lib.baseboard_fab2(sch_1):\PP796\" )
				( pinPairRef "@baseboard_fab2_lib.baseboard_fab2(sch_1):\PP798\" )
				( objectStatus "M_H_DQS_DP<6>" )
			)
			( signal "@baseboard_fab2_lib.baseboard_fab2(sch_1):m_h_dqs_dn(7)"
				( pinPairRef "@baseboard_fab2_lib.baseboard_fab2(sch_1):\PP781\" )
				( pinPairRef "@baseboard_fab2_lib.baseboard_fab2(sch_1):\PP783\" )
				( attribute "NO_TEST" "1"
					( Origin gBackEnd )
				)
				( objectStatus "M_H_DQS_DN<7>" )
			)
			( signal "@baseboard_fab2_lib.baseboard_fab2(sch_1):m_h_dqs_dp(7)"
				( pinPairRef "@baseboard_fab2_lib.baseboard_fab2(sch_1):\PP784\" )
				( pinPairRef "@baseboard_fab2_lib.baseboard_fab2(sch_1):\PP786\" )
				( attribute "NO_TEST" "1"
					( Origin gBackEnd )
				)
				( objectStatus "M_H_DQS_DP<7>" )
			)
			( signal "@baseboard_fab2_lib.baseboard_fab2(sch_1):m_h_dqs_dn(8)"
				( pinPairRef "@baseboard_fab2_lib.baseboard_fab2(sch_1):\PP769\" )
				( pinPairRef "@baseboard_fab2_lib.baseboard_fab2(sch_1):\PP770\" )
				( attribute "NO_TEST" "1"
					( Origin gBackEnd )
				)
				( objectStatus "M_H_DQS_DN<8>" )
			)
			( signal "@baseboard_fab2_lib.baseboard_fab2(sch_1):m_h_dqs_dp(8)"
				( pinPairRef "@baseboard_fab2_lib.baseboard_fab2(sch_1):\PP772\" )
				( pinPairRef "@baseboard_fab2_lib.baseboard_fab2(sch_1):\PP773\" )
				( attribute "NO_TEST" "1"
					( Origin gBackEnd )
				)
				( objectStatus "M_H_DQS_DP<8>" )
			)
			( signal "@baseboard_fab2_lib.baseboard_fab2(sch_1):m_h_dqs_dn(9)"
				( pinPairRef "@baseboard_fab2_lib.baseboard_fab2(sch_1):\PP859\" )
				( pinPairRef "@baseboard_fab2_lib.baseboard_fab2(sch_1):\PP860\" )
				( objectStatus "M_H_DQS_DN<9>" )
			)
			( signal "@baseboard_fab2_lib.baseboard_fab2(sch_1):m_h_dqs_dp(9)"
				( pinPairRef "@baseboard_fab2_lib.baseboard_fab2(sch_1):\PP862\" )
				( pinPairRef "@baseboard_fab2_lib.baseboard_fab2(sch_1):\PP863\" )
				( attribute "NO_TEST" "1"
					( Origin gBackEnd )
				)
				( objectStatus "M_H_DQS_DP<9>" )
			)
			( signal "@baseboard_fab2_lib.baseboard_fab2(sch_1):m_h_dqs_dn(10)"
				( pinPairRef "@baseboard_fab2_lib.baseboard_fab2(sch_1):\PP847\" )
				( pinPairRef "@baseboard_fab2_lib.baseboard_fab2(sch_1):\PP848\" )
				( attribute "NO_TEST" "1"
					( Origin gBackEnd )
				)
				( objectStatus "M_H_DQS_DN<10>" )
			)
			( signal "@baseboard_fab2_lib.baseboard_fab2(sch_1):m_h_dqs_dp(10)"
				( pinPairRef "@baseboard_fab2_lib.baseboard_fab2(sch_1):\PP850\" )
				( pinPairRef "@baseboard_fab2_lib.baseboard_fab2(sch_1):\PP851\" )
				( objectStatus "M_H_DQS_DP<10>" )
			)
			( signal "@baseboard_fab2_lib.baseboard_fab2(sch_1):m_h_dqs_dn(11)"
				( pinPairRef "@baseboard_fab2_lib.baseboard_fab2(sch_1):\PP835\" )
				( pinPairRef "@baseboard_fab2_lib.baseboard_fab2(sch_1):\PP836\" )
				( objectStatus "M_H_DQS_DN<11>" )
			)
			( signal "@baseboard_fab2_lib.baseboard_fab2(sch_1):m_h_dqs_dp(11)"
				( pinPairRef "@baseboard_fab2_lib.baseboard_fab2(sch_1):\PP838\" )
				( pinPairRef "@baseboard_fab2_lib.baseboard_fab2(sch_1):\PP839\" )
				( attribute "NO_TEST" "1"
					( Origin gBackEnd )
				)
				( objectStatus "M_H_DQS_DP<11>" )
			)
			( signal "@baseboard_fab2_lib.baseboard_fab2(sch_1):m_h_dqs_dn(12)"
				( pinPairRef "@baseboard_fab2_lib.baseboard_fab2(sch_1):\PP823\" )
				( pinPairRef "@baseboard_fab2_lib.baseboard_fab2(sch_1):\PP824\" )
				( objectStatus "M_H_DQS_DN<12>" )
			)
			( signal "@baseboard_fab2_lib.baseboard_fab2(sch_1):m_h_dqs_dp(12)"
				( pinPairRef "@baseboard_fab2_lib.baseboard_fab2(sch_1):\PP826\" )
				( pinPairRef "@baseboard_fab2_lib.baseboard_fab2(sch_1):\PP827\" )
				( objectStatus "M_H_DQS_DP<12>" )
			)
			( signal "@baseboard_fab2_lib.baseboard_fab2(sch_1):m_h_dqs_dn(13)"
				( pinPairRef "@baseboard_fab2_lib.baseboard_fab2(sch_1):\PP811\" )
				( pinPairRef "@baseboard_fab2_lib.baseboard_fab2(sch_1):\PP813\" )
				( objectStatus "M_H_DQS_DN<13>" )
			)
			( signal "@baseboard_fab2_lib.baseboard_fab2(sch_1):m_h_dqs_dp(13)"
				( pinPairRef "@baseboard_fab2_lib.baseboard_fab2(sch_1):\PP814\" )
				( pinPairRef "@baseboard_fab2_lib.baseboard_fab2(sch_1):\PP816\" )
				( attribute "NO_TEST" "1"
					( Origin gBackEnd )
				)
				( objectStatus "M_H_DQS_DP<13>" )
			)
			( signal "@baseboard_fab2_lib.baseboard_fab2(sch_1):m_h_dqs_dn(14)"
				( pinPairRef "@baseboard_fab2_lib.baseboard_fab2(sch_1):\PP799\" )
				( pinPairRef "@baseboard_fab2_lib.baseboard_fab2(sch_1):\PP801\" )
				( attribute "NO_TEST" "1"
					( Origin gBackEnd )
				)
				( objectStatus "M_H_DQS_DN<14>" )
			)
			( signal "@baseboard_fab2_lib.baseboard_fab2(sch_1):m_h_dqs_dp(14)"
				( pinPairRef "@baseboard_fab2_lib.baseboard_fab2(sch_1):\PP802\" )
				( pinPairRef "@baseboard_fab2_lib.baseboard_fab2(sch_1):\PP804\" )
				( attribute "NO_TEST" "1"
					( Origin gBackEnd )
				)
				( objectStatus "M_H_DQS_DP<14>" )
			)
			( signal "@baseboard_fab2_lib.baseboard_fab2(sch_1):m_h_dqs_dn(15)"
				( pinPairRef "@baseboard_fab2_lib.baseboard_fab2(sch_1):\PP787\" )
				( pinPairRef "@baseboard_fab2_lib.baseboard_fab2(sch_1):\PP789\" )
				( objectStatus "M_H_DQS_DN<15>" )
			)
			( signal "@baseboard_fab2_lib.baseboard_fab2(sch_1):m_h_dqs_dp(15)"
				( pinPairRef "@baseboard_fab2_lib.baseboard_fab2(sch_1):\PP790\" )
				( pinPairRef "@baseboard_fab2_lib.baseboard_fab2(sch_1):\PP792\" )
				( objectStatus "M_H_DQS_DP<15>" )
			)
			( signal "@baseboard_fab2_lib.baseboard_fab2(sch_1):m_h_dqs_dn(16)"
				( pinPairRef "@baseboard_fab2_lib.baseboard_fab2(sch_1):\PP775\" )
				( pinPairRef "@baseboard_fab2_lib.baseboard_fab2(sch_1):\PP777\" )
				( attribute "NO_TEST" "1"
					( Origin gBackEnd )
				)
				( objectStatus "M_H_DQS_DN<16>" )
			)
			( signal "@baseboard_fab2_lib.baseboard_fab2(sch_1):m_h_dqs_dp(16)"
				( pinPairRef "@baseboard_fab2_lib.baseboard_fab2(sch_1):\PP778\" )
				( pinPairRef "@baseboard_fab2_lib.baseboard_fab2(sch_1):\PP780\" )
				( objectStatus "M_H_DQS_DP<16>" )
			)
			( signal "@baseboard_fab2_lib.baseboard_fab2(sch_1):m_h_dqs_dn(17)"
				( pinPairRef "@baseboard_fab2_lib.baseboard_fab2(sch_1):\PP763\" )
				( pinPairRef "@baseboard_fab2_lib.baseboard_fab2(sch_1):\PP764\" )
				( attribute "NO_TEST" "1"
					( Origin gBackEnd )
				)
				( objectStatus "M_H_DQS_DN<17>" )
			)
			( signal "@baseboard_fab2_lib.baseboard_fab2(sch_1):m_h_dqs_dp(17)"
				( pinPairRef "@baseboard_fab2_lib.baseboard_fab2(sch_1):\PP766\" )
				( pinPairRef "@baseboard_fab2_lib.baseboard_fab2(sch_1):\PP767\" )
				( attribute "NO_TEST" "1"
					( Origin gBackEnd )
				)
				( objectStatus "M_H_DQS_DP<17>" )
			)
			( signal "@baseboard_fab2_lib.baseboard_fab2(sch_1):m_j_dqs_dn(0)"
				( pinPairRef "@baseboard_fab2_lib.baseboard_fab2(sch_1):\PP1669\" )
				( pinPairRef "@baseboard_fab2_lib.baseboard_fab2(sch_1):\PP1670\" )
				( attribute "NO_TEST" "1"
					( Origin gBackEnd )
				)
				( objectStatus "M_J_DQS_DN<0>" )
			)
			( signal "@baseboard_fab2_lib.baseboard_fab2(sch_1):m_j_dqs_dp(0)"
				( pinPairRef "@baseboard_fab2_lib.baseboard_fab2(sch_1):\PP1672\" )
				( pinPairRef "@baseboard_fab2_lib.baseboard_fab2(sch_1):\PP1673\" )
				( attribute "NO_TEST" "1"
					( Origin gBackEnd )
				)
				( objectStatus "M_J_DQS_DP<0>" )
			)
			( signal "@baseboard_fab2_lib.baseboard_fab2(sch_1):m_j_dqs_dn(1)"
				( pinPairRef "@baseboard_fab2_lib.baseboard_fab2(sch_1):\PP1657\" )
				( pinPairRef "@baseboard_fab2_lib.baseboard_fab2(sch_1):\PP1658\" )
				( attribute "NO_TEST" "1"
					( Origin gBackEnd )
				)
				( objectStatus "M_J_DQS_DN<1>" )
			)
			( signal "@baseboard_fab2_lib.baseboard_fab2(sch_1):m_j_dqs_dp(1)"
				( pinPairRef "@baseboard_fab2_lib.baseboard_fab2(sch_1):\PP1660\" )
				( pinPairRef "@baseboard_fab2_lib.baseboard_fab2(sch_1):\PP1661\" )
				( attribute "NO_TEST" "1"
					( Origin gBackEnd )
				)
				( objectStatus "M_J_DQS_DP<1>" )
			)
			( signal "@baseboard_fab2_lib.baseboard_fab2(sch_1):m_j_dqs_dn(2)"
				( pinPairRef "@baseboard_fab2_lib.baseboard_fab2(sch_1):\PP1645\" )
				( pinPairRef "@baseboard_fab2_lib.baseboard_fab2(sch_1):\PP1646\" )
				( attribute "NO_TEST" "1"
					( Origin gBackEnd )
				)
				( objectStatus "M_J_DQS_DN<2>" )
			)
			( signal "@baseboard_fab2_lib.baseboard_fab2(sch_1):m_j_dqs_dp(2)"
				( pinPairRef "@baseboard_fab2_lib.baseboard_fab2(sch_1):\PP1648\" )
				( pinPairRef "@baseboard_fab2_lib.baseboard_fab2(sch_1):\PP1649\" )
				( objectStatus "M_J_DQS_DP<2>" )
			)
			( signal "@baseboard_fab2_lib.baseboard_fab2(sch_1):m_j_dqs_dn(3)"
				( pinPairRef "@baseboard_fab2_lib.baseboard_fab2(sch_1):\PP1633\" )
				( pinPairRef "@baseboard_fab2_lib.baseboard_fab2(sch_1):\PP1634\" )
				( attribute "NO_TEST" "1"
					( Origin gBackEnd )
				)
				( objectStatus "M_J_DQS_DN<3>" )
			)
			( signal "@baseboard_fab2_lib.baseboard_fab2(sch_1):m_j_dqs_dp(3)"
				( pinPairRef "@baseboard_fab2_lib.baseboard_fab2(sch_1):\PP1636\" )
				( pinPairRef "@baseboard_fab2_lib.baseboard_fab2(sch_1):\PP1637\" )
				( objectStatus "M_J_DQS_DP<3>" )
			)
			( signal "@baseboard_fab2_lib.baseboard_fab2(sch_1):m_j_dqs_dn(4)"
				( pinPairRef "@baseboard_fab2_lib.baseboard_fab2(sch_1):\PP1621\" )
				( pinPairRef "@baseboard_fab2_lib.baseboard_fab2(sch_1):\PP1623\" )
				( attribute "NO_TEST" "1"
					( Origin gBackEnd )
				)
				( objectStatus "M_J_DQS_DN<4>" )
			)
			( signal "@baseboard_fab2_lib.baseboard_fab2(sch_1):m_j_dqs_dp(4)"
				( pinPairRef "@baseboard_fab2_lib.baseboard_fab2(sch_1):\PP1624\" )
				( pinPairRef "@baseboard_fab2_lib.baseboard_fab2(sch_1):\PP1626\" )
				( objectStatus "M_J_DQS_DP<4>" )
			)
			( signal "@baseboard_fab2_lib.baseboard_fab2(sch_1):m_j_dqs_dn(5)"
				( pinPairRef "@baseboard_fab2_lib.baseboard_fab2(sch_1):\PP1609\" )
				( pinPairRef "@baseboard_fab2_lib.baseboard_fab2(sch_1):\PP1611\" )
				( attribute "NO_TEST" "1"
					( Origin gBackEnd )
				)
				( objectStatus "M_J_DQS_DN<5>" )
			)
			( signal "@baseboard_fab2_lib.baseboard_fab2(sch_1):m_j_dqs_dp(5)"
				( pinPairRef "@baseboard_fab2_lib.baseboard_fab2(sch_1):\PP1612\" )
				( pinPairRef "@baseboard_fab2_lib.baseboard_fab2(sch_1):\PP1614\" )
				( objectStatus "M_J_DQS_DP<5>" )
			)
			( signal "@baseboard_fab2_lib.baseboard_fab2(sch_1):m_j_dqs_dn(6)"
				( pinPairRef "@baseboard_fab2_lib.baseboard_fab2(sch_1):\PP1597\" )
				( pinPairRef "@baseboard_fab2_lib.baseboard_fab2(sch_1):\PP1599\" )
				( attribute "NO_TEST" "1"
					( Origin gBackEnd )
				)
				( objectStatus "M_J_DQS_DN<6>" )
			)
			( signal "@baseboard_fab2_lib.baseboard_fab2(sch_1):m_j_dqs_dp(6)"
				( pinPairRef "@baseboard_fab2_lib.baseboard_fab2(sch_1):\PP1600\" )
				( pinPairRef "@baseboard_fab2_lib.baseboard_fab2(sch_1):\PP1602\" )
				( objectStatus "M_J_DQS_DP<6>" )
			)
			( signal "@baseboard_fab2_lib.baseboard_fab2(sch_1):m_j_dqs_dn(7)"
				( pinPairRef "@baseboard_fab2_lib.baseboard_fab2(sch_1):\PP1585\" )
				( pinPairRef "@baseboard_fab2_lib.baseboard_fab2(sch_1):\PP1587\" )
				( attribute "NO_TEST" "1"
					( Origin gBackEnd )
				)
				( objectStatus "M_J_DQS_DN<7>" )
			)
			( signal "@baseboard_fab2_lib.baseboard_fab2(sch_1):m_j_dqs_dp(7)"
				( pinPairRef "@baseboard_fab2_lib.baseboard_fab2(sch_1):\PP1588\" )
				( pinPairRef "@baseboard_fab2_lib.baseboard_fab2(sch_1):\PP1590\" )
				( objectStatus "M_J_DQS_DP<7>" )
			)
			( signal "@baseboard_fab2_lib.baseboard_fab2(sch_1):m_j_dqs_dn(8)"
				( pinPairRef "@baseboard_fab2_lib.baseboard_fab2(sch_1):\PP1249\" )
				( pinPairRef "@baseboard_fab2_lib.baseboard_fab2(sch_1):\PP1250\" )
				( attribute "NO_TEST" "1"
					( Origin gBackEnd )
				)
				( objectStatus "M_J_DQS_DN<8>" )
			)
			( signal "@baseboard_fab2_lib.baseboard_fab2(sch_1):m_j_dqs_dp(8)"
				( pinPairRef "@baseboard_fab2_lib.baseboard_fab2(sch_1):\PP1252\" )
				( pinPairRef "@baseboard_fab2_lib.baseboard_fab2(sch_1):\PP1253\" )
				( objectStatus "M_J_DQS_DP<8>" )
			)
			( signal "@baseboard_fab2_lib.baseboard_fab2(sch_1):m_j_dqs_dn(9)"
				( pinPairRef "@baseboard_fab2_lib.baseboard_fab2(sch_1):\PP1663\" )
				( pinPairRef "@baseboard_fab2_lib.baseboard_fab2(sch_1):\PP1664\" )
				( objectStatus "M_J_DQS_DN<9>" )
			)
			( signal "@baseboard_fab2_lib.baseboard_fab2(sch_1):m_j_dqs_dp(9)"
				( pinPairRef "@baseboard_fab2_lib.baseboard_fab2(sch_1):\PP1666\" )
				( pinPairRef "@baseboard_fab2_lib.baseboard_fab2(sch_1):\PP1667\" )
				( attribute "NO_TEST" "1"
					( Origin gBackEnd )
				)
				( objectStatus "M_J_DQS_DP<9>" )
			)
			( signal "@baseboard_fab2_lib.baseboard_fab2(sch_1):m_j_dqs_dn(10)"
				( pinPairRef "@baseboard_fab2_lib.baseboard_fab2(sch_1):\PP1651\" )
				( pinPairRef "@baseboard_fab2_lib.baseboard_fab2(sch_1):\PP1652\" )
				( objectStatus "M_J_DQS_DN<10>" )
			)
			( signal "@baseboard_fab2_lib.baseboard_fab2(sch_1):m_j_dqs_dp(10)"
				( pinPairRef "@baseboard_fab2_lib.baseboard_fab2(sch_1):\PP1654\" )
				( pinPairRef "@baseboard_fab2_lib.baseboard_fab2(sch_1):\PP1655\" )
				( attribute "NO_TEST" "1"
					( Origin gBackEnd )
				)
				( objectStatus "M_J_DQS_DP<10>" )
			)
			( signal "@baseboard_fab2_lib.baseboard_fab2(sch_1):m_j_dqs_dn(11)"
				( pinPairRef "@baseboard_fab2_lib.baseboard_fab2(sch_1):\PP1639\" )
				( pinPairRef "@baseboard_fab2_lib.baseboard_fab2(sch_1):\PP1640\" )
				( objectStatus "M_J_DQS_DN<11>" )
			)
			( signal "@baseboard_fab2_lib.baseboard_fab2(sch_1):m_j_dqs_dp(11)"
				( pinPairRef "@baseboard_fab2_lib.baseboard_fab2(sch_1):\PP1642\" )
				( pinPairRef "@baseboard_fab2_lib.baseboard_fab2(sch_1):\PP1643\" )
				( attribute "NO_TEST" "1"
					( Origin gBackEnd )
				)
				( objectStatus "M_J_DQS_DP<11>" )
			)
			( signal "@baseboard_fab2_lib.baseboard_fab2(sch_1):m_j_dqs_dn(12)"
				( pinPairRef "@baseboard_fab2_lib.baseboard_fab2(sch_1):\PP1627\" )
				( pinPairRef "@baseboard_fab2_lib.baseboard_fab2(sch_1):\PP1628\" )
				( attribute "NO_TEST" "1"
					( Origin gBackEnd )
				)
				( objectStatus "M_J_DQS_DN<12>" )
			)
			( signal "@baseboard_fab2_lib.baseboard_fab2(sch_1):m_j_dqs_dp(12)"
				( pinPairRef "@baseboard_fab2_lib.baseboard_fab2(sch_1):\PP1630\" )
				( pinPairRef "@baseboard_fab2_lib.baseboard_fab2(sch_1):\PP1631\" )
				( attribute "NO_TEST" "1"
					( Origin gBackEnd )
				)
				( objectStatus "M_J_DQS_DP<12>" )
			)
			( signal "@baseboard_fab2_lib.baseboard_fab2(sch_1):m_j_dqs_dn(13)"
				( pinPairRef "@baseboard_fab2_lib.baseboard_fab2(sch_1):\PP1615\" )
				( pinPairRef "@baseboard_fab2_lib.baseboard_fab2(sch_1):\PP1617\" )
				( objectStatus "M_J_DQS_DN<13>" )
			)
			( signal "@baseboard_fab2_lib.baseboard_fab2(sch_1):m_j_dqs_dp(13)"
				( pinPairRef "@baseboard_fab2_lib.baseboard_fab2(sch_1):\PP1618\" )
				( pinPairRef "@baseboard_fab2_lib.baseboard_fab2(sch_1):\PP1620\" )
				( attribute "NO_TEST" "1"
					( Origin gBackEnd )
				)
				( objectStatus "M_J_DQS_DP<13>" )
			)
			( signal "@baseboard_fab2_lib.baseboard_fab2(sch_1):m_j_dqs_dn(14)"
				( pinPairRef "@baseboard_fab2_lib.baseboard_fab2(sch_1):\PP1603\" )
				( pinPairRef "@baseboard_fab2_lib.baseboard_fab2(sch_1):\PP1605\" )
				( objectStatus "M_J_DQS_DN<14>" )
			)
			( signal "@baseboard_fab2_lib.baseboard_fab2(sch_1):m_j_dqs_dp(14)"
				( pinPairRef "@baseboard_fab2_lib.baseboard_fab2(sch_1):\PP1606\" )
				( pinPairRef "@baseboard_fab2_lib.baseboard_fab2(sch_1):\PP1608\" )
				( attribute "NO_TEST" "1"
					( Origin gBackEnd )
				)
				( objectStatus "M_J_DQS_DP<14>" )
			)
			( signal "@baseboard_fab2_lib.baseboard_fab2(sch_1):m_j_dqs_dn(15)"
				( pinPairRef "@baseboard_fab2_lib.baseboard_fab2(sch_1):\PP1591\" )
				( pinPairRef "@baseboard_fab2_lib.baseboard_fab2(sch_1):\PP1593\" )
				( attribute "NO_TEST" "1"
					( Origin gBackEnd )
				)
				( objectStatus "M_J_DQS_DN<15>" )
			)
			( signal "@baseboard_fab2_lib.baseboard_fab2(sch_1):m_j_dqs_dp(15)"
				( pinPairRef "@baseboard_fab2_lib.baseboard_fab2(sch_1):\PP1594\" )
				( pinPairRef "@baseboard_fab2_lib.baseboard_fab2(sch_1):\PP1596\" )
				( attribute "NO_TEST" "1"
					( Origin gBackEnd )
				)
				( objectStatus "M_J_DQS_DP<15>" )
			)
			( signal "@baseboard_fab2_lib.baseboard_fab2(sch_1):m_j_dqs_dn(16)"
				( pinPairRef "@baseboard_fab2_lib.baseboard_fab2(sch_1):\PP1579\" )
				( pinPairRef "@baseboard_fab2_lib.baseboard_fab2(sch_1):\PP1581\" )
				( attribute "NO_TEST" "1"
					( Origin gBackEnd )
				)
				( objectStatus "M_J_DQS_DN<16>" )
			)
			( signal "@baseboard_fab2_lib.baseboard_fab2(sch_1):m_j_dqs_dp(16)"
				( pinPairRef "@baseboard_fab2_lib.baseboard_fab2(sch_1):\PP1582\" )
				( pinPairRef "@baseboard_fab2_lib.baseboard_fab2(sch_1):\PP1584\" )
				( attribute "NO_TEST" "1"
					( Origin gBackEnd )
				)
				( objectStatus "M_J_DQS_DP<16>" )
			)
			( signal "@baseboard_fab2_lib.baseboard_fab2(sch_1):m_j_dqs_dn(17)"
				( pinPairRef "@baseboard_fab2_lib.baseboard_fab2(sch_1):\PP1243\" )
				( pinPairRef "@baseboard_fab2_lib.baseboard_fab2(sch_1):\PP1244\" )
				( attribute "NO_TEST" "1"
					( Origin gBackEnd )
				)
				( objectStatus "M_J_DQS_DN<17>" )
			)
			( signal "@baseboard_fab2_lib.baseboard_fab2(sch_1):m_j_dqs_dp(17)"
				( pinPairRef "@baseboard_fab2_lib.baseboard_fab2(sch_1):\PP1246\" )
				( pinPairRef "@baseboard_fab2_lib.baseboard_fab2(sch_1):\PP1247\" )
				( attribute "NO_TEST" "1"
					( Origin gBackEnd )
				)
				( objectStatus "M_J_DQS_DP<17>" )
			)
			( signal "@baseboard_fab2_lib.baseboard_fab2(sch_1):m_k_dqs_dn(0)"
				( pinPairRef "@baseboard_fab2_lib.baseboard_fab2(sch_1):\PP1573\" )
				( pinPairRef "@baseboard_fab2_lib.baseboard_fab2(sch_1):\PP1574\" )
				( attribute "NO_TEST" "1"
					( Origin gBackEnd )
				)
				( objectStatus "M_K_DQS_DN<0>" )
			)
			( signal "@baseboard_fab2_lib.baseboard_fab2(sch_1):m_k_dqs_dp(0)"
				( pinPairRef "@baseboard_fab2_lib.baseboard_fab2(sch_1):\PP1576\" )
				( pinPairRef "@baseboard_fab2_lib.baseboard_fab2(sch_1):\PP1577\" )
				( attribute "NO_TEST" "1"
					( Origin gBackEnd )
				)
				( objectStatus "M_K_DQS_DP<0>" )
			)
			( signal "@baseboard_fab2_lib.baseboard_fab2(sch_1):m_k_dqs_dn(1)"
				( pinPairRef "@baseboard_fab2_lib.baseboard_fab2(sch_1):\PP1561\" )
				( pinPairRef "@baseboard_fab2_lib.baseboard_fab2(sch_1):\PP1562\" )
				( attribute "NO_TEST" "1"
					( Origin gBackEnd )
				)
				( objectStatus "M_K_DQS_DN<1>" )
			)
			( signal "@baseboard_fab2_lib.baseboard_fab2(sch_1):m_k_dqs_dp(1)"
				( pinPairRef "@baseboard_fab2_lib.baseboard_fab2(sch_1):\PP1564\" )
				( pinPairRef "@baseboard_fab2_lib.baseboard_fab2(sch_1):\PP1565\" )
				( attribute "NO_TEST" "1"
					( Origin gBackEnd )
				)
				( objectStatus "M_K_DQS_DP<1>" )
			)
			( signal "@baseboard_fab2_lib.baseboard_fab2(sch_1):m_k_dqs_dn(2)"
				( pinPairRef "@baseboard_fab2_lib.baseboard_fab2(sch_1):\PP1549\" )
				( pinPairRef "@baseboard_fab2_lib.baseboard_fab2(sch_1):\PP1550\" )
				( attribute "NO_TEST" "1"
					( Origin gBackEnd )
				)
				( objectStatus "M_K_DQS_DN<2>" )
			)
			( signal "@baseboard_fab2_lib.baseboard_fab2(sch_1):m_k_dqs_dp(2)"
				( pinPairRef "@baseboard_fab2_lib.baseboard_fab2(sch_1):\PP1552\" )
				( pinPairRef "@baseboard_fab2_lib.baseboard_fab2(sch_1):\PP1553\" )
				( attribute "NO_TEST" "1"
					( Origin gBackEnd )
				)
				( objectStatus "M_K_DQS_DP<2>" )
			)
			( signal "@baseboard_fab2_lib.baseboard_fab2(sch_1):m_k_dqs_dn(3)"
				( pinPairRef "@baseboard_fab2_lib.baseboard_fab2(sch_1):\PP1537\" )
				( pinPairRef "@baseboard_fab2_lib.baseboard_fab2(sch_1):\PP1538\" )
				( attribute "NO_TEST" "1"
					( Origin gBackEnd )
				)
				( objectStatus "M_K_DQS_DN<3>" )
			)
			( signal "@baseboard_fab2_lib.baseboard_fab2(sch_1):m_k_dqs_dp(3)"
				( pinPairRef "@baseboard_fab2_lib.baseboard_fab2(sch_1):\PP1540\" )
				( pinPairRef "@baseboard_fab2_lib.baseboard_fab2(sch_1):\PP1541\" )
				( objectStatus "M_K_DQS_DP<3>" )
			)
			( signal "@baseboard_fab2_lib.baseboard_fab2(sch_1):m_k_dqs_dn(4)"
				( pinPairRef "@baseboard_fab2_lib.baseboard_fab2(sch_1):\PP1525\" )
				( pinPairRef "@baseboard_fab2_lib.baseboard_fab2(sch_1):\PP1527\" )
				( attribute "NO_TEST" "1"
					( Origin gBackEnd )
				)
				( objectStatus "M_K_DQS_DN<4>" )
			)
			( signal "@baseboard_fab2_lib.baseboard_fab2(sch_1):m_k_dqs_dp(4)"
				( pinPairRef "@baseboard_fab2_lib.baseboard_fab2(sch_1):\PP1528\" )
				( pinPairRef "@baseboard_fab2_lib.baseboard_fab2(sch_1):\PP1530\" )
				( attribute "NO_TEST" "1"
					( Origin gBackEnd )
				)
				( objectStatus "M_K_DQS_DP<4>" )
			)
			( signal "@baseboard_fab2_lib.baseboard_fab2(sch_1):m_k_dqs_dn(5)"
				( pinPairRef "@baseboard_fab2_lib.baseboard_fab2(sch_1):\PP1513\" )
				( pinPairRef "@baseboard_fab2_lib.baseboard_fab2(sch_1):\PP1515\" )
				( attribute "NO_TEST" "1"
					( Origin gBackEnd )
				)
				( objectStatus "M_K_DQS_DN<5>" )
			)
			( signal "@baseboard_fab2_lib.baseboard_fab2(sch_1):m_k_dqs_dp(5)"
				( pinPairRef "@baseboard_fab2_lib.baseboard_fab2(sch_1):\PP1516\" )
				( pinPairRef "@baseboard_fab2_lib.baseboard_fab2(sch_1):\PP1518\" )
				( attribute "NO_TEST" "1"
					( Origin gBackEnd )
				)
				( objectStatus "M_K_DQS_DP<5>" )
			)
			( signal "@baseboard_fab2_lib.baseboard_fab2(sch_1):m_k_dqs_dn(6)"
				( pinPairRef "@baseboard_fab2_lib.baseboard_fab2(sch_1):\PP1501\" )
				( pinPairRef "@baseboard_fab2_lib.baseboard_fab2(sch_1):\PP1503\" )
				( attribute "NO_TEST" "1"
					( Origin gBackEnd )
				)
				( objectStatus "M_K_DQS_DN<6>" )
			)
			( signal "@baseboard_fab2_lib.baseboard_fab2(sch_1):m_k_dqs_dp(6)"
				( pinPairRef "@baseboard_fab2_lib.baseboard_fab2(sch_1):\PP1504\" )
				( pinPairRef "@baseboard_fab2_lib.baseboard_fab2(sch_1):\PP1506\" )
				( objectStatus "M_K_DQS_DP<6>" )
			)
			( signal "@baseboard_fab2_lib.baseboard_fab2(sch_1):m_k_dqs_dn(7)"
				( pinPairRef "@baseboard_fab2_lib.baseboard_fab2(sch_1):\PP1489\" )
				( pinPairRef "@baseboard_fab2_lib.baseboard_fab2(sch_1):\PP1491\" )
				( attribute "NO_TEST" "1"
					( Origin gBackEnd )
				)
				( objectStatus "M_K_DQS_DN<7>" )
			)
			( signal "@baseboard_fab2_lib.baseboard_fab2(sch_1):m_k_dqs_dp(7)"
				( pinPairRef "@baseboard_fab2_lib.baseboard_fab2(sch_1):\PP1492\" )
				( pinPairRef "@baseboard_fab2_lib.baseboard_fab2(sch_1):\PP1494\" )
				( attribute "NO_TEST" "1"
					( Origin gBackEnd )
				)
				( objectStatus "M_K_DQS_DP<7>" )
			)
			( signal "@baseboard_fab2_lib.baseboard_fab2(sch_1):m_k_dqs_dn(8)"
				( pinPairRef "@baseboard_fab2_lib.baseboard_fab2(sch_1):\PP1261\" )
				( pinPairRef "@baseboard_fab2_lib.baseboard_fab2(sch_1):\PP1262\" )
				( objectStatus "M_K_DQS_DN<8>" )
			)
			( signal "@baseboard_fab2_lib.baseboard_fab2(sch_1):m_k_dqs_dp(8)"
				( pinPairRef "@baseboard_fab2_lib.baseboard_fab2(sch_1):\PP1264\" )
				( pinPairRef "@baseboard_fab2_lib.baseboard_fab2(sch_1):\PP1265\" )
				( attribute "NO_TEST" "1"
					( Origin gBackEnd )
				)
				( objectStatus "M_K_DQS_DP<8>" )
			)
			( signal "@baseboard_fab2_lib.baseboard_fab2(sch_1):m_k_dqs_dn(9)"
				( pinPairRef "@baseboard_fab2_lib.baseboard_fab2(sch_1):\PP1567\" )
				( pinPairRef "@baseboard_fab2_lib.baseboard_fab2(sch_1):\PP1568\" )
				( objectStatus "M_K_DQS_DN<9>" )
			)
			( signal "@baseboard_fab2_lib.baseboard_fab2(sch_1):m_k_dqs_dp(9)"
				( pinPairRef "@baseboard_fab2_lib.baseboard_fab2(sch_1):\PP1570\" )
				( pinPairRef "@baseboard_fab2_lib.baseboard_fab2(sch_1):\PP1571\" )
				( attribute "NO_TEST" "1"
					( Origin gBackEnd )
				)
				( objectStatus "M_K_DQS_DP<9>" )
			)
			( signal "@baseboard_fab2_lib.baseboard_fab2(sch_1):m_k_dqs_dn(10)"
				( pinPairRef "@baseboard_fab2_lib.baseboard_fab2(sch_1):\PP1555\" )
				( pinPairRef "@baseboard_fab2_lib.baseboard_fab2(sch_1):\PP1556\" )
				( attribute "NO_TEST" "1"
					( Origin gBackEnd )
				)
				( objectStatus "M_K_DQS_DN<10>" )
			)
			( signal "@baseboard_fab2_lib.baseboard_fab2(sch_1):m_k_dqs_dp(10)"
				( pinPairRef "@baseboard_fab2_lib.baseboard_fab2(sch_1):\PP1558\" )
				( pinPairRef "@baseboard_fab2_lib.baseboard_fab2(sch_1):\PP1559\" )
				( attribute "NO_TEST" "1"
					( Origin gBackEnd )
				)
				( objectStatus "M_K_DQS_DP<10>" )
			)
			( signal "@baseboard_fab2_lib.baseboard_fab2(sch_1):m_k_dqs_dn(11)"
				( pinPairRef "@baseboard_fab2_lib.baseboard_fab2(sch_1):\PP1543\" )
				( pinPairRef "@baseboard_fab2_lib.baseboard_fab2(sch_1):\PP1544\" )
				( objectStatus "M_K_DQS_DN<11>" )
			)
			( signal "@baseboard_fab2_lib.baseboard_fab2(sch_1):m_k_dqs_dp(11)"
				( pinPairRef "@baseboard_fab2_lib.baseboard_fab2(sch_1):\PP1546\" )
				( pinPairRef "@baseboard_fab2_lib.baseboard_fab2(sch_1):\PP1547\" )
				( attribute "NO_TEST" "1"
					( Origin gBackEnd )
				)
				( objectStatus "M_K_DQS_DP<11>" )
			)
			( signal "@baseboard_fab2_lib.baseboard_fab2(sch_1):m_k_dqs_dn(12)"
				( pinPairRef "@baseboard_fab2_lib.baseboard_fab2(sch_1):\PP1531\" )
				( pinPairRef "@baseboard_fab2_lib.baseboard_fab2(sch_1):\PP1532\" )
				( attribute "NO_TEST" "1"
					( Origin gBackEnd )
				)
				( objectStatus "M_K_DQS_DN<12>" )
			)
			( signal "@baseboard_fab2_lib.baseboard_fab2(sch_1):m_k_dqs_dp(12)"
				( pinPairRef "@baseboard_fab2_lib.baseboard_fab2(sch_1):\PP1534\" )
				( pinPairRef "@baseboard_fab2_lib.baseboard_fab2(sch_1):\PP1535\" )
				( attribute "NO_TEST" "1"
					( Origin gBackEnd )
				)
				( objectStatus "M_K_DQS_DP<12>" )
			)
			( signal "@baseboard_fab2_lib.baseboard_fab2(sch_1):m_k_dqs_dn(13)"
				( pinPairRef "@baseboard_fab2_lib.baseboard_fab2(sch_1):\PP1519\" )
				( pinPairRef "@baseboard_fab2_lib.baseboard_fab2(sch_1):\PP1521\" )
				( attribute "NO_TEST" "1"
					( Origin gBackEnd )
				)
				( objectStatus "M_K_DQS_DN<13>" )
			)
			( signal "@baseboard_fab2_lib.baseboard_fab2(sch_1):m_k_dqs_dp(13)"
				( pinPairRef "@baseboard_fab2_lib.baseboard_fab2(sch_1):\PP1522\" )
				( pinPairRef "@baseboard_fab2_lib.baseboard_fab2(sch_1):\PP1524\" )
				( attribute "NO_TEST" "1"
					( Origin gBackEnd )
				)
				( objectStatus "M_K_DQS_DP<13>" )
			)
			( signal "@baseboard_fab2_lib.baseboard_fab2(sch_1):m_k_dqs_dn(14)"
				( pinPairRef "@baseboard_fab2_lib.baseboard_fab2(sch_1):\PP1507\" )
				( pinPairRef "@baseboard_fab2_lib.baseboard_fab2(sch_1):\PP1509\" )
				( objectStatus "M_K_DQS_DN<14>" )
			)
			( signal "@baseboard_fab2_lib.baseboard_fab2(sch_1):m_k_dqs_dp(14)"
				( pinPairRef "@baseboard_fab2_lib.baseboard_fab2(sch_1):\PP1510\" )
				( pinPairRef "@baseboard_fab2_lib.baseboard_fab2(sch_1):\PP1512\" )
				( attribute "NO_TEST" "1"
					( Origin gBackEnd )
				)
				( objectStatus "M_K_DQS_DP<14>" )
			)
			( signal "@baseboard_fab2_lib.baseboard_fab2(sch_1):m_k_dqs_dn(15)"
				( pinPairRef "@baseboard_fab2_lib.baseboard_fab2(sch_1):\PP1495\" )
				( pinPairRef "@baseboard_fab2_lib.baseboard_fab2(sch_1):\PP1497\" )
				( objectStatus "M_K_DQS_DN<15>" )
			)
			( signal "@baseboard_fab2_lib.baseboard_fab2(sch_1):m_k_dqs_dp(15)"
				( pinPairRef "@baseboard_fab2_lib.baseboard_fab2(sch_1):\PP1498\" )
				( pinPairRef "@baseboard_fab2_lib.baseboard_fab2(sch_1):\PP1500\" )
				( attribute "NO_TEST" "1"
					( Origin gBackEnd )
				)
				( objectStatus "M_K_DQS_DP<15>" )
			)
			( signal "@baseboard_fab2_lib.baseboard_fab2(sch_1):m_k_dqs_dn(16)"
				( pinPairRef "@baseboard_fab2_lib.baseboard_fab2(sch_1):\PP1483\" )
				( pinPairRef "@baseboard_fab2_lib.baseboard_fab2(sch_1):\PP1485\" )
				( attribute "NO_TEST" "1"
					( Origin gBackEnd )
				)
				( objectStatus "M_K_DQS_DN<16>" )
			)
			( signal "@baseboard_fab2_lib.baseboard_fab2(sch_1):m_k_dqs_dp(16)"
				( pinPairRef "@baseboard_fab2_lib.baseboard_fab2(sch_1):\PP1486\" )
				( pinPairRef "@baseboard_fab2_lib.baseboard_fab2(sch_1):\PP1488\" )
				( objectStatus "M_K_DQS_DP<16>" )
			)
			( signal "@baseboard_fab2_lib.baseboard_fab2(sch_1):m_k_dqs_dn(17)"
				( pinPairRef "@baseboard_fab2_lib.baseboard_fab2(sch_1):\PP1255\" )
				( pinPairRef "@baseboard_fab2_lib.baseboard_fab2(sch_1):\PP1256\" )
				( attribute "NO_TEST" "1"
					( Origin gBackEnd )
				)
				( objectStatus "M_K_DQS_DN<17>" )
			)
			( signal "@baseboard_fab2_lib.baseboard_fab2(sch_1):m_k_dqs_dp(17)"
				( pinPairRef "@baseboard_fab2_lib.baseboard_fab2(sch_1):\PP1258\" )
				( pinPairRef "@baseboard_fab2_lib.baseboard_fab2(sch_1):\PP1259\" )
				( attribute "NO_TEST" "1"
					( Origin gBackEnd )
				)
				( objectStatus "M_K_DQS_DP<17>" )
			)
			( signal "@baseboard_fab2_lib.baseboard_fab2(sch_1):m_l_dqs_dn(0)"
				( pinPairRef "@baseboard_fab2_lib.baseboard_fab2(sch_1):\PP1477\" )
				( pinPairRef "@baseboard_fab2_lib.baseboard_fab2(sch_1):\PP1478\" )
				( attribute "NO_TEST" "1"
					( Origin gBackEnd )
				)
				( objectStatus "M_L_DQS_DN<0>" )
			)
			( signal "@baseboard_fab2_lib.baseboard_fab2(sch_1):m_l_dqs_dp(0)"
				( pinPairRef "@baseboard_fab2_lib.baseboard_fab2(sch_1):\PP1480\" )
				( pinPairRef "@baseboard_fab2_lib.baseboard_fab2(sch_1):\PP1481\" )
				( attribute "NO_TEST" "1"
					( Origin gBackEnd )
				)
				( objectStatus "M_L_DQS_DP<0>" )
			)
			( signal "@baseboard_fab2_lib.baseboard_fab2(sch_1):m_l_dqs_dn(1)"
				( pinPairRef "@baseboard_fab2_lib.baseboard_fab2(sch_1):\PP1465\" )
				( pinPairRef "@baseboard_fab2_lib.baseboard_fab2(sch_1):\PP1466\" )
				( attribute "NO_TEST" "1"
					( Origin gBackEnd )
				)
				( objectStatus "M_L_DQS_DN<1>" )
			)
			( signal "@baseboard_fab2_lib.baseboard_fab2(sch_1):m_l_dqs_dp(1)"
				( pinPairRef "@baseboard_fab2_lib.baseboard_fab2(sch_1):\PP1468\" )
				( pinPairRef "@baseboard_fab2_lib.baseboard_fab2(sch_1):\PP1469\" )
				( attribute "NO_TEST" "1"
					( Origin gBackEnd )
				)
				( objectStatus "M_L_DQS_DP<1>" )
			)
			( signal "@baseboard_fab2_lib.baseboard_fab2(sch_1):m_l_dqs_dn(2)"
				( pinPairRef "@baseboard_fab2_lib.baseboard_fab2(sch_1):\PP1453\" )
				( pinPairRef "@baseboard_fab2_lib.baseboard_fab2(sch_1):\PP1454\" )
				( attribute "NO_TEST" "1"
					( Origin gBackEnd )
				)
				( objectStatus "M_L_DQS_DN<2>" )
			)
			( signal "@baseboard_fab2_lib.baseboard_fab2(sch_1):m_l_dqs_dp(2)"
				( pinPairRef "@baseboard_fab2_lib.baseboard_fab2(sch_1):\PP1456\" )
				( pinPairRef "@baseboard_fab2_lib.baseboard_fab2(sch_1):\PP1457\" )
				( attribute "NO_TEST" "1"
					( Origin gBackEnd )
				)
				( objectStatus "M_L_DQS_DP<2>" )
			)
			( signal "@baseboard_fab2_lib.baseboard_fab2(sch_1):m_l_dqs_dn(3)"
				( pinPairRef "@baseboard_fab2_lib.baseboard_fab2(sch_1):\PP1441\" )
				( pinPairRef "@baseboard_fab2_lib.baseboard_fab2(sch_1):\PP1442\" )
				( attribute "NO_TEST" "1"
					( Origin gBackEnd )
				)
				( objectStatus "M_L_DQS_DN<3>" )
			)
			( signal "@baseboard_fab2_lib.baseboard_fab2(sch_1):m_l_dqs_dp(3)"
				( pinPairRef "@baseboard_fab2_lib.baseboard_fab2(sch_1):\PP1444\" )
				( pinPairRef "@baseboard_fab2_lib.baseboard_fab2(sch_1):\PP1445\" )
				( attribute "NO_TEST" "1"
					( Origin gBackEnd )
				)
				( objectStatus "M_L_DQS_DP<3>" )
			)
			( signal "@baseboard_fab2_lib.baseboard_fab2(sch_1):m_l_dqs_dn(4)"
				( pinPairRef "@baseboard_fab2_lib.baseboard_fab2(sch_1):\PP1429\" )
				( pinPairRef "@baseboard_fab2_lib.baseboard_fab2(sch_1):\PP1431\" )
				( attribute "NO_TEST" "1"
					( Origin gBackEnd )
				)
				( objectStatus "M_L_DQS_DN<4>" )
			)
			( signal "@baseboard_fab2_lib.baseboard_fab2(sch_1):m_l_dqs_dp(4)"
				( pinPairRef "@baseboard_fab2_lib.baseboard_fab2(sch_1):\PP1432\" )
				( pinPairRef "@baseboard_fab2_lib.baseboard_fab2(sch_1):\PP1434\" )
				( objectStatus "M_L_DQS_DP<4>" )
			)
			( signal "@baseboard_fab2_lib.baseboard_fab2(sch_1):m_l_dqs_dn(5)"
				( pinPairRef "@baseboard_fab2_lib.baseboard_fab2(sch_1):\PP1417\" )
				( pinPairRef "@baseboard_fab2_lib.baseboard_fab2(sch_1):\PP1419\" )
				( attribute "NO_TEST" "1"
					( Origin gBackEnd )
				)
				( objectStatus "M_L_DQS_DN<5>" )
			)
			( signal "@baseboard_fab2_lib.baseboard_fab2(sch_1):m_l_dqs_dp(5)"
				( pinPairRef "@baseboard_fab2_lib.baseboard_fab2(sch_1):\PP1420\" )
				( pinPairRef "@baseboard_fab2_lib.baseboard_fab2(sch_1):\PP1422\" )
				( attribute "NO_TEST" "1"
					( Origin gBackEnd )
				)
				( objectStatus "M_L_DQS_DP<5>" )
			)
			( signal "@baseboard_fab2_lib.baseboard_fab2(sch_1):m_l_dqs_dn(6)"
				( pinPairRef "@baseboard_fab2_lib.baseboard_fab2(sch_1):\PP1405\" )
				( pinPairRef "@baseboard_fab2_lib.baseboard_fab2(sch_1):\PP1407\" )
				( attribute "NO_TEST" "1"
					( Origin gBackEnd )
				)
				( objectStatus "M_L_DQS_DN<6>" )
			)
			( signal "@baseboard_fab2_lib.baseboard_fab2(sch_1):m_l_dqs_dp(6)"
				( pinPairRef "@baseboard_fab2_lib.baseboard_fab2(sch_1):\PP1408\" )
				( pinPairRef "@baseboard_fab2_lib.baseboard_fab2(sch_1):\PP1410\" )
				( attribute "NO_TEST" "1"
					( Origin gBackEnd )
				)
				( objectStatus "M_L_DQS_DP<6>" )
			)
			( signal "@baseboard_fab2_lib.baseboard_fab2(sch_1):m_l_dqs_dn(7)"
				( pinPairRef "@baseboard_fab2_lib.baseboard_fab2(sch_1):\PP1393\" )
				( pinPairRef "@baseboard_fab2_lib.baseboard_fab2(sch_1):\PP1395\" )
				( attribute "NO_TEST" "1"
					( Origin gBackEnd )
				)
				( objectStatus "M_L_DQS_DN<7>" )
			)
			( signal "@baseboard_fab2_lib.baseboard_fab2(sch_1):m_l_dqs_dp(7)"
				( pinPairRef "@baseboard_fab2_lib.baseboard_fab2(sch_1):\PP1396\" )
				( pinPairRef "@baseboard_fab2_lib.baseboard_fab2(sch_1):\PP1398\" )
				( objectStatus "M_L_DQS_DP<7>" )
			)
			( signal "@baseboard_fab2_lib.baseboard_fab2(sch_1):m_l_dqs_dn(8)"
				( pinPairRef "@baseboard_fab2_lib.baseboard_fab2(sch_1):\PP1273\" )
				( pinPairRef "@baseboard_fab2_lib.baseboard_fab2(sch_1):\PP1274\" )
				( attribute "NO_TEST" "1"
					( Origin gBackEnd )
				)
				( objectStatus "M_L_DQS_DN<8>" )
			)
			( signal "@baseboard_fab2_lib.baseboard_fab2(sch_1):m_l_dqs_dp(8)"
				( pinPairRef "@baseboard_fab2_lib.baseboard_fab2(sch_1):\PP1276\" )
				( pinPairRef "@baseboard_fab2_lib.baseboard_fab2(sch_1):\PP1277\" )
				( attribute "NO_TEST" "1"
					( Origin gBackEnd )
				)
				( objectStatus "M_L_DQS_DP<8>" )
			)
			( signal "@baseboard_fab2_lib.baseboard_fab2(sch_1):m_l_dqs_dn(9)"
				( pinPairRef "@baseboard_fab2_lib.baseboard_fab2(sch_1):\PP1471\" )
				( pinPairRef "@baseboard_fab2_lib.baseboard_fab2(sch_1):\PP1472\" )
				( objectStatus "M_L_DQS_DN<9>" )
			)
			( signal "@baseboard_fab2_lib.baseboard_fab2(sch_1):m_l_dqs_dp(9)"
				( pinPairRef "@baseboard_fab2_lib.baseboard_fab2(sch_1):\PP1474\" )
				( pinPairRef "@baseboard_fab2_lib.baseboard_fab2(sch_1):\PP1475\" )
				( attribute "NO_TEST" "1"
					( Origin gBackEnd )
				)
				( objectStatus "M_L_DQS_DP<9>" )
			)
			( signal "@baseboard_fab2_lib.baseboard_fab2(sch_1):m_l_dqs_dn(10)"
				( pinPairRef "@baseboard_fab2_lib.baseboard_fab2(sch_1):\PP1459\" )
				( pinPairRef "@baseboard_fab2_lib.baseboard_fab2(sch_1):\PP1460\" )
				( objectStatus "M_L_DQS_DN<10>" )
			)
			( signal "@baseboard_fab2_lib.baseboard_fab2(sch_1):m_l_dqs_dp(10)"
				( pinPairRef "@baseboard_fab2_lib.baseboard_fab2(sch_1):\PP1462\" )
				( pinPairRef "@baseboard_fab2_lib.baseboard_fab2(sch_1):\PP1463\" )
				( attribute "NO_TEST" "1"
					( Origin gBackEnd )
				)
				( objectStatus "M_L_DQS_DP<10>" )
			)
			( signal "@baseboard_fab2_lib.baseboard_fab2(sch_1):m_l_dqs_dn(11)"
				( pinPairRef "@baseboard_fab2_lib.baseboard_fab2(sch_1):\PP1447\" )
				( pinPairRef "@baseboard_fab2_lib.baseboard_fab2(sch_1):\PP1448\" )
				( objectStatus "M_L_DQS_DN<11>" )
			)
			( signal "@baseboard_fab2_lib.baseboard_fab2(sch_1):m_l_dqs_dp(11)"
				( pinPairRef "@baseboard_fab2_lib.baseboard_fab2(sch_1):\PP1450\" )
				( pinPairRef "@baseboard_fab2_lib.baseboard_fab2(sch_1):\PP1451\" )
				( attribute "NO_TEST" "1"
					( Origin gBackEnd )
				)
				( objectStatus "M_L_DQS_DP<11>" )
			)
			( signal "@baseboard_fab2_lib.baseboard_fab2(sch_1):m_l_dqs_dn(12)"
				( pinPairRef "@baseboard_fab2_lib.baseboard_fab2(sch_1):\PP1435\" )
				( pinPairRef "@baseboard_fab2_lib.baseboard_fab2(sch_1):\PP1436\" )
				( attribute "NO_TEST" "1"
					( Origin gBackEnd )
				)
				( objectStatus "M_L_DQS_DN<12>" )
			)
			( signal "@baseboard_fab2_lib.baseboard_fab2(sch_1):m_l_dqs_dp(12)"
				( pinPairRef "@baseboard_fab2_lib.baseboard_fab2(sch_1):\PP1438\" )
				( pinPairRef "@baseboard_fab2_lib.baseboard_fab2(sch_1):\PP1439\" )
				( attribute "NO_TEST" "1"
					( Origin gBackEnd )
				)
				( objectStatus "M_L_DQS_DP<12>" )
			)
			( signal "@baseboard_fab2_lib.baseboard_fab2(sch_1):m_l_dqs_dn(13)"
				( pinPairRef "@baseboard_fab2_lib.baseboard_fab2(sch_1):\PP1423\" )
				( pinPairRef "@baseboard_fab2_lib.baseboard_fab2(sch_1):\PP1425\" )
				( attribute "NO_TEST" "1"
					( Origin gBackEnd )
				)
				( objectStatus "M_L_DQS_DN<13>" )
			)
			( signal "@baseboard_fab2_lib.baseboard_fab2(sch_1):m_l_dqs_dp(13)"
				( pinPairRef "@baseboard_fab2_lib.baseboard_fab2(sch_1):\PP1426\" )
				( pinPairRef "@baseboard_fab2_lib.baseboard_fab2(sch_1):\PP1428\" )
				( attribute "NO_TEST" "1"
					( Origin gBackEnd )
				)
				( objectStatus "M_L_DQS_DP<13>" )
			)
			( signal "@baseboard_fab2_lib.baseboard_fab2(sch_1):m_l_dqs_dn(14)"
				( pinPairRef "@baseboard_fab2_lib.baseboard_fab2(sch_1):\PP1411\" )
				( pinPairRef "@baseboard_fab2_lib.baseboard_fab2(sch_1):\PP1413\" )
				( attribute "NO_TEST" "1"
					( Origin gBackEnd )
				)
				( objectStatus "M_L_DQS_DN<14>" )
			)
			( signal "@baseboard_fab2_lib.baseboard_fab2(sch_1):m_l_dqs_dp(14)"
				( pinPairRef "@baseboard_fab2_lib.baseboard_fab2(sch_1):\PP1414\" )
				( pinPairRef "@baseboard_fab2_lib.baseboard_fab2(sch_1):\PP1416\" )
				( attribute "NO_TEST" "1"
					( Origin gBackEnd )
				)
				( objectStatus "M_L_DQS_DP<14>" )
			)
			( signal "@baseboard_fab2_lib.baseboard_fab2(sch_1):m_l_dqs_dn(15)"
				( pinPairRef "@baseboard_fab2_lib.baseboard_fab2(sch_1):\PP1399\" )
				( pinPairRef "@baseboard_fab2_lib.baseboard_fab2(sch_1):\PP1401\" )
				( attribute "NO_TEST" "1"
					( Origin gBackEnd )
				)
				( objectStatus "M_L_DQS_DN<15>" )
			)
			( signal "@baseboard_fab2_lib.baseboard_fab2(sch_1):m_l_dqs_dp(15)"
				( pinPairRef "@baseboard_fab2_lib.baseboard_fab2(sch_1):\PP1402\" )
				( pinPairRef "@baseboard_fab2_lib.baseboard_fab2(sch_1):\PP1404\" )
				( attribute "NO_TEST" "1"
					( Origin gBackEnd )
				)
				( objectStatus "M_L_DQS_DP<15>" )
			)
			( signal "@baseboard_fab2_lib.baseboard_fab2(sch_1):m_l_dqs_dn(16)"
				( pinPairRef "@baseboard_fab2_lib.baseboard_fab2(sch_1):\PP1387\" )
				( pinPairRef "@baseboard_fab2_lib.baseboard_fab2(sch_1):\PP1389\" )
				( attribute "NO_TEST" "1"
					( Origin gBackEnd )
				)
				( objectStatus "M_L_DQS_DN<16>" )
			)
			( signal "@baseboard_fab2_lib.baseboard_fab2(sch_1):m_l_dqs_dp(16)"
				( pinPairRef "@baseboard_fab2_lib.baseboard_fab2(sch_1):\PP1390\" )
				( pinPairRef "@baseboard_fab2_lib.baseboard_fab2(sch_1):\PP1392\" )
				( attribute "NO_TEST" "1"
					( Origin gBackEnd )
				)
				( objectStatus "M_L_DQS_DP<16>" )
			)
			( signal "@baseboard_fab2_lib.baseboard_fab2(sch_1):m_l_dqs_dn(17)"
				( pinPairRef "@baseboard_fab2_lib.baseboard_fab2(sch_1):\PP1267\" )
				( pinPairRef "@baseboard_fab2_lib.baseboard_fab2(sch_1):\PP1268\" )
				( attribute "NO_TEST" "1"
					( Origin gBackEnd )
				)
				( objectStatus "M_L_DQS_DN<17>" )
			)
			( signal "@baseboard_fab2_lib.baseboard_fab2(sch_1):m_l_dqs_dp(17)"
				( pinPairRef "@baseboard_fab2_lib.baseboard_fab2(sch_1):\PP1270\" )
				( pinPairRef "@baseboard_fab2_lib.baseboard_fab2(sch_1):\PP1271\" )
				( attribute "NO_TEST" "1"
					( Origin gBackEnd )
				)
				( objectStatus "M_L_DQS_DP<17>" )
			)
			( signal "@baseboard_fab2_lib.baseboard_fab2(sch_1):m_m_dqs_dn(0)"
				( pinPairRef "@baseboard_fab2_lib.baseboard_fab2(sch_1):\PP1381\" )
				( pinPairRef "@baseboard_fab2_lib.baseboard_fab2(sch_1):\PP1382\" )
				( attribute "NO_TEST" "1"
					( Origin gBackEnd )
				)
				( objectStatus "M_M_DQS_DN<0>" )
			)
			( signal "@baseboard_fab2_lib.baseboard_fab2(sch_1):m_m_dqs_dp(0)"
				( pinPairRef "@baseboard_fab2_lib.baseboard_fab2(sch_1):\PP1384\" )
				( pinPairRef "@baseboard_fab2_lib.baseboard_fab2(sch_1):\PP1385\" )
				( attribute "NO_TEST" "1"
					( Origin gBackEnd )
				)
				( objectStatus "M_M_DQS_DP<0>" )
			)
			( signal "@baseboard_fab2_lib.baseboard_fab2(sch_1):m_m_dqs_dn(1)"
				( pinPairRef "@baseboard_fab2_lib.baseboard_fab2(sch_1):\PP1369\" )
				( pinPairRef "@baseboard_fab2_lib.baseboard_fab2(sch_1):\PP1370\" )
				( attribute "NO_TEST" "1"
					( Origin gBackEnd )
				)
				( objectStatus "M_M_DQS_DN<1>" )
			)
			( signal "@baseboard_fab2_lib.baseboard_fab2(sch_1):m_m_dqs_dp(1)"
				( pinPairRef "@baseboard_fab2_lib.baseboard_fab2(sch_1):\PP1372\" )
				( pinPairRef "@baseboard_fab2_lib.baseboard_fab2(sch_1):\PP1373\" )
				( attribute "NO_TEST" "1"
					( Origin gBackEnd )
				)
				( objectStatus "M_M_DQS_DP<1>" )
			)
			( signal "@baseboard_fab2_lib.baseboard_fab2(sch_1):m_m_dqs_dn(2)"
				( pinPairRef "@baseboard_fab2_lib.baseboard_fab2(sch_1):\PP1357\" )
				( pinPairRef "@baseboard_fab2_lib.baseboard_fab2(sch_1):\PP1358\" )
				( attribute "NO_TEST" "1"
					( Origin gBackEnd )
				)
				( objectStatus "M_M_DQS_DN<2>" )
			)
			( signal "@baseboard_fab2_lib.baseboard_fab2(sch_1):m_m_dqs_dp(2)"
				( pinPairRef "@baseboard_fab2_lib.baseboard_fab2(sch_1):\PP1360\" )
				( pinPairRef "@baseboard_fab2_lib.baseboard_fab2(sch_1):\PP1361\" )
				( objectStatus "M_M_DQS_DP<2>" )
			)
			( signal "@baseboard_fab2_lib.baseboard_fab2(sch_1):m_m_dqs_dn(3)"
				( pinPairRef "@baseboard_fab2_lib.baseboard_fab2(sch_1):\PP1345\" )
				( pinPairRef "@baseboard_fab2_lib.baseboard_fab2(sch_1):\PP1346\" )
				( attribute "NO_TEST" "1"
					( Origin gBackEnd )
				)
				( objectStatus "M_M_DQS_DN<3>" )
			)
			( signal "@baseboard_fab2_lib.baseboard_fab2(sch_1):m_m_dqs_dp(3)"
				( pinPairRef "@baseboard_fab2_lib.baseboard_fab2(sch_1):\PP1348\" )
				( pinPairRef "@baseboard_fab2_lib.baseboard_fab2(sch_1):\PP1349\" )
				( objectStatus "M_M_DQS_DP<3>" )
			)
			( signal "@baseboard_fab2_lib.baseboard_fab2(sch_1):m_m_dqs_dn(4)"
				( pinPairRef "@baseboard_fab2_lib.baseboard_fab2(sch_1):\PP1333\" )
				( pinPairRef "@baseboard_fab2_lib.baseboard_fab2(sch_1):\PP1335\" )
				( objectStatus "M_M_DQS_DN<4>" )
			)
			( signal "@baseboard_fab2_lib.baseboard_fab2(sch_1):m_m_dqs_dp(4)"
				( pinPairRef "@baseboard_fab2_lib.baseboard_fab2(sch_1):\PP1336\" )
				( pinPairRef "@baseboard_fab2_lib.baseboard_fab2(sch_1):\PP1338\" )
				( attribute "NO_TEST" "1"
					( Origin gBackEnd )
				)
				( objectStatus "M_M_DQS_DP<4>" )
			)
			( signal "@baseboard_fab2_lib.baseboard_fab2(sch_1):m_m_dqs_dn(5)"
				( pinPairRef "@baseboard_fab2_lib.baseboard_fab2(sch_1):\PP1321\" )
				( pinPairRef "@baseboard_fab2_lib.baseboard_fab2(sch_1):\PP1323\" )
				( attribute "NO_TEST" "1"
					( Origin gBackEnd )
				)
				( objectStatus "M_M_DQS_DN<5>" )
			)
			( signal "@baseboard_fab2_lib.baseboard_fab2(sch_1):m_m_dqs_dp(5)"
				( pinPairRef "@baseboard_fab2_lib.baseboard_fab2(sch_1):\PP1324\" )
				( pinPairRef "@baseboard_fab2_lib.baseboard_fab2(sch_1):\PP1326\" )
				( objectStatus "M_M_DQS_DP<5>" )
			)
			( signal "@baseboard_fab2_lib.baseboard_fab2(sch_1):m_m_dqs_dn(6)"
				( pinPairRef "@baseboard_fab2_lib.baseboard_fab2(sch_1):\PP1309\" )
				( pinPairRef "@baseboard_fab2_lib.baseboard_fab2(sch_1):\PP1311\" )
				( attribute "NO_TEST" "1"
					( Origin gBackEnd )
				)
				( objectStatus "M_M_DQS_DN<6>" )
			)
			( signal "@baseboard_fab2_lib.baseboard_fab2(sch_1):m_m_dqs_dp(6)"
				( pinPairRef "@baseboard_fab2_lib.baseboard_fab2(sch_1):\PP1312\" )
				( pinPairRef "@baseboard_fab2_lib.baseboard_fab2(sch_1):\PP1314\" )
				( objectStatus "M_M_DQS_DP<6>" )
			)
			( signal "@baseboard_fab2_lib.baseboard_fab2(sch_1):m_m_dqs_dn(7)"
				( pinPairRef "@baseboard_fab2_lib.baseboard_fab2(sch_1):\PP1297\" )
				( pinPairRef "@baseboard_fab2_lib.baseboard_fab2(sch_1):\PP1299\" )
				( attribute "NO_TEST" "1"
					( Origin gBackEnd )
				)
				( objectStatus "M_M_DQS_DN<7>" )
			)
			( signal "@baseboard_fab2_lib.baseboard_fab2(sch_1):m_m_dqs_dp(7)"
				( pinPairRef "@baseboard_fab2_lib.baseboard_fab2(sch_1):\PP1300\" )
				( pinPairRef "@baseboard_fab2_lib.baseboard_fab2(sch_1):\PP1302\" )
				( objectStatus "M_M_DQS_DP<7>" )
			)
			( signal "@baseboard_fab2_lib.baseboard_fab2(sch_1):m_m_dqs_dn(8)"
				( pinPairRef "@baseboard_fab2_lib.baseboard_fab2(sch_1):\PP1285\" )
				( pinPairRef "@baseboard_fab2_lib.baseboard_fab2(sch_1):\PP1286\" )
				( attribute "NO_TEST" "1"
					( Origin gBackEnd )
				)
				( objectStatus "M_M_DQS_DN<8>" )
			)
			( signal "@baseboard_fab2_lib.baseboard_fab2(sch_1):m_m_dqs_dp(8)"
				( pinPairRef "@baseboard_fab2_lib.baseboard_fab2(sch_1):\PP1288\" )
				( pinPairRef "@baseboard_fab2_lib.baseboard_fab2(sch_1):\PP1289\" )
				( objectStatus "M_M_DQS_DP<8>" )
			)
			( signal "@baseboard_fab2_lib.baseboard_fab2(sch_1):m_m_dqs_dn(9)"
				( pinPairRef "@baseboard_fab2_lib.baseboard_fab2(sch_1):\PP1375\" )
				( pinPairRef "@baseboard_fab2_lib.baseboard_fab2(sch_1):\PP1376\" )
				( objectStatus "M_M_DQS_DN<9>" )
			)
			( signal "@baseboard_fab2_lib.baseboard_fab2(sch_1):m_m_dqs_dp(9)"
				( pinPairRef "@baseboard_fab2_lib.baseboard_fab2(sch_1):\PP1378\" )
				( pinPairRef "@baseboard_fab2_lib.baseboard_fab2(sch_1):\PP1379\" )
				( attribute "NO_TEST" "1"
					( Origin gBackEnd )
				)
				( objectStatus "M_M_DQS_DP<9>" )
			)
			( signal "@baseboard_fab2_lib.baseboard_fab2(sch_1):m_m_dqs_dn(10)"
				( pinPairRef "@baseboard_fab2_lib.baseboard_fab2(sch_1):\PP1363\" )
				( pinPairRef "@baseboard_fab2_lib.baseboard_fab2(sch_1):\PP1364\" )
				( objectStatus "M_M_DQS_DN<10>" )
			)
			( signal "@baseboard_fab2_lib.baseboard_fab2(sch_1):m_m_dqs_dp(10)"
				( pinPairRef "@baseboard_fab2_lib.baseboard_fab2(sch_1):\PP1366\" )
				( pinPairRef "@baseboard_fab2_lib.baseboard_fab2(sch_1):\PP1367\" )
				( attribute "NO_TEST" "1"
					( Origin gBackEnd )
				)
				( objectStatus "M_M_DQS_DP<10>" )
			)
			( signal "@baseboard_fab2_lib.baseboard_fab2(sch_1):m_m_dqs_dn(11)"
				( pinPairRef "@baseboard_fab2_lib.baseboard_fab2(sch_1):\PP1351\" )
				( pinPairRef "@baseboard_fab2_lib.baseboard_fab2(sch_1):\PP1352\" )
				( attribute "NO_TEST" "1"
					( Origin gBackEnd )
				)
				( objectStatus "M_M_DQS_DN<11>" )
			)
			( signal "@baseboard_fab2_lib.baseboard_fab2(sch_1):m_m_dqs_dp(11)"
				( pinPairRef "@baseboard_fab2_lib.baseboard_fab2(sch_1):\PP1354\" )
				( pinPairRef "@baseboard_fab2_lib.baseboard_fab2(sch_1):\PP1355\" )
				( attribute "NO_TEST" "1"
					( Origin gBackEnd )
				)
				( objectStatus "M_M_DQS_DP<11>" )
			)
			( signal "@baseboard_fab2_lib.baseboard_fab2(sch_1):m_m_dqs_dn(12)"
				( pinPairRef "@baseboard_fab2_lib.baseboard_fab2(sch_1):\PP1339\" )
				( pinPairRef "@baseboard_fab2_lib.baseboard_fab2(sch_1):\PP1340\" )
				( attribute "NO_TEST" "1"
					( Origin gBackEnd )
				)
				( objectStatus "M_M_DQS_DN<12>" )
			)
			( signal "@baseboard_fab2_lib.baseboard_fab2(sch_1):m_m_dqs_dp(12)"
				( pinPairRef "@baseboard_fab2_lib.baseboard_fab2(sch_1):\PP1342\" )
				( pinPairRef "@baseboard_fab2_lib.baseboard_fab2(sch_1):\PP1343\" )
				( attribute "NO_TEST" "1"
					( Origin gBackEnd )
				)
				( objectStatus "M_M_DQS_DP<12>" )
			)
			( signal "@baseboard_fab2_lib.baseboard_fab2(sch_1):m_m_dqs_dn(13)"
				( pinPairRef "@baseboard_fab2_lib.baseboard_fab2(sch_1):\PP1327\" )
				( pinPairRef "@baseboard_fab2_lib.baseboard_fab2(sch_1):\PP1329\" )
				( attribute "NO_TEST" "1"
					( Origin gBackEnd )
				)
				( objectStatus "M_M_DQS_DN<13>" )
			)
			( signal "@baseboard_fab2_lib.baseboard_fab2(sch_1):m_m_dqs_dp(13)"
				( pinPairRef "@baseboard_fab2_lib.baseboard_fab2(sch_1):\PP1330\" )
				( pinPairRef "@baseboard_fab2_lib.baseboard_fab2(sch_1):\PP1332\" )
				( objectStatus "M_M_DQS_DP<13>" )
			)
			( signal "@baseboard_fab2_lib.baseboard_fab2(sch_1):m_m_dqs_dn(14)"
				( pinPairRef "@baseboard_fab2_lib.baseboard_fab2(sch_1):\PP1315\" )
				( pinPairRef "@baseboard_fab2_lib.baseboard_fab2(sch_1):\PP1317\" )
				( attribute "NO_TEST" "1"
					( Origin gBackEnd )
				)
				( objectStatus "M_M_DQS_DN<14>" )
			)
			( signal "@baseboard_fab2_lib.baseboard_fab2(sch_1):m_m_dqs_dp(14)"
				( pinPairRef "@baseboard_fab2_lib.baseboard_fab2(sch_1):\PP1318\" )
				( pinPairRef "@baseboard_fab2_lib.baseboard_fab2(sch_1):\PP1320\" )
				( attribute "NO_TEST" "1"
					( Origin gBackEnd )
				)
				( objectStatus "M_M_DQS_DP<14>" )
			)
			( signal "@baseboard_fab2_lib.baseboard_fab2(sch_1):m_m_dqs_dn(15)"
				( pinPairRef "@baseboard_fab2_lib.baseboard_fab2(sch_1):\PP1303\" )
				( pinPairRef "@baseboard_fab2_lib.baseboard_fab2(sch_1):\PP1305\" )
				( attribute "NO_TEST" "1"
					( Origin gBackEnd )
				)
				( objectStatus "M_M_DQS_DN<15>" )
			)
			( signal "@baseboard_fab2_lib.baseboard_fab2(sch_1):m_m_dqs_dp(15)"
				( pinPairRef "@baseboard_fab2_lib.baseboard_fab2(sch_1):\PP1306\" )
				( pinPairRef "@baseboard_fab2_lib.baseboard_fab2(sch_1):\PP1308\" )
				( attribute "NO_TEST" "1"
					( Origin gBackEnd )
				)
				( objectStatus "M_M_DQS_DP<15>" )
			)
			( signal "@baseboard_fab2_lib.baseboard_fab2(sch_1):m_m_dqs_dn(16)"
				( pinPairRef "@baseboard_fab2_lib.baseboard_fab2(sch_1):\PP1291\" )
				( pinPairRef "@baseboard_fab2_lib.baseboard_fab2(sch_1):\PP1293\" )
				( attribute "NO_TEST" "1"
					( Origin gBackEnd )
				)
				( objectStatus "M_M_DQS_DN<16>" )
			)
			( signal "@baseboard_fab2_lib.baseboard_fab2(sch_1):m_m_dqs_dp(16)"
				( pinPairRef "@baseboard_fab2_lib.baseboard_fab2(sch_1):\PP1294\" )
				( pinPairRef "@baseboard_fab2_lib.baseboard_fab2(sch_1):\PP1296\" )
				( attribute "NO_TEST" "1"
					( Origin gBackEnd )
				)
				( objectStatus "M_M_DQS_DP<16>" )
			)
			( signal "@baseboard_fab2_lib.baseboard_fab2(sch_1):m_m_dqs_dn(17)"
				( pinPairRef "@baseboard_fab2_lib.baseboard_fab2(sch_1):\PP1279\" )
				( pinPairRef "@baseboard_fab2_lib.baseboard_fab2(sch_1):\PP1280\" )
				( attribute "NO_TEST" "1"
					( Origin gBackEnd )
				)
				( objectStatus "M_M_DQS_DN<17>" )
			)
			( signal "@baseboard_fab2_lib.baseboard_fab2(sch_1):m_m_dqs_dp(17)"
				( pinPairRef "@baseboard_fab2_lib.baseboard_fab2(sch_1):\PP1282\" )
				( pinPairRef "@baseboard_fab2_lib.baseboard_fab2(sch_1):\PP1283\" )
				( attribute "NO_TEST" "1"
					( Origin gBackEnd )
				)
				( objectStatus "M_M_DQS_DP<17>" )
			)
			( signal "@baseboard_fab2_lib.baseboard_fab2(sch_1):m_g_dqs_dn(0)"
				( pinPairRef "@baseboard_fab2_lib.baseboard_fab2(sch_1):\PP973\" )
				( pinPairRef "@baseboard_fab2_lib.baseboard_fab2(sch_1):\PP974\" )
				( attribute "NO_TEST" "1"
					( Origin gBackEnd )
				)
				( objectStatus "M_G_DQS_DN<0>" )
			)
			( signal "@baseboard_fab2_lib.baseboard_fab2(sch_1):m_g_dqs_dp(0)"
				( pinPairRef "@baseboard_fab2_lib.baseboard_fab2(sch_1):\PP976\" )
				( pinPairRef "@baseboard_fab2_lib.baseboard_fab2(sch_1):\PP977\" )
				( objectStatus "M_G_DQS_DP<0>" )
			)
			( signal "@baseboard_fab2_lib.baseboard_fab2(sch_1):m_g_dqs_dn(1)"
				( pinPairRef "@baseboard_fab2_lib.baseboard_fab2(sch_1):\PP961\" )
				( pinPairRef "@baseboard_fab2_lib.baseboard_fab2(sch_1):\PP962\" )
				( attribute "NO_TEST" "1"
					( Origin gBackEnd )
				)
				( objectStatus "M_G_DQS_DN<1>" )
			)
			( signal "@baseboard_fab2_lib.baseboard_fab2(sch_1):m_g_dqs_dp(1)"
				( pinPairRef "@baseboard_fab2_lib.baseboard_fab2(sch_1):\PP964\" )
				( pinPairRef "@baseboard_fab2_lib.baseboard_fab2(sch_1):\PP965\" )
				( attribute "NO_TEST" "1"
					( Origin gBackEnd )
				)
				( objectStatus "M_G_DQS_DP<1>" )
			)
			( signal "@baseboard_fab2_lib.baseboard_fab2(sch_1):m_g_dqs_dn(2)"
				( pinPairRef "@baseboard_fab2_lib.baseboard_fab2(sch_1):\PP949\" )
				( pinPairRef "@baseboard_fab2_lib.baseboard_fab2(sch_1):\PP950\" )
				( objectStatus "M_G_DQS_DN<2>" )
			)
			( signal "@baseboard_fab2_lib.baseboard_fab2(sch_1):m_g_dqs_dp(2)"
				( pinPairRef "@baseboard_fab2_lib.baseboard_fab2(sch_1):\PP952\" )
				( pinPairRef "@baseboard_fab2_lib.baseboard_fab2(sch_1):\PP953\" )
				( attribute "NO_TEST" "1"
					( Origin gBackEnd )
				)
				( objectStatus "M_G_DQS_DP<2>" )
			)
			( signal "@baseboard_fab2_lib.baseboard_fab2(sch_1):m_g_dqs_dn(3)"
				( pinPairRef "@baseboard_fab2_lib.baseboard_fab2(sch_1):\PP937\" )
				( pinPairRef "@baseboard_fab2_lib.baseboard_fab2(sch_1):\PP938\" )
				( attribute "NO_TEST" "1"
					( Origin gBackEnd )
				)
				( objectStatus "M_G_DQS_DN<3>" )
			)
			( signal "@baseboard_fab2_lib.baseboard_fab2(sch_1):m_g_dqs_dp(3)"
				( pinPairRef "@baseboard_fab2_lib.baseboard_fab2(sch_1):\PP940\" )
				( pinPairRef "@baseboard_fab2_lib.baseboard_fab2(sch_1):\PP941\" )
				( attribute "NO_TEST" "1"
					( Origin gBackEnd )
				)
				( objectStatus "M_G_DQS_DP<3>" )
			)
			( signal "@baseboard_fab2_lib.baseboard_fab2(sch_1):m_g_dqs_dn(4)"
				( pinPairRef "@baseboard_fab2_lib.baseboard_fab2(sch_1):\PP925\" )
				( pinPairRef "@baseboard_fab2_lib.baseboard_fab2(sch_1):\PP927\" )
				( objectStatus "M_G_DQS_DN<4>" )
			)
			( signal "@baseboard_fab2_lib.baseboard_fab2(sch_1):m_g_dqs_dp(4)"
				( pinPairRef "@baseboard_fab2_lib.baseboard_fab2(sch_1):\PP928\" )
				( pinPairRef "@baseboard_fab2_lib.baseboard_fab2(sch_1):\PP930\" )
				( objectStatus "M_G_DQS_DP<4>" )
			)
			( signal "@baseboard_fab2_lib.baseboard_fab2(sch_1):m_g_dqs_dn(5)"
				( pinPairRef "@baseboard_fab2_lib.baseboard_fab2(sch_1):\PP913\" )
				( pinPairRef "@baseboard_fab2_lib.baseboard_fab2(sch_1):\PP915\" )
				( objectStatus "M_G_DQS_DN<5>" )
			)
			( signal "@baseboard_fab2_lib.baseboard_fab2(sch_1):m_g_dqs_dp(5)"
				( pinPairRef "@baseboard_fab2_lib.baseboard_fab2(sch_1):\PP916\" )
				( pinPairRef "@baseboard_fab2_lib.baseboard_fab2(sch_1):\PP918\" )
				( attribute "NO_TEST" "1"
					( Origin gBackEnd )
				)
				( objectStatus "M_G_DQS_DP<5>" )
			)
			( signal "@baseboard_fab2_lib.baseboard_fab2(sch_1):m_g_dqs_dn(6)"
				( pinPairRef "@baseboard_fab2_lib.baseboard_fab2(sch_1):\PP901\" )
				( pinPairRef "@baseboard_fab2_lib.baseboard_fab2(sch_1):\PP903\" )
				( objectStatus "M_G_DQS_DN<6>" )
			)
			( signal "@baseboard_fab2_lib.baseboard_fab2(sch_1):m_g_dqs_dp(6)"
				( pinPairRef "@baseboard_fab2_lib.baseboard_fab2(sch_1):\PP904\" )
				( pinPairRef "@baseboard_fab2_lib.baseboard_fab2(sch_1):\PP906\" )
				( attribute "NO_TEST" "1"
					( Origin gBackEnd )
				)
				( objectStatus "M_G_DQS_DP<6>" )
			)
			( signal "@baseboard_fab2_lib.baseboard_fab2(sch_1):m_g_dqs_dn(7)"
				( pinPairRef "@baseboard_fab2_lib.baseboard_fab2(sch_1):\PP889\" )
				( pinPairRef "@baseboard_fab2_lib.baseboard_fab2(sch_1):\PP891\" )
				( objectStatus "M_G_DQS_DN<7>" )
			)
			( signal "@baseboard_fab2_lib.baseboard_fab2(sch_1):m_g_dqs_dp(7)"
				( pinPairRef "@baseboard_fab2_lib.baseboard_fab2(sch_1):\PP892\" )
				( pinPairRef "@baseboard_fab2_lib.baseboard_fab2(sch_1):\PP894\" )
				( attribute "NO_TEST" "1"
					( Origin gBackEnd )
				)
				( objectStatus "M_G_DQS_DP<7>" )
			)
			( signal "@baseboard_fab2_lib.baseboard_fab2(sch_1):m_g_dqs_dn(8)"
				( pinPairRef "@baseboard_fab2_lib.baseboard_fab2(sch_1):\PP877\" )
				( pinPairRef "@baseboard_fab2_lib.baseboard_fab2(sch_1):\PP878\" )
				( attribute "NO_TEST" "1"
					( Origin gBackEnd )
				)
				( objectStatus "M_G_DQS_DN<8>" )
			)
			( signal "@baseboard_fab2_lib.baseboard_fab2(sch_1):m_g_dqs_dp(8)"
				( pinPairRef "@baseboard_fab2_lib.baseboard_fab2(sch_1):\PP880\" )
				( pinPairRef "@baseboard_fab2_lib.baseboard_fab2(sch_1):\PP881\" )
				( objectStatus "M_G_DQS_DP<8>" )
			)
			( signal "@baseboard_fab2_lib.baseboard_fab2(sch_1):m_g_dqs_dn(9)"
				( pinPairRef "@baseboard_fab2_lib.baseboard_fab2(sch_1):\PP967\" )
				( pinPairRef "@baseboard_fab2_lib.baseboard_fab2(sch_1):\PP968\" )
				( objectStatus "M_G_DQS_DN<9>" )
			)
			( signal "@baseboard_fab2_lib.baseboard_fab2(sch_1):m_g_dqs_dp(9)"
				( pinPairRef "@baseboard_fab2_lib.baseboard_fab2(sch_1):\PP970\" )
				( pinPairRef "@baseboard_fab2_lib.baseboard_fab2(sch_1):\PP971\" )
				( attribute "NO_TEST" "1"
					( Origin gBackEnd )
				)
				( objectStatus "M_G_DQS_DP<9>" )
			)
			( signal "@baseboard_fab2_lib.baseboard_fab2(sch_1):m_g_dqs_dn(10)"
				( pinPairRef "@baseboard_fab2_lib.baseboard_fab2(sch_1):\PP955\" )
				( pinPairRef "@baseboard_fab2_lib.baseboard_fab2(sch_1):\PP956\" )
				( attribute "NO_TEST" "1"
					( Origin gBackEnd )
				)
				( objectStatus "M_G_DQS_DN<10>" )
			)
			( signal "@baseboard_fab2_lib.baseboard_fab2(sch_1):m_g_dqs_dp(10)"
				( pinPairRef "@baseboard_fab2_lib.baseboard_fab2(sch_1):\PP958\" )
				( pinPairRef "@baseboard_fab2_lib.baseboard_fab2(sch_1):\PP959\" )
				( attribute "NO_TEST" "1"
					( Origin gBackEnd )
				)
				( objectStatus "M_G_DQS_DP<10>" )
			)
			( signal "@baseboard_fab2_lib.baseboard_fab2(sch_1):m_g_dqs_dn(11)"
				( pinPairRef "@baseboard_fab2_lib.baseboard_fab2(sch_1):\PP943\" )
				( pinPairRef "@baseboard_fab2_lib.baseboard_fab2(sch_1):\PP944\" )
				( objectStatus "M_G_DQS_DN<11>" )
			)
			( signal "@baseboard_fab2_lib.baseboard_fab2(sch_1):m_g_dqs_dp(11)"
				( pinPairRef "@baseboard_fab2_lib.baseboard_fab2(sch_1):\PP946\" )
				( pinPairRef "@baseboard_fab2_lib.baseboard_fab2(sch_1):\PP947\" )
				( attribute "NO_TEST" "1"
					( Origin gBackEnd )
				)
				( objectStatus "M_G_DQS_DP<11>" )
			)
			( signal "@baseboard_fab2_lib.baseboard_fab2(sch_1):m_g_dqs_dn(12)"
				( pinPairRef "@baseboard_fab2_lib.baseboard_fab2(sch_1):\PP931\" )
				( pinPairRef "@baseboard_fab2_lib.baseboard_fab2(sch_1):\PP932\" )
				( attribute "NO_TEST" "1"
					( Origin gBackEnd )
				)
				( objectStatus "M_G_DQS_DN<12>" )
			)
			( signal "@baseboard_fab2_lib.baseboard_fab2(sch_1):m_g_dqs_dp(12)"
				( pinPairRef "@baseboard_fab2_lib.baseboard_fab2(sch_1):\PP934\" )
				( pinPairRef "@baseboard_fab2_lib.baseboard_fab2(sch_1):\PP935\" )
				( objectStatus "M_G_DQS_DP<12>" )
			)
			( signal "@baseboard_fab2_lib.baseboard_fab2(sch_1):m_g_dqs_dn(13)"
				( pinPairRef "@baseboard_fab2_lib.baseboard_fab2(sch_1):\PP919\" )
				( pinPairRef "@baseboard_fab2_lib.baseboard_fab2(sch_1):\PP921\" )
				( attribute "NO_TEST" "1"
					( Origin gBackEnd )
				)
				( objectStatus "M_G_DQS_DN<13>" )
			)
			( signal "@baseboard_fab2_lib.baseboard_fab2(sch_1):m_g_dqs_dp(13)"
				( pinPairRef "@baseboard_fab2_lib.baseboard_fab2(sch_1):\PP922\" )
				( pinPairRef "@baseboard_fab2_lib.baseboard_fab2(sch_1):\PP924\" )
				( objectStatus "M_G_DQS_DP<13>" )
			)
			( signal "@baseboard_fab2_lib.baseboard_fab2(sch_1):m_g_dqs_dn(14)"
				( pinPairRef "@baseboard_fab2_lib.baseboard_fab2(sch_1):\PP907\" )
				( pinPairRef "@baseboard_fab2_lib.baseboard_fab2(sch_1):\PP909\" )
				( attribute "NO_TEST" "1"
					( Origin gBackEnd )
				)
				( objectStatus "M_G_DQS_DN<14>" )
			)
			( signal "@baseboard_fab2_lib.baseboard_fab2(sch_1):m_g_dqs_dp(14)"
				( pinPairRef "@baseboard_fab2_lib.baseboard_fab2(sch_1):\PP910\" )
				( pinPairRef "@baseboard_fab2_lib.baseboard_fab2(sch_1):\PP912\" )
				( objectStatus "M_G_DQS_DP<14>" )
			)
			( signal "@baseboard_fab2_lib.baseboard_fab2(sch_1):m_g_dqs_dn(15)"
				( pinPairRef "@baseboard_fab2_lib.baseboard_fab2(sch_1):\PP895\" )
				( pinPairRef "@baseboard_fab2_lib.baseboard_fab2(sch_1):\PP897\" )
				( attribute "NO_TEST" "1"
					( Origin gBackEnd )
				)
				( objectStatus "M_G_DQS_DN<15>" )
			)
			( signal "@baseboard_fab2_lib.baseboard_fab2(sch_1):m_g_dqs_dp(15)"
				( pinPairRef "@baseboard_fab2_lib.baseboard_fab2(sch_1):\PP898\" )
				( pinPairRef "@baseboard_fab2_lib.baseboard_fab2(sch_1):\PP900\" )
				( attribute "NO_TEST" "1"
					( Origin gBackEnd )
				)
				( objectStatus "M_G_DQS_DP<15>" )
			)
			( signal "@baseboard_fab2_lib.baseboard_fab2(sch_1):m_g_dqs_dn(16)"
				( pinPairRef "@baseboard_fab2_lib.baseboard_fab2(sch_1):\PP883\" )
				( pinPairRef "@baseboard_fab2_lib.baseboard_fab2(sch_1):\PP885\" )
				( attribute "NO_TEST" "1"
					( Origin gBackEnd )
				)
				( objectStatus "M_G_DQS_DN<16>" )
			)
			( signal "@baseboard_fab2_lib.baseboard_fab2(sch_1):m_g_dqs_dp(16)"
				( pinPairRef "@baseboard_fab2_lib.baseboard_fab2(sch_1):\PP886\" )
				( pinPairRef "@baseboard_fab2_lib.baseboard_fab2(sch_1):\PP888\" )
				( attribute "NO_TEST" "1"
					( Origin gBackEnd )
				)
				( objectStatus "M_G_DQS_DP<16>" )
			)
			( signal "@baseboard_fab2_lib.baseboard_fab2(sch_1):m_g_dqs_dn(17)"
				( pinPairRef "@baseboard_fab2_lib.baseboard_fab2(sch_1):\PP871\" )
				( pinPairRef "@baseboard_fab2_lib.baseboard_fab2(sch_1):\PP872\" )
				( objectStatus "M_G_DQS_DN<17>" )
			)
			( signal "@baseboard_fab2_lib.baseboard_fab2(sch_1):m_g_dqs_dp(17)"
				( pinPairRef "@baseboard_fab2_lib.baseboard_fab2(sch_1):\PP874\" )
				( pinPairRef "@baseboard_fab2_lib.baseboard_fab2(sch_1):\PP875\" )
				( attribute "NO_TEST" "1"
					( Origin gBackEnd )
				)
				( objectStatus "M_G_DQS_DP<17>" )
			)
			( signal "@baseboard_fab2_lib.baseboard_fab2(sch_1):m_h_dqs_dn(0)"
				( pinPairRef "@baseboard_fab2_lib.baseboard_fab2(sch_1):\PP865\" )
				( pinPairRef "@baseboard_fab2_lib.baseboard_fab2(sch_1):\PP866\" )
				( objectStatus "M_H_DQS_DN<0>" )
			)
			( signal "@baseboard_fab2_lib.baseboard_fab2(sch_1):m_h_dqs_dp(0)"
				( pinPairRef "@baseboard_fab2_lib.baseboard_fab2(sch_1):\PP868\" )
				( pinPairRef "@baseboard_fab2_lib.baseboard_fab2(sch_1):\PP869\" )
				( attribute "NO_TEST" "1"
					( Origin gBackEnd )
				)
				( objectStatus "M_H_DQS_DP<0>" )
			)
			( signal "@baseboard_fab2_lib.baseboard_fab2(sch_1):m_h_dqs_dn(1)"
				( pinPairRef "@baseboard_fab2_lib.baseboard_fab2(sch_1):\PP853\" )
				( pinPairRef "@baseboard_fab2_lib.baseboard_fab2(sch_1):\PP854\" )
				( objectStatus "M_H_DQS_DN<1>" )
			)
			( signal "@baseboard_fab2_lib.baseboard_fab2(sch_1):m_h_dqs_dp(1)"
				( pinPairRef "@baseboard_fab2_lib.baseboard_fab2(sch_1):\PP856\" )
				( pinPairRef "@baseboard_fab2_lib.baseboard_fab2(sch_1):\PP857\" )
				( attribute "NO_TEST" "1"
					( Origin gBackEnd )
				)
				( objectStatus "M_H_DQS_DP<1>" )
			)
			( signal "@baseboard_fab2_lib.baseboard_fab2(sch_1):m_a_clk_dn(1)"
				( objectStatus "M_A_CLK_DN<1>" )
			)
			( signal "@baseboard_fab2_lib.baseboard_fab2(sch_1):m_a_clk_dp(1)"
				( objectStatus "M_A_CLK_DP<1>" )
			)
			( signal "@baseboard_fab2_lib.baseboard_fab2(sch_1):m_a_clk_dn(3)"
				( objectStatus "M_A_CLK_DN<3>" )
			)
			( signal "@baseboard_fab2_lib.baseboard_fab2(sch_1):m_a_clk_dp(3)"
				( objectStatus "M_A_CLK_DP<3>" )
			)
			( signal "@baseboard_fab2_lib.baseboard_fab2(sch_1):m_b_clk_dn(1)"
				( attribute "NO_TEST" "1"
					( Origin gBackEnd )
				)
				( objectStatus "M_B_CLK_DN<1>" )
			)
			( signal "@baseboard_fab2_lib.baseboard_fab2(sch_1):m_b_clk_dp(1)"
				( objectStatus "M_B_CLK_DP<1>" )
			)
			( signal "@baseboard_fab2_lib.baseboard_fab2(sch_1):m_h_clk_dn(3)"
				( attribute "NO_TEST" "1"
					( Origin gBackEnd )
				)
				( objectStatus "M_H_CLK_DN<3>" )
			)
			( signal "@baseboard_fab2_lib.baseboard_fab2(sch_1):m_h_clk_dp(3)"
				( objectStatus "M_H_CLK_DP<3>" )
			)
			( signal "@baseboard_fab2_lib.baseboard_fab2(sch_1):m_c_clk_dn(1)"
				( objectStatus "M_C_CLK_DN<1>" )
			)
			( signal "@baseboard_fab2_lib.baseboard_fab2(sch_1):m_c_clk_dp(1)"
				( attribute "NO_TEST" "1"
					( Origin gBackEnd )
				)
				( objectStatus "M_C_CLK_DP<1>" )
			)
			( signal "@baseboard_fab2_lib.baseboard_fab2(sch_1):m_d_clk_dn(1)"
				( attribute "NO_TEST" "1"
					( Origin gBackEnd )
				)
				( objectStatus "M_D_CLK_DN<1>" )
			)
			( signal "@baseboard_fab2_lib.baseboard_fab2(sch_1):m_d_clk_dp(1)"
				( attribute "NO_TEST" "1"
					( Origin gBackEnd )
				)
				( objectStatus "M_D_CLK_DP<1>" )
			)
			( signal "@baseboard_fab2_lib.baseboard_fab2(sch_1):m_d_clk_dn(3)"
				( attribute "NO_TEST" "1"
					( Origin gBackEnd )
				)
				( objectStatus "M_D_CLK_DN<3>" )
			)
			( signal "@baseboard_fab2_lib.baseboard_fab2(sch_1):m_d_clk_dp(3)"
				( attribute "NO_TEST" "1"
					( Origin gBackEnd )
				)
				( objectStatus "M_D_CLK_DP<3>" )
			)
			( signal "@baseboard_fab2_lib.baseboard_fab2(sch_1):m_l_clk_dn(3)"
				( objectStatus "M_L_CLK_DN<3>" )
			)
			( signal "@baseboard_fab2_lib.baseboard_fab2(sch_1):m_l_clk_dp(3)"
				( attribute "NO_TEST" "1"
					( Origin gBackEnd )
				)
				( objectStatus "M_L_CLK_DP<3>" )
			)
			( signal "@baseboard_fab2_lib.baseboard_fab2(sch_1):m_e_clk_dn(1)"
				( objectStatus "M_E_CLK_DN<1>" )
			)
			( signal "@baseboard_fab2_lib.baseboard_fab2(sch_1):m_e_clk_dp(1)"
				( attribute "NO_TEST" "1"
					( Origin gBackEnd )
				)
				( objectStatus "M_E_CLK_DP<1>" )
			)
			( signal "@baseboard_fab2_lib.baseboard_fab2(sch_1):m_f_clk_dn(1)"
				( objectStatus "M_F_CLK_DN<1>" )
			)
			( signal "@baseboard_fab2_lib.baseboard_fab2(sch_1):m_f_clk_dp(1)"
				( attribute "NO_TEST" "1"
					( Origin gBackEnd )
				)
				( objectStatus "M_F_CLK_DP<1>" )
			)
			( signal "@baseboard_fab2_lib.baseboard_fab2(sch_1):m_g_clk_dp(3)"
				( objectStatus "M_G_CLK_DP<3>" )
			)
			( signal "@baseboard_fab2_lib.baseboard_fab2(sch_1):m_g_clk_dn(3)"
				( objectStatus "M_G_CLK_DN<3>" )
			)
			( signal "@baseboard_fab2_lib.baseboard_fab2(sch_1):m_g_clk_dn(1)"
				( attribute "NO_TEST" "1"
					( Origin gBackEnd )
				)
				( objectStatus "M_G_CLK_DN<1>" )
			)
			( signal "@baseboard_fab2_lib.baseboard_fab2(sch_1):m_g_clk_dp(1)"
				( attribute "NO_TEST" "1"
					( Origin gBackEnd )
				)
				( objectStatus "M_G_CLK_DP<1>" )
			)
			( signal "@baseboard_fab2_lib.baseboard_fab2(sch_1):m_c_clk_dn(3)"
				( objectStatus "M_C_CLK_DN<3>" )
			)
			( signal "@baseboard_fab2_lib.baseboard_fab2(sch_1):m_c_clk_dp(3)"
				( attribute "NO_TEST" "1"
					( Origin gBackEnd )
				)
				( objectStatus "M_C_CLK_DP<3>" )
			)
			( signal "@baseboard_fab2_lib.baseboard_fab2(sch_1):m_h_clk_dn(1)"
				( attribute "NO_TEST" "1"
					( Origin gBackEnd )
				)
				( objectStatus "M_H_CLK_DN<1>" )
			)
			( signal "@baseboard_fab2_lib.baseboard_fab2(sch_1):m_h_clk_dp(1)"
				( objectStatus "M_H_CLK_DP<1>" )
			)
			( signal "@baseboard_fab2_lib.baseboard_fab2(sch_1):m_b_clk_dn(3)"
				( attribute "NO_TEST" "1"
					( Origin gBackEnd )
				)
				( objectStatus "M_B_CLK_DN<3>" )
			)
			( signal "@baseboard_fab2_lib.baseboard_fab2(sch_1):m_b_clk_dp(3)"
				( objectStatus "M_B_CLK_DP<3>" )
			)
			( signal "@baseboard_fab2_lib.baseboard_fab2(sch_1):m_j_clk_dp(3)"
				( attribute "NO_TEST" "1"
					( Origin gBackEnd )
				)
				( objectStatus "M_J_CLK_DP<3>" )
			)
			( signal "@baseboard_fab2_lib.baseboard_fab2(sch_1):m_j_clk_dn(3)"
				( objectStatus "M_J_CLK_DN<3>" )
			)
			( signal "@baseboard_fab2_lib.baseboard_fab2(sch_1):m_j_clk_dn(1)"
				( objectStatus "M_J_CLK_DN<1>" )
			)
			( signal "@baseboard_fab2_lib.baseboard_fab2(sch_1):m_j_clk_dp(1)"
				( attribute "NO_TEST" "1"
					( Origin gBackEnd )
				)
				( objectStatus "M_J_CLK_DP<1>" )
			)
			( signal "@baseboard_fab2_lib.baseboard_fab2(sch_1):m_k_clk_dp(3)"
				( attribute "NO_TEST" "1"
					( Origin gBackEnd )
				)
				( objectStatus "M_K_CLK_DP<3>" )
			)
			( signal "@baseboard_fab2_lib.baseboard_fab2(sch_1):m_k_clk_dn(3)"
				( attribute "NO_TEST" "1"
					( Origin gBackEnd )
				)
				( objectStatus "M_K_CLK_DN<3>" )
			)
			( signal "@baseboard_fab2_lib.baseboard_fab2(sch_1):m_f_clk_dn(3)"
				( objectStatus "M_F_CLK_DN<3>" )
			)
			( signal "@baseboard_fab2_lib.baseboard_fab2(sch_1):m_f_clk_dp(3)"
				( attribute "NO_TEST" "1"
					( Origin gBackEnd )
				)
				( objectStatus "M_F_CLK_DP<3>" )
			)
			( signal "@baseboard_fab2_lib.baseboard_fab2(sch_1):m_k_clk_dn(1)"
				( attribute "NO_TEST" "1"
					( Origin gBackEnd )
				)
				( objectStatus "M_K_CLK_DN<1>" )
			)
			( signal "@baseboard_fab2_lib.baseboard_fab2(sch_1):m_k_clk_dp(1)"
				( attribute "NO_TEST" "1"
					( Origin gBackEnd )
				)
				( objectStatus "M_K_CLK_DP<1>" )
			)
			( signal "@baseboard_fab2_lib.baseboard_fab2(sch_1):m_e_clk_dn(3)"
				( attribute "NO_TEST" "1"
					( Origin gBackEnd )
				)
				( objectStatus "M_E_CLK_DN<3>" )
			)
			( signal "@baseboard_fab2_lib.baseboard_fab2(sch_1):m_e_clk_dp(3)"
				( objectStatus "M_E_CLK_DP<3>" )
			)
			( signal "@baseboard_fab2_lib.baseboard_fab2(sch_1):m_l_clk_dn(1)"
				( attribute "NO_TEST" "1"
					( Origin gBackEnd )
				)
				( objectStatus "M_L_CLK_DN<1>" )
			)
			( signal "@baseboard_fab2_lib.baseboard_fab2(sch_1):m_l_clk_dp(1)"
				( objectStatus "M_L_CLK_DP<1>" )
			)
			( signal "@baseboard_fab2_lib.baseboard_fab2(sch_1):m_m_clk_dn(3)"
				( attribute "NO_TEST" "1"
					( Origin gBackEnd )
				)
				( objectStatus "M_M_CLK_DN<3>" )
			)
			( signal "@baseboard_fab2_lib.baseboard_fab2(sch_1):m_m_clk_dp(3)"
				( objectStatus "M_M_CLK_DP<3>" )
			)
			( signal "@baseboard_fab2_lib.baseboard_fab2(sch_1):m_m_clk_dn(1)"
				( attribute "NO_TEST" "1"
					( Origin gBackEnd )
				)
				( objectStatus "M_M_CLK_DN<1>" )
			)
			( signal "@baseboard_fab2_lib.baseboard_fab2(sch_1):m_m_clk_dp(1)"
				( objectStatus "M_M_CLK_DP<1>" )
			)
			( signal "@baseboard_fab2_lib.baseboard_fab2(sch_1):m_d_dqs_dp(8)"
				( pinPairRef "@baseboard_fab2_lib.baseboard_fab2(sch_1):\PP1204\" )
				( pinPairRef "@baseboard_fab2_lib.baseboard_fab2(sch_1):\PP1205\" )
				( attribute "NO_TEST" "1"
					( Origin gBackEnd )
				)
				( objectStatus "M_D_DQS_DP<8>" )
			)
			( signal "@baseboard_fab2_lib.baseboard_fab2(sch_1):m_d_dqs_dp(9)"
				( pinPairRef "@baseboard_fab2_lib.baseboard_fab2(sch_1):\PP670\" )
				( pinPairRef "@baseboard_fab2_lib.baseboard_fab2(sch_1):\PP671\" )
				( attribute "NO_TEST" "1"
					( Origin gBackEnd )
				)
				( objectStatus "M_D_DQS_DP<9>" )
			)
			( signal "@baseboard_fab2_lib.baseboard_fab2(sch_1):m_d_dqs_dp(10)"
				( pinPairRef "@baseboard_fab2_lib.baseboard_fab2(sch_1):\PP682\" )
				( pinPairRef "@baseboard_fab2_lib.baseboard_fab2(sch_1):\PP683\" )
				( attribute "NO_TEST" "1"
					( Origin gBackEnd )
				)
				( objectStatus "M_D_DQS_DP<10>" )
			)
			( signal "@baseboard_fab2_lib.baseboard_fab2(sch_1):m_d_dqs_dp(11)"
				( pinPairRef "@baseboard_fab2_lib.baseboard_fab2(sch_1):\PP694\" )
				( pinPairRef "@baseboard_fab2_lib.baseboard_fab2(sch_1):\PP695\" )
				( attribute "NO_TEST" "1"
					( Origin gBackEnd )
				)
				( objectStatus "M_D_DQS_DP<11>" )
			)
			( signal "@baseboard_fab2_lib.baseboard_fab2(sch_1):m_d_dqs_dp(12)"
				( pinPairRef "@baseboard_fab2_lib.baseboard_fab2(sch_1):\PP706\" )
				( pinPairRef "@baseboard_fab2_lib.baseboard_fab2(sch_1):\PP707\" )
				( objectStatus "M_D_DQS_DP<12>" )
			)
			( signal "@baseboard_fab2_lib.baseboard_fab2(sch_1):m_d_dqs_dp(13)"
				( pinPairRef "@baseboard_fab2_lib.baseboard_fab2(sch_1):\PP718\" )
				( pinPairRef "@baseboard_fab2_lib.baseboard_fab2(sch_1):\PP720\" )
				( attribute "NO_TEST" "1"
					( Origin gBackEnd )
				)
				( objectStatus "M_D_DQS_DP<13>" )
			)
			( signal "@baseboard_fab2_lib.baseboard_fab2(sch_1):m_d_dqs_dp(14)"
				( pinPairRef "@baseboard_fab2_lib.baseboard_fab2(sch_1):\PP730\" )
				( pinPairRef "@baseboard_fab2_lib.baseboard_fab2(sch_1):\PP732\" )
				( attribute "NO_TEST" "1"
					( Origin gBackEnd )
				)
				( objectStatus "M_D_DQS_DP<14>" )
			)
			( signal "@baseboard_fab2_lib.baseboard_fab2(sch_1):m_d_dqs_dp(15)"
				( pinPairRef "@baseboard_fab2_lib.baseboard_fab2(sch_1):\PP742\" )
				( pinPairRef "@baseboard_fab2_lib.baseboard_fab2(sch_1):\PP744\" )
				( attribute "NO_TEST" "1"
					( Origin gBackEnd )
				)
				( objectStatus "M_D_DQS_DP<15>" )
			)
			( signal "@baseboard_fab2_lib.baseboard_fab2(sch_1):m_d_dqs_dp(16)"
				( pinPairRef "@baseboard_fab2_lib.baseboard_fab2(sch_1):\PP754\" )
				( pinPairRef "@baseboard_fab2_lib.baseboard_fab2(sch_1):\PP756\" )
				( attribute "NO_TEST" "1"
					( Origin gBackEnd )
				)
				( objectStatus "M_D_DQS_DP<16>" )
			)
			( signal "@baseboard_fab2_lib.baseboard_fab2(sch_1):m_d_dqs_dp(17)"
				( pinPairRef "@baseboard_fab2_lib.baseboard_fab2(sch_1):\PP1198\" )
				( pinPairRef "@baseboard_fab2_lib.baseboard_fab2(sch_1):\PP1199\" )
				( attribute "NO_TEST" "1"
					( Origin gBackEnd )
				)
				( objectStatus "M_D_DQS_DP<17>" )
			)
			( signal "@baseboard_fab2_lib.baseboard_fab2(sch_1):m_e_dqs_dp(0)"
				( pinPairRef "@baseboard_fab2_lib.baseboard_fab2(sch_1):\PP1192\" )
				( pinPairRef "@baseboard_fab2_lib.baseboard_fab2(sch_1):\PP1193\" )
				( attribute "NO_TEST" "1"
					( Origin gBackEnd )
				)
				( objectStatus "M_E_DQS_DP<0>" )
			)
			( signal "@baseboard_fab2_lib.baseboard_fab2(sch_1):m_e_dqs_dp(1)"
				( pinPairRef "@baseboard_fab2_lib.baseboard_fab2(sch_1):\PP1180\" )
				( pinPairRef "@baseboard_fab2_lib.baseboard_fab2(sch_1):\PP1181\" )
				( attribute "NO_TEST" "1"
					( Origin gBackEnd )
				)
				( objectStatus "M_E_DQS_DP<1>" )
			)
			( signal "@baseboard_fab2_lib.baseboard_fab2(sch_1):m_e_dqs_dp(2)"
				( pinPairRef "@baseboard_fab2_lib.baseboard_fab2(sch_1):\PP1168\" )
				( pinPairRef "@baseboard_fab2_lib.baseboard_fab2(sch_1):\PP1169\" )
				( attribute "NO_TEST" "1"
					( Origin gBackEnd )
				)
				( objectStatus "M_E_DQS_DP<2>" )
			)
			( signal "@baseboard_fab2_lib.baseboard_fab2(sch_1):m_e_dqs_dp(3)"
				( pinPairRef "@baseboard_fab2_lib.baseboard_fab2(sch_1):\PP1156\" )
				( pinPairRef "@baseboard_fab2_lib.baseboard_fab2(sch_1):\PP1157\" )
				( attribute "NO_TEST" "1"
					( Origin gBackEnd )
				)
				( objectStatus "M_E_DQS_DP<3>" )
			)
			( signal "@baseboard_fab2_lib.baseboard_fab2(sch_1):m_e_dqs_dp(4)"
				( pinPairRef "@baseboard_fab2_lib.baseboard_fab2(sch_1):\PP1144\" )
				( pinPairRef "@baseboard_fab2_lib.baseboard_fab2(sch_1):\PP1146\" )
				( attribute "NO_TEST" "1"
					( Origin gBackEnd )
				)
				( objectStatus "M_E_DQS_DP<4>" )
			)
			( signal "@baseboard_fab2_lib.baseboard_fab2(sch_1):m_e_dqs_dp(5)"
				( pinPairRef "@baseboard_fab2_lib.baseboard_fab2(sch_1):\PP1132\" )
				( pinPairRef "@baseboard_fab2_lib.baseboard_fab2(sch_1):\PP1134\" )
				( attribute "NO_TEST" "1"
					( Origin gBackEnd )
				)
				( objectStatus "M_E_DQS_DP<5>" )
			)
			( signal "@baseboard_fab2_lib.baseboard_fab2(sch_1):m_e_dqs_dp(6)"
				( pinPairRef "@baseboard_fab2_lib.baseboard_fab2(sch_1):\PP1120\" )
				( pinPairRef "@baseboard_fab2_lib.baseboard_fab2(sch_1):\PP1122\" )
				( attribute "NO_TEST" "1"
					( Origin gBackEnd )
				)
				( objectStatus "M_E_DQS_DP<6>" )
			)
			( signal "@baseboard_fab2_lib.baseboard_fab2(sch_1):m_e_dqs_dp(7)"
				( pinPairRef "@baseboard_fab2_lib.baseboard_fab2(sch_1):\PP1108\" )
				( pinPairRef "@baseboard_fab2_lib.baseboard_fab2(sch_1):\PP1110\" )
				( objectStatus "M_E_DQS_DP<7>" )
			)
			( signal "@baseboard_fab2_lib.baseboard_fab2(sch_1):m_e_dqs_dp(8)"
				( pinPairRef "@baseboard_fab2_lib.baseboard_fab2(sch_1):\PP1096\" )
				( pinPairRef "@baseboard_fab2_lib.baseboard_fab2(sch_1):\PP1097\" )
				( attribute "NO_TEST" "1"
					( Origin gBackEnd )
				)
				( objectStatus "M_E_DQS_DP<8>" )
			)
			( signal "@baseboard_fab2_lib.baseboard_fab2(sch_1):m_e_dqs_dp(9)"
				( pinPairRef "@baseboard_fab2_lib.baseboard_fab2(sch_1):\PP1186\" )
				( pinPairRef "@baseboard_fab2_lib.baseboard_fab2(sch_1):\PP1187\" )
				( attribute "NO_TEST" "1"
					( Origin gBackEnd )
				)
				( objectStatus "M_E_DQS_DP<9>" )
			)
			( signal "@baseboard_fab2_lib.baseboard_fab2(sch_1):m_e_dqs_dp(10)"
				( pinPairRef "@baseboard_fab2_lib.baseboard_fab2(sch_1):\PP1174\" )
				( pinPairRef "@baseboard_fab2_lib.baseboard_fab2(sch_1):\PP1175\" )
				( attribute "NO_TEST" "1"
					( Origin gBackEnd )
				)
				( objectStatus "M_E_DQS_DP<10>" )
			)
			( signal "@baseboard_fab2_lib.baseboard_fab2(sch_1):m_e_dqs_dp(11)"
				( pinPairRef "@baseboard_fab2_lib.baseboard_fab2(sch_1):\PP1162\" )
				( pinPairRef "@baseboard_fab2_lib.baseboard_fab2(sch_1):\PP1163\" )
				( attribute "NO_TEST" "1"
					( Origin gBackEnd )
				)
				( objectStatus "M_E_DQS_DP<11>" )
			)
			( signal "@baseboard_fab2_lib.baseboard_fab2(sch_1):m_e_dqs_dp(12)"
				( pinPairRef "@baseboard_fab2_lib.baseboard_fab2(sch_1):\PP1150\" )
				( pinPairRef "@baseboard_fab2_lib.baseboard_fab2(sch_1):\PP1151\" )
				( attribute "NO_TEST" "1"
					( Origin gBackEnd )
				)
				( objectStatus "M_E_DQS_DP<12>" )
			)
			( signal "@baseboard_fab2_lib.baseboard_fab2(sch_1):m_e_dqs_dp(13)"
				( pinPairRef "@baseboard_fab2_lib.baseboard_fab2(sch_1):\PP1138\" )
				( pinPairRef "@baseboard_fab2_lib.baseboard_fab2(sch_1):\PP1140\" )
				( attribute "NO_TEST" "1"
					( Origin gBackEnd )
				)
				( objectStatus "M_E_DQS_DP<13>" )
			)
			( signal "@baseboard_fab2_lib.baseboard_fab2(sch_1):m_e_dqs_dp(14)"
				( pinPairRef "@baseboard_fab2_lib.baseboard_fab2(sch_1):\PP1126\" )
				( pinPairRef "@baseboard_fab2_lib.baseboard_fab2(sch_1):\PP1128\" )
				( attribute "NO_TEST" "1"
					( Origin gBackEnd )
				)
				( objectStatus "M_E_DQS_DP<14>" )
			)
			( signal "@baseboard_fab2_lib.baseboard_fab2(sch_1):m_e_dqs_dp(15)"
				( pinPairRef "@baseboard_fab2_lib.baseboard_fab2(sch_1):\PP1114\" )
				( pinPairRef "@baseboard_fab2_lib.baseboard_fab2(sch_1):\PP1116\" )
				( attribute "NO_TEST" "1"
					( Origin gBackEnd )
				)
				( objectStatus "M_E_DQS_DP<15>" )
			)
			( signal "@baseboard_fab2_lib.baseboard_fab2(sch_1):m_e_dqs_dp(16)"
				( pinPairRef "@baseboard_fab2_lib.baseboard_fab2(sch_1):\PP1102\" )
				( pinPairRef "@baseboard_fab2_lib.baseboard_fab2(sch_1):\PP1104\" )
				( attribute "NO_TEST" "1"
					( Origin gBackEnd )
				)
				( objectStatus "M_E_DQS_DP<16>" )
			)
			( signal "@baseboard_fab2_lib.baseboard_fab2(sch_1):m_e_dqs_dp(17)"
				( pinPairRef "@baseboard_fab2_lib.baseboard_fab2(sch_1):\PP1090\" )
				( pinPairRef "@baseboard_fab2_lib.baseboard_fab2(sch_1):\PP1091\" )
				( attribute "NO_TEST" "1"
					( Origin gBackEnd )
				)
				( objectStatus "M_E_DQS_DP<17>" )
			)
			( signal "@baseboard_fab2_lib.baseboard_fab2(sch_1):m_f_dqs_dn(0)"
				( pinPairRef "@baseboard_fab2_lib.baseboard_fab2(sch_1):\PP1081\" )
				( pinPairRef "@baseboard_fab2_lib.baseboard_fab2(sch_1):\PP1082\" )
				( attribute "NO_TEST" "1"
					( Origin gBackEnd )
				)
				( objectStatus "M_F_DQS_DN<0>" )
			)
			( signal "@baseboard_fab2_lib.baseboard_fab2(sch_1):m_f_dqs_dn(1)"
				( pinPairRef "@baseboard_fab2_lib.baseboard_fab2(sch_1):\PP1069\" )
				( pinPairRef "@baseboard_fab2_lib.baseboard_fab2(sch_1):\PP1070\" )
				( objectStatus "M_F_DQS_DN<1>" )
			)
			( signal "@baseboard_fab2_lib.baseboard_fab2(sch_1):m_f_dqs_dn(2)"
				( pinPairRef "@baseboard_fab2_lib.baseboard_fab2(sch_1):\PP1057\" )
				( pinPairRef "@baseboard_fab2_lib.baseboard_fab2(sch_1):\PP1058\" )
				( attribute "NO_TEST" "1"
					( Origin gBackEnd )
				)
				( objectStatus "M_F_DQS_DN<2>" )
			)
			( signal "@baseboard_fab2_lib.baseboard_fab2(sch_1):m_f_dqs_dn(3)"
				( pinPairRef "@baseboard_fab2_lib.baseboard_fab2(sch_1):\PP1045\" )
				( pinPairRef "@baseboard_fab2_lib.baseboard_fab2(sch_1):\PP1046\" )
				( attribute "NO_TEST" "1"
					( Origin gBackEnd )
				)
				( objectStatus "M_F_DQS_DN<3>" )
			)
			( signal "@baseboard_fab2_lib.baseboard_fab2(sch_1):m_f_dqs_dn(4)"
				( pinPairRef "@baseboard_fab2_lib.baseboard_fab2(sch_1):\PP1033\" )
				( pinPairRef "@baseboard_fab2_lib.baseboard_fab2(sch_1):\PP1035\" )
				( attribute "NO_TEST" "1"
					( Origin gBackEnd )
				)
				( objectStatus "M_F_DQS_DN<4>" )
			)
			( signal "@baseboard_fab2_lib.baseboard_fab2(sch_1):m_f_dqs_dn(5)"
				( pinPairRef "@baseboard_fab2_lib.baseboard_fab2(sch_1):\PP1021\" )
				( pinPairRef "@baseboard_fab2_lib.baseboard_fab2(sch_1):\PP1023\" )
				( attribute "NO_TEST" "1"
					( Origin gBackEnd )
				)
				( objectStatus "M_F_DQS_DN<5>" )
			)
			( signal "@baseboard_fab2_lib.baseboard_fab2(sch_1):m_f_dqs_dn(6)"
				( pinPairRef "@baseboard_fab2_lib.baseboard_fab2(sch_1):\PP1009\" )
				( pinPairRef "@baseboard_fab2_lib.baseboard_fab2(sch_1):\PP1011\" )
				( objectStatus "M_F_DQS_DN<6>" )
			)
			( signal "@baseboard_fab2_lib.baseboard_fab2(sch_1):m_f_dqs_dn(7)"
				( pinPairRef "@baseboard_fab2_lib.baseboard_fab2(sch_1):\PP997\" )
				( pinPairRef "@baseboard_fab2_lib.baseboard_fab2(sch_1):\PP999\" )
				( objectStatus "M_F_DQS_DN<7>" )
			)
			( signal "@baseboard_fab2_lib.baseboard_fab2(sch_1):m_f_dqs_dn(8)"
				( pinPairRef "@baseboard_fab2_lib.baseboard_fab2(sch_1):\PP985\" )
				( pinPairRef "@baseboard_fab2_lib.baseboard_fab2(sch_1):\PP986\" )
				( attribute "NO_TEST" "1"
					( Origin gBackEnd )
				)
				( objectStatus "M_F_DQS_DN<8>" )
			)
			( signal "@baseboard_fab2_lib.baseboard_fab2(sch_1):m_f_dqs_dn(9)"
				( pinPairRef "@baseboard_fab2_lib.baseboard_fab2(sch_1):\PP1075\" )
				( pinPairRef "@baseboard_fab2_lib.baseboard_fab2(sch_1):\PP1076\" )
				( objectStatus "M_F_DQS_DN<9>" )
			)
			( signal "@baseboard_fab2_lib.baseboard_fab2(sch_1):m_f_dqs_dn(10)"
				( pinPairRef "@baseboard_fab2_lib.baseboard_fab2(sch_1):\PP1063\" )
				( pinPairRef "@baseboard_fab2_lib.baseboard_fab2(sch_1):\PP1064\" )
				( attribute "NO_TEST" "1"
					( Origin gBackEnd )
				)
				( objectStatus "M_F_DQS_DN<10>" )
			)
			( signal "@baseboard_fab2_lib.baseboard_fab2(sch_1):m_f_dqs_dn(11)"
				( pinPairRef "@baseboard_fab2_lib.baseboard_fab2(sch_1):\PP1051\" )
				( pinPairRef "@baseboard_fab2_lib.baseboard_fab2(sch_1):\PP1052\" )
				( attribute "NO_TEST" "1"
					( Origin gBackEnd )
				)
				( objectStatus "M_F_DQS_DN<11>" )
			)
			( signal "@baseboard_fab2_lib.baseboard_fab2(sch_1):m_f_dqs_dn(12)"
				( pinPairRef "@baseboard_fab2_lib.baseboard_fab2(sch_1):\PP1039\" )
				( pinPairRef "@baseboard_fab2_lib.baseboard_fab2(sch_1):\PP1040\" )
				( attribute "NO_TEST" "1"
					( Origin gBackEnd )
				)
				( objectStatus "M_F_DQS_DN<12>" )
			)
			( signal "@baseboard_fab2_lib.baseboard_fab2(sch_1):m_f_dqs_dn(13)"
				( pinPairRef "@baseboard_fab2_lib.baseboard_fab2(sch_1):\PP1027\" )
				( pinPairRef "@baseboard_fab2_lib.baseboard_fab2(sch_1):\PP1029\" )
				( attribute "NO_TEST" "1"
					( Origin gBackEnd )
				)
				( objectStatus "M_F_DQS_DN<13>" )
			)
			( signal "@baseboard_fab2_lib.baseboard_fab2(sch_1):m_f_dqs_dn(14)"
				( pinPairRef "@baseboard_fab2_lib.baseboard_fab2(sch_1):\PP1015\" )
				( pinPairRef "@baseboard_fab2_lib.baseboard_fab2(sch_1):\PP1017\" )
				( attribute "NO_TEST" "1"
					( Origin gBackEnd )
				)
				( objectStatus "M_F_DQS_DN<14>" )
			)
			( signal "@baseboard_fab2_lib.baseboard_fab2(sch_1):m_f_dqs_dn(15)"
				( pinPairRef "@baseboard_fab2_lib.baseboard_fab2(sch_1):\PP1003\" )
				( pinPairRef "@baseboard_fab2_lib.baseboard_fab2(sch_1):\PP1005\" )
				( attribute "NO_TEST" "1"
					( Origin gBackEnd )
				)
				( objectStatus "M_F_DQS_DN<15>" )
			)
			( signal "@baseboard_fab2_lib.baseboard_fab2(sch_1):m_f_dqs_dn(16)"
				( pinPairRef "@baseboard_fab2_lib.baseboard_fab2(sch_1):\PP991\" )
				( pinPairRef "@baseboard_fab2_lib.baseboard_fab2(sch_1):\PP993\" )
				( attribute "NO_TEST" "1"
					( Origin gBackEnd )
				)
				( objectStatus "M_F_DQS_DN<16>" )
			)
			( signal "@baseboard_fab2_lib.baseboard_fab2(sch_1):m_f_dqs_dn(17)"
				( pinPairRef "@baseboard_fab2_lib.baseboard_fab2(sch_1):\PP979\" )
				( pinPairRef "@baseboard_fab2_lib.baseboard_fab2(sch_1):\PP980\" )
				( attribute "NO_TEST" "1"
					( Origin gBackEnd )
				)
				( objectStatus "M_F_DQS_DN<17>" )
			)
			( signal "@baseboard_fab2_lib.baseboard_fab2(sch_1):m_f_dqs_dp(0)"
				( pinPairRef "@baseboard_fab2_lib.baseboard_fab2(sch_1):\PP1084\" )
				( pinPairRef "@baseboard_fab2_lib.baseboard_fab2(sch_1):\PP1085\" )
				( attribute "NO_TEST" "1"
					( Origin gBackEnd )
				)
				( objectStatus "M_F_DQS_DP<0>" )
			)
			( signal "@baseboard_fab2_lib.baseboard_fab2(sch_1):m_f_dqs_dp(1)"
				( pinPairRef "@baseboard_fab2_lib.baseboard_fab2(sch_1):\PP1072\" )
				( pinPairRef "@baseboard_fab2_lib.baseboard_fab2(sch_1):\PP1073\" )
				( attribute "NO_TEST" "1"
					( Origin gBackEnd )
				)
				( objectStatus "M_F_DQS_DP<1>" )
			)
			( signal "@baseboard_fab2_lib.baseboard_fab2(sch_1):m_f_dqs_dp(2)"
				( pinPairRef "@baseboard_fab2_lib.baseboard_fab2(sch_1):\PP1060\" )
				( pinPairRef "@baseboard_fab2_lib.baseboard_fab2(sch_1):\PP1061\" )
				( attribute "NO_TEST" "1"
					( Origin gBackEnd )
				)
				( objectStatus "M_F_DQS_DP<2>" )
			)
			( signal "@baseboard_fab2_lib.baseboard_fab2(sch_1):m_f_dqs_dp(3)"
				( pinPairRef "@baseboard_fab2_lib.baseboard_fab2(sch_1):\PP1048\" )
				( pinPairRef "@baseboard_fab2_lib.baseboard_fab2(sch_1):\PP1049\" )
				( attribute "NO_TEST" "1"
					( Origin gBackEnd )
				)
				( objectStatus "M_F_DQS_DP<3>" )
			)
			( signal "@baseboard_fab2_lib.baseboard_fab2(sch_1):m_f_dqs_dp(4)"
				( pinPairRef "@baseboard_fab2_lib.baseboard_fab2(sch_1):\PP1036\" )
				( pinPairRef "@baseboard_fab2_lib.baseboard_fab2(sch_1):\PP1038\" )
				( objectStatus "M_F_DQS_DP<4>" )
			)
			( signal "@baseboard_fab2_lib.baseboard_fab2(sch_1):m_f_dqs_dp(5)"
				( pinPairRef "@baseboard_fab2_lib.baseboard_fab2(sch_1):\PP1024\" )
				( pinPairRef "@baseboard_fab2_lib.baseboard_fab2(sch_1):\PP1026\" )
				( attribute "NO_TEST" "1"
					( Origin gBackEnd )
				)
				( objectStatus "M_F_DQS_DP<5>" )
			)
			( signal "@baseboard_fab2_lib.baseboard_fab2(sch_1):m_f_dqs_dp(6)"
				( pinPairRef "@baseboard_fab2_lib.baseboard_fab2(sch_1):\PP1012\" )
				( pinPairRef "@baseboard_fab2_lib.baseboard_fab2(sch_1):\PP1014\" )
				( attribute "NO_TEST" "1"
					( Origin gBackEnd )
				)
				( objectStatus "M_F_DQS_DP<6>" )
			)
			( signal "@baseboard_fab2_lib.baseboard_fab2(sch_1):m_f_dqs_dp(7)"
				( pinPairRef "@baseboard_fab2_lib.baseboard_fab2(sch_1):\PP1000\" )
				( pinPairRef "@baseboard_fab2_lib.baseboard_fab2(sch_1):\PP1002\" )
				( attribute "NO_TEST" "1"
					( Origin gBackEnd )
				)
				( objectStatus "M_F_DQS_DP<7>" )
			)
			( signal "@baseboard_fab2_lib.baseboard_fab2(sch_1):m_f_dqs_dp(8)"
				( pinPairRef "@baseboard_fab2_lib.baseboard_fab2(sch_1):\PP988\" )
				( pinPairRef "@baseboard_fab2_lib.baseboard_fab2(sch_1):\PP989\" )
				( objectStatus "M_F_DQS_DP<8>" )
			)
			( signal "@baseboard_fab2_lib.baseboard_fab2(sch_1):m_f_dqs_dp(9)"
				( pinPairRef "@baseboard_fab2_lib.baseboard_fab2(sch_1):\PP1078\" )
				( pinPairRef "@baseboard_fab2_lib.baseboard_fab2(sch_1):\PP1079\" )
				( attribute "NO_TEST" "1"
					( Origin gBackEnd )
				)
				( objectStatus "M_F_DQS_DP<9>" )
			)
			( signal "@baseboard_fab2_lib.baseboard_fab2(sch_1):m_f_dqs_dp(10)"
				( pinPairRef "@baseboard_fab2_lib.baseboard_fab2(sch_1):\PP1066\" )
				( pinPairRef "@baseboard_fab2_lib.baseboard_fab2(sch_1):\PP1067\" )
				( attribute "NO_TEST" "1"
					( Origin gBackEnd )
				)
				( objectStatus "M_F_DQS_DP<10>" )
			)
			( signal "@baseboard_fab2_lib.baseboard_fab2(sch_1):m_f_dqs_dp(11)"
				( pinPairRef "@baseboard_fab2_lib.baseboard_fab2(sch_1):\PP1054\" )
				( pinPairRef "@baseboard_fab2_lib.baseboard_fab2(sch_1):\PP1055\" )
				( objectStatus "M_F_DQS_DP<11>" )
			)
			( signal "@baseboard_fab2_lib.baseboard_fab2(sch_1):m_f_dqs_dp(12)"
				( pinPairRef "@baseboard_fab2_lib.baseboard_fab2(sch_1):\PP1042\" )
				( pinPairRef "@baseboard_fab2_lib.baseboard_fab2(sch_1):\PP1043\" )
				( objectStatus "M_F_DQS_DP<12>" )
			)
			( signal "@baseboard_fab2_lib.baseboard_fab2(sch_1):m_f_dqs_dp(13)"
				( pinPairRef "@baseboard_fab2_lib.baseboard_fab2(sch_1):\PP1030\" )
				( pinPairRef "@baseboard_fab2_lib.baseboard_fab2(sch_1):\PP1032\" )
				( attribute "NO_TEST" "1"
					( Origin gBackEnd )
				)
				( objectStatus "M_F_DQS_DP<13>" )
			)
			( signal "@baseboard_fab2_lib.baseboard_fab2(sch_1):m_f_dqs_dp(14)"
				( pinPairRef "@baseboard_fab2_lib.baseboard_fab2(sch_1):\PP1018\" )
				( pinPairRef "@baseboard_fab2_lib.baseboard_fab2(sch_1):\PP1020\" )
				( objectStatus "M_F_DQS_DP<14>" )
			)
			( signal "@baseboard_fab2_lib.baseboard_fab2(sch_1):m_f_dqs_dp(15)"
				( pinPairRef "@baseboard_fab2_lib.baseboard_fab2(sch_1):\PP1006\" )
				( pinPairRef "@baseboard_fab2_lib.baseboard_fab2(sch_1):\PP1008\" )
				( attribute "NO_TEST" "1"
					( Origin gBackEnd )
				)
				( objectStatus "M_F_DQS_DP<15>" )
			)
			( signal "@baseboard_fab2_lib.baseboard_fab2(sch_1):m_f_dqs_dp(16)"
				( pinPairRef "@baseboard_fab2_lib.baseboard_fab2(sch_1):\PP994\" )
				( pinPairRef "@baseboard_fab2_lib.baseboard_fab2(sch_1):\PP996\" )
				( attribute "NO_TEST" "1"
					( Origin gBackEnd )
				)
				( objectStatus "M_F_DQS_DP<16>" )
			)
			( signal "@baseboard_fab2_lib.baseboard_fab2(sch_1):m_f_dqs_dp(17)"
				( pinPairRef "@baseboard_fab2_lib.baseboard_fab2(sch_1):\PP982\" )
				( pinPairRef "@baseboard_fab2_lib.baseboard_fab2(sch_1):\PP983\" )
				( attribute "NO_TEST" "1"
					( Origin gBackEnd )
				)
				( objectStatus "M_F_DQS_DP<17>" )
			)
			( signal "@baseboard_fab2_lib.baseboard_fab2(sch_1):m_b_dqs_dn(16)"
				( pinPairRef "@baseboard_fab2_lib.baseboard_fab2(sch_1):\PP475\" )
				( pinPairRef "@baseboard_fab2_lib.baseboard_fab2(sch_1):\PP477\" )
				( attribute "NO_TEST" "1"
					( Origin gBackEnd )
				)
				( objectStatus "M_B_DQS_DN<16>" )
			)
			( signal "@baseboard_fab2_lib.baseboard_fab2(sch_1):m_b_dqs_dn(17)"
				( pinPairRef "@baseboard_fab2_lib.baseboard_fab2(sch_1):\PP1219\" )
				( pinPairRef "@baseboard_fab2_lib.baseboard_fab2(sch_1):\PP1220\" )
				( objectStatus "M_B_DQS_DN<17>" )
			)
			( signal "@baseboard_fab2_lib.baseboard_fab2(sch_1):m_b_dqs_dp(0)"
				( pinPairRef "@baseboard_fab2_lib.baseboard_fab2(sch_1):\PP568\" )
				( pinPairRef "@baseboard_fab2_lib.baseboard_fab2(sch_1):\PP569\" )
				( attribute "NO_TEST" "1"
					( Origin gBackEnd )
				)
				( objectStatus "M_B_DQS_DP<0>" )
			)
			( signal "@baseboard_fab2_lib.baseboard_fab2(sch_1):m_b_dqs_dp(1)"
				( pinPairRef "@baseboard_fab2_lib.baseboard_fab2(sch_1):\PP556\" )
				( pinPairRef "@baseboard_fab2_lib.baseboard_fab2(sch_1):\PP557\" )
				( attribute "NO_TEST" "1"
					( Origin gBackEnd )
				)
				( objectStatus "M_B_DQS_DP<1>" )
			)
			( signal "@baseboard_fab2_lib.baseboard_fab2(sch_1):m_b_dqs_dp(2)"
				( pinPairRef "@baseboard_fab2_lib.baseboard_fab2(sch_1):\PP544\" )
				( pinPairRef "@baseboard_fab2_lib.baseboard_fab2(sch_1):\PP545\" )
				( objectStatus "M_B_DQS_DP<2>" )
			)
			( signal "@baseboard_fab2_lib.baseboard_fab2(sch_1):m_b_dqs_dp(3)"
				( pinPairRef "@baseboard_fab2_lib.baseboard_fab2(sch_1):\PP532\" )
				( pinPairRef "@baseboard_fab2_lib.baseboard_fab2(sch_1):\PP533\" )
				( objectStatus "M_B_DQS_DP<3>" )
			)
			( signal "@baseboard_fab2_lib.baseboard_fab2(sch_1):m_b_dqs_dp(4)"
				( pinPairRef "@baseboard_fab2_lib.baseboard_fab2(sch_1):\PP520\" )
				( pinPairRef "@baseboard_fab2_lib.baseboard_fab2(sch_1):\PP522\" )
				( attribute "NO_TEST" "1"
					( Origin gBackEnd )
				)
				( objectStatus "M_B_DQS_DP<4>" )
			)
			( signal "@baseboard_fab2_lib.baseboard_fab2(sch_1):m_b_dqs_dp(5)"
				( pinPairRef "@baseboard_fab2_lib.baseboard_fab2(sch_1):\PP508\" )
				( pinPairRef "@baseboard_fab2_lib.baseboard_fab2(sch_1):\PP509\" )
				( attribute "NO_TEST" "1"
					( Origin gBackEnd )
				)
				( objectStatus "M_B_DQS_DP<5>" )
			)
			( signal "@baseboard_fab2_lib.baseboard_fab2(sch_1):m_b_dqs_dp(6)"
				( pinPairRef "@baseboard_fab2_lib.baseboard_fab2(sch_1):\PP496\" )
				( pinPairRef "@baseboard_fab2_lib.baseboard_fab2(sch_1):\PP497\" )
				( objectStatus "M_B_DQS_DP<6>" )
			)
			( signal "@baseboard_fab2_lib.baseboard_fab2(sch_1):m_b_dqs_dp(7)"
				( pinPairRef "@baseboard_fab2_lib.baseboard_fab2(sch_1):\PP484\" )
				( pinPairRef "@baseboard_fab2_lib.baseboard_fab2(sch_1):\PP486\" )
				( attribute "NO_TEST" "1"
					( Origin gBackEnd )
				)
				( objectStatus "M_B_DQS_DP<7>" )
			)
			( signal "@baseboard_fab2_lib.baseboard_fab2(sch_1):m_b_dqs_dp(8)"
				( pinPairRef "@baseboard_fab2_lib.baseboard_fab2(sch_1):\PP1228\" )
				( pinPairRef "@baseboard_fab2_lib.baseboard_fab2(sch_1):\PP1229\" )
				( attribute "NO_TEST" "1"
					( Origin gBackEnd )
				)
				( objectStatus "M_B_DQS_DP<8>" )
			)
			( signal "@baseboard_fab2_lib.baseboard_fab2(sch_1):m_b_dqs_dp(9)"
				( pinPairRef "@baseboard_fab2_lib.baseboard_fab2(sch_1):\PP562\" )
				( pinPairRef "@baseboard_fab2_lib.baseboard_fab2(sch_1):\PP563\" )
				( attribute "NO_TEST" "1"
					( Origin gBackEnd )
				)
				( objectStatus "M_B_DQS_DP<9>" )
			)
			( signal "@baseboard_fab2_lib.baseboard_fab2(sch_1):m_b_dqs_dp(10)"
				( pinPairRef "@baseboard_fab2_lib.baseboard_fab2(sch_1):\PP550\" )
				( pinPairRef "@baseboard_fab2_lib.baseboard_fab2(sch_1):\PP551\" )
				( attribute "NO_TEST" "1"
					( Origin gBackEnd )
				)
				( objectStatus "M_B_DQS_DP<10>" )
			)
			( signal "@baseboard_fab2_lib.baseboard_fab2(sch_1):m_b_dqs_dp(11)"
				( pinPairRef "@baseboard_fab2_lib.baseboard_fab2(sch_1):\PP538\" )
				( pinPairRef "@baseboard_fab2_lib.baseboard_fab2(sch_1):\PP539\" )
				( attribute "NO_TEST" "1"
					( Origin gBackEnd )
				)
				( objectStatus "M_B_DQS_DP<11>" )
			)
			( signal "@baseboard_fab2_lib.baseboard_fab2(sch_1):m_b_dqs_dp(12)"
				( pinPairRef "@baseboard_fab2_lib.baseboard_fab2(sch_1):\PP526\" )
				( pinPairRef "@baseboard_fab2_lib.baseboard_fab2(sch_1):\PP527\" )
				( objectStatus "M_B_DQS_DP<12>" )
			)
			( signal "@baseboard_fab2_lib.baseboard_fab2(sch_1):m_b_dqs_dp(13)"
				( pinPairRef "@baseboard_fab2_lib.baseboard_fab2(sch_1):\PP514\" )
				( pinPairRef "@baseboard_fab2_lib.baseboard_fab2(sch_1):\PP516\" )
				( objectStatus "M_B_DQS_DP<13>" )
			)
			( signal "@baseboard_fab2_lib.baseboard_fab2(sch_1):m_b_dqs_dp(14)"
				( pinPairRef "@baseboard_fab2_lib.baseboard_fab2(sch_1):\PP502\" )
				( pinPairRef "@baseboard_fab2_lib.baseboard_fab2(sch_1):\PP503\" )
				( attribute "NO_TEST" "1"
					( Origin gBackEnd )
				)
				( objectStatus "M_B_DQS_DP<14>" )
			)
			( signal "@baseboard_fab2_lib.baseboard_fab2(sch_1):m_b_dqs_dp(15)"
				( pinPairRef "@baseboard_fab2_lib.baseboard_fab2(sch_1):\PP490\" )
				( pinPairRef "@baseboard_fab2_lib.baseboard_fab2(sch_1):\PP491\" )
				( objectStatus "M_B_DQS_DP<15>" )
			)
			( signal "@baseboard_fab2_lib.baseboard_fab2(sch_1):m_b_dqs_dp(16)"
				( pinPairRef "@baseboard_fab2_lib.baseboard_fab2(sch_1):\PP478\" )
				( pinPairRef "@baseboard_fab2_lib.baseboard_fab2(sch_1):\PP480\" )
				( objectStatus "M_B_DQS_DP<16>" )
			)
			( signal "@baseboard_fab2_lib.baseboard_fab2(sch_1):m_b_dqs_dp(17)"
				( pinPairRef "@baseboard_fab2_lib.baseboard_fab2(sch_1):\PP1222\" )
				( pinPairRef "@baseboard_fab2_lib.baseboard_fab2(sch_1):\PP1223\" )
				( objectStatus "M_B_DQS_DP<17>" )
			)
			( signal "@baseboard_fab2_lib.baseboard_fab2(sch_1):m_c_dqs_dn(0)"
				( pinPairRef "@baseboard_fab2_lib.baseboard_fab2(sch_1):\PP661\" )
				( pinPairRef "@baseboard_fab2_lib.baseboard_fab2(sch_1):\PP662\" )
				( attribute "NO_TEST" "1"
					( Origin gBackEnd )
				)
				( objectStatus "M_C_DQS_DN<0>" )
			)
			( signal "@baseboard_fab2_lib.baseboard_fab2(sch_1):m_c_dqs_dn(1)"
				( pinPairRef "@baseboard_fab2_lib.baseboard_fab2(sch_1):\PP649\" )
				( pinPairRef "@baseboard_fab2_lib.baseboard_fab2(sch_1):\PP650\" )
				( attribute "NO_TEST" "1"
					( Origin gBackEnd )
				)
				( objectStatus "M_C_DQS_DN<1>" )
			)
			( signal "@baseboard_fab2_lib.baseboard_fab2(sch_1):m_c_dqs_dn(2)"
				( pinPairRef "@baseboard_fab2_lib.baseboard_fab2(sch_1):\PP637\" )
				( pinPairRef "@baseboard_fab2_lib.baseboard_fab2(sch_1):\PP638\" )
				( attribute "NO_TEST" "1"
					( Origin gBackEnd )
				)
				( objectStatus "M_C_DQS_DN<2>" )
			)
			( signal "@baseboard_fab2_lib.baseboard_fab2(sch_1):m_c_dqs_dn(3)"
				( pinPairRef "@baseboard_fab2_lib.baseboard_fab2(sch_1):\PP625\" )
				( pinPairRef "@baseboard_fab2_lib.baseboard_fab2(sch_1):\PP626\" )
				( attribute "NO_TEST" "1"
					( Origin gBackEnd )
				)
				( objectStatus "M_C_DQS_DN<3>" )
			)
			( signal "@baseboard_fab2_lib.baseboard_fab2(sch_1):m_c_dqs_dn(4)"
				( pinPairRef "@baseboard_fab2_lib.baseboard_fab2(sch_1):\PP613\" )
				( pinPairRef "@baseboard_fab2_lib.baseboard_fab2(sch_1):\PP615\" )
				( attribute "NO_TEST" "1"
					( Origin gBackEnd )
				)
				( objectStatus "M_C_DQS_DN<4>" )
			)
			( signal "@baseboard_fab2_lib.baseboard_fab2(sch_1):m_c_dqs_dn(5)"
				( pinPairRef "@baseboard_fab2_lib.baseboard_fab2(sch_1):\PP601\" )
				( pinPairRef "@baseboard_fab2_lib.baseboard_fab2(sch_1):\PP603\" )
				( attribute "NO_TEST" "1"
					( Origin gBackEnd )
				)
				( objectStatus "M_C_DQS_DN<5>" )
			)
			( signal "@baseboard_fab2_lib.baseboard_fab2(sch_1):m_c_dqs_dn(6)"
				( pinPairRef "@baseboard_fab2_lib.baseboard_fab2(sch_1):\PP589\" )
				( pinPairRef "@baseboard_fab2_lib.baseboard_fab2(sch_1):\PP591\" )
				( attribute "NO_TEST" "1"
					( Origin gBackEnd )
				)
				( objectStatus "M_C_DQS_DN<6>" )
			)
			( signal "@baseboard_fab2_lib.baseboard_fab2(sch_1):m_c_dqs_dn(7)"
				( pinPairRef "@baseboard_fab2_lib.baseboard_fab2(sch_1):\PP577\" )
				( pinPairRef "@baseboard_fab2_lib.baseboard_fab2(sch_1):\PP579\" )
				( objectStatus "M_C_DQS_DN<7>" )
			)
			( signal "@baseboard_fab2_lib.baseboard_fab2(sch_1):m_c_dqs_dn(8)"
				( pinPairRef "@baseboard_fab2_lib.baseboard_fab2(sch_1):\PP1213\" )
				( pinPairRef "@baseboard_fab2_lib.baseboard_fab2(sch_1):\PP1214\" )
				( objectStatus "M_C_DQS_DN<8>" )
			)
			( signal "@baseboard_fab2_lib.baseboard_fab2(sch_1):m_c_dqs_dn(9)"
				( pinPairRef "@baseboard_fab2_lib.baseboard_fab2(sch_1):\PP655\" )
				( pinPairRef "@baseboard_fab2_lib.baseboard_fab2(sch_1):\PP656\" )
				( objectStatus "M_C_DQS_DN<9>" )
			)
			( signal "@baseboard_fab2_lib.baseboard_fab2(sch_1):m_c_dqs_dn(10)"
				( pinPairRef "@baseboard_fab2_lib.baseboard_fab2(sch_1):\PP643\" )
				( pinPairRef "@baseboard_fab2_lib.baseboard_fab2(sch_1):\PP644\" )
				( objectStatus "M_C_DQS_DN<10>" )
			)
			( signal "@baseboard_fab2_lib.baseboard_fab2(sch_1):m_c_dqs_dn(11)"
				( pinPairRef "@baseboard_fab2_lib.baseboard_fab2(sch_1):\PP631\" )
				( pinPairRef "@baseboard_fab2_lib.baseboard_fab2(sch_1):\PP632\" )
				( objectStatus "M_C_DQS_DN<11>" )
			)
			( signal "@baseboard_fab2_lib.baseboard_fab2(sch_1):m_c_dqs_dn(12)"
				( pinPairRef "@baseboard_fab2_lib.baseboard_fab2(sch_1):\PP619\" )
				( pinPairRef "@baseboard_fab2_lib.baseboard_fab2(sch_1):\PP620\" )
				( objectStatus "M_C_DQS_DN<12>" )
			)
			( signal "@baseboard_fab2_lib.baseboard_fab2(sch_1):m_c_dqs_dn(13)"
				( pinPairRef "@baseboard_fab2_lib.baseboard_fab2(sch_1):\PP607\" )
				( pinPairRef "@baseboard_fab2_lib.baseboard_fab2(sch_1):\PP609\" )
				( objectStatus "M_C_DQS_DN<13>" )
			)
			( signal "@baseboard_fab2_lib.baseboard_fab2(sch_1):m_c_dqs_dn(14)"
				( pinPairRef "@baseboard_fab2_lib.baseboard_fab2(sch_1):\PP595\" )
				( pinPairRef "@baseboard_fab2_lib.baseboard_fab2(sch_1):\PP597\" )
				( objectStatus "M_C_DQS_DN<14>" )
			)
			( signal "@baseboard_fab2_lib.baseboard_fab2(sch_1):m_c_dqs_dn(15)"
				( pinPairRef "@baseboard_fab2_lib.baseboard_fab2(sch_1):\PP583\" )
				( pinPairRef "@baseboard_fab2_lib.baseboard_fab2(sch_1):\PP585\" )
				( attribute "NO_TEST" "1"
					( Origin gBackEnd )
				)
				( objectStatus "M_C_DQS_DN<15>" )
			)
			( signal "@baseboard_fab2_lib.baseboard_fab2(sch_1):m_c_dqs_dn(16)"
				( pinPairRef "@baseboard_fab2_lib.baseboard_fab2(sch_1):\PP571\" )
				( pinPairRef "@baseboard_fab2_lib.baseboard_fab2(sch_1):\PP573\" )
				( attribute "NO_TEST" "1"
					( Origin gBackEnd )
				)
				( objectStatus "M_C_DQS_DN<16>" )
			)
			( signal "@baseboard_fab2_lib.baseboard_fab2(sch_1):m_c_dqs_dn(17)"
				( pinPairRef "@baseboard_fab2_lib.baseboard_fab2(sch_1):\PP1207\" )
				( pinPairRef "@baseboard_fab2_lib.baseboard_fab2(sch_1):\PP1208\" )
				( attribute "NO_TEST" "1"
					( Origin gBackEnd )
				)
				( objectStatus "M_C_DQS_DN<17>" )
			)
			( signal "@baseboard_fab2_lib.baseboard_fab2(sch_1):m_e_dqs_dn(0)"
				( pinPairRef "@baseboard_fab2_lib.baseboard_fab2(sch_1):\PP1189\" )
				( pinPairRef "@baseboard_fab2_lib.baseboard_fab2(sch_1):\PP1190\" )
				( attribute "NO_TEST" "1"
					( Origin gBackEnd )
				)
				( objectStatus "M_E_DQS_DN<0>" )
			)
			( signal "@baseboard_fab2_lib.baseboard_fab2(sch_1):m_e_dqs_dn(1)"
				( pinPairRef "@baseboard_fab2_lib.baseboard_fab2(sch_1):\PP1177\" )
				( pinPairRef "@baseboard_fab2_lib.baseboard_fab2(sch_1):\PP1178\" )
				( objectStatus "M_E_DQS_DN<1>" )
			)
			( signal "@baseboard_fab2_lib.baseboard_fab2(sch_1):m_e_dqs_dn(2)"
				( pinPairRef "@baseboard_fab2_lib.baseboard_fab2(sch_1):\PP1165\" )
				( pinPairRef "@baseboard_fab2_lib.baseboard_fab2(sch_1):\PP1166\" )
				( objectStatus "M_E_DQS_DN<2>" )
			)
			( signal "@baseboard_fab2_lib.baseboard_fab2(sch_1):m_e_dqs_dn(3)"
				( pinPairRef "@baseboard_fab2_lib.baseboard_fab2(sch_1):\PP1153\" )
				( pinPairRef "@baseboard_fab2_lib.baseboard_fab2(sch_1):\PP1154\" )
				( attribute "NO_TEST" "1"
					( Origin gBackEnd )
				)
				( objectStatus "M_E_DQS_DN<3>" )
			)
			( signal "@baseboard_fab2_lib.baseboard_fab2(sch_1):m_e_dqs_dn(4)"
				( pinPairRef "@baseboard_fab2_lib.baseboard_fab2(sch_1):\PP1141\" )
				( pinPairRef "@baseboard_fab2_lib.baseboard_fab2(sch_1):\PP1143\" )
				( attribute "NO_TEST" "1"
					( Origin gBackEnd )
				)
				( objectStatus "M_E_DQS_DN<4>" )
			)
			( signal "@baseboard_fab2_lib.baseboard_fab2(sch_1):m_e_dqs_dn(5)"
				( pinPairRef "@baseboard_fab2_lib.baseboard_fab2(sch_1):\PP1129\" )
				( pinPairRef "@baseboard_fab2_lib.baseboard_fab2(sch_1):\PP1131\" )
				( attribute "NO_TEST" "1"
					( Origin gBackEnd )
				)
				( objectStatus "M_E_DQS_DN<5>" )
			)
			( signal "@baseboard_fab2_lib.baseboard_fab2(sch_1):m_e_dqs_dn(6)"
				( pinPairRef "@baseboard_fab2_lib.baseboard_fab2(sch_1):\PP1117\" )
				( pinPairRef "@baseboard_fab2_lib.baseboard_fab2(sch_1):\PP1119\" )
				( attribute "NO_TEST" "1"
					( Origin gBackEnd )
				)
				( objectStatus "M_E_DQS_DN<6>" )
			)
			( signal "@baseboard_fab2_lib.baseboard_fab2(sch_1):m_e_dqs_dn(7)"
				( pinPairRef "@baseboard_fab2_lib.baseboard_fab2(sch_1):\PP1105\" )
				( pinPairRef "@baseboard_fab2_lib.baseboard_fab2(sch_1):\PP1107\" )
				( attribute "NO_TEST" "1"
					( Origin gBackEnd )
				)
				( objectStatus "M_E_DQS_DN<7>" )
			)
			( signal "@baseboard_fab2_lib.baseboard_fab2(sch_1):m_e_dqs_dn(8)"
				( pinPairRef "@baseboard_fab2_lib.baseboard_fab2(sch_1):\PP1093\" )
				( pinPairRef "@baseboard_fab2_lib.baseboard_fab2(sch_1):\PP1094\" )
				( attribute "NO_TEST" "1"
					( Origin gBackEnd )
				)
				( objectStatus "M_E_DQS_DN<8>" )
			)
			( signal "@baseboard_fab2_lib.baseboard_fab2(sch_1):m_e_dqs_dn(9)"
				( pinPairRef "@baseboard_fab2_lib.baseboard_fab2(sch_1):\PP1183\" )
				( pinPairRef "@baseboard_fab2_lib.baseboard_fab2(sch_1):\PP1184\" )
				( objectStatus "M_E_DQS_DN<9>" )
			)
			( signal "@baseboard_fab2_lib.baseboard_fab2(sch_1):m_e_dqs_dn(10)"
				( pinPairRef "@baseboard_fab2_lib.baseboard_fab2(sch_1):\PP1171\" )
				( pinPairRef "@baseboard_fab2_lib.baseboard_fab2(sch_1):\PP1172\" )
				( objectStatus "M_E_DQS_DN<10>" )
			)
			( signal "@baseboard_fab2_lib.baseboard_fab2(sch_1):m_e_dqs_dn(11)"
				( pinPairRef "@baseboard_fab2_lib.baseboard_fab2(sch_1):\PP1159\" )
				( pinPairRef "@baseboard_fab2_lib.baseboard_fab2(sch_1):\PP1160\" )
				( attribute "NO_TEST" "1"
					( Origin gBackEnd )
				)
				( objectStatus "M_E_DQS_DN<11>" )
			)
			( signal "@baseboard_fab2_lib.baseboard_fab2(sch_1):m_e_dqs_dn(12)"
				( pinPairRef "@baseboard_fab2_lib.baseboard_fab2(sch_1):\PP1147\" )
				( pinPairRef "@baseboard_fab2_lib.baseboard_fab2(sch_1):\PP1148\" )
				( attribute "NO_TEST" "1"
					( Origin gBackEnd )
				)
				( objectStatus "M_E_DQS_DN<12>" )
			)
			( signal "@baseboard_fab2_lib.baseboard_fab2(sch_1):m_e_dqs_dn(13)"
				( pinPairRef "@baseboard_fab2_lib.baseboard_fab2(sch_1):\PP1135\" )
				( pinPairRef "@baseboard_fab2_lib.baseboard_fab2(sch_1):\PP1137\" )
				( objectStatus "M_E_DQS_DN<13>" )
			)
			( signal "@baseboard_fab2_lib.baseboard_fab2(sch_1):m_e_dqs_dn(14)"
				( pinPairRef "@baseboard_fab2_lib.baseboard_fab2(sch_1):\PP1123\" )
				( pinPairRef "@baseboard_fab2_lib.baseboard_fab2(sch_1):\PP1125\" )
				( attribute "NO_TEST" "1"
					( Origin gBackEnd )
				)
				( objectStatus "M_E_DQS_DN<14>" )
			)
			( signal "@baseboard_fab2_lib.baseboard_fab2(sch_1):m_e_dqs_dn(15)"
				( pinPairRef "@baseboard_fab2_lib.baseboard_fab2(sch_1):\PP1111\" )
				( pinPairRef "@baseboard_fab2_lib.baseboard_fab2(sch_1):\PP1113\" )
				( attribute "NO_TEST" "1"
					( Origin gBackEnd )
				)
				( objectStatus "M_E_DQS_DN<15>" )
			)
			( signal "@baseboard_fab2_lib.baseboard_fab2(sch_1):m_e_dqs_dn(16)"
				( pinPairRef "@baseboard_fab2_lib.baseboard_fab2(sch_1):\PP1099\" )
				( pinPairRef "@baseboard_fab2_lib.baseboard_fab2(sch_1):\PP1101\" )
				( attribute "NO_TEST" "1"
					( Origin gBackEnd )
				)
				( objectStatus "M_E_DQS_DN<16>" )
			)
			( signal "@baseboard_fab2_lib.baseboard_fab2(sch_1):m_e_dqs_dn(17)"
				( pinPairRef "@baseboard_fab2_lib.baseboard_fab2(sch_1):\PP1087\" )
				( pinPairRef "@baseboard_fab2_lib.baseboard_fab2(sch_1):\PP1088\" )
				( attribute "NO_TEST" "1"
					( Origin gBackEnd )
				)
				( objectStatus "M_E_DQS_DN<17>" )
			)
			( signal "@baseboard_fab2_lib.baseboard_fab2(sch_1):m_c_dqs_dp(0)"
				( pinPairRef "@baseboard_fab2_lib.baseboard_fab2(sch_1):\PP664\" )
				( pinPairRef "@baseboard_fab2_lib.baseboard_fab2(sch_1):\PP665\" )
				( attribute "NO_TEST" "1"
					( Origin gBackEnd )
				)
				( objectStatus "M_C_DQS_DP<0>" )
			)
			( signal "@baseboard_fab2_lib.baseboard_fab2(sch_1):m_c_dqs_dp(1)"
				( pinPairRef "@baseboard_fab2_lib.baseboard_fab2(sch_1):\PP652\" )
				( pinPairRef "@baseboard_fab2_lib.baseboard_fab2(sch_1):\PP653\" )
				( attribute "NO_TEST" "1"
					( Origin gBackEnd )
				)
				( objectStatus "M_C_DQS_DP<1>" )
			)
			( signal "@baseboard_fab2_lib.baseboard_fab2(sch_1):m_c_dqs_dp(2)"
				( pinPairRef "@baseboard_fab2_lib.baseboard_fab2(sch_1):\PP640\" )
				( pinPairRef "@baseboard_fab2_lib.baseboard_fab2(sch_1):\PP641\" )
				( attribute "NO_TEST" "1"
					( Origin gBackEnd )
				)
				( objectStatus "M_C_DQS_DP<2>" )
			)
			( signal "@baseboard_fab2_lib.baseboard_fab2(sch_1):m_c_dqs_dp(3)"
				( pinPairRef "@baseboard_fab2_lib.baseboard_fab2(sch_1):\PP628\" )
				( pinPairRef "@baseboard_fab2_lib.baseboard_fab2(sch_1):\PP629\" )
				( attribute "NO_TEST" "1"
					( Origin gBackEnd )
				)
				( objectStatus "M_C_DQS_DP<3>" )
			)
			( signal "@baseboard_fab2_lib.baseboard_fab2(sch_1):m_c_dqs_dp(4)"
				( pinPairRef "@baseboard_fab2_lib.baseboard_fab2(sch_1):\PP616\" )
				( pinPairRef "@baseboard_fab2_lib.baseboard_fab2(sch_1):\PP618\" )
				( attribute "NO_TEST" "1"
					( Origin gBackEnd )
				)
				( objectStatus "M_C_DQS_DP<4>" )
			)
			( signal "@baseboard_fab2_lib.baseboard_fab2(sch_1):m_c_dqs_dp(5)"
				( pinPairRef "@baseboard_fab2_lib.baseboard_fab2(sch_1):\PP604\" )
				( pinPairRef "@baseboard_fab2_lib.baseboard_fab2(sch_1):\PP606\" )
				( attribute "NO_TEST" "1"
					( Origin gBackEnd )
				)
				( objectStatus "M_C_DQS_DP<5>" )
			)
			( signal "@baseboard_fab2_lib.baseboard_fab2(sch_1):m_c_dqs_dp(6)"
				( pinPairRef "@baseboard_fab2_lib.baseboard_fab2(sch_1):\PP592\" )
				( pinPairRef "@baseboard_fab2_lib.baseboard_fab2(sch_1):\PP594\" )
				( attribute "NO_TEST" "1"
					( Origin gBackEnd )
				)
				( objectStatus "M_C_DQS_DP<6>" )
			)
			( signal "@baseboard_fab2_lib.baseboard_fab2(sch_1):m_c_dqs_dp(7)"
				( pinPairRef "@baseboard_fab2_lib.baseboard_fab2(sch_1):\PP580\" )
				( pinPairRef "@baseboard_fab2_lib.baseboard_fab2(sch_1):\PP582\" )
				( attribute "NO_TEST" "1"
					( Origin gBackEnd )
				)
				( objectStatus "M_C_DQS_DP<7>" )
			)
			( signal "@baseboard_fab2_lib.baseboard_fab2(sch_1):m_c_dqs_dp(8)"
				( pinPairRef "@baseboard_fab2_lib.baseboard_fab2(sch_1):\PP1216\" )
				( pinPairRef "@baseboard_fab2_lib.baseboard_fab2(sch_1):\PP1217\" )
				( attribute "NO_TEST" "1"
					( Origin gBackEnd )
				)
				( objectStatus "M_C_DQS_DP<8>" )
			)
			( signal "@baseboard_fab2_lib.baseboard_fab2(sch_1):m_c_dqs_dp(9)"
				( pinPairRef "@baseboard_fab2_lib.baseboard_fab2(sch_1):\PP658\" )
				( pinPairRef "@baseboard_fab2_lib.baseboard_fab2(sch_1):\PP659\" )
				( attribute "NO_TEST" "1"
					( Origin gBackEnd )
				)
				( objectStatus "M_C_DQS_DP<9>" )
			)
			( signal "@baseboard_fab2_lib.baseboard_fab2(sch_1):m_c_dqs_dp(10)"
				( pinPairRef "@baseboard_fab2_lib.baseboard_fab2(sch_1):\PP646\" )
				( pinPairRef "@baseboard_fab2_lib.baseboard_fab2(sch_1):\PP647\" )
				( attribute "NO_TEST" "1"
					( Origin gBackEnd )
				)
				( objectStatus "M_C_DQS_DP<10>" )
			)
			( signal "@baseboard_fab2_lib.baseboard_fab2(sch_1):m_c_dqs_dp(11)"
				( pinPairRef "@baseboard_fab2_lib.baseboard_fab2(sch_1):\PP634\" )
				( pinPairRef "@baseboard_fab2_lib.baseboard_fab2(sch_1):\PP635\" )
				( attribute "NO_TEST" "1"
					( Origin gBackEnd )
				)
				( objectStatus "M_C_DQS_DP<11>" )
			)
			( signal "@baseboard_fab2_lib.baseboard_fab2(sch_1):m_c_dqs_dp(12)"
				( pinPairRef "@baseboard_fab2_lib.baseboard_fab2(sch_1):\PP622\" )
				( pinPairRef "@baseboard_fab2_lib.baseboard_fab2(sch_1):\PP623\" )
				( attribute "NO_TEST" "1"
					( Origin gBackEnd )
				)
				( objectStatus "M_C_DQS_DP<12>" )
			)
			( signal "@baseboard_fab2_lib.baseboard_fab2(sch_1):m_c_dqs_dp(13)"
				( pinPairRef "@baseboard_fab2_lib.baseboard_fab2(sch_1):\PP610\" )
				( pinPairRef "@baseboard_fab2_lib.baseboard_fab2(sch_1):\PP612\" )
				( attribute "NO_TEST" "1"
					( Origin gBackEnd )
				)
				( objectStatus "M_C_DQS_DP<13>" )
			)
			( signal "@baseboard_fab2_lib.baseboard_fab2(sch_1):m_c_dqs_dp(14)"
				( pinPairRef "@baseboard_fab2_lib.baseboard_fab2(sch_1):\PP598\" )
				( pinPairRef "@baseboard_fab2_lib.baseboard_fab2(sch_1):\PP600\" )
				( attribute "NO_TEST" "1"
					( Origin gBackEnd )
				)
				( objectStatus "M_C_DQS_DP<14>" )
			)
			( signal "@baseboard_fab2_lib.baseboard_fab2(sch_1):m_c_dqs_dp(15)"
				( pinPairRef "@baseboard_fab2_lib.baseboard_fab2(sch_1):\PP586\" )
				( pinPairRef "@baseboard_fab2_lib.baseboard_fab2(sch_1):\PP588\" )
				( objectStatus "M_C_DQS_DP<15>" )
			)
			( signal "@baseboard_fab2_lib.baseboard_fab2(sch_1):m_c_dqs_dp(16)"
				( pinPairRef "@baseboard_fab2_lib.baseboard_fab2(sch_1):\PP574\" )
				( pinPairRef "@baseboard_fab2_lib.baseboard_fab2(sch_1):\PP576\" )
				( attribute "NO_TEST" "1"
					( Origin gBackEnd )
				)
				( objectStatus "M_C_DQS_DP<16>" )
			)
			( signal "@baseboard_fab2_lib.baseboard_fab2(sch_1):m_c_dqs_dp(17)"
				( pinPairRef "@baseboard_fab2_lib.baseboard_fab2(sch_1):\PP1210\" )
				( pinPairRef "@baseboard_fab2_lib.baseboard_fab2(sch_1):\PP1211\" )
				( attribute "NO_TEST" "1"
					( Origin gBackEnd )
				)
				( objectStatus "M_C_DQS_DP<17>" )
			)
			( signal "@baseboard_fab2_lib.baseboard_fab2(sch_1):m_d_dqs_dn(0)"
				( pinPairRef "@baseboard_fab2_lib.baseboard_fab2(sch_1):\PP673\" )
				( pinPairRef "@baseboard_fab2_lib.baseboard_fab2(sch_1):\PP674\" )
				( attribute "NO_TEST" "1"
					( Origin gBackEnd )
				)
				( objectStatus "M_D_DQS_DN<0>" )
			)
			( signal "@baseboard_fab2_lib.baseboard_fab2(sch_1):m_d_dqs_dn(1)"
				( pinPairRef "@baseboard_fab2_lib.baseboard_fab2(sch_1):\PP685\" )
				( pinPairRef "@baseboard_fab2_lib.baseboard_fab2(sch_1):\PP686\" )
				( attribute "NO_TEST" "1"
					( Origin gBackEnd )
				)
				( objectStatus "M_D_DQS_DN<1>" )
			)
			( signal "@baseboard_fab2_lib.baseboard_fab2(sch_1):m_d_dqs_dn(2)"
				( pinPairRef "@baseboard_fab2_lib.baseboard_fab2(sch_1):\PP697\" )
				( pinPairRef "@baseboard_fab2_lib.baseboard_fab2(sch_1):\PP698\" )
				( objectStatus "M_D_DQS_DN<2>" )
			)
			( signal "@baseboard_fab2_lib.baseboard_fab2(sch_1):m_d_dqs_dn(3)"
				( pinPairRef "@baseboard_fab2_lib.baseboard_fab2(sch_1):\PP709\" )
				( pinPairRef "@baseboard_fab2_lib.baseboard_fab2(sch_1):\PP710\" )
				( attribute "NO_TEST" "1"
					( Origin gBackEnd )
				)
				( objectStatus "M_D_DQS_DN<3>" )
			)
			( signal "@baseboard_fab2_lib.baseboard_fab2(sch_1):m_d_dqs_dn(4)"
				( pinPairRef "@baseboard_fab2_lib.baseboard_fab2(sch_1):\PP721\" )
				( pinPairRef "@baseboard_fab2_lib.baseboard_fab2(sch_1):\PP723\" )
				( attribute "NO_TEST" "1"
					( Origin gBackEnd )
				)
				( objectStatus "M_D_DQS_DN<4>" )
			)
			( signal "@baseboard_fab2_lib.baseboard_fab2(sch_1):m_d_dqs_dn(5)"
				( pinPairRef "@baseboard_fab2_lib.baseboard_fab2(sch_1):\PP733\" )
				( pinPairRef "@baseboard_fab2_lib.baseboard_fab2(sch_1):\PP735\" )
				( objectStatus "M_D_DQS_DN<5>" )
			)
			( signal "@baseboard_fab2_lib.baseboard_fab2(sch_1):m_d_dqs_dn(6)"
				( pinPairRef "@baseboard_fab2_lib.baseboard_fab2(sch_1):\PP745\" )
				( pinPairRef "@baseboard_fab2_lib.baseboard_fab2(sch_1):\PP747\" )
				( attribute "NO_TEST" "1"
					( Origin gBackEnd )
				)
				( objectStatus "M_D_DQS_DN<6>" )
			)
			( signal "@baseboard_fab2_lib.baseboard_fab2(sch_1):m_d_dqs_dn(7)"
				( pinPairRef "@baseboard_fab2_lib.baseboard_fab2(sch_1):\PP757\" )
				( pinPairRef "@baseboard_fab2_lib.baseboard_fab2(sch_1):\PP759\" )
				( attribute "NO_TEST" "1"
					( Origin gBackEnd )
				)
				( objectStatus "M_D_DQS_DN<7>" )
			)
			( signal "@baseboard_fab2_lib.baseboard_fab2(sch_1):m_d_dqs_dn(8)"
				( pinPairRef "@baseboard_fab2_lib.baseboard_fab2(sch_1):\PP1201\" )
				( pinPairRef "@baseboard_fab2_lib.baseboard_fab2(sch_1):\PP1202\" )
				( objectStatus "M_D_DQS_DN<8>" )
			)
			( signal "@baseboard_fab2_lib.baseboard_fab2(sch_1):m_d_dqs_dn(9)"
				( pinPairRef "@baseboard_fab2_lib.baseboard_fab2(sch_1):\PP667\" )
				( pinPairRef "@baseboard_fab2_lib.baseboard_fab2(sch_1):\PP668\" )
				( objectStatus "M_D_DQS_DN<9>" )
			)
			( signal "@baseboard_fab2_lib.baseboard_fab2(sch_1):m_d_dqs_dn(10)"
				( pinPairRef "@baseboard_fab2_lib.baseboard_fab2(sch_1):\PP679\" )
				( pinPairRef "@baseboard_fab2_lib.baseboard_fab2(sch_1):\PP680\" )
				( attribute "NO_TEST" "1"
					( Origin gBackEnd )
				)
				( objectStatus "M_D_DQS_DN<10>" )
			)
			( signal "@baseboard_fab2_lib.baseboard_fab2(sch_1):m_d_dqs_dn(11)"
				( pinPairRef "@baseboard_fab2_lib.baseboard_fab2(sch_1):\PP691\" )
				( pinPairRef "@baseboard_fab2_lib.baseboard_fab2(sch_1):\PP692\" )
				( attribute "NO_TEST" "1"
					( Origin gBackEnd )
				)
				( objectStatus "M_D_DQS_DN<11>" )
			)
			( signal "@baseboard_fab2_lib.baseboard_fab2(sch_1):m_d_dqs_dn(12)"
				( pinPairRef "@baseboard_fab2_lib.baseboard_fab2(sch_1):\PP703\" )
				( pinPairRef "@baseboard_fab2_lib.baseboard_fab2(sch_1):\PP704\" )
				( attribute "NO_TEST" "1"
					( Origin gBackEnd )
				)
				( objectStatus "M_D_DQS_DN<12>" )
			)
			( signal "@baseboard_fab2_lib.baseboard_fab2(sch_1):m_d_dqs_dn(13)"
				( pinPairRef "@baseboard_fab2_lib.baseboard_fab2(sch_1):\PP715\" )
				( pinPairRef "@baseboard_fab2_lib.baseboard_fab2(sch_1):\PP717\" )
				( attribute "NO_TEST" "1"
					( Origin gBackEnd )
				)
				( objectStatus "M_D_DQS_DN<13>" )
			)
			( signal "@baseboard_fab2_lib.baseboard_fab2(sch_1):m_d_dqs_dn(14)"
				( pinPairRef "@baseboard_fab2_lib.baseboard_fab2(sch_1):\PP727\" )
				( pinPairRef "@baseboard_fab2_lib.baseboard_fab2(sch_1):\PP729\" )
				( attribute "NO_TEST" "1"
					( Origin gBackEnd )
				)
				( objectStatus "M_D_DQS_DN<14>" )
			)
			( signal "@baseboard_fab2_lib.baseboard_fab2(sch_1):m_d_dqs_dn(15)"
				( pinPairRef "@baseboard_fab2_lib.baseboard_fab2(sch_1):\PP739\" )
				( pinPairRef "@baseboard_fab2_lib.baseboard_fab2(sch_1):\PP741\" )
				( objectStatus "M_D_DQS_DN<15>" )
			)
			( signal "@baseboard_fab2_lib.baseboard_fab2(sch_1):m_d_dqs_dn(16)"
				( pinPairRef "@baseboard_fab2_lib.baseboard_fab2(sch_1):\PP751\" )
				( pinPairRef "@baseboard_fab2_lib.baseboard_fab2(sch_1):\PP753\" )
				( objectStatus "M_D_DQS_DN<16>" )
			)
			( signal "@baseboard_fab2_lib.baseboard_fab2(sch_1):m_d_dqs_dn(17)"
				( pinPairRef "@baseboard_fab2_lib.baseboard_fab2(sch_1):\PP1195\" )
				( pinPairRef "@baseboard_fab2_lib.baseboard_fab2(sch_1):\PP1196\" )
				( attribute "NO_TEST" "1"
					( Origin gBackEnd )
				)
				( objectStatus "M_D_DQS_DN<17>" )
			)
			( signal "@baseboard_fab2_lib.baseboard_fab2(sch_1):m_d_dqs_dp(0)"
				( pinPairRef "@baseboard_fab2_lib.baseboard_fab2(sch_1):\PP676\" )
				( pinPairRef "@baseboard_fab2_lib.baseboard_fab2(sch_1):\PP677\" )
				( objectStatus "M_D_DQS_DP<0>" )
			)
			( signal "@baseboard_fab2_lib.baseboard_fab2(sch_1):m_d_dqs_dp(1)"
				( pinPairRef "@baseboard_fab2_lib.baseboard_fab2(sch_1):\PP688\" )
				( pinPairRef "@baseboard_fab2_lib.baseboard_fab2(sch_1):\PP689\" )
				( attribute "NO_TEST" "1"
					( Origin gBackEnd )
				)
				( objectStatus "M_D_DQS_DP<1>" )
			)
			( signal "@baseboard_fab2_lib.baseboard_fab2(sch_1):m_d_dqs_dp(2)"
				( pinPairRef "@baseboard_fab2_lib.baseboard_fab2(sch_1):\PP700\" )
				( pinPairRef "@baseboard_fab2_lib.baseboard_fab2(sch_1):\PP701\" )
				( attribute "NO_TEST" "1"
					( Origin gBackEnd )
				)
				( objectStatus "M_D_DQS_DP<2>" )
			)
			( signal "@baseboard_fab2_lib.baseboard_fab2(sch_1):m_d_dqs_dp(3)"
				( pinPairRef "@baseboard_fab2_lib.baseboard_fab2(sch_1):\PP712\" )
				( pinPairRef "@baseboard_fab2_lib.baseboard_fab2(sch_1):\PP713\" )
				( attribute "NO_TEST" "1"
					( Origin gBackEnd )
				)
				( objectStatus "M_D_DQS_DP<3>" )
			)
			( signal "@baseboard_fab2_lib.baseboard_fab2(sch_1):m_d_dqs_dp(4)"
				( pinPairRef "@baseboard_fab2_lib.baseboard_fab2(sch_1):\PP724\" )
				( pinPairRef "@baseboard_fab2_lib.baseboard_fab2(sch_1):\PP726\" )
				( attribute "NO_TEST" "1"
					( Origin gBackEnd )
				)
				( objectStatus "M_D_DQS_DP<4>" )
			)
			( signal "@baseboard_fab2_lib.baseboard_fab2(sch_1):m_d_dqs_dp(5)"
				( pinPairRef "@baseboard_fab2_lib.baseboard_fab2(sch_1):\PP736\" )
				( pinPairRef "@baseboard_fab2_lib.baseboard_fab2(sch_1):\PP738\" )
				( attribute "NO_TEST" "1"
					( Origin gBackEnd )
				)
				( objectStatus "M_D_DQS_DP<5>" )
			)
			( signal "@baseboard_fab2_lib.baseboard_fab2(sch_1):m_d_dqs_dp(6)"
				( pinPairRef "@baseboard_fab2_lib.baseboard_fab2(sch_1):\PP748\" )
				( pinPairRef "@baseboard_fab2_lib.baseboard_fab2(sch_1):\PP750\" )
				( attribute "NO_TEST" "1"
					( Origin gBackEnd )
				)
				( objectStatus "M_D_DQS_DP<6>" )
			)
			( signal "@baseboard_fab2_lib.baseboard_fab2(sch_1):m_d_dqs_dp(7)"
				( pinPairRef "@baseboard_fab2_lib.baseboard_fab2(sch_1):\PP760\" )
				( pinPairRef "@baseboard_fab2_lib.baseboard_fab2(sch_1):\PP762\" )
				( objectStatus "M_D_DQS_DP<7>" )
			)
			( signal "@baseboard_fab2_lib.baseboard_fab2(sch_1):m_a_dqs_dn(0)"
				( pinPairRef "@baseboard_fab2_lib.baseboard_fab2(sch_1):\PP469\" )
				( pinPairRef "@baseboard_fab2_lib.baseboard_fab2(sch_1):\PP471\" )
				( attribute "NO_TEST" "1"
					( Origin gBackEnd )
				)
				( objectStatus "M_A_DQS_DN<0>" )
			)
			( signal "@baseboard_fab2_lib.baseboard_fab2(sch_1):m_a_dqs_dn(1)"
				( pinPairRef "@baseboard_fab2_lib.baseboard_fab2(sch_1):\PP457\" )
				( pinPairRef "@baseboard_fab2_lib.baseboard_fab2(sch_1):\PP459\" )
				( attribute "NO_TEST" "1"
					( Origin gBackEnd )
				)
				( objectStatus "M_A_DQS_DN<1>" )
			)
			( signal "@baseboard_fab2_lib.baseboard_fab2(sch_1):m_a_dqs_dn(2)"
				( pinPairRef "@baseboard_fab2_lib.baseboard_fab2(sch_1):\PP445\" )
				( pinPairRef "@baseboard_fab2_lib.baseboard_fab2(sch_1):\PP447\" )
				( attribute "NO_TEST" "1"
					( Origin gBackEnd )
				)
				( objectStatus "M_A_DQS_DN<2>" )
			)
			( signal "@baseboard_fab2_lib.baseboard_fab2(sch_1):m_a_dqs_dn(3)"
				( pinPairRef "@baseboard_fab2_lib.baseboard_fab2(sch_1):\PP433\" )
				( pinPairRef "@baseboard_fab2_lib.baseboard_fab2(sch_1):\PP435\" )
				( attribute "NO_TEST" "1"
					( Origin gBackEnd )
				)
				( objectStatus "M_A_DQS_DN<3>" )
			)
			( signal "@baseboard_fab2_lib.baseboard_fab2(sch_1):m_a_dqs_dn(4)"
				( pinPairRef "@baseboard_fab2_lib.baseboard_fab2(sch_1):\PP421\" )
				( pinPairRef "@baseboard_fab2_lib.baseboard_fab2(sch_1):\PP423\" )
				( objectStatus "M_A_DQS_DN<4>" )
			)
			( signal "@baseboard_fab2_lib.baseboard_fab2(sch_1):m_a_dqs_dn(5)"
				( pinPairRef "@baseboard_fab2_lib.baseboard_fab2(sch_1):\PP409\" )
				( pinPairRef "@baseboard_fab2_lib.baseboard_fab2(sch_1):\PP411\" )
				( objectStatus "M_A_DQS_DN<5>" )
			)
			( signal "@baseboard_fab2_lib.baseboard_fab2(sch_1):m_a_dqs_dn(6)"
				( pinPairRef "@baseboard_fab2_lib.baseboard_fab2(sch_1):\PP397\" )
				( pinPairRef "@baseboard_fab2_lib.baseboard_fab2(sch_1):\PP399\" )
				( objectStatus "M_A_DQS_DN<6>" )
			)
			( signal "@baseboard_fab2_lib.baseboard_fab2(sch_1):m_a_dqs_dn(7)"
				( electricalCSetRef "@crescent_city_bb_fab1_lib.crescent_city_bb_fab1(sch_1):\DDR_DQS_A\" )
				( pinPairRef "@baseboard_fab2_lib.baseboard_fab2(sch_1):\PP5187\" )
				( pinPairRef "@baseboard_fab2_lib.baseboard_fab2(sch_1):\PP5189\" )
				( attribute "NO_TEST" "1"
					( Origin gBackEnd )
				)
				( objectStatus "M_A_DQS_DN<7>" )
			)
			( signal "@baseboard_fab2_lib.baseboard_fab2(sch_1):m_a_dqs_dn(8)"
				( pinPairRef "@baseboard_fab2_lib.baseboard_fab2(sch_1):\PP1237\" )
				( pinPairRef "@baseboard_fab2_lib.baseboard_fab2(sch_1):\PP1239\" )
				( attribute "NO_TEST" "1"
					( Origin gBackEnd )
				)
				( objectStatus "M_A_DQS_DN<8>" )
			)
			( signal "@baseboard_fab2_lib.baseboard_fab2(sch_1):m_a_dqs_dn(9)"
				( pinPairRef "@baseboard_fab2_lib.baseboard_fab2(sch_1):\PP463\" )
				( pinPairRef "@baseboard_fab2_lib.baseboard_fab2(sch_1):\PP465\" )
				( objectStatus "M_A_DQS_DN<9>" )
			)
			( signal "@baseboard_fab2_lib.baseboard_fab2(sch_1):m_a_dqs_dn(10)"
				( pinPairRef "@baseboard_fab2_lib.baseboard_fab2(sch_1):\PP451\" )
				( pinPairRef "@baseboard_fab2_lib.baseboard_fab2(sch_1):\PP453\" )
				( attribute "NO_TEST" "1"
					( Origin gBackEnd )
				)
				( objectStatus "M_A_DQS_DN<10>" )
			)
			( signal "@baseboard_fab2_lib.baseboard_fab2(sch_1):m_a_dqs_dn(11)"
				( pinPairRef "@baseboard_fab2_lib.baseboard_fab2(sch_1):\PP439\" )
				( pinPairRef "@baseboard_fab2_lib.baseboard_fab2(sch_1):\PP441\" )
				( attribute "NO_TEST" "1"
					( Origin gBackEnd )
				)
				( objectStatus "M_A_DQS_DN<11>" )
			)
			( signal "@baseboard_fab2_lib.baseboard_fab2(sch_1):m_a_dqs_dn(12)"
				( pinPairRef "@baseboard_fab2_lib.baseboard_fab2(sch_1):\PP427\" )
				( pinPairRef "@baseboard_fab2_lib.baseboard_fab2(sch_1):\PP429\" )
				( objectStatus "M_A_DQS_DN<12>" )
			)
			( signal "@baseboard_fab2_lib.baseboard_fab2(sch_1):m_a_dqs_dn(13)"
				( pinPairRef "@baseboard_fab2_lib.baseboard_fab2(sch_1):\PP415\" )
				( pinPairRef "@baseboard_fab2_lib.baseboard_fab2(sch_1):\PP417\" )
				( attribute "NO_TEST" "1"
					( Origin gBackEnd )
				)
				( objectStatus "M_A_DQS_DN<13>" )
			)
			( signal "@baseboard_fab2_lib.baseboard_fab2(sch_1):m_a_dqs_dn(14)"
				( pinPairRef "@baseboard_fab2_lib.baseboard_fab2(sch_1):\PP403\" )
				( pinPairRef "@baseboard_fab2_lib.baseboard_fab2(sch_1):\PP405\" )
				( attribute "NO_TEST" "1"
					( Origin gBackEnd )
				)
				( objectStatus "M_A_DQS_DN<14>" )
			)
			( signal "@baseboard_fab2_lib.baseboard_fab2(sch_1):m_a_dqs_dn(15)"
				( pinPairRef "@baseboard_fab2_lib.baseboard_fab2(sch_1):\PP391\" )
				( pinPairRef "@baseboard_fab2_lib.baseboard_fab2(sch_1):\PP393\" )
				( attribute "NO_TEST" "1"
					( Origin gBackEnd )
				)
				( objectStatus "M_A_DQS_DN<15>" )
			)
			( signal "@baseboard_fab2_lib.baseboard_fab2(sch_1):m_a_dqs_dn(16)"
				( electricalCSetRef "@crescent_city_bb_fab1_lib.crescent_city_bb_fab1(sch_1):\DDR_DQS_A\" )
				( pinPairRef "@baseboard_fab2_lib.baseboard_fab2(sch_1):\PP5193\" )
				( pinPairRef "@baseboard_fab2_lib.baseboard_fab2(sch_1):\PP5195\" )
				( attribute "NO_TEST" "1"
					( Origin gBackEnd )
				)
				( objectStatus "M_A_DQS_DN<16>" )
			)
			( signal "@baseboard_fab2_lib.baseboard_fab2(sch_1):m_a_dqs_dn(17)"
				( pinPairRef "@baseboard_fab2_lib.baseboard_fab2(sch_1):\PP1231\" )
				( pinPairRef "@baseboard_fab2_lib.baseboard_fab2(sch_1):\PP1233\" )
				( objectStatus "M_A_DQS_DN<17>" )
			)
			( signal "@baseboard_fab2_lib.baseboard_fab2(sch_1):m_a_dqs_dp(0)"
				( pinPairRef "@baseboard_fab2_lib.baseboard_fab2(sch_1):\PP472\" )
				( pinPairRef "@baseboard_fab2_lib.baseboard_fab2(sch_1):\PP474\" )
				( objectStatus "M_A_DQS_DP<0>" )
			)
			( signal "@baseboard_fab2_lib.baseboard_fab2(sch_1):m_a_dqs_dp(1)"
				( pinPairRef "@baseboard_fab2_lib.baseboard_fab2(sch_1):\PP460\" )
				( pinPairRef "@baseboard_fab2_lib.baseboard_fab2(sch_1):\PP462\" )
				( attribute "NO_TEST" "1"
					( Origin gBackEnd )
				)
				( objectStatus "M_A_DQS_DP<1>" )
			)
			( signal "@baseboard_fab2_lib.baseboard_fab2(sch_1):m_a_dqs_dp(2)"
				( pinPairRef "@baseboard_fab2_lib.baseboard_fab2(sch_1):\PP448\" )
				( pinPairRef "@baseboard_fab2_lib.baseboard_fab2(sch_1):\PP450\" )
				( objectStatus "M_A_DQS_DP<2>" )
			)
			( signal "@baseboard_fab2_lib.baseboard_fab2(sch_1):m_a_dqs_dp(3)"
				( pinPairRef "@baseboard_fab2_lib.baseboard_fab2(sch_1):\PP436\" )
				( pinPairRef "@baseboard_fab2_lib.baseboard_fab2(sch_1):\PP438\" )
				( attribute "NO_TEST" "1"
					( Origin gBackEnd )
				)
				( objectStatus "M_A_DQS_DP<3>" )
			)
			( signal "@baseboard_fab2_lib.baseboard_fab2(sch_1):m_a_dqs_dp(4)"
				( pinPairRef "@baseboard_fab2_lib.baseboard_fab2(sch_1):\PP424\" )
				( pinPairRef "@baseboard_fab2_lib.baseboard_fab2(sch_1):\PP426\" )
				( objectStatus "M_A_DQS_DP<4>" )
			)
			( signal "@baseboard_fab2_lib.baseboard_fab2(sch_1):m_a_dqs_dp(5)"
				( electricalCSetRef "@crescent_city_bb_fab1_lib.crescent_city_bb_fab1(sch_1):\DDR_DQS_A\" )
				( pinPairRef "@baseboard_fab2_lib.baseboard_fab2(sch_1):\PP412\" )
				( pinPairRef "@baseboard_fab2_lib.baseboard_fab2(sch_1):\PP414\" )
				( attribute "NO_TEST" "1"
					( Origin gBackEnd )
				)
				( objectStatus "M_A_DQS_DP<5>" )
			)
			( signal "@baseboard_fab2_lib.baseboard_fab2(sch_1):m_a_dqs_dp(6)"
				( pinPairRef "@baseboard_fab2_lib.baseboard_fab2(sch_1):\PP400\" )
				( pinPairRef "@baseboard_fab2_lib.baseboard_fab2(sch_1):\PP402\" )
				( attribute "NO_TEST" "1"
					( Origin gBackEnd )
				)
				( objectStatus "M_A_DQS_DP<6>" )
			)
			( signal "@baseboard_fab2_lib.baseboard_fab2(sch_1):m_a_dqs_dp(7)"
				( electricalCSetRef "@crescent_city_bb_fab1_lib.crescent_city_bb_fab1(sch_1):\DDR_DQS_A\" )
				( pinPairRef "@baseboard_fab2_lib.baseboard_fab2(sch_1):\PP5190\" )
				( pinPairRef "@baseboard_fab2_lib.baseboard_fab2(sch_1):\PP5192\" )
				( objectStatus "M_A_DQS_DP<7>" )
			)
			( signal "@baseboard_fab2_lib.baseboard_fab2(sch_1):m_a_dqs_dp(8)"
				( pinPairRef "@baseboard_fab2_lib.baseboard_fab2(sch_1):\PP1240\" )
				( pinPairRef "@baseboard_fab2_lib.baseboard_fab2(sch_1):\PP1242\" )
				( attribute "NO_TEST" "1"
					( Origin gBackEnd )
				)
				( objectStatus "M_A_DQS_DP<8>" )
			)
			( signal "@baseboard_fab2_lib.baseboard_fab2(sch_1):m_a_dqs_dp(9)"
				( pinPairRef "@baseboard_fab2_lib.baseboard_fab2(sch_1):\PP466\" )
				( pinPairRef "@baseboard_fab2_lib.baseboard_fab2(sch_1):\PP468\" )
				( attribute "NO_TEST" "1"
					( Origin gBackEnd )
				)
				( objectStatus "M_A_DQS_DP<9>" )
			)
			( signal "@baseboard_fab2_lib.baseboard_fab2(sch_1):m_a_dqs_dp(10)"
				( pinPairRef "@baseboard_fab2_lib.baseboard_fab2(sch_1):\PP454\" )
				( pinPairRef "@baseboard_fab2_lib.baseboard_fab2(sch_1):\PP456\" )
				( attribute "NO_TEST" "1"
					( Origin gBackEnd )
				)
				( objectStatus "M_A_DQS_DP<10>" )
			)
			( signal "@baseboard_fab2_lib.baseboard_fab2(sch_1):m_a_dqs_dp(11)"
				( pinPairRef "@baseboard_fab2_lib.baseboard_fab2(sch_1):\PP442\" )
				( pinPairRef "@baseboard_fab2_lib.baseboard_fab2(sch_1):\PP444\" )
				( attribute "NO_TEST" "1"
					( Origin gBackEnd )
				)
				( objectStatus "M_A_DQS_DP<11>" )
			)
			( signal "@baseboard_fab2_lib.baseboard_fab2(sch_1):m_a_dqs_dp(12)"
				( pinPairRef "@baseboard_fab2_lib.baseboard_fab2(sch_1):\PP430\" )
				( pinPairRef "@baseboard_fab2_lib.baseboard_fab2(sch_1):\PP432\" )
				( attribute "NO_TEST" "1"
					( Origin gBackEnd )
				)
				( objectStatus "M_A_DQS_DP<12>" )
			)
			( signal "@baseboard_fab2_lib.baseboard_fab2(sch_1):m_a_dqs_dp(13)"
				( pinPairRef "@baseboard_fab2_lib.baseboard_fab2(sch_1):\PP418\" )
				( pinPairRef "@baseboard_fab2_lib.baseboard_fab2(sch_1):\PP420\" )
				( objectStatus "M_A_DQS_DP<13>" )
			)
			( signal "@baseboard_fab2_lib.baseboard_fab2(sch_1):m_a_dqs_dp(14)"
				( pinPairRef "@baseboard_fab2_lib.baseboard_fab2(sch_1):\PP406\" )
				( pinPairRef "@baseboard_fab2_lib.baseboard_fab2(sch_1):\PP408\" )
				( attribute "NO_TEST" "1"
					( Origin gBackEnd )
				)
				( objectStatus "M_A_DQS_DP<14>" )
			)
			( signal "@baseboard_fab2_lib.baseboard_fab2(sch_1):m_a_dqs_dp(15)"
				( pinPairRef "@baseboard_fab2_lib.baseboard_fab2(sch_1):\PP394\" )
				( pinPairRef "@baseboard_fab2_lib.baseboard_fab2(sch_1):\PP396\" )
				( attribute "NO_TEST" "1"
					( Origin gBackEnd )
				)
				( objectStatus "M_A_DQS_DP<15>" )
			)
			( signal "@baseboard_fab2_lib.baseboard_fab2(sch_1):m_a_dqs_dp(16)"
				( electricalCSetRef "@crescent_city_bb_fab1_lib.crescent_city_bb_fab1(sch_1):\DDR_DQS_A\" )
				( pinPairRef "@baseboard_fab2_lib.baseboard_fab2(sch_1):\PP5196\" )
				( pinPairRef "@baseboard_fab2_lib.baseboard_fab2(sch_1):\PP5198\" )
				( attribute "NO_TEST" "1"
					( Origin gBackEnd )
				)
				( objectStatus "M_A_DQS_DP<16>" )
			)
			( signal "@baseboard_fab2_lib.baseboard_fab2(sch_1):m_a_dqs_dp(17)"
				( pinPairRef "@baseboard_fab2_lib.baseboard_fab2(sch_1):\PP1234\" )
				( pinPairRef "@baseboard_fab2_lib.baseboard_fab2(sch_1):\PP1236\" )
				( attribute "NO_TEST" "1"
					( Origin gBackEnd )
				)
				( objectStatus "M_A_DQS_DP<17>" )
			)
			( signal "@baseboard_fab2_lib.baseboard_fab2(sch_1):m_b_dqs_dn(0)"
				( pinPairRef "@baseboard_fab2_lib.baseboard_fab2(sch_1):\PP565\" )
				( pinPairRef "@baseboard_fab2_lib.baseboard_fab2(sch_1):\PP566\" )
				( objectStatus "M_B_DQS_DN<0>" )
			)
			( signal "@baseboard_fab2_lib.baseboard_fab2(sch_1):m_b_dqs_dn(1)"
				( pinPairRef "@baseboard_fab2_lib.baseboard_fab2(sch_1):\PP553\" )
				( pinPairRef "@baseboard_fab2_lib.baseboard_fab2(sch_1):\PP554\" )
				( attribute "NO_TEST" "1"
					( Origin gBackEnd )
				)
				( objectStatus "M_B_DQS_DN<1>" )
			)
			( signal "@baseboard_fab2_lib.baseboard_fab2(sch_1):m_b_dqs_dn(2)"
				( pinPairRef "@baseboard_fab2_lib.baseboard_fab2(sch_1):\PP541\" )
				( pinPairRef "@baseboard_fab2_lib.baseboard_fab2(sch_1):\PP542\" )
				( attribute "NO_TEST" "1"
					( Origin gBackEnd )
				)
				( objectStatus "M_B_DQS_DN<2>" )
			)
			( signal "@baseboard_fab2_lib.baseboard_fab2(sch_1):m_b_dqs_dn(3)"
				( pinPairRef "@baseboard_fab2_lib.baseboard_fab2(sch_1):\PP529\" )
				( pinPairRef "@baseboard_fab2_lib.baseboard_fab2(sch_1):\PP530\" )
				( objectStatus "M_B_DQS_DN<3>" )
			)
			( signal "@baseboard_fab2_lib.baseboard_fab2(sch_1):m_b_dqs_dn(4)"
				( pinPairRef "@baseboard_fab2_lib.baseboard_fab2(sch_1):\PP517\" )
				( pinPairRef "@baseboard_fab2_lib.baseboard_fab2(sch_1):\PP519\" )
				( attribute "NO_TEST" "1"
					( Origin gBackEnd )
				)
				( objectStatus "M_B_DQS_DN<4>" )
			)
			( signal "@baseboard_fab2_lib.baseboard_fab2(sch_1):m_b_dqs_dn(5)"
				( pinPairRef "@baseboard_fab2_lib.baseboard_fab2(sch_1):\PP505\" )
				( pinPairRef "@baseboard_fab2_lib.baseboard_fab2(sch_1):\PP506\" )
				( attribute "NO_TEST" "1"
					( Origin gBackEnd )
				)
				( objectStatus "M_B_DQS_DN<5>" )
			)
			( signal "@baseboard_fab2_lib.baseboard_fab2(sch_1):m_b_dqs_dn(6)"
				( pinPairRef "@baseboard_fab2_lib.baseboard_fab2(sch_1):\PP493\" )
				( pinPairRef "@baseboard_fab2_lib.baseboard_fab2(sch_1):\PP494\" )
				( objectStatus "M_B_DQS_DN<6>" )
			)
			( signal "@baseboard_fab2_lib.baseboard_fab2(sch_1):m_b_dqs_dn(7)"
				( pinPairRef "@baseboard_fab2_lib.baseboard_fab2(sch_1):\PP481\" )
				( pinPairRef "@baseboard_fab2_lib.baseboard_fab2(sch_1):\PP483\" )
				( attribute "NO_TEST" "1"
					( Origin gBackEnd )
				)
				( objectStatus "M_B_DQS_DN<7>" )
			)
			( signal "@baseboard_fab2_lib.baseboard_fab2(sch_1):m_b_dqs_dn(8)"
				( pinPairRef "@baseboard_fab2_lib.baseboard_fab2(sch_1):\PP1225\" )
				( pinPairRef "@baseboard_fab2_lib.baseboard_fab2(sch_1):\PP1226\" )
				( objectStatus "M_B_DQS_DN<8>" )
			)
			( signal "@baseboard_fab2_lib.baseboard_fab2(sch_1):m_b_dqs_dn(9)"
				( pinPairRef "@baseboard_fab2_lib.baseboard_fab2(sch_1):\PP559\" )
				( pinPairRef "@baseboard_fab2_lib.baseboard_fab2(sch_1):\PP560\" )
				( attribute "NO_TEST" "1"
					( Origin gBackEnd )
				)
				( objectStatus "M_B_DQS_DN<9>" )
			)
			( signal "@baseboard_fab2_lib.baseboard_fab2(sch_1):m_b_dqs_dn(10)"
				( pinPairRef "@baseboard_fab2_lib.baseboard_fab2(sch_1):\PP547\" )
				( pinPairRef "@baseboard_fab2_lib.baseboard_fab2(sch_1):\PP548\" )
				( objectStatus "M_B_DQS_DN<10>" )
			)
			( signal "@baseboard_fab2_lib.baseboard_fab2(sch_1):m_b_dqs_dn(11)"
				( pinPairRef "@baseboard_fab2_lib.baseboard_fab2(sch_1):\PP535\" )
				( pinPairRef "@baseboard_fab2_lib.baseboard_fab2(sch_1):\PP536\" )
				( objectStatus "M_B_DQS_DN<11>" )
			)
			( signal "@baseboard_fab2_lib.baseboard_fab2(sch_1):m_b_dqs_dn(12)"
				( pinPairRef "@baseboard_fab2_lib.baseboard_fab2(sch_1):\PP523\" )
				( pinPairRef "@baseboard_fab2_lib.baseboard_fab2(sch_1):\PP524\" )
				( objectStatus "M_B_DQS_DN<12>" )
			)
			( signal "@baseboard_fab2_lib.baseboard_fab2(sch_1):m_b_dqs_dn(13)"
				( pinPairRef "@baseboard_fab2_lib.baseboard_fab2(sch_1):\PP511\" )
				( pinPairRef "@baseboard_fab2_lib.baseboard_fab2(sch_1):\PP513\" )
				( attribute "NO_TEST" "1"
					( Origin gBackEnd )
				)
				( objectStatus "M_B_DQS_DN<13>" )
			)
			( signal "@baseboard_fab2_lib.baseboard_fab2(sch_1):m_b_dqs_dn(14)"
				( pinPairRef "@baseboard_fab2_lib.baseboard_fab2(sch_1):\PP499\" )
				( pinPairRef "@baseboard_fab2_lib.baseboard_fab2(sch_1):\PP500\" )
				( attribute "NO_TEST" "1"
					( Origin gBackEnd )
				)
				( objectStatus "M_B_DQS_DN<14>" )
			)
			( signal "@baseboard_fab2_lib.baseboard_fab2(sch_1):m_b_dqs_dn(15)"
				( pinPairRef "@baseboard_fab2_lib.baseboard_fab2(sch_1):\PP487\" )
				( pinPairRef "@baseboard_fab2_lib.baseboard_fab2(sch_1):\PP488\" )
				( objectStatus "M_B_DQS_DN<15>" )
			)
			( signal "@baseboard_fab2_lib.baseboard_fab2(sch_1):fm_cpu_err0_lvt3_bmc_n"
				( objectStatus "FM_CPU_ERR0_LVT3_BMC_N" )
			)
			( signal "@baseboard_fab2_lib.baseboard_fab2(sch_1):fm_cpu0_rc_error_n"
				( objectStatus "FM_CPU0_RC_ERROR_N" )
			)
			( signal "@baseboard_fab2_lib.baseboard_fab2(sch_1):fm_cpu1_rc_error_n"
				( objectStatus "FM_CPU1_RC_ERROR_N" )
			)
			( signal "@baseboard_fab2_lib.baseboard_fab2(sch_1):tp_pvccin_cpu0_ph1_gl_1"
				( objectStatus "TP_PVCCIN_CPU0_PH1_GL_1" )
			)
			( signal "@baseboard_fab2_lib.baseboard_fab2(sch_1):tp_pvccin_cpu0_ph1_gl_0"
				( objectStatus "TP_PVCCIN_CPU0_PH1_GL_0" )
			)
			( signal "@baseboard_fab2_lib.baseboard_fab2(sch_1):tp_ext_mdio_i2c_sel"
				( objectStatus "TP_EXT_MDIO_I2C_SEL" )
			)
			( signal "@baseboard_fab2_lib.baseboard_fab2(sch_1):jtag_mcp_cpu0_tdi"
				( objectStatus "JTAG_MCP_CPU0_TDI" )
			)
			( signal "@baseboard_fab2_lib.baseboard_fab2(sch_1):fm_cpu0_stl_brd_osc_en"
				( objectStatus "FM_CPU0_STL_BRD_OSC_EN" )
			)
			( signal "@baseboard_fab2_lib.baseboard_fab2(sch_1):tp_usb3_p02_rxn"
				( objectStatus "TP_USB3_P02_RXN" )
			)
			( signal "@baseboard_fab2_lib.baseboard_fab2(sch_1):tp_usb3_p02_rxp"
				( objectStatus "TP_USB3_P02_RXP" )
			)
			( signal "@baseboard_fab2_lib.baseboard_fab2(sch_1):tp_usb3_p02_txn"
				( objectStatus "TP_USB3_P02_TXN" )
			)
			( signal "@baseboard_fab2_lib.baseboard_fab2(sch_1):tp_usb3_p02_txp"
				( objectStatus "TP_USB3_P02_TXP" )
			)
			( signal "@baseboard_fab2_lib.baseboard_fab2(sch_1):tp_usb3_p03_rxn"
				( objectStatus "TP_USB3_P03_RXN" )
			)
			( signal "@baseboard_fab2_lib.baseboard_fab2(sch_1):tp_usb3_p03_rxp"
				( objectStatus "TP_USB3_P03_RXP" )
			)
			( signal "@baseboard_fab2_lib.baseboard_fab2(sch_1):tp_usb3_p03_txn"
				( objectStatus "TP_USB3_P03_TXN" )
			)
			( signal "@baseboard_fab2_lib.baseboard_fab2(sch_1):tp_usb3_p03_txp"
				( objectStatus "TP_USB3_P03_TXP" )
			)
			( signal "@baseboard_fab2_lib.baseboard_fab2(sch_1):tp_xdp_cpu_obsdata_c0"
				( objectStatus "TP_XDP_CPU_OBSDATA_C0" )
			)
			( signal "@baseboard_fab2_lib.baseboard_fab2(sch_1):tp_xdp_cpu_obsdata_c1"
				( objectStatus "TP_XDP_CPU_OBSDATA_C1" )
			)
			( signal "@baseboard_fab2_lib.baseboard_fab2(sch_1):tp_xdp_cpu_obsdata_c2"
				( objectStatus "TP_XDP_CPU_OBSDATA_C2" )
			)
			( signal "@baseboard_fab2_lib.baseboard_fab2(sch_1):tp_xdp_cpu_obsdata_c3"
				( objectStatus "TP_XDP_CPU_OBSDATA_C3" )
			)
			( signal "@baseboard_fab2_lib.baseboard_fab2(sch_1):tp_xdp_cpu_obsdata_d0"
				( objectStatus "TP_XDP_CPU_OBSDATA_D0" )
			)
			( signal "@baseboard_fab2_lib.baseboard_fab2(sch_1):tp_xdp_cpu_obsdata_d1"
				( objectStatus "TP_XDP_CPU_OBSDATA_D1" )
			)
			( signal "@baseboard_fab2_lib.baseboard_fab2(sch_1):tp_xdp_cpu_obsdata_d2"
				( objectStatus "TP_XDP_CPU_OBSDATA_D2" )
			)
			( signal "@baseboard_fab2_lib.baseboard_fab2(sch_1):tp_xdp_cpu_obsdata_d3"
				( objectStatus "TP_XDP_CPU_OBSDATA_D3" )
			)
			( signal "@baseboard_fab2_lib.baseboard_fab2(sch_1):tp_xdp_obsdata_a0"
				( objectStatus "TP_XDP_OBSDATA_A0" )
			)
			( signal "@baseboard_fab2_lib.baseboard_fab2(sch_1):tp_xdp_obsdata_a1"
				( objectStatus "TP_XDP_OBSDATA_A1" )
			)
			( signal "@baseboard_fab2_lib.baseboard_fab2(sch_1):tp_xdp_obsdata_a2"
				( objectStatus "TP_XDP_OBSDATA_A2" )
			)
			( signal "@baseboard_fab2_lib.baseboard_fab2(sch_1):tp_xdp_obsdata_a3"
				( objectStatus "TP_XDP_OBSDATA_A3" )
			)
			( signal "@baseboard_fab2_lib.baseboard_fab2(sch_1):tp_xdp_obsdata_b0"
				( objectStatus "TP_XDP_OBSDATA_B0" )
			)
			( signal "@baseboard_fab2_lib.baseboard_fab2(sch_1):tp_xdp_obsdata_b1"
				( objectStatus "TP_XDP_OBSDATA_B1" )
			)
			( signal "@baseboard_fab2_lib.baseboard_fab2(sch_1):tp_xdp_obsdata_b2"
				( objectStatus "TP_XDP_OBSDATA_B2" )
			)
			( signal "@baseboard_fab2_lib.baseboard_fab2(sch_1):tp_xdp_obsdata_b3"
				( objectStatus "TP_XDP_OBSDATA_B3" )
			)
			( signal "@baseboard_fab2_lib.baseboard_fab2(sch_1):tp_xdp_obsfn_b0"
				( objectStatus "TP_XDP_OBSFN_B0" )
			)
			( signal "@baseboard_fab2_lib.baseboard_fab2(sch_1):tp_xdp_obsfn_b1"
				( objectStatus "TP_XDP_OBSFN_B1" )
			)
			( signal "@baseboard_fab2_lib.baseboard_fab2(sch_1):tp_cpld1_pr11b"
				( objectStatus "TP_CPLD1_PR11B" )
			)
			( signal "@baseboard_fab2_lib.baseboard_fab2(sch_1):tp_bmc_disable"
				( objectStatus "TP_BMC_DISABLE" )
			)
			( signal "@baseboard_fab2_lib.baseboard_fab2(sch_1):tp_slg55021_p3v3_8"
				( objectStatus "TP_SLG55021_P3V3_8" )
			)
			( signal "@baseboard_fab2_lib.baseboard_fab2(sch_1):tp_slg55021_p5v_8"
				( objectStatus "TP_SLG55021_P5V_8" )
			)
			( signal "@baseboard_fab2_lib.baseboard_fab2(sch_1):tp_slg55021_p12v_fan_8"
				( objectStatus "TP_SLG55021_P12V_FAN_8" )
			)
			( signal "@baseboard_fab2_lib.baseboard_fab2(sch_1):tp_pvddq_abc_ph2_gl_1"
				( objectStatus "TP_PVDDQ_ABC_PH2_GL_1" )
			)
			( signal "@baseboard_fab2_lib.baseboard_fab2(sch_1):tp_pvccin_cpu0_ph2_gl_1"
				( objectStatus "TP_PVCCIN_CPU0_PH2_GL_1" )
			)
			( signal "@baseboard_fab2_lib.baseboard_fab2(sch_1):tp_pvddq_def_ph1_gl_1"
				( objectStatus "TP_PVDDQ_DEF_PH1_GL_1" )
			)
			( signal "@baseboard_fab2_lib.baseboard_fab2(sch_1):tp_pvccin_cpu0_ph3_gl_1"
				( objectStatus "TP_PVCCIN_CPU0_PH3_GL_1" )
			)
			( signal "@baseboard_fab2_lib.baseboard_fab2(sch_1):tp_pvddq_def_ph2_gl_1"
				( objectStatus "TP_PVDDQ_DEF_PH2_GL_1" )
			)
			( signal "@baseboard_fab2_lib.baseboard_fab2(sch_1):tp_pvccin_cpu0_ph4_gl_1"
				( objectStatus "TP_PVCCIN_CPU0_PH4_GL_1" )
			)
			( signal "@baseboard_fab2_lib.baseboard_fab2(sch_1):tp_pvddq_ghj_ph1_gl_1"
				( objectStatus "TP_PVDDQ_GHJ_PH1_GL_1" )
			)
			( signal "@baseboard_fab2_lib.baseboard_fab2(sch_1):tp_pvccio_cpu1_gl_1"
				( objectStatus "TP_PVCCIO_CPU1_GL_1" )
			)
			( signal "@baseboard_fab2_lib.baseboard_fab2(sch_1):tp_pvddq_ghj_ph2_gl_1"
				( objectStatus "TP_PVDDQ_GHJ_PH2_GL_1" )
			)
			( signal "@baseboard_fab2_lib.baseboard_fab2(sch_1):tp_pvccin_cpu0_ph5_gl_1"
				( objectStatus "TP_PVCCIN_CPU0_PH5_GL_1" )
			)
			( signal "@baseboard_fab2_lib.baseboard_fab2(sch_1):fm_cpu0_vrm_322m_156m_osc_en"
				( objectStatus "FM_CPU0_VRM_322M_156M_OSC_EN" )
			)
			( signal "@baseboard_fab2_lib.baseboard_fab2(sch_1):fm_cpu0_vrm_osc_en"
				( objectStatus "FM_CPU0_VRM_OSC_EN" )
			)
			( signal "@baseboard_fab2_lib.baseboard_fab2(sch_1):jtag_mcp_cpu0_tdi_r"
				( objectStatus "JTAG_MCP_CPU0_TDI_R" )
			)
			( signal "@baseboard_fab2_lib.baseboard_fab2(sch_1):tp_cpld1_pt19d"
				( objectStatus "TP_CPLD1_PT19D" )
			)
			( signal "@baseboard_fab2_lib.baseboard_fab2(sch_1):tp_cpld1_pb8d"
				( objectStatus "TP_CPLD1_PB8D" )
			)
			( signal "@baseboard_fab2_lib.baseboard_fab2(sch_1):tp_pvddq_abc_ph1_gl_1"
				( objectStatus "TP_PVDDQ_ABC_PH1_GL_1" )
			)
			( signal "@baseboard_fab2_lib.baseboard_fab2(sch_1):tp_pvccio_cpu0_gl_1"
				( objectStatus "TP_PVCCIO_CPU0_GL_1" )
			)
			( signal "@baseboard_fab2_lib.baseboard_fab2(sch_1):tp_pvccin_cpu0_aisen6"
				( objectStatus "TP_PVCCIN_CPU0_AISEN6" )
			)
			( signal "@baseboard_fab2_lib.baseboard_fab2(sch_1):tp_pvccin_cpu0_fault1_20"
				( objectStatus "TP_PVCCIN_CPU0_FAULT1_20" )
			)
			( signal "@baseboard_fab2_lib.baseboard_fab2(sch_1):tp_pvccin_cpu1_ph4_gl_1"
				( objectStatus "TP_PVCCIN_CPU1_PH4_GL_1" )
			)
			( signal "@baseboard_fab2_lib.baseboard_fab2(sch_1):fm_cpu1_stl_brd_osc_en"
				( objectStatus "FM_CPU1_STL_BRD_OSC_EN" )
			)
			( signal "@baseboard_fab2_lib.baseboard_fab2(sch_1):tp_pvccin_cpu1_aisen6"
				( objectStatus "TP_PVCCIN_CPU1_AISEN6" )
			)
			( signal "@baseboard_fab2_lib.baseboard_fab2(sch_1):tp_pvccin_cpu1_fault1_20"
				( objectStatus "TP_PVCCIN_CPU1_FAULT1_20" )
			)
			( signal "@baseboard_fab2_lib.baseboard_fab2(sch_1):tp_pvccinc_cpu1_ph1_gl_1"
				( objectStatus "TP_PVCCINC_CPU1_PH1_GL_1" )
			)
			( signal "@baseboard_fab2_lib.baseboard_fab2(sch_1):fm_cpu0_mcp_clk_en_n"
				( objectStatus "FM_CPU0_MCP_CLK_EN_N" )
			)
			( signal "@baseboard_fab2_lib.baseboard_fab2(sch_1):tp_pvccinc_cpu1_ph2_gl_1"
				( objectStatus "TP_PVCCINC_CPU1_PH2_GL_1" )
			)
			( signal "@baseboard_fab2_lib.baseboard_fab2(sch_1):fm_cpu1_mcp_clk_en_n"
				( attribute "NO_TEST" "1"
					( Origin gBackEnd )
				)
				( objectStatus "FM_CPU1_MCP_CLK_EN_N" )
			)
			( signal "@baseboard_fab2_lib.baseboard_fab2(sch_1):fm_pch_bmc_thermtrip_exi_strap_n"
				( objectStatus "FM_PCH_BMC_THERMTRIP_EXI_STRAP_" )
			)
			( signal "@baseboard_fab2_lib.baseboard_fab2(sch_1):fm_db1200zl_bclks_en_n"
				( objectStatus "FM_DB1200ZL_BCLKS_EN_N" )
			)
			( signal "@baseboard_fab2_lib.baseboard_fab2(sch_1):fm_156m_cpu0_brd_osc_en"
				( objectStatus "FM_156M_CPU0_BRD_OSC_EN" )
			)
			( signal "@baseboard_fab2_lib.baseboard_fab2(sch_1):fm_cpu1_vrm_osc_en"
				( objectStatus "FM_CPU1_VRM_OSC_EN" )
			)
			( signal "@baseboard_fab2_lib.baseboard_fab2(sch_1):fm_156m_cpu1_brd_osc_en"
				( objectStatus "FM_156M_CPU1_BRD_OSC_EN" )
			)
			( signal "@baseboard_fab2_lib.baseboard_fab2(sch_1):fm_cpu1_vrm_322m_156m_osc_en"
				( objectStatus "FM_CPU1_VRM_322M_156M_OSC_EN" )
			)
			( signal "@baseboard_fab2_lib.baseboard_fab2(sch_1):fm_cpu0_rc_en"
				( objectStatus "FM_CPU0_RC_EN" )
			)
			( signal "@baseboard_fab2_lib.baseboard_fab2(sch_1):tp_jumper_block_1_1"
				( objectStatus "TP_JUMPER_BLOCK_1_1" )
			)
			( signal "@baseboard_fab2_lib.baseboard_fab2(sch_1):fm_cpu1_rc_en"
				( objectStatus "FM_CPU1_RC_EN" )
			)
			( signal "@baseboard_fab2_lib.baseboard_fab2(sch_1):tp_pvddq_klm_ph1_gl_1"
				( objectStatus "TP_PVDDQ_KLM_PH1_GL_1" )
			)
			( signal "@baseboard_fab2_lib.baseboard_fab2(sch_1):tp_pvddq_klm_ph2_gl_1"
				( objectStatus "TP_PVDDQ_KLM_PH2_GL_1" )
			)
			( signal "@baseboard_fab2_lib.baseboard_fab2(sch_1):tp_pvnn_pch_gl_1"
				( objectStatus "TP_PVNN_PCH_GL_1" )
			)
			( signal "@baseboard_fab2_lib.baseboard_fab2(sch_1):tp_pvsa_cpu0_gl_1"
				( objectStatus "TP_PVSA_CPU0_GL_1" )
			)
			( signal "@baseboard_fab2_lib.baseboard_fab2(sch_1):tp_p1v05_pch_gl_1"
				( objectStatus "TP_P1V05_PCH_GL_1" )
			)
			( signal "@baseboard_fab2_lib.baseboard_fab2(sch_1):tp_shared_kr_mdc_0"
				( objectStatus "TP_SHARED_KR_MDC_0" )
			)
			( signal "@baseboard_fab2_lib.baseboard_fab2(sch_1):tp_rsvd(0)"
				( objectStatus "TP_RSVD<0>" )
			)
			( signal "@baseboard_fab2_lib.baseboard_fab2(sch_1):nc_pvccin_cpu0_ph1_p31"
				( objectStatus "NC_PVCCIN_CPU0_PH1_P31" )
			)
			( signal "@baseboard_fab2_lib.baseboard_fab2(sch_1):nc_pvccin_cpu0_ph2_p31"
				( objectStatus "NC_PVCCIN_CPU0_PH2_P31" )
			)
			( signal "@baseboard_fab2_lib.baseboard_fab2(sch_1):nc_pvccin_cpu0_ph3_p31"
				( objectStatus "NC_PVCCIN_CPU0_PH3_P31" )
			)
			( signal "@baseboard_fab2_lib.baseboard_fab2(sch_1):nc_pvccin_cpu0_ph4_p31"
				( objectStatus "NC_PVCCIN_CPU0_PH4_P31" )
			)
			( signal "@baseboard_fab2_lib.baseboard_fab2(sch_1):nc_pvccin_cpu0_ph5_p31"
				( objectStatus "NC_PVCCIN_CPU0_PH5_P31" )
			)
			( signal "@baseboard_fab2_lib.baseboard_fab2(sch_1):nc_pvccio_cpu0_ph1_p31"
				( objectStatus "NC_PVCCIO_CPU0_PH1_P31" )
			)
			( signal "@baseboard_fab2_lib.baseboard_fab2(sch_1):nc_pvccio_cpu1_ph1_p31"
				( objectStatus "NC_PVCCIO_CPU1_PH1_P31" )
			)
			( signal "@baseboard_fab2_lib.baseboard_fab2(sch_1):nc_pvddq_abc_ph1_p31"
				( objectStatus "NC_PVDDQ_ABC_PH1_P31" )
			)
			( signal "@baseboard_fab2_lib.baseboard_fab2(sch_1):nc_pvddq_abc_ph2_p31"
				( objectStatus "NC_PVDDQ_ABC_PH2_P31" )
			)
			( signal "@baseboard_fab2_lib.baseboard_fab2(sch_1):nc_pvddq_def_ph1_p31"
				( objectStatus "NC_PVDDQ_DEF_PH1_P31" )
			)
			( signal "@baseboard_fab2_lib.baseboard_fab2(sch_1):nc_pvddq_def_ph2_p31"
				( objectStatus "NC_PVDDQ_DEF_PH2_P31" )
			)
			( signal "@baseboard_fab2_lib.baseboard_fab2(sch_1):nc_pvddq_ghj_ph1_p31"
				( objectStatus "NC_PVDDQ_GHJ_PH1_P31" )
			)
			( signal "@baseboard_fab2_lib.baseboard_fab2(sch_1):nc_pvddq_ghj_ph2_p31"
				( objectStatus "NC_PVDDQ_GHJ_PH2_P31" )
			)
			( signal "@baseboard_fab2_lib.baseboard_fab2(sch_1):nc_pvddq_klm_ph1_p31"
				( objectStatus "NC_PVDDQ_KLM_PH1_P31" )
			)
			( signal "@baseboard_fab2_lib.baseboard_fab2(sch_1):nc_pvddq_klm_ph2_p31"
				( objectStatus "NC_PVDDQ_KLM_PH2_P31" )
			)
			( signal "@baseboard_fab2_lib.baseboard_fab2(sch_1):nc_pvnn_pch_ph1_p31"
				( objectStatus "NC_PVNN_PCH_PH1_P31" )
			)
			( signal "@baseboard_fab2_lib.baseboard_fab2(sch_1):nc_pvsa_cpu0_p31"
				( objectStatus "NC_PVSA_CPU0_P31" )
			)
			( signal "@baseboard_fab2_lib.baseboard_fab2(sch_1):fm_global_rst_warn_n"
				( objectStatus "FM_GLOBAL_RST_WARN_N" )
			)
			( signal "@baseboard_fab2_lib.baseboard_fab2(sch_1):tp_pch_gpp_d12"
				( objectStatus "TP_PCH_GPP_D12" )
			)
			( signal "@baseboard_fab2_lib.baseboard_fab2(sch_1):tp_pch_gpp_f12"
				( objectStatus "TP_PCH_GPP_F12" )
			)
			( signal "@baseboard_fab2_lib.baseboard_fab2(sch_1):tp_jumper_block_1_2"
				( objectStatus "TP_JUMPER_BLOCK_1_2" )
			)
			( signal "@baseboard_fab2_lib.baseboard_fab2(sch_1):fm_gbe1_lvc3_mod_abs"
				( objectStatus "FM_GBE1_LVC3_MOD_ABS" )
			)
			( signal "@baseboard_fab2_lib.baseboard_fab2(sch_1):\tp_jumper_block_ 1_7\"
				( objectStatus "TP_JUMPER_BLOCK_1_7" )
			)
			( signal "@baseboard_fab2_lib.baseboard_fab2(sch_1):fm_gbe0_lvc3_mod_abs"
				( objectStatus "FM_GBE0_LVC3_MOD_ABS" )
			)
			( signal "@baseboard_fab2_lib.baseboard_fab2(sch_1):led_gbe_p2_1"
				( objectStatus "LED_GBE_P2_1" )
			)
			( signal "@baseboard_fab2_lib.baseboard_fab2(sch_1):led_gbe_p3_0"
				( objectStatus "LED_GBE_P3_0" )
			)
			( signal "@baseboard_fab2_lib.baseboard_fab2(sch_1):fm_pvcciomcp_cpu0_en"
				( objectStatus "FM_PVCCIOMCP_CPU0_EN" )
			)
			( signal "@baseboard_fab2_lib.baseboard_fab2(sch_1):fm_pvcciomcp_cpu1_en"
				( objectStatus "FM_PVCCIOMCP_CPU1_EN" )
			)
			( signal "@baseboard_fab2_lib.baseboard_fab2(sch_1):fm_pvccmcp_cpu0_en"
				( objectStatus "FM_PVCCMCP_CPU0_EN" )
			)
			( signal "@baseboard_fab2_lib.baseboard_fab2(sch_1):fm_p1v8mcp_cpu0_en"
				( objectStatus "FM_P1V8MCP_CPU0_EN" )
			)
			( signal "@baseboard_fab2_lib.baseboard_fab2(sch_1):pwrgd_pvcciomcp_cpu1"
				( objectStatus "PWRGD_PVCCIOMCP_CPU1" )
			)
			( signal "@baseboard_fab2_lib.baseboard_fab2(sch_1):fm_pwrbrk_n"
				( objectStatus "FM_PWRBRK_N" )
			)
			( signal "@baseboard_fab2_lib.baseboard_fab2(sch_1):pwrgd_pvccmcp_cpu0"
				( objectStatus "PWRGD_PVCCMCP_CPU0" )
			)
			( signal "@baseboard_fab2_lib.baseboard_fab2(sch_1):pwrgd_pvccmcp_cpu1"
				( objectStatus "PWRGD_PVCCMCP_CPU1" )
			)
			( signal "@baseboard_fab2_lib.baseboard_fab2(sch_1):pwrgd_p1v8mcp_cpu0"
				( objectStatus "PWRGD_P1V8MCP_CPU0" )
			)
			( signal "@baseboard_fab2_lib.baseboard_fab2(sch_1):led_gbe_p2_0"
				( objectStatus "LED_GBE_P2_0" )
			)
			( signal "@baseboard_fab2_lib.baseboard_fab2(sch_1):fm_cpu_bmc_init"
				( objectStatus "FM_CPU_BMC_INIT" )
			)
			( signal "@baseboard_fab2_lib.baseboard_fab2(sch_1):fm_cpu_err0_pch_n"
				( objectStatus "FM_CPU_ERR0_PCH_N" )
			)
			( signal "@baseboard_fab2_lib.baseboard_fab2(sch_1):fm_cpu_err1_pch_n"
				( objectStatus "FM_CPU_ERR1_PCH_N" )
			)
			( signal "@baseboard_fab2_lib.baseboard_fab2(sch_1):tp_fan_0"
				( objectStatus "TP_FAN_0" )
			)
			( signal "@baseboard_fab2_lib.baseboard_fab2(sch_1):tp_fan_1"
				( objectStatus "TP_FAN_1" )
			)
			( signal "@baseboard_fab2_lib.baseboard_fab2(sch_1):fm_battery_sense_en_n"
				( objectStatus "FM_BATTERY_SENSE_EN_N" )
			)
			( signal "@baseboard_fab2_lib.baseboard_fab2(sch_1):pu_fab2_marker_cpld"
				( objectStatus "PU_FAB2_MARKER_CPLD" )
			)
			( signal "@baseboard_fab2_lib.baseboard_fab2(sch_1):tp_fet_q56_3"
				( objectStatus "TP_FET_Q56_3" )
			)
			( signal "@baseboard_fab2_lib.baseboard_fab2(sch_1):tp_fet_q56_4"
				( objectStatus "TP_FET_Q56_4" )
			)
			( signal "@baseboard_fab2_lib.baseboard_fab2(sch_1):tp_cpld1_pr10c"
				( objectStatus "TP_CPLD1_PR10C" )
			)
			( signal "@baseboard_fab2_lib.baseboard_fab2(sch_1):vr_pvccin_cpu1_ph4_ocset"
				( objectStatus "VR_PVCCIN_CPU1_PH4_OCSET" )
			)
			( signal "@baseboard_fab2_lib.baseboard_fab2(sch_1):tp_gpioe7_rxd3"
				( objectStatus "TP_GPIOE7_RXD3" )
			)
			( signal "@baseboard_fab2_lib.baseboard_fab2(sch_1):jtag_mcp_mux_tdi"
				( objectStatus "JTAG_MCP_MUX_TDI" )
			)
			( signal "@baseboard_fab2_lib.baseboard_fab2(sch_1):tp_jumper_block_1_8"
				( objectStatus "TP_JUMPER_BLOCK_1_8" )
			)
			( signal "@baseboard_fab2_lib.baseboard_fab2(sch_1):tp_jumper_block_2_8"
				( objectStatus "TP_JUMPER_BLOCK_2_8" )
			)
			( signal "@baseboard_fab2_lib.baseboard_fab2(sch_1):tp_jumper_block_2_10"
				( objectStatus "TP_JUMPER_BLOCK_2_10" )
			)
			( signal "@baseboard_fab2_lib.baseboard_fab2(sch_1):tp_ioa5"
				( objectStatus "TP_IOA5" )
			)
			( signal "@baseboard_fab2_lib.baseboard_fab2(sch_1):nc_p1v05_pch_stby_ph1_p31"
				( objectStatus "NC_P1V05_PCH_STBY_PH1_P31" )
			)
			( signal "@baseboard_fab2_lib.baseboard_fab2(sch_1):fm_pwrbrk_slot_n"
				( objectStatus "FM_PWRBRK_SLOT_N" )
			)
			( signal "@baseboard_fab2_lib.baseboard_fab2(sch_1):fm_gbe2_lvc3_mod_abs"
				( objectStatus "FM_GBE2_LVC3_MOD_ABS" )
			)
			( signal "@baseboard_fab2_lib.baseboard_fab2(sch_1):fm_gbe3_lvc3_mod_abs"
				( objectStatus "FM_GBE3_LVC3_MOD_ABS" )
			)
			( signal "@baseboard_fab2_lib.baseboard_fab2(sch_1):pwrgd_p5v_n"
				( objectStatus "PWRGD_P5V_N" )
			)
			( signal "@baseboard_fab2_lib.baseboard_fab2(sch_1):tp_cpu1_rsvd_199"
				( objectStatus "TP_CPU1_RSVD_199" )
			)
			( signal "@baseboard_fab2_lib.baseboard_fab2(sch_1):tp_ie_fm_uv_threshold_set"
				( objectStatus "TP_IE_FM_UV_THRESHOLD_SET" )
			)
			( signal "@baseboard_fab2_lib.baseboard_fab2(sch_1):fm_cpu0_prochot_pch_n"
				( objectStatus "FM_CPU0_PROCHOT_PCH_N" )
			)
			( signal "@baseboard_fab2_lib.baseboard_fab2(sch_1):fm_cpu1_prochot_pch_n"
				( objectStatus "FM_CPU1_PROCHOT_PCH_N" )
			)
			( signal "@baseboard_fab2_lib.baseboard_fab2(sch_1):tp_cpu1_rsvd_32"
				( objectStatus "TP_CPU1_RSVD_32" )
			)
			( signal "@baseboard_fab2_lib.baseboard_fab2(sch_1):tp_cpu1_rsvd_33"
				( objectStatus "TP_CPU1_RSVD_33" )
			)
			( signal "@baseboard_fab2_lib.baseboard_fab2(sch_1):tp_cpu1_rsvd_34"
				( objectStatus "TP_CPU1_RSVD_34" )
			)
			( signal "@baseboard_fab2_lib.baseboard_fab2(sch_1):tp_cpu1_rsvd_35"
				( objectStatus "TP_CPU1_RSVD_35" )
			)
			( signal "@baseboard_fab2_lib.baseboard_fab2(sch_1):tp_cpu1_rsvd_36"
				( objectStatus "TP_CPU1_RSVD_36" )
			)
			( signal "@baseboard_fab2_lib.baseboard_fab2(sch_1):tp_cpu1_rsvd_37"
				( objectStatus "TP_CPU1_RSVD_37" )
			)
			( signal "@baseboard_fab2_lib.baseboard_fab2(sch_1):tp_cpu1_rsvd_38"
				( objectStatus "TP_CPU1_RSVD_38" )
			)
			( signal "@baseboard_fab2_lib.baseboard_fab2(sch_1):tp_cpu1_rsvd_39"
				( objectStatus "TP_CPU1_RSVD_39" )
			)
			( signal "@baseboard_fab2_lib.baseboard_fab2(sch_1):tp_cpu1_rsvd_40"
				( objectStatus "TP_CPU1_RSVD_40" )
			)
			( signal "@baseboard_fab2_lib.baseboard_fab2(sch_1):tp_cpu1_rsvd_41"
				( objectStatus "TP_CPU1_RSVD_41" )
			)
			( signal "@baseboard_fab2_lib.baseboard_fab2(sch_1):tp_cpu1_rsvd_42"
				( objectStatus "TP_CPU1_RSVD_42" )
			)
			( signal "@baseboard_fab2_lib.baseboard_fab2(sch_1):tp_cpu1_rsvd_43"
				( objectStatus "TP_CPU1_RSVD_43" )
			)
			( signal "@baseboard_fab2_lib.baseboard_fab2(sch_1):tp_cpu1_rsvd_44"
				( objectStatus "TP_CPU1_RSVD_44" )
			)
			( signal "@baseboard_fab2_lib.baseboard_fab2(sch_1):tp_cpu1_rsvd_45"
				( objectStatus "TP_CPU1_RSVD_45" )
			)
			( signal "@baseboard_fab2_lib.baseboard_fab2(sch_1):tp_cpu1_rsvd_46"
				( objectStatus "TP_CPU1_RSVD_46" )
			)
			( signal "@baseboard_fab2_lib.baseboard_fab2(sch_1):tp_cpu1_rsvd_47"
				( objectStatus "TP_CPU1_RSVD_47" )
			)
			( signal "@baseboard_fab2_lib.baseboard_fab2(sch_1):tp_cpu1_rsvd_48"
				( objectStatus "TP_CPU1_RSVD_48" )
			)
			( signal "@baseboard_fab2_lib.baseboard_fab2(sch_1):tp_cpu1_rsvd_49"
				( objectStatus "TP_CPU1_RSVD_49" )
			)
			( signal "@baseboard_fab2_lib.baseboard_fab2(sch_1):tp_cpu1_rsvd_50"
				( objectStatus "TP_CPU1_RSVD_50" )
			)
			( signal "@baseboard_fab2_lib.baseboard_fab2(sch_1):tp_cpu1_rsvd_51"
				( objectStatus "TP_CPU1_RSVD_51" )
			)
			( signal "@baseboard_fab2_lib.baseboard_fab2(sch_1):tp_cpu1_rsvd_53"
				( objectStatus "TP_CPU1_RSVD_53" )
			)
			( signal "@baseboard_fab2_lib.baseboard_fab2(sch_1):tp_cpu1_rsvd_54"
				( objectStatus "TP_CPU1_RSVD_54" )
			)
			( signal "@baseboard_fab2_lib.baseboard_fab2(sch_1):tp_cpu1_rsvd_55"
				( objectStatus "TP_CPU1_RSVD_55" )
			)
			( signal "@baseboard_fab2_lib.baseboard_fab2(sch_1):tp_cpu1_rsvd_56"
				( objectStatus "TP_CPU1_RSVD_56" )
			)
			( signal "@baseboard_fab2_lib.baseboard_fab2(sch_1):tp_cpu1_rsvd_57"
				( objectStatus "TP_CPU1_RSVD_57" )
			)
			( signal "@baseboard_fab2_lib.baseboard_fab2(sch_1):tp_cpu1_rsvd_59"
				( objectStatus "TP_CPU1_RSVD_59" )
			)
			( signal "@baseboard_fab2_lib.baseboard_fab2(sch_1):tp_cpu1_rsvd_60"
				( objectStatus "TP_CPU1_RSVD_60" )
			)
			( signal "@baseboard_fab2_lib.baseboard_fab2(sch_1):tp_cpu1_rsvd_61"
				( objectStatus "TP_CPU1_RSVD_61" )
			)
			( signal "@baseboard_fab2_lib.baseboard_fab2(sch_1):tp_cpu1_rsvd_64"
				( objectStatus "TP_CPU1_RSVD_64" )
			)
			( signal "@baseboard_fab2_lib.baseboard_fab2(sch_1):tp_cpu1_rsvd_66"
				( objectStatus "TP_CPU1_RSVD_66" )
			)
			( signal "@baseboard_fab2_lib.baseboard_fab2(sch_1):tp_cpu1_rsvd_67"
				( objectStatus "TP_CPU1_RSVD_67" )
			)
			( signal "@baseboard_fab2_lib.baseboard_fab2(sch_1):tp_cpu1_rsvd_69"
				( objectStatus "TP_CPU1_RSVD_69" )
			)
			( signal "@baseboard_fab2_lib.baseboard_fab2(sch_1):tp_cpu1_rsvd_70"
				( objectStatus "TP_CPU1_RSVD_70" )
			)
			( signal "@baseboard_fab2_lib.baseboard_fab2(sch_1):tp_cpu1_rsvd_72"
				( objectStatus "TP_CPU1_RSVD_72" )
			)
			( signal "@baseboard_fab2_lib.baseboard_fab2(sch_1):tp_cpu1_rsvd_73"
				( objectStatus "TP_CPU1_RSVD_73" )
			)
			( signal "@baseboard_fab2_lib.baseboard_fab2(sch_1):tp_cpu1_rsvd_194"
				( objectStatus "TP_CPU1_RSVD_194" )
			)
			( signal "@baseboard_fab2_lib.baseboard_fab2(sch_1):tp_cpu1_rsvd_198"
				( objectStatus "TP_CPU1_RSVD_198" )
			)
			( signal "@baseboard_fab2_lib.baseboard_fab2(sch_1):tp_cpu1_kti2_amonv"
				( objectStatus "TP_CPU1_KTI2_AMONV" )
			)
			( signal "@baseboard_fab2_lib.baseboard_fab2(sch_1):tp_cpu1_kti2_dfx_dn"
				( objectStatus "TP_CPU1_KTI2_DFX_DN" )
			)
			( signal "@baseboard_fab2_lib.baseboard_fab2(sch_1):fm_usb_p0_en_boot_bios_strap_n"
				( objectStatus "FM_USB_P0_EN_BOOT_BIOS_STRAP_N" )
			)
			( signal "@baseboard_fab2_lib.baseboard_fab2(sch_1):vr_pvccio_cpu0_en"
				( objectStatus "VR_PVCCIO_CPU0_EN" )
			)
			( signal "@baseboard_fab2_lib.baseboard_fab2(sch_1):tp_cpu1_rsvd_0"
				( objectStatus "TP_CPU1_RSVD_0" )
			)
			( signal "@baseboard_fab2_lib.baseboard_fab2(sch_1):tp_cpu1_rsvd_1"
				( objectStatus "TP_CPU1_RSVD_1" )
			)
			( signal "@baseboard_fab2_lib.baseboard_fab2(sch_1):tp_cpu1_rsvd_2"
				( objectStatus "TP_CPU1_RSVD_2" )
			)
			( signal "@baseboard_fab2_lib.baseboard_fab2(sch_1):tp_cpu1_rsvd_3"
				( objectStatus "TP_CPU1_RSVD_3" )
			)
			( signal "@baseboard_fab2_lib.baseboard_fab2(sch_1):tp_cpu1_rsvd_4"
				( objectStatus "TP_CPU1_RSVD_4" )
			)
			( signal "@baseboard_fab2_lib.baseboard_fab2(sch_1):tp_cpu1_rsvd_5"
				( objectStatus "TP_CPU1_RSVD_5" )
			)
			( signal "@baseboard_fab2_lib.baseboard_fab2(sch_1):tp_cpu1_rsvd_6"
				( objectStatus "TP_CPU1_RSVD_6" )
			)
			( signal "@baseboard_fab2_lib.baseboard_fab2(sch_1):tp_cpu1_rsvd_7"
				( objectStatus "TP_CPU1_RSVD_7" )
			)
			( signal "@baseboard_fab2_lib.baseboard_fab2(sch_1):tp_cpu1_rsvd_8"
				( objectStatus "TP_CPU1_RSVD_8" )
			)
			( signal "@baseboard_fab2_lib.baseboard_fab2(sch_1):tp_cpu1_rsvd_9"
				( objectStatus "TP_CPU1_RSVD_9" )
			)
			( signal "@baseboard_fab2_lib.baseboard_fab2(sch_1):tp_cpu1_rsvd_10"
				( objectStatus "TP_CPU1_RSVD_10" )
			)
			( signal "@baseboard_fab2_lib.baseboard_fab2(sch_1):tp_cpu1_rsvd_11"
				( objectStatus "TP_CPU1_RSVD_11" )
			)
			( signal "@baseboard_fab2_lib.baseboard_fab2(sch_1):tp_cpu1_rsvd_12"
				( objectStatus "TP_CPU1_RSVD_12" )
			)
			( signal "@baseboard_fab2_lib.baseboard_fab2(sch_1):tp_cpu1_rsvd_13"
				( objectStatus "TP_CPU1_RSVD_13" )
			)
			( signal "@baseboard_fab2_lib.baseboard_fab2(sch_1):tp_cpu1_rsvd_14"
				( objectStatus "TP_CPU1_RSVD_14" )
			)
			( signal "@baseboard_fab2_lib.baseboard_fab2(sch_1):tp_cpu1_rsvd_15"
				( objectStatus "TP_CPU1_RSVD_15" )
			)
			( signal "@baseboard_fab2_lib.baseboard_fab2(sch_1):tp_cpu1_rsvd_16"
				( objectStatus "TP_CPU1_RSVD_16" )
			)
			( signal "@baseboard_fab2_lib.baseboard_fab2(sch_1):tp_cpu1_rsvd_17"
				( objectStatus "TP_CPU1_RSVD_17" )
			)
			( signal "@baseboard_fab2_lib.baseboard_fab2(sch_1):tp_cpu1_rsvd_18"
				( objectStatus "TP_CPU1_RSVD_18" )
			)
			( signal "@baseboard_fab2_lib.baseboard_fab2(sch_1):tp_cpu1_rsvd_19"
				( objectStatus "TP_CPU1_RSVD_19" )
			)
			( signal "@baseboard_fab2_lib.baseboard_fab2(sch_1):tp_cpu1_rsvd_20"
				( objectStatus "TP_CPU1_RSVD_20" )
			)
			( signal "@baseboard_fab2_lib.baseboard_fab2(sch_1):tp_cpu1_rsvd_21"
				( objectStatus "TP_CPU1_RSVD_21" )
			)
			( signal "@baseboard_fab2_lib.baseboard_fab2(sch_1):tp_cpu1_rsvd_22"
				( objectStatus "TP_CPU1_RSVD_22" )
			)
			( signal "@baseboard_fab2_lib.baseboard_fab2(sch_1):tp_cpu1_rsvd_23"
				( objectStatus "TP_CPU1_RSVD_23" )
			)
			( signal "@baseboard_fab2_lib.baseboard_fab2(sch_1):tp_cpu1_rsvd_24"
				( objectStatus "TP_CPU1_RSVD_24" )
			)
			( signal "@baseboard_fab2_lib.baseboard_fab2(sch_1):tp_cpu1_rsvd_25"
				( objectStatus "TP_CPU1_RSVD_25" )
			)
			( signal "@baseboard_fab2_lib.baseboard_fab2(sch_1):tp_cpu1_rsvd_26"
				( objectStatus "TP_CPU1_RSVD_26" )
			)
			( signal "@baseboard_fab2_lib.baseboard_fab2(sch_1):tp_cpu1_rsvd_27"
				( objectStatus "TP_CPU1_RSVD_27" )
			)
			( signal "@baseboard_fab2_lib.baseboard_fab2(sch_1):tp_cpu1_rsvd_28"
				( objectStatus "TP_CPU1_RSVD_28" )
			)
			( signal "@baseboard_fab2_lib.baseboard_fab2(sch_1):tp_cpu1_rsvd_29"
				( objectStatus "TP_CPU1_RSVD_29" )
			)
			( signal "@baseboard_fab2_lib.baseboard_fab2(sch_1):tp_cpu1_rsvd_30"
				( objectStatus "TP_CPU1_RSVD_30" )
			)
			( signal "@baseboard_fab2_lib.baseboard_fab2(sch_1):tp_cpu1_rsvd_31"
				( objectStatus "TP_CPU1_RSVD_31" )
			)
			( signal "@baseboard_fab2_lib.baseboard_fab2(sch_1):tp_jumper_block_2_12"
				( objectStatus "TP_JUMPER_BLOCK_2_12" )
			)
			( signal "@baseboard_fab2_lib.baseboard_fab2(sch_1):tp_cpu0_rsvd_19"
				( objectStatus "TP_CPU0_RSVD_19" )
			)
			( signal "@baseboard_fab2_lib.baseboard_fab2(sch_1):tp_cpu0_rsvd_20"
				( objectStatus "TP_CPU0_RSVD_20" )
			)
			( signal "@baseboard_fab2_lib.baseboard_fab2(sch_1):tp_cpu0_rsvd_21"
				( objectStatus "TP_CPU0_RSVD_21" )
			)
			( signal "@baseboard_fab2_lib.baseboard_fab2(sch_1):tp_cpu0_rsvd_22"
				( objectStatus "TP_CPU0_RSVD_22" )
			)
			( signal "@baseboard_fab2_lib.baseboard_fab2(sch_1):tp_cpu0_rsvd_23"
				( objectStatus "TP_CPU0_RSVD_23" )
			)
			( signal "@baseboard_fab2_lib.baseboard_fab2(sch_1):tp_cpu0_rsvd_24"
				( objectStatus "TP_CPU0_RSVD_24" )
			)
			( signal "@baseboard_fab2_lib.baseboard_fab2(sch_1):tp_cpu0_rsvd_25"
				( objectStatus "TP_CPU0_RSVD_25" )
			)
			( signal "@baseboard_fab2_lib.baseboard_fab2(sch_1):tp_cpu0_rsvd_26"
				( objectStatus "TP_CPU0_RSVD_26" )
			)
			( signal "@baseboard_fab2_lib.baseboard_fab2(sch_1):tp_cpu0_rsvd_27"
				( objectStatus "TP_CPU0_RSVD_27" )
			)
			( signal "@baseboard_fab2_lib.baseboard_fab2(sch_1):tp_cpu0_rsvd_28"
				( objectStatus "TP_CPU0_RSVD_28" )
			)
			( signal "@baseboard_fab2_lib.baseboard_fab2(sch_1):tp_cpu0_rsvd_29"
				( objectStatus "TP_CPU0_RSVD_29" )
			)
			( signal "@baseboard_fab2_lib.baseboard_fab2(sch_1):tp_cpu0_rsvd_30"
				( objectStatus "TP_CPU0_RSVD_30" )
			)
			( signal "@baseboard_fab2_lib.baseboard_fab2(sch_1):tp_cpu0_rsvd_31"
				( objectStatus "TP_CPU0_RSVD_31" )
			)
			( signal "@baseboard_fab2_lib.baseboard_fab2(sch_1):tp_cpu0_rsvd_32"
				( objectStatus "TP_CPU0_RSVD_32" )
			)
			( signal "@baseboard_fab2_lib.baseboard_fab2(sch_1):tp_cpu0_rsvd_33"
				( objectStatus "TP_CPU0_RSVD_33" )
			)
			( signal "@baseboard_fab2_lib.baseboard_fab2(sch_1):tp_cpu0_rsvd_34"
				( objectStatus "TP_CPU0_RSVD_34" )
			)
			( signal "@baseboard_fab2_lib.baseboard_fab2(sch_1):tp_cpu0_rsvd_35"
				( objectStatus "TP_CPU0_RSVD_35" )
			)
			( signal "@baseboard_fab2_lib.baseboard_fab2(sch_1):tp_cpu0_rsvd_36"
				( objectStatus "TP_CPU0_RSVD_36" )
			)
			( signal "@baseboard_fab2_lib.baseboard_fab2(sch_1):tp_cpu0_rsvd_37"
				( objectStatus "TP_CPU0_RSVD_37" )
			)
			( signal "@baseboard_fab2_lib.baseboard_fab2(sch_1):tp_cpu0_rsvd_38"
				( objectStatus "TP_CPU0_RSVD_38" )
			)
			( signal "@baseboard_fab2_lib.baseboard_fab2(sch_1):tp_cpu0_rsvd_39"
				( objectStatus "TP_CPU0_RSVD_39" )
			)
			( signal "@baseboard_fab2_lib.baseboard_fab2(sch_1):tp_cpu0_rsvd_40"
				( objectStatus "TP_CPU0_RSVD_40" )
			)
			( signal "@baseboard_fab2_lib.baseboard_fab2(sch_1):tp_cpu0_rsvd_41"
				( objectStatus "TP_CPU0_RSVD_41" )
			)
			( signal "@baseboard_fab2_lib.baseboard_fab2(sch_1):tp_cpu0_rsvd_42"
				( objectStatus "TP_CPU0_RSVD_42" )
			)
			( signal "@baseboard_fab2_lib.baseboard_fab2(sch_1):tp_cpu0_rsvd_43"
				( objectStatus "TP_CPU0_RSVD_43" )
			)
			( signal "@baseboard_fab2_lib.baseboard_fab2(sch_1):tp_cpu0_rsvd_44"
				( objectStatus "TP_CPU0_RSVD_44" )
			)
			( signal "@baseboard_fab2_lib.baseboard_fab2(sch_1):tp_cpu0_rsvd_45"
				( objectStatus "TP_CPU0_RSVD_45" )
			)
			( signal "@baseboard_fab2_lib.baseboard_fab2(sch_1):tp_cpu0_rsvd_46"
				( objectStatus "TP_CPU0_RSVD_46" )
			)
			( signal "@baseboard_fab2_lib.baseboard_fab2(sch_1):tp_cpu0_rsvd_47"
				( objectStatus "TP_CPU0_RSVD_47" )
			)
			( signal "@baseboard_fab2_lib.baseboard_fab2(sch_1):tp_cpu0_rsvd_48"
				( objectStatus "TP_CPU0_RSVD_48" )
			)
			( signal "@baseboard_fab2_lib.baseboard_fab2(sch_1):tp_cpu0_rsvd_49"
				( objectStatus "TP_CPU0_RSVD_49" )
			)
			( signal "@baseboard_fab2_lib.baseboard_fab2(sch_1):tp_cpu0_rsvd_50"
				( objectStatus "TP_CPU0_RSVD_50" )
			)
			( signal "@baseboard_fab2_lib.baseboard_fab2(sch_1):tp_cpu0_rsvd_51"
				( objectStatus "TP_CPU0_RSVD_51" )
			)
			( signal "@baseboard_fab2_lib.baseboard_fab2(sch_1):tp_cpu0_rsvd_53"
				( objectStatus "TP_CPU0_RSVD_53" )
			)
			( signal "@baseboard_fab2_lib.baseboard_fab2(sch_1):tp_cpu0_rsvd_54"
				( objectStatus "TP_CPU0_RSVD_54" )
			)
			( signal "@baseboard_fab2_lib.baseboard_fab2(sch_1):tp_cpu0_rsvd_55"
				( objectStatus "TP_CPU0_RSVD_55" )
			)
			( signal "@baseboard_fab2_lib.baseboard_fab2(sch_1):tp_cpu0_rsvd_56"
				( objectStatus "TP_CPU0_RSVD_56" )
			)
			( signal "@baseboard_fab2_lib.baseboard_fab2(sch_1):tp_cpu0_rsvd_57"
				( objectStatus "TP_CPU0_RSVD_57" )
			)
			( signal "@baseboard_fab2_lib.baseboard_fab2(sch_1):tp_cpu0_rsvd_59"
				( objectStatus "TP_CPU0_RSVD_59" )
			)
			( signal "@baseboard_fab2_lib.baseboard_fab2(sch_1):tp_cpu0_rsvd_60"
				( objectStatus "TP_CPU0_RSVD_60" )
			)
			( signal "@baseboard_fab2_lib.baseboard_fab2(sch_1):tp_cpu0_rsvd_61"
				( objectStatus "TP_CPU0_RSVD_61" )
			)
			( signal "@baseboard_fab2_lib.baseboard_fab2(sch_1):tp_cpu0_rsvd_64"
				( objectStatus "TP_CPU0_RSVD_64" )
			)
			( signal "@baseboard_fab2_lib.baseboard_fab2(sch_1):tp_cpu0_rsvd_66"
				( objectStatus "TP_CPU0_RSVD_66" )
			)
			( signal "@baseboard_fab2_lib.baseboard_fab2(sch_1):tp_cpu0_rsvd_67"
				( objectStatus "TP_CPU0_RSVD_67" )
			)
			( signal "@baseboard_fab2_lib.baseboard_fab2(sch_1):tp_cpu0_rsvd_69"
				( objectStatus "TP_CPU0_RSVD_69" )
			)
			( signal "@baseboard_fab2_lib.baseboard_fab2(sch_1):tp_cpu0_rsvd_70"
				( objectStatus "TP_CPU0_RSVD_70" )
			)
			( signal "@baseboard_fab2_lib.baseboard_fab2(sch_1):tp_cpu0_rsvd_72"
				( objectStatus "TP_CPU0_RSVD_72" )
			)
			( signal "@baseboard_fab2_lib.baseboard_fab2(sch_1):tp_cpu0_rsvd_73"
				( objectStatus "TP_CPU0_RSVD_73" )
			)
			( signal "@baseboard_fab2_lib.baseboard_fab2(sch_1):tp_clk_100m_nsscc0_dn"
				( objectStatus "TP_CLK_100M_NSSCC0_DN" )
			)
			( signal "@baseboard_fab2_lib.baseboard_fab2(sch_1):tp_clk_100m_nsscc0_dp"
				( objectStatus "TP_CLK_100M_NSSCC0_DP" )
			)
			( signal "@baseboard_fab2_lib.baseboard_fab2(sch_1):tp_clk_100m_plat1_dn"
				( objectStatus "TP_CLK_100M_PLAT1_DN" )
			)
			( signal "@baseboard_fab2_lib.baseboard_fab2(sch_1):tp_clk_100m_plat1_dp"
				( objectStatus "TP_CLK_100M_PLAT1_DP" )
			)
			( signal "@baseboard_fab2_lib.baseboard_fab2(sch_1):jtag_mcp_tck"
				( objectStatus "JTAG_MCP_TCK" )
			)
			( signal "@baseboard_fab2_lib.baseboard_fab2(sch_1):tp_pvccin_cpu1_ph5_gl_1"
				( objectStatus "TP_PVCCIN_CPU1_PH5_GL_1" )
			)
			( signal "@baseboard_fab2_lib.baseboard_fab2(sch_1):tp_cpld1_pb25b_si_sispi"
				( objectStatus "TP_CPLD1_PB25B_SI_SISPI" )
			)
			( signal "@baseboard_fab2_lib.baseboard_fab2(sch_1):tp_cpld1_pl12b_pclkc3_0"
				( objectStatus "TP_CPLD1_PL12B_PCLKC3_0" )
			)
			( signal "@baseboard_fab2_lib.baseboard_fab2(sch_1):tp_pvccin_cpu1_ph3_gl_1"
				( objectStatus "TP_PVCCIN_CPU1_PH3_GL_1" )
			)
			( signal "@baseboard_fab2_lib.baseboard_fab2(sch_1):vr_pvccin_cpu1_ph5_ocset"
				( objectStatus "VR_PVCCIN_CPU1_PH5_OCSET" )
			)
			( signal "@baseboard_fab2_lib.baseboard_fab2(sch_1):tp_cpu0_kti2_amonv"
				( objectStatus "TP_CPU0_KTI2_AMONV" )
			)
			( signal "@baseboard_fab2_lib.baseboard_fab2(sch_1):tp_cpu0_kti2_dfx_dn"
				( objectStatus "TP_CPU0_KTI2_DFX_DN" )
			)
			( signal "@baseboard_fab2_lib.baseboard_fab2(sch_1):tp_cpu0_rsvd_0"
				( objectStatus "TP_CPU0_RSVD_0" )
			)
			( signal "@baseboard_fab2_lib.baseboard_fab2(sch_1):tp_cpu0_rsvd_1"
				( objectStatus "TP_CPU0_RSVD_1" )
			)
			( signal "@baseboard_fab2_lib.baseboard_fab2(sch_1):tp_cpu0_rsvd_2"
				( objectStatus "TP_CPU0_RSVD_2" )
			)
			( signal "@baseboard_fab2_lib.baseboard_fab2(sch_1):tp_cpu0_rsvd_3"
				( objectStatus "TP_CPU0_RSVD_3" )
			)
			( signal "@baseboard_fab2_lib.baseboard_fab2(sch_1):tp_cpu0_rsvd_4"
				( objectStatus "TP_CPU0_RSVD_4" )
			)
			( signal "@baseboard_fab2_lib.baseboard_fab2(sch_1):tp_cpu0_rsvd_5"
				( objectStatus "TP_CPU0_RSVD_5" )
			)
			( signal "@baseboard_fab2_lib.baseboard_fab2(sch_1):tp_cpu0_rsvd_6"
				( objectStatus "TP_CPU0_RSVD_6" )
			)
			( signal "@baseboard_fab2_lib.baseboard_fab2(sch_1):tp_cpu0_rsvd_7"
				( objectStatus "TP_CPU0_RSVD_7" )
			)
			( signal "@baseboard_fab2_lib.baseboard_fab2(sch_1):tp_cpu0_rsvd_8"
				( objectStatus "TP_CPU0_RSVD_8" )
			)
			( signal "@baseboard_fab2_lib.baseboard_fab2(sch_1):tp_cpu0_rsvd_9"
				( objectStatus "TP_CPU0_RSVD_9" )
			)
			( signal "@baseboard_fab2_lib.baseboard_fab2(sch_1):tp_cpu0_rsvd_10"
				( objectStatus "TP_CPU0_RSVD_10" )
			)
			( signal "@baseboard_fab2_lib.baseboard_fab2(sch_1):tp_cpu0_rsvd_11"
				( objectStatus "TP_CPU0_RSVD_11" )
			)
			( signal "@baseboard_fab2_lib.baseboard_fab2(sch_1):tp_cpu0_rsvd_12"
				( objectStatus "TP_CPU0_RSVD_12" )
			)
			( signal "@baseboard_fab2_lib.baseboard_fab2(sch_1):tp_cpu0_rsvd_13"
				( objectStatus "TP_CPU0_RSVD_13" )
			)
			( signal "@baseboard_fab2_lib.baseboard_fab2(sch_1):tp_cpu0_rsvd_14"
				( objectStatus "TP_CPU0_RSVD_14" )
			)
			( signal "@baseboard_fab2_lib.baseboard_fab2(sch_1):tp_cpu0_rsvd_15"
				( objectStatus "TP_CPU0_RSVD_15" )
			)
			( signal "@baseboard_fab2_lib.baseboard_fab2(sch_1):tp_cpu0_rsvd_16"
				( objectStatus "TP_CPU0_RSVD_16" )
			)
			( signal "@baseboard_fab2_lib.baseboard_fab2(sch_1):tp_cpu0_rsvd_17"
				( objectStatus "TP_CPU0_RSVD_17" )
			)
			( signal "@baseboard_fab2_lib.baseboard_fab2(sch_1):tp_cpu0_rsvd_18"
				( objectStatus "TP_CPU0_RSVD_18" )
			)
			( signal "@baseboard_fab2_lib.baseboard_fab2(sch_1):tp_pch_gpp_l10"
				( objectStatus "TP_PCH_GPP_L10" )
			)
			( signal "@baseboard_fab2_lib.baseboard_fab2(sch_1):pwrgd_p12v_main_r"
				( objectStatus "PWRGD_P12V_MAIN_R" )
			)
			( signal "@baseboard_fab2_lib.baseboard_fab2(sch_1):smb_pch_mezz_lom0_scl"
				( objectStatus "SMB_PCH_MEZZ_LOM0_SCL" )
			)
			( signal "@baseboard_fab2_lib.baseboard_fab2(sch_1):smb_pch_mezz_lom1_sda"
				( objectStatus "SMB_PCH_MEZZ_LOM1_SDA" )
			)
			( signal "@baseboard_fab2_lib.baseboard_fab2(sch_1):smb_pch_mezz_lom2_scl"
				( objectStatus "SMB_PCH_MEZZ_LOM2_SCL" )
			)
			( signal "@baseboard_fab2_lib.baseboard_fab2(sch_1):smb_pch_mezz_lom2_sda"
				( objectStatus "SMB_PCH_MEZZ_LOM2_SDA" )
			)
			( signal "@baseboard_fab2_lib.baseboard_fab2(sch_1):smb_pch_mezz_lom3_scl"
				( objectStatus "SMB_PCH_MEZZ_LOM3_SCL" )
			)
			( signal "@baseboard_fab2_lib.baseboard_fab2(sch_1):smb_pch_mezz_lom0_sda"
				( objectStatus "SMB_PCH_MEZZ_LOM0_SDA" )
			)
			( signal "@baseboard_fab2_lib.baseboard_fab2(sch_1):smb_pch_mezz_lom1_scl"
				( objectStatus "SMB_PCH_MEZZ_LOM1_SCL" )
			)
			( signal "@baseboard_fab2_lib.baseboard_fab2(sch_1):pu_vr_pvccin_cpu0_flt1_smbalt_n_imon"
				( objectStatus "PU_VR_PVCCIN_CPU0_FLT1_SMBALT_N" )
			)
			( signal "@baseboard_fab2_lib.baseboard_fab2(sch_1):pu_vr_pvccin_cpu1_flt1_smbalt_n_imon"
				( objectStatus "PU_VR_PVCCIN_CPU1_FLT1_SMBALT_N" )
			)
			( signal "@baseboard_fab2_lib.baseboard_fab2(sch_1):pu_10gbe_lom_pci_disable_n"
				( objectStatus "PU_10GBE_LOM_PCI_DISABLE_N" )
			)
			( signal "@baseboard_fab2_lib.baseboard_fab2(sch_1):tp_cpu0_rsvd_275"
				( objectStatus "TP_CPU0_RSVD_275" )
			)
			( signal "@baseboard_fab2_lib.baseboard_fab2(sch_1):tp_bios_usb_recovery"
				( objectStatus "TP_BIOS_USB_RECOVERY" )
			)
			( signal "@baseboard_fab2_lib.baseboard_fab2(sch_1):tp_pvddq_def_mp2"
				( objectStatus "TP_PVDDQ_DEF_MP2" )
			)
			( signal "@baseboard_fab2_lib.baseboard_fab2(sch_1):nic_led_act_anode_r"
				( objectStatus "NIC_LED_ACT_ANODE_R" )
			)
			( signal "@baseboard_fab2_lib.baseboard_fab2(sch_1):tp_cpu0_rsvd_282"
				( objectStatus "TP_CPU0_RSVD_282" )
			)
			( signal "@baseboard_fab2_lib.baseboard_fab2(sch_1):pd_cpu0_mcp01_dmon"
				( objectStatus "PD_CPU0_MCP01_DMON" )
			)
			( signal "@baseboard_fab2_lib.baseboard_fab2(sch_1):pd_cpu0_test12"
				( objectStatus "PD_CPU0_TEST12" )
			)
			( signal "@baseboard_fab2_lib.baseboard_fab2(sch_1):pd_cpu0_test13"
				( objectStatus "PD_CPU0_TEST13" )
			)
			( signal "@baseboard_fab2_lib.baseboard_fab2(sch_1):pd_cpu0_test14"
				( objectStatus "PD_CPU0_TEST14" )
			)
			( signal "@baseboard_fab2_lib.baseboard_fab2(sch_1):pd_cpu1_mcp01_dmon"
				( objectStatus "PD_CPU1_MCP01_DMON" )
			)
			( signal "@baseboard_fab2_lib.baseboard_fab2(sch_1):pd_cpu1_test12"
				( objectStatus "PD_CPU1_TEST12" )
			)
			( signal "@baseboard_fab2_lib.baseboard_fab2(sch_1):pd_cpu1_test13"
				( objectStatus "PD_CPU1_TEST13" )
			)
			( signal "@baseboard_fab2_lib.baseboard_fab2(sch_1):pd_cpu1_test14"
				( objectStatus "PD_CPU1_TEST14" )
			)
			( signal "@baseboard_fab2_lib.baseboard_fab2(sch_1):tp_pvddq_abc_mp2"
				( objectStatus "TP_PVDDQ_ABC_MP2" )
			)
			( signal "@baseboard_fab2_lib.baseboard_fab2(sch_1):smb_pch_mezz_lom3_sda"
				( objectStatus "SMB_PCH_MEZZ_LOM3_SDA" )
			)
			( signal "@baseboard_fab2_lib.baseboard_fab2(sch_1):tp_pch_gpp_j17"
				( objectStatus "TP_PCH_GPP_J17" )
			)
			( signal "@baseboard_fab2_lib.baseboard_fab2(sch_1):tp_pvnn_pch_mp3"
				( objectStatus "TP_PVNN_PCH_MP3" )
			)
			( signal "@baseboard_fab2_lib.baseboard_fab2(sch_1):tp_pch_gpp_j19"
				( objectStatus "TP_PCH_GPP_J19" )
			)
			( signal "@baseboard_fab2_lib.baseboard_fab2(sch_1):led_hfi0_cpu0_n"
				( objectStatus "LED_HFI0_CPU0_N" )
			)
			( signal "@baseboard_fab2_lib.baseboard_fab2(sch_1):led_hfi1_cpu0_n"
				( objectStatus "LED_HFI1_CPU0_N" )
			)
			( signal "@baseboard_fab2_lib.baseboard_fab2(sch_1):led_lan_0_n"
				( objectStatus "LED_LAN_0_N" )
			)
			( signal "@baseboard_fab2_lib.baseboard_fab2(sch_1):led_lan_0_r_n"
				( objectStatus "LED_LAN_0_R_N" )
			)
			( signal "@baseboard_fab2_lib.baseboard_fab2(sch_1):led_lan_1_n"
				( objectStatus "LED_LAN_1_N" )
			)
			( signal "@baseboard_fab2_lib.baseboard_fab2(sch_1):tp_vr_pvccio_cpu0_mp2"
				( objectStatus "TP_VR_PVCCIO_CPU0_MP2" )
			)
			( signal "@baseboard_fab2_lib.baseboard_fab2(sch_1):led_lan_1_r_n"
				( objectStatus "LED_LAN_1_R_N" )
			)
			( signal "@baseboard_fab2_lib.baseboard_fab2(sch_1):led_lan_2_n"
				( objectStatus "LED_LAN_2_N" )
			)
			( signal "@baseboard_fab2_lib.baseboard_fab2(sch_1):led_lan_2_r_n"
				( objectStatus "LED_LAN_2_R_N" )
			)
			( signal "@baseboard_fab2_lib.baseboard_fab2(sch_1):led_pch_sata_hdd_n"
				( objectStatus "LED_PCH_SATA_HDD_N" )
			)
			( signal "@baseboard_fab2_lib.baseboard_fab2(sch_1):led_pch_ssata_hdd_n"
				( objectStatus "LED_PCH_SSATA_HDD_N" )
			)
			( signal "@baseboard_fab2_lib.baseboard_fab2(sch_1):led_postcode_0"
				( objectStatus "LED_POSTCODE_0" )
			)
			( signal "@baseboard_fab2_lib.baseboard_fab2(sch_1):led_postcode_0_r"
				( objectStatus "LED_POSTCODE_0_R" )
			)
			( signal "@baseboard_fab2_lib.baseboard_fab2(sch_1):led_postcode_1"
				( objectStatus "LED_POSTCODE_1" )
			)
			( signal "@baseboard_fab2_lib.baseboard_fab2(sch_1):led_postcode_1_r"
				( objectStatus "LED_POSTCODE_1_R" )
			)
			( signal "@baseboard_fab2_lib.baseboard_fab2(sch_1):led_postcode_2"
				( objectStatus "LED_POSTCODE_2" )
			)
			( signal "@baseboard_fab2_lib.baseboard_fab2(sch_1):led_postcode_2_r"
				( objectStatus "LED_POSTCODE_2_R" )
			)
			( signal "@baseboard_fab2_lib.baseboard_fab2(sch_1):led_postcode_3"
				( objectStatus "LED_POSTCODE_3" )
			)
			( signal "@baseboard_fab2_lib.baseboard_fab2(sch_1):led_postcode_3_r"
				( objectStatus "LED_POSTCODE_3_R" )
			)
			( signal "@baseboard_fab2_lib.baseboard_fab2(sch_1):led_postcode_4"
				( objectStatus "LED_POSTCODE_4" )
			)
			( signal "@baseboard_fab2_lib.baseboard_fab2(sch_1):led_postcode_4_r"
				( objectStatus "LED_POSTCODE_4_R" )
			)
			( signal "@baseboard_fab2_lib.baseboard_fab2(sch_1):led_postcode_5"
				( objectStatus "LED_POSTCODE_5" )
			)
			( signal "@baseboard_fab2_lib.baseboard_fab2(sch_1):led_postcode_5_r"
				( objectStatus "LED_POSTCODE_5_R" )
			)
			( signal "@baseboard_fab2_lib.baseboard_fab2(sch_1):led_postcode_6"
				( objectStatus "LED_POSTCODE_6" )
			)
			( signal "@baseboard_fab2_lib.baseboard_fab2(sch_1):led_postcode_6_r"
				( objectStatus "LED_POSTCODE_6_R" )
			)
			( signal "@baseboard_fab2_lib.baseboard_fab2(sch_1):led_postcode_7"
				( objectStatus "LED_POSTCODE_7" )
			)
			( signal "@baseboard_fab2_lib.baseboard_fab2(sch_1):led_postcode_7_r"
				( objectStatus "LED_POSTCODE_7_R" )
			)
			( signal "@baseboard_fab2_lib.baseboard_fab2(sch_1):led_p5v_stby"
				( objectStatus "LED_P5V_STBY" )
			)
			( signal "@baseboard_fab2_lib.baseboard_fab2(sch_1):led_sas_act_r_n"
				( objectStatus "LED_SAS_ACT_R_N" )
			)
			( signal "@baseboard_fab2_lib.baseboard_fab2(sch_1):led_sata_act_r_n"
				( objectStatus "LED_SATA_ACT_R_N" )
			)
			( signal "@baseboard_fab2_lib.baseboard_fab2(sch_1):nc_db1200zl(0)"
				( objectStatus "NC_DB1200ZL<0>" )
			)
			( signal "@baseboard_fab2_lib.baseboard_fab2(sch_1):nc_db1200zl(1)"
				( objectStatus "NC_DB1200ZL<1>" )
			)
			( signal "@baseboard_fab2_lib.baseboard_fab2(sch_1):nc_db1200zl(2)"
				( objectStatus "NC_DB1200ZL<2>" )
			)
			( signal "@baseboard_fab2_lib.baseboard_fab2(sch_1):tp_slg55021_p12v_main_8"
				( objectStatus "TP_SLG55021_P12V_MAIN_8" )
			)
			( signal "@baseboard_fab2_lib.baseboard_fab2(sch_1):nc_m2(0)"
				( objectStatus "NC_M2<0>" )
			)
			( signal "@baseboard_fab2_lib.baseboard_fab2(sch_1):nc_m2(1)"
				( objectStatus "NC_M2<1>" )
			)
			( signal "@baseboard_fab2_lib.baseboard_fab2(sch_1):nc_m2(2)"
				( objectStatus "NC_M2<2>" )
			)
			( signal "@baseboard_fab2_lib.baseboard_fab2(sch_1):nc_m2(3)"
				( objectStatus "NC_M2<3>" )
			)
			( signal "@baseboard_fab2_lib.baseboard_fab2(sch_1):nc_m2(4)"
				( objectStatus "NC_M2<4>" )
			)
			( signal "@baseboard_fab2_lib.baseboard_fab2(sch_1):nc_m2(5)"
				( objectStatus "NC_M2<5>" )
			)
			( signal "@baseboard_fab2_lib.baseboard_fab2(sch_1):nc_m2(6)"
				( objectStatus "NC_M2<6>" )
			)
			( signal "@baseboard_fab2_lib.baseboard_fab2(sch_1):nc_m2(7)"
				( objectStatus "NC_M2<7>" )
			)
			( signal "@baseboard_fab2_lib.baseboard_fab2(sch_1):nc_m2(8)"
				( objectStatus "NC_M2<8>" )
			)
			( signal "@baseboard_fab2_lib.baseboard_fab2(sch_1):nc_m2(9)"
				( objectStatus "NC_M2<9>" )
			)
			( signal "@baseboard_fab2_lib.baseboard_fab2(sch_1):nc_m2(10)"
				( objectStatus "NC_M2<10>" )
			)
			( signal "@baseboard_fab2_lib.baseboard_fab2(sch_1):nc_m2(11)"
				( objectStatus "NC_M2<11>" )
			)
			( signal "@baseboard_fab2_lib.baseboard_fab2(sch_1):nc_m2(12)"
				( objectStatus "NC_M2<12>" )
			)
			( signal "@baseboard_fab2_lib.baseboard_fab2(sch_1):nc_m2(13)"
				( objectStatus "NC_M2<13>" )
			)
			( signal "@baseboard_fab2_lib.baseboard_fab2(sch_1):nc_m2(14)"
				( objectStatus "NC_M2<14>" )
			)
			( signal "@baseboard_fab2_lib.baseboard_fab2(sch_1):nc_m2(15)"
				( objectStatus "NC_M2<15>" )
			)
			( signal "@baseboard_fab2_lib.baseboard_fab2(sch_1):nc_m2(16)"
				( objectStatus "NC_M2<16>" )
			)
			( signal "@baseboard_fab2_lib.baseboard_fab2(sch_1):nc_m2(17)"
				( objectStatus "NC_M2<17>" )
			)
			( signal "@baseboard_fab2_lib.baseboard_fab2(sch_1):nc_m2(18)"
				( objectStatus "NC_M2<18>" )
			)
			( signal "@baseboard_fab2_lib.baseboard_fab2(sch_1):tp_cpu0_rsvd_283"
				( objectStatus "TP_CPU0_RSVD_283" )
			)
			( signal "@baseboard_fab2_lib.baseboard_fab2(sch_1):tp_pvsa_cpu1_gl_1"
				( objectStatus "TP_PVSA_CPU1_GL_1" )
			)
			( signal "@baseboard_fab2_lib.baseboard_fab2(sch_1):led_gbe_p0_0"
				( objectStatus "LED_GBE_P0_0" )
			)
			( signal "@baseboard_fab2_lib.baseboard_fab2(sch_1):tp_pvddq_ghj_mp2"
				( objectStatus "TP_PVDDQ_GHJ_MP2" )
			)
			( signal "@baseboard_fab2_lib.baseboard_fab2(sch_1):tp_pvnn_pch_mp2"
				( objectStatus "TP_PVNN_PCH_MP2" )
			)
			( signal "@baseboard_fab2_lib.baseboard_fab2(sch_1):rst_pcie_riser1_perst_r_n"
				( objectStatus "RST_PCIE_RISER1_PERST_R_N" )
			)
			( signal "@baseboard_fab2_lib.baseboard_fab2(sch_1):rst_system_btn_buf_n"
				( objectStatus "RST_SYSTEM_BTN_BUF_N" )
			)
			( signal "@baseboard_fab2_lib.baseboard_fab2(sch_1):fm_cpu0_prochot_lvt3_r_n"
				( objectStatus "FM_CPU0_PROCHOT_LVT3_R_N" )
			)
			( signal "@baseboard_fab2_lib.baseboard_fab2(sch_1):fm_cpu_err1_lvt3_bmc_n"
				( objectStatus "FM_CPU_ERR1_LVT3_BMC_N" )
			)
			( signal "@baseboard_fab2_lib.baseboard_fab2(sch_1):led_gbe_p0_1"
				( objectStatus "LED_GBE_P0_1" )
			)
			( signal "@baseboard_fab2_lib.baseboard_fab2(sch_1):xtal_pch_48m_in"
				( objectStatus "XTAL_PCH_48M_IN" )
			)
			( signal "@baseboard_fab2_lib.baseboard_fab2(sch_1):xtal_pch_48m_out"
				( objectStatus "XTAL_PCH_48M_OUT" )
			)
			( signal "@baseboard_fab2_lib.baseboard_fab2(sch_1):jtag_mcp_tck_r"
				( objectStatus "JTAG_MCP_TCK_R" )
			)
			( signal "@baseboard_fab2_lib.baseboard_fab2(sch_1):xtal_25mhz_in"
				( objectStatus "XTAL_25MHZ_IN" )
			)
			( signal "@baseboard_fab2_lib.baseboard_fab2(sch_1):xtal_25mhz_in_r"
				( objectStatus "XTAL_25MHZ_IN_R" )
			)
			( signal "@baseboard_fab2_lib.baseboard_fab2(sch_1):xtal_25mhz_out_r"
				( objectStatus "XTAL_25MHZ_OUT_R" )
			)
			( signal "@baseboard_fab2_lib.baseboard_fab2(sch_1):xtal_33k_rtc1"
				( objectStatus "XTAL_33K_RTC1" )
			)
			( signal "@baseboard_fab2_lib.baseboard_fab2(sch_1):xtal_33k_rtc2"
				( objectStatus "XTAL_33K_RTC2" )
			)
			( signal "@baseboard_fab2_lib.baseboard_fab2(sch_1):fm_cpu0_prochot_lvt3_bmc_n"
				( objectStatus "FM_CPU0_PROCHOT_LVT3_BMC_N" )
			)
			( signal "@baseboard_fab2_lib.baseboard_fab2(sch_1):fan_tach0_r"
				( objectStatus "FAN_TACH0_R" )
			)
			( signal "@baseboard_fab2_lib.baseboard_fab2(sch_1):led_gbe_p1_0"
				( objectStatus "LED_GBE_P1_0" )
			)
			( signal "@baseboard_fab2_lib.baseboard_fab2(sch_1):vr_pvccin_cpu1_ph2_ocset"
				( objectStatus "VR_PVCCIN_CPU1_PH2_OCSET" )
			)
			( signal "@baseboard_fab2_lib.baseboard_fab2(sch_1):vr_pvccin_cpu1_ph3_ocset"
				( objectStatus "VR_PVCCIN_CPU1_PH3_OCSET" )
			)
			( signal "@baseboard_fab2_lib.baseboard_fab2(sch_1):nc_pvccin_cpu1_ph1_p31"
				( objectStatus "NC_PVCCIN_CPU1_PH1_P31" )
			)
			( signal "@baseboard_fab2_lib.baseboard_fab2(sch_1):nc_pvccin_cpu1_ph2_p31"
				( objectStatus "NC_PVCCIN_CPU1_PH2_P31" )
			)
			( signal "@baseboard_fab2_lib.baseboard_fab2(sch_1):nc_pvccin_cpu1_ph3_p31"
				( objectStatus "NC_PVCCIN_CPU1_PH3_P31" )
			)
			( signal "@baseboard_fab2_lib.baseboard_fab2(sch_1):led_gbe_p1_1"
				( objectStatus "LED_GBE_P1_1" )
			)
			( signal "@baseboard_fab2_lib.baseboard_fab2(sch_1):tp_usb3_p05_rxn"
				( objectStatus "TP_USB3_P05_RXN" )
			)
			( signal "@baseboard_fab2_lib.baseboard_fab2(sch_1):tp_usb3_p05_rxp"
				( objectStatus "TP_USB3_P05_RXP" )
			)
			( signal "@baseboard_fab2_lib.baseboard_fab2(sch_1):tp_usb3_p05_txn"
				( objectStatus "TP_USB3_P05_TXN" )
			)
			( signal "@baseboard_fab2_lib.baseboard_fab2(sch_1):tp_usb3_p05_txp"
				( objectStatus "TP_USB3_P05_TXP" )
			)
			( signal "@baseboard_fab2_lib.baseboard_fab2(sch_1):tp_usb3_p06_rxn"
				( objectStatus "TP_USB3_P06_RXN" )
			)
			( signal "@baseboard_fab2_lib.baseboard_fab2(sch_1):tp_usb3_p06_rxp"
				( objectStatus "TP_USB3_P06_RXP" )
			)
			( signal "@baseboard_fab2_lib.baseboard_fab2(sch_1):tp_usb3_p06_txn"
				( objectStatus "TP_USB3_P06_TXN" )
			)
			( signal "@baseboard_fab2_lib.baseboard_fab2(sch_1):tp_usb3_p06_txp"
				( objectStatus "TP_USB3_P06_TXP" )
			)
			( signal "@baseboard_fab2_lib.baseboard_fab2(sch_1):fm_cpu1_prochot_lvt3_bmc_n"
				( objectStatus "FM_CPU1_PROCHOT_LVT3_BMC_N" )
			)
			( signal "@baseboard_fab2_lib.baseboard_fab2(sch_1):tp_vr_pvccio_cpu0_mp3"
				( objectStatus "TP_VR_PVCCIO_CPU0_MP3" )
			)
			( signal "@baseboard_fab2_lib.baseboard_fab2(sch_1):fm_bmc_nmi_n"
				( objectStatus "FM_BMC_NMI_N" )
			)
			( signal "@baseboard_fab2_lib.baseboard_fab2(sch_1):fm_bmc_sys_throttle_r_n"
				( objectStatus "FM_BMC_SYS_THROTTLE_R_N" )
			)
			( signal "@baseboard_fab2_lib.baseboard_fab2(sch_1):fm_cpu_caterr_lvt3_n"
				( objectStatus "FM_CPU_CATERR_LVT3_N" )
			)
			( signal "@baseboard_fab2_lib.baseboard_fab2(sch_1):rst_bmc_ddr3_buf_in_n"
				( objectStatus "RST_BMC_DDR3_BUF_IN_N" )
			)
			( signal "@baseboard_fab2_lib.baseboard_fab2(sch_1):fm_cpu_err0_lvt3_r_n"
				( objectStatus "FM_CPU_ERR0_LVT3_R_N" )
			)
			( signal "@baseboard_fab2_lib.baseboard_fab2(sch_1):fm_cpu_err1_lvt3_r_n"
				( objectStatus "FM_CPU_ERR1_LVT3_R_N" )
			)
			( signal "@baseboard_fab2_lib.baseboard_fab2(sch_1):fm_cpu_err2_lvt3_n"
				( objectStatus "FM_CPU_ERR2_LVT3_N" )
			)
			( signal "@baseboard_fab2_lib.baseboard_fab2(sch_1):tp_pch_gpp_l11"
				( objectStatus "TP_PCH_GPP_L11" )
			)
			( signal "@baseboard_fab2_lib.baseboard_fab2(sch_1):fm_cpu_msmi_lvt3_n"
				( objectStatus "FM_CPU_MSMI_LVT3_N" )
			)
			( signal "@baseboard_fab2_lib.baseboard_fab2(sch_1):fm_cpu_msmi_lvt3_r_n"
				( objectStatus "FM_CPU_MSMI_LVT3_R_N" )
			)
			( signal "@baseboard_fab2_lib.baseboard_fab2(sch_1):fm_cpu0_fivr_fault_lvt3"
				( objectStatus "FM_CPU0_FIVR_FAULT_LVT3" )
			)
			( signal "@baseboard_fab2_lib.baseboard_fab2(sch_1):fm_cpu0_fivr_fault_lvt3_n"
				( objectStatus "FM_CPU0_FIVR_FAULT_LVT3_N" )
			)
			( signal "@baseboard_fab2_lib.baseboard_fab2(sch_1):fm_cpu0_fivr_fault_lvt3_r_n"
				( objectStatus "FM_CPU0_FIVR_FAULT_LVT3_R_N" )
			)
			( signal "@baseboard_fab2_lib.baseboard_fab2(sch_1):fm_cpu0_fivr_fault_lvt3_r2_n"
				( objectStatus "FM_CPU0_FIVR_FAULT_LVT3_R2_N" )
			)
			( signal "@baseboard_fab2_lib.baseboard_fab2(sch_1):fm_cpu_err2_lvt3_r_n"
				( objectStatus "FM_CPU_ERR2_LVT3_R_N" )
			)
			( signal "@baseboard_fab2_lib.baseboard_fab2(sch_1):fm_cpu0_thermtrip_lvt3_n"
				( objectStatus "FM_CPU0_THERMTRIP_LVT3_N" )
			)
			( signal "@baseboard_fab2_lib.baseboard_fab2(sch_1):fm_cpu0_thermtrip_lvt3_r_n"
				( objectStatus "FM_CPU0_THERMTRIP_LVT3_R_N" )
			)
			( signal "@baseboard_fab2_lib.baseboard_fab2(sch_1):fm_cpu1_fivr_fault_lvt3"
				( objectStatus "FM_CPU1_FIVR_FAULT_LVT3" )
			)
			( signal "@baseboard_fab2_lib.baseboard_fab2(sch_1):fm_cpu1_fivr_fault_lvt3_n"
				( objectStatus "FM_CPU1_FIVR_FAULT_LVT3_N" )
			)
			( signal "@baseboard_fab2_lib.baseboard_fab2(sch_1):fm_cpu1_fivr_fault_lvt3_r_n"
				( objectStatus "FM_CPU1_FIVR_FAULT_LVT3_R_N" )
			)
			( signal "@baseboard_fab2_lib.baseboard_fab2(sch_1):fm_cpu1_fivr_fault_lvt3_r1_n"
				( objectStatus "FM_CPU1_FIVR_FAULT_LVT3_R1_N" )
			)
			( signal "@baseboard_fab2_lib.baseboard_fab2(sch_1):fm_cpu_caterr_lvt3_r2_n"
				( objectStatus "FM_CPU_CATERR_LVT3_R2_N" )
			)
			( signal "@baseboard_fab2_lib.baseboard_fab2(sch_1):fm_cpu1_thermtrip_lvt3_n"
				( objectStatus "FM_CPU1_THERMTRIP_LVT3_N" )
			)
			( signal "@baseboard_fab2_lib.baseboard_fab2(sch_1):fm_cpu1_thermtrip_lvt3_r_n"
				( objectStatus "FM_CPU1_THERMTRIP_LVT3_R_N" )
			)
			( signal "@baseboard_fab2_lib.baseboard_fab2(sch_1):fm_ctnr_ps_on"
				( objectStatus "FM_CTNR_PS_ON" )
			)
			( signal "@baseboard_fab2_lib.baseboard_fab2(sch_1):fm_ctnr_ps_on_r"
				( objectStatus "FM_CTNR_PS_ON_R" )
			)
			( signal "@baseboard_fab2_lib.baseboard_fab2(sch_1):fm_db_uart_sel0_n"
				( objectStatus "FM_DB_UART_SEL0_N" )
			)
			( signal "@baseboard_fab2_lib.baseboard_fab2(sch_1):fm_debug_rst_btn_n"
				( objectStatus "FM_DEBUG_RST_BTN_N" )
			)
			( signal "@baseboard_fab2_lib.baseboard_fab2(sch_1):fm_debug_rst_btn_r1_n"
				( objectStatus "FM_DEBUG_RST_BTN_R1_N" )
			)
			( signal "@baseboard_fab2_lib.baseboard_fab2(sch_1):fm_m2_det_lvc3"
				( objectStatus "FM_M2_DET_LVC3" )
			)
			( signal "@baseboard_fab2_lib.baseboard_fab2(sch_1):fm_nmi_event_n"
				( objectStatus "FM_NMI_EVENT_N" )
			)
			( signal "@baseboard_fab2_lib.baseboard_fab2(sch_1):fm_pch_sata_raid_key"
				( objectStatus "FM_PCH_SATA_RAID_KEY" )
			)
			( signal "@baseboard_fab2_lib.baseboard_fab2(sch_1):fm_pch_sata_raid_key_r"
				( objectStatus "FM_PCH_SATA_RAID_KEY_R" )
			)
			( signal "@baseboard_fab2_lib.baseboard_fab2(sch_1):fm_pvtt_ghj_en_r"
				( objectStatus "FM_PVTT_GHJ_EN_R" )
			)
			( signal "@baseboard_fab2_lib.baseboard_fab2(sch_1):fm_pvtt_klm_en_r"
				( objectStatus "FM_PVTT_KLM_EN_R" )
			)
			( signal "@baseboard_fab2_lib.baseboard_fab2(sch_1):fm_pwr_btn_n"
				( objectStatus "FM_PWR_BTN_N" )
			)
			( signal "@baseboard_fab2_lib.baseboard_fab2(sch_1):fm_pwr_btn_r_n"
				( objectStatus "FM_PWR_BTN_R_N" )
			)
			( signal "@baseboard_fab2_lib.baseboard_fab2(sch_1):pu_24m_osc_oe"
				( objectStatus "PU_24M_OSC_OE" )
			)
			( signal "@baseboard_fab2_lib.baseboard_fab2(sch_1):pwrgd_p1v8mcp_cpu1"
				( objectStatus "PWRGD_P1V8MCP_CPU1" )
			)
			( signal "@baseboard_fab2_lib.baseboard_fab2(sch_1):a_hsc_low_drain"
				( objectStatus "A_HSC_LOW_DRAIN" )
			)
			( signal "@baseboard_fab2_lib.baseboard_fab2(sch_1):fm_bmc_disable"
				( objectStatus "FM_BMC_DISABLE" )
			)
			( signal "@baseboard_fab2_lib.baseboard_fab2(sch_1):fm_bmc_enable_n"
				( objectStatus "FM_BMC_ENABLE_N" )
			)
			( signal "@baseboard_fab2_lib.baseboard_fab2(sch_1):rst_bmc_srst_n"
				( objectStatus "RST_BMC_SRST_N" )
			)
			( signal "@baseboard_fab2_lib.baseboard_fab2(sch_1):pwrgd_pvccio_cpu0"
				( objectStatus "PWRGD_PVCCIO_CPU0" )
			)
			( signal "@baseboard_fab2_lib.baseboard_fab2(sch_1):pwrgd_pvccio_cpu1"
				( objectStatus "PWRGD_PVCCIO_CPU1" )
			)
			( signal "@baseboard_fab2_lib.baseboard_fab2(sch_1):pwrgd_pvccio_cpu1_r"
				( objectStatus "PWRGD_PVCCIO_CPU1_R" )
			)
			( signal "@baseboard_fab2_lib.baseboard_fab2(sch_1):fm_adr_smi_gpio_r_n"
				( objectStatus "FM_ADR_SMI_GPIO_R_N" )
			)
			( signal "@baseboard_fab2_lib.baseboard_fab2(sch_1):rst_pch_sysrst_btn_out_n"
				( objectStatus "RST_PCH_SYSRST_BTN_OUT_N" )
			)
			( signal "@baseboard_fab2_lib.baseboard_fab2(sch_1):rst_pltrst_top_swap"
				( objectStatus "RST_PLTRST_TOP_SWAP" )
			)
			( signal "@baseboard_fab2_lib.baseboard_fab2(sch_1):fm_pvccin_pvccsa_cpu0_en_lvc1"
				( objectStatus "FM_PVCCIN_PVCCSA_CPU0_EN_LVC1" )
			)
			( signal "@baseboard_fab2_lib.baseboard_fab2(sch_1):fm_pvddq_def_en"
				( objectStatus "FM_PVDDQ_DEF_EN" )
			)
			( signal "@baseboard_fab2_lib.baseboard_fab2(sch_1):fm_pvddq_klm_en"
				( objectStatus "FM_PVDDQ_KLM_EN" )
			)
			( signal "@baseboard_fab2_lib.baseboard_fab2(sch_1):vr_pvccin_cpu0_vren"
				( attribute "VOLTAGE" "3.3"
					( Units "uVoltage" "V" 1.000000)
					( Origin gFrontEnd )
				)
				( objectStatus "VR_PVCCIN_CPU0_VREN" )
			)
			( signal "@baseboard_fab2_lib.baseboard_fab2(sch_1):vr_pvddq_def_vren"
				( objectStatus "VR_PVDDQ_DEF_VREN" )
			)
			( signal "@baseboard_fab2_lib.baseboard_fab2(sch_1):vr_pvddq_klm_vren"
				( objectStatus "VR_PVDDQ_KLM_VREN" )
			)
			( signal "@baseboard_fab2_lib.baseboard_fab2(sch_1):vr_pvnn_pch_vren"
				( objectStatus "VR_PVNN_PCH_VREN" )
			)
			( signal "@baseboard_fab2_lib.baseboard_fab2(sch_1):vr_p3v3_stby_en"
				( objectStatus "VR_P3V3_STBY_EN" )
			)
			( signal "@baseboard_fab2_lib.baseboard_fab2(sch_1):jtag_mcp_tms_r"
				( objectStatus "JTAG_MCP_TMS_R" )
			)
			( signal "@baseboard_fab2_lib.baseboard_fab2(sch_1):fm_bmc_fault_led"
				( objectStatus "FM_BMC_FAULT_LED" )
			)
			( signal "@baseboard_fab2_lib.baseboard_fab2(sch_1):fm_red_led_anode"
				( objectStatus "FM_RED_LED_ANODE" )
			)
			( signal "@baseboard_fab2_lib.baseboard_fab2(sch_1):fm_red_led_cathode"
				( objectStatus "FM_RED_LED_CATHODE" )
			)
			( signal "@baseboard_fab2_lib.baseboard_fab2(sch_1):fp_led_hdd_activity_and_n"
				( objectStatus "FP_LED_HDD_ACTIVITY_AND_N" )
			)
			( signal "@baseboard_fab2_lib.baseboard_fab2(sch_1):fp_led_hdd_activity_and_r_n"
				( objectStatus "FP_LED_HDD_ACTIVITY_AND_R_N" )
			)
			( signal "@baseboard_fab2_lib.baseboard_fab2(sch_1):rst_rsmrst_dly"
				( objectStatus "RST_RSMRST_DLY" )
			)
			( signal "@baseboard_fab2_lib.baseboard_fab2(sch_1):tp_cpld1_pb16a_pclkt2_1"
				( objectStatus "TP_CPLD1_PB16A_PCLKT2_1" )
			)
			( signal "@baseboard_fab2_lib.baseboard_fab2(sch_1):tp_cpld1_pt24b"
				( objectStatus "TP_CPLD1_PT24B" )
			)
			( signal "@baseboard_fab2_lib.baseboard_fab2(sch_1):tp_cpu0_rsvd_test_3"
				( objectStatus "TP_CPU0_RSVD_TEST_3" )
			)
			( signal "@baseboard_fab2_lib.baseboard_fab2(sch_1):fm_pvccin_pvccsa_cpu1_en_lvc1"
				( attribute "RATSNEST_SCHEDULE" "MIN_DAISY_CHAIN"
					( Origin gBackEnd )
				)
				( objectStatus "FM_PVCCIN_PVCCSA_CPU1_EN_LVC1" )
			)
			( signal "@baseboard_fab2_lib.baseboard_fab2(sch_1):fm_adr_complete_abc_n"
				( objectStatus "FM_ADR_COMPLETE_ABC_N" )
			)
			( signal "@baseboard_fab2_lib.baseboard_fab2(sch_1):fm_adr_complete_def_n"
				( objectStatus "FM_ADR_COMPLETE_DEF_N" )
			)
			( signal "@baseboard_fab2_lib.baseboard_fab2(sch_1):fm_adr_complete_ghj_n"
				( objectStatus "FM_ADR_COMPLETE_GHJ_N" )
			)
			( signal "@baseboard_fab2_lib.baseboard_fab2(sch_1):fm_adr_complete_klm_n"
				( objectStatus "FM_ADR_COMPLETE_KLM_N" )
			)
			( signal "@baseboard_fab2_lib.baseboard_fab2(sch_1):fm_mem_therm_event_lvt3_n"
				( objectStatus "FM_MEM_THERM_EVENT_LVT3_N" )
			)
			( signal "@baseboard_fab2_lib.baseboard_fab2(sch_1):irq_dimm_save_n"
				( objectStatus "IRQ_DIMM_SAVE_N" )
			)
			( signal "@baseboard_fab2_lib.baseboard_fab2(sch_1):fm_bmc_cpld_mp_rst_n"
				( objectStatus "FM_BMC_CPLD_MP_RST_N" )
			)
			( signal "@baseboard_fab2_lib.baseboard_fab2(sch_1):fm_cpld_dbg_pwr_en_r_n"
				( objectStatus "FM_CPLD_DBG_PWR_EN_R_N" )
			)
			( signal "@baseboard_fab2_lib.baseboard_fab2(sch_1):fm_oc_detect_en_n"
				( objectStatus "FM_OC_DETECT_EN_N" )
			)
			( signal "@baseboard_fab2_lib.baseboard_fab2(sch_1):irq_dimm_save_r_n"
				( objectStatus "IRQ_DIMM_SAVE_R_N" )
			)
			( signal "@baseboard_fab2_lib.baseboard_fab2(sch_1):fm_cpld_dbg_pwr_en"
				( objectStatus "FM_CPLD_DBG_PWR_EN" )
			)
			( signal "@baseboard_fab2_lib.baseboard_fab2(sch_1):fm_pvddq_abc_en"
				( objectStatus "FM_PVDDQ_ABC_EN" )
			)
			( signal "@baseboard_fab2_lib.baseboard_fab2(sch_1):irq_oob_mgmt_riser_alert_n"
				( objectStatus "IRQ_OOB_MGMT_RISER_ALERT_N" )
			)
			( signal "@baseboard_fab2_lib.baseboard_fab2(sch_1):fm_pch_pld_data_r"
				( objectStatus "FM_PCH_PLD_DATA_R" )
			)
			( signal "@baseboard_fab2_lib.baseboard_fab2(sch_1):vr_pvddq_ghj_vren"
				( objectStatus "VR_PVDDQ_GHJ_VREN" )
			)
			( signal "@baseboard_fab2_lib.baseboard_fab2(sch_1):fm_pvddq_ghj_en"
				( objectStatus "FM_PVDDQ_GHJ_EN" )
			)
			( signal "@baseboard_fab2_lib.baseboard_fab2(sch_1):vr_pvddq_abc_vren"
				( objectStatus "VR_PVDDQ_ABC_VREN" )
			)
			( signal "@baseboard_fab2_lib.baseboard_fab2(sch_1):fm_pvpp_cpu0_en"
				( objectStatus "FM_PVPP_CPU0_EN" )
			)
			( signal "@baseboard_fab2_lib.baseboard_fab2(sch_1):fm_pvpp_cpu1_en"
				( objectStatus "FM_PVPP_CPU1_EN" )
			)
			( signal "@baseboard_fab2_lib.baseboard_fab2(sch_1):fm_sint_prsnt_n"
				( objectStatus "FM_SINT_PRSNT_N" )
			)
			( signal "@baseboard_fab2_lib.baseboard_fab2(sch_1):fm_adr_complete_r"
				( objectStatus "FM_ADR_COMPLETE_R" )
			)
			( signal "@baseboard_fab2_lib.baseboard_fab2(sch_1):fm_adr_complete_r1"
				( objectStatus "FM_ADR_COMPLETE_R1" )
			)
			( signal "@baseboard_fab2_lib.baseboard_fab2(sch_1):rst_bmc_sysrst_btn_out_b_r_n"
				( objectStatus "RST_BMC_SYSRST_BTN_OUT_B_R_N" )
			)
			( signal "@baseboard_fab2_lib.baseboard_fab2(sch_1):fm_adr_complete_dly"
				( objectStatus "FM_ADR_COMPLETE_DLY" )
			)
			( signal "@baseboard_fab2_lib.baseboard_fab2(sch_1):fan_tach1_cpu1_d1"
				( objectStatus "FAN_TACH1_CPU1_D1" )
			)
			( signal "@baseboard_fab2_lib.baseboard_fab2(sch_1):pwrgd_cpu0_g_r"
				( objectStatus "PWRGD_CPU0_G_R" )
			)
			( signal "@baseboard_fab2_lib.baseboard_fab2(sch_1):fm_pch_pld_data"
				( objectStatus "FM_PCH_PLD_DATA" )
			)
			( signal "@baseboard_fab2_lib.baseboard_fab2(sch_1):irq_pch_nic_alert_n"
				( objectStatus "IRQ_PCH_NIC_ALERT_N" )
			)
			( signal "@baseboard_fab2_lib.baseboard_fab2(sch_1):fm_cpld_dbg_pwr_en_n"
				( objectStatus "FM_CPLD_DBG_PWR_EN_N" )
			)
			( signal "@baseboard_fab2_lib.baseboard_fab2(sch_1):fm_cpld_uart_ch_lock_n"
				( objectStatus "FM_CPLD_UART_CH_LOCK_N" )
			)
			( signal "@baseboard_fab2_lib.baseboard_fab2(sch_1):fm_flash_desc_override"
				( objectStatus "FM_FLASH_DESC_OVERRIDE" )
			)
			( signal "@baseboard_fab2_lib.baseboard_fab2(sch_1):fm_flash_desc_override_r"
				( objectStatus "FM_FLASH_DESC_OVERRIDE_R" )
			)
			( signal "@baseboard_fab2_lib.baseboard_fab2(sch_1):fm_mem_therm_event_pch_n"
				( objectStatus "FM_MEM_THERM_EVENT_PCH_N" )
			)
			( signal "@baseboard_fab2_lib.baseboard_fab2(sch_1):fm_pch_pwrbtn_out_n"
				( objectStatus "FM_PCH_PWRBTN_OUT_N" )
			)
			( signal "@baseboard_fab2_lib.baseboard_fab2(sch_1):clk_24m_bmc_clkin_r"
				( objectStatus "CLK_24M_BMC_CLKIN_R" )
			)
			( signal "@baseboard_fab2_lib.baseboard_fab2(sch_1):fm_p1v8mcp_cpu1_en"
				( objectStatus "FM_P1V8MCP_CPU1_EN" )
			)
			( signal "@baseboard_fab2_lib.baseboard_fab2(sch_1):fm_pvpp_pvddq_cpu0_en_abc"
				( objectStatus "FM_PVPP_PVDDQ_CPU0_EN_ABC" )
			)
			( signal "@baseboard_fab2_lib.baseboard_fab2(sch_1):fm_pvpp_pvddq_cpu0_en_def"
				( objectStatus "FM_PVPP_PVDDQ_CPU0_EN_DEF" )
			)
			( signal "@baseboard_fab2_lib.baseboard_fab2(sch_1):fm_pvpp_pvddq_cpu1_en_ghj"
				( objectStatus "FM_PVPP_PVDDQ_CPU1_EN_GHJ" )
			)
			( signal "@baseboard_fab2_lib.baseboard_fab2(sch_1):fm_pvpp_pvddq_cpu1_en_klm"
				( objectStatus "FM_PVPP_PVDDQ_CPU1_EN_KLM" )
			)
			( signal "@baseboard_fab2_lib.baseboard_fab2(sch_1):fm_thermtrip_dly_r"
				( objectStatus "FM_THERMTRIP_DLY_R" )
			)
			( signal "@baseboard_fab2_lib.baseboard_fab2(sch_1):fm_uart_alert_n"
				( objectStatus "FM_UART_ALERT_N" )
			)
			( signal "@baseboard_fab2_lib.baseboard_fab2(sch_1):fan_tach3_cpu1_d1"
				( objectStatus "FAN_TACH3_CPU1_D1" )
			)
			( signal "@baseboard_fab2_lib.baseboard_fab2(sch_1):fan_tach1_cpu1_d2"
				( objectStatus "FAN_TACH1_CPU1_D2" )
			)
			( signal "@baseboard_fab2_lib.baseboard_fab2(sch_1):fan_tach3_cpu1_d2"
				( objectStatus "FAN_TACH3_CPU1_D2" )
			)
			( signal "@baseboard_fab2_lib.baseboard_fab2(sch_1):nc_pvccin_cpu1_ph4_p31"
				( objectStatus "NC_PVCCIN_CPU1_PH4_P31" )
			)
			( signal "@baseboard_fab2_lib.baseboard_fab2(sch_1):xdp_cpu_tck_buf"
				( objectStatus "XDP_CPU_TCK_BUF" )
			)
			( signal "@baseboard_fab2_lib.baseboard_fab2(sch_1):tp_vr_pvccio_cpu1_mp2"
				( objectStatus "TP_VR_PVCCIO_CPU1_MP2" )
			)
			( signal "@baseboard_fab2_lib.baseboard_fab2(sch_1):nc_pvccin_cpu1_ph5_p31"
				( objectStatus "NC_PVCCIN_CPU1_PH5_P31" )
			)
			( signal "@baseboard_fab2_lib.baseboard_fab2(sch_1):nc_pvsa_cpu1_p31"
				( objectStatus "NC_PVSA_CPU1_P31" )
			)
			( signal "@baseboard_fab2_lib.baseboard_fab2(sch_1):rmii_bmc_ocp_crsdv_r"
				( objectStatus "RMII_BMC_OCP_CRSDV_R" )
			)
			( signal "@baseboard_fab2_lib.baseboard_fab2(sch_1):pu_jtag_sprv_tck"
				( objectStatus "PU_JTAG_SPRV_TCK" )
			)
			( signal "@baseboard_fab2_lib.baseboard_fab2(sch_1):pu_jtag_sprv_tdo"
				( objectStatus "PU_JTAG_SPRV_TDO" )
			)
			( signal "@baseboard_fab2_lib.baseboard_fab2(sch_1):pu_jtag_sprv_tms"
				( objectStatus "PU_JTAG_SPRV_TMS" )
			)
			( signal "@baseboard_fab2_lib.baseboard_fab2(sch_1):pu_jtag_sprv_tdi"
				( objectStatus "PU_JTAG_SPRV_TDI" )
			)
			( signal "@baseboard_fab2_lib.baseboard_fab2(sch_1):smb_host_stby_lvc3_scl_r2"
				( objectStatus "SMB_HOST_STBY_LVC3_SCL_R2" )
			)
			( signal "@baseboard_fab2_lib.baseboard_fab2(sch_1):sgpio_bmc_ld_n"
				( objectStatus "SGPIO_BMC_LD_N" )
			)
			( signal "@baseboard_fab2_lib.baseboard_fab2(sch_1):sgpio_bmc_ld_r_n"
				( objectStatus "SGPIO_BMC_LD_R_N" )
			)
			( signal "@baseboard_fab2_lib.baseboard_fab2(sch_1):fm_pvtt_def_en_r"
				( objectStatus "FM_PVTT_DEF_EN_R" )
			)
			( signal "@baseboard_fab2_lib.baseboard_fab2(sch_1):fm_ssata_pcie_m2_sel"
				( objectStatus "FM_SSATA_PCIE_M2_SEL" )
			)
			( signal "@baseboard_fab2_lib.baseboard_fab2(sch_1):fp_pwr_btn_r1_n"
				( objectStatus "FP_PWR_BTN_R1_N" )
			)
			( signal "@baseboard_fab2_lib.baseboard_fab2(sch_1):fp_rst_btn_r_n"
				( objectStatus "FP_RST_BTN_R_N" )
			)
			( signal "@baseboard_fab2_lib.baseboard_fab2(sch_1):fm_prsnt_2_2_n"
				( objectStatus "FM_PRSNT_2_2_N" )
			)
			( signal "@baseboard_fab2_lib.baseboard_fab2(sch_1):fm_prsnt_2_1_n"
				( objectStatus "FM_PRSNT_2_1_N" )
			)
			( signal "@baseboard_fab2_lib.baseboard_fab2(sch_1):fm_100m_n"
				( objectStatus "FM_100M_N" )
			)
			( signal "@baseboard_fab2_lib.baseboard_fab2(sch_1):fp_nmi_btn_r_n"
				( objectStatus "FP_NMI_BTN_R_N" )
			)
			( signal "@baseboard_fab2_lib.baseboard_fab2(sch_1):sgpio_bmc_clk"
				( objectStatus "SGPIO_BMC_CLK" )
			)
			( signal "@baseboard_fab2_lib.baseboard_fab2(sch_1):sgpio_bmc_clk_r"
				( objectStatus "SGPIO_BMC_CLK_R" )
			)
			( signal "@baseboard_fab2_lib.baseboard_fab2(sch_1):sgpio_pch_sata_clock"
				( objectStatus "SGPIO_PCH_SATA_CLOCK" )
			)
			( signal "@baseboard_fab2_lib.baseboard_fab2(sch_1):sgpio_pch_sata_clock_r"
				( objectStatus "SGPIO_PCH_SATA_CLOCK_R" )
			)
			( signal "@baseboard_fab2_lib.baseboard_fab2(sch_1):sgpio_pch_sata_dout0"
				( objectStatus "SGPIO_PCH_SATA_DOUT0" )
			)
			( signal "@baseboard_fab2_lib.baseboard_fab2(sch_1):sgpio_pch_sata_dout0_r"
				( objectStatus "SGPIO_PCH_SATA_DOUT0_R" )
			)
			( signal "@baseboard_fab2_lib.baseboard_fab2(sch_1):sgpio_pch_sata_load"
				( objectStatus "SGPIO_PCH_SATA_LOAD" )
			)
			( signal "@baseboard_fab2_lib.baseboard_fab2(sch_1):sgpio_pch_sata_load_r"
				( objectStatus "SGPIO_PCH_SATA_LOAD_R" )
			)
			( signal "@baseboard_fab2_lib.baseboard_fab2(sch_1):fm_adr_mode_sel_r"
				( objectStatus "FM_ADR_MODE_SEL_R" )
			)
			( signal "@baseboard_fab2_lib.baseboard_fab2(sch_1):fm_cpld_adr_trigger_r_n"
				( objectStatus "FM_CPLD_ADR_TRIGGER_R_N" )
			)
			( signal "@baseboard_fab2_lib.baseboard_fab2(sch_1):fm_cpu_caterr_dly_lvt3_n"
				( objectStatus "FM_CPU_CATERR_DLY_LVT3_N" )
			)
			( signal "@baseboard_fab2_lib.baseboard_fab2(sch_1):fm_uart_pres_n"
				( objectStatus "FM_UART_PRES_N" )
			)
			( signal "@baseboard_fab2_lib.baseboard_fab2(sch_1):irq_hsc_fault_r_n"
				( objectStatus "IRQ_HSC_FAULT_R_N" )
			)
			( signal "@baseboard_fab2_lib.baseboard_fab2(sch_1):irq_pvccin_cpu0_vrhot_lvc3_r_n"
				( objectStatus "IRQ_PVCCIN_CPU0_VRHOT_LVC3_R_N" )
			)
			( signal "@baseboard_fab2_lib.baseboard_fab2(sch_1):irq_pvccin_cpu1_vrhot_lvc3_r_n"
				( objectStatus "IRQ_PVCCIN_CPU1_VRHOT_LVC3_R_N" )
			)
			( signal "@baseboard_fab2_lib.baseboard_fab2(sch_1):irq_pvddq_abc_vrhot_lvt3_r_n"
				( objectStatus "IRQ_PVDDQ_ABC_VRHOT_LVT3_R_N" )
			)
			( signal "@baseboard_fab2_lib.baseboard_fab2(sch_1):irq_pvddq_def_vrhot_lvt3_r_n"
				( objectStatus "IRQ_PVDDQ_DEF_VRHOT_LVT3_R_N" )
			)
			( signal "@baseboard_fab2_lib.baseboard_fab2(sch_1):irq_pvddq_ghj_vrhot_lvt3_r_n"
				( objectStatus "IRQ_PVDDQ_GHJ_VRHOT_LVT3_R_N" )
			)
			( signal "@baseboard_fab2_lib.baseboard_fab2(sch_1):irq_pvddq_klm_vrhot_lvt3_r_n"
				( objectStatus "IRQ_PVDDQ_KLM_VRHOT_LVT3_R_N" )
			)
			( signal "@baseboard_fab2_lib.baseboard_fab2(sch_1):irq_sml1_pmbus_alert_r_n"
				( objectStatus "IRQ_SML1_PMBUS_ALERT_R_N" )
			)
			( signal "@baseboard_fab2_lib.baseboard_fab2(sch_1):irq_vm_int_r_n"
				( objectStatus "IRQ_VM_INT_R_N" )
			)
			( signal "@baseboard_fab2_lib.baseboard_fab2(sch_1):tp_vr_pvccio_cpu1_mp3"
				( objectStatus "TP_VR_PVCCIO_CPU1_MP3" )
			)
			( signal "@baseboard_fab2_lib.baseboard_fab2(sch_1):vid_pch_core_pvnn_aux_vid_0"
				( objectStatus "VID_PCH_CORE_PVNN_AUX_VID_0" )
			)
			( signal "@baseboard_fab2_lib.baseboard_fab2(sch_1):fm_uart_sel_n"
				( objectStatus "FM_UART_SEL_N" )
			)
			( signal "@baseboard_fab2_lib.baseboard_fab2(sch_1):fp_pwr_btn_r_n"
				( objectStatus "FP_PWR_BTN_R_N" )
			)
			( signal "@baseboard_fab2_lib.baseboard_fab2(sch_1):fm_uart_switch_n"
				( objectStatus "FM_UART_SWITCH_N" )
			)
			( signal "@baseboard_fab2_lib.baseboard_fab2(sch_1):fm_bios_top_swap"
				( objectStatus "FM_BIOS_TOP_SWAP" )
			)
			( signal "@baseboard_fab2_lib.baseboard_fab2(sch_1):fm_bios_top_swap_spkr"
				( objectStatus "FM_BIOS_TOP_SWAP_SPKR" )
			)
			( signal "@baseboard_fab2_lib.baseboard_fab2(sch_1):fm_bios_top_swap_spkr_r"
				( objectStatus "FM_BIOS_TOP_SWAP_SPKR_R" )
			)
			( signal "@baseboard_fab2_lib.baseboard_fab2(sch_1):fm_fast_prochot_en_n"
				( objectStatus "FM_FAST_PROCHOT_EN_N" )
			)
			( signal "@baseboard_fab2_lib.baseboard_fab2(sch_1):fm_pch_bmc_thermtrip_n"
				( objectStatus "FM_PCH_BMC_THERMTRIP_N" )
			)
			( signal "@baseboard_fab2_lib.baseboard_fab2(sch_1):fm_pmbus_alert_buf_en_n"
				( objectStatus "FM_PMBUS_ALERT_BUF_EN_N" )
			)
			( signal "@baseboard_fab2_lib.baseboard_fab2(sch_1):fm_pwr_led"
				( objectStatus "FM_PWR_LED" )
			)
			( signal "@baseboard_fab2_lib.baseboard_fab2(sch_1):fm_pwr_led_a"
				( objectStatus "FM_PWR_LED_A" )
			)
			( signal "@baseboard_fab2_lib.baseboard_fab2(sch_1):fm_pwr_led_k"
				( objectStatus "FM_PWR_LED_K" )
			)
			( signal "@baseboard_fab2_lib.baseboard_fab2(sch_1):fm_pwr_led_n"
				( objectStatus "FM_PWR_LED_N" )
			)
			( signal "@baseboard_fab2_lib.baseboard_fab2(sch_1):fm_slt_cfg0"
				( objectStatus "FM_SLT_CFG0" )
			)
			( signal "@baseboard_fab2_lib.baseboard_fab2(sch_1):fm_slt_cfg1"
				( objectStatus "FM_SLT_CFG1" )
			)
			( signal "@baseboard_fab2_lib.baseboard_fab2(sch_1):fm_slt_cfg2_r"
				( objectStatus "FM_SLT_CFG2_R" )
			)
			( signal "@baseboard_fab2_lib.baseboard_fab2(sch_1):fm_1gb_lom_disable_n"
				( objectStatus "FM_1GB_LOM_DISABLE_N" )
			)
			( signal "@baseboard_fab2_lib.baseboard_fab2(sch_1):fm_bb_bmc_mp_gpio"
				( objectStatus "FM_BB_BMC_MP_GPIO" )
			)
			( signal "@baseboard_fab2_lib.baseboard_fab2(sch_1):irq_bmc_pch_nmi_stby_r_n"
				( objectStatus "IRQ_BMC_PCH_NMI_STBY_R_N" )
			)
			( signal "@baseboard_fab2_lib.baseboard_fab2(sch_1):fm_pvtt_abc_en_r"
				( objectStatus "FM_PVTT_ABC_EN_R" )
			)
			( signal "@baseboard_fab2_lib.baseboard_fab2(sch_1):jtag_mcp_trst_n"
				( objectStatus "JTAG_MCP_TRST_N" )
			)
			( signal "@baseboard_fab2_lib.baseboard_fab2(sch_1):fm_bmc_cpu_init_n"
				( objectStatus "FM_BMC_CPU_INIT_N" )
			)
			( signal "@baseboard_fab2_lib.baseboard_fab2(sch_1):fan_pwm_out_sys0"
				( objectStatus "FAN_PWM_OUT_SYS0" )
			)
			( signal "@baseboard_fab2_lib.baseboard_fab2(sch_1):fan_pwm_out_sys1"
				( objectStatus "FAN_PWM_OUT_SYS1" )
			)
			( signal "@baseboard_fab2_lib.baseboard_fab2(sch_1):fm_cpld_bmc_pwrdn_n"
				( objectStatus "FM_CPLD_BMC_PWRDN_N" )
			)
			( signal "@baseboard_fab2_lib.baseboard_fab2(sch_1):fp_id_led_p5v_stby_n"
				( objectStatus "FP_ID_LED_P5V_STBY_N" )
			)
			( signal "@baseboard_fab2_lib.baseboard_fab2(sch_1):fp_nmi_btn"
				( objectStatus "FP_NMI_BTN" )
			)
			( signal "@baseboard_fab2_lib.baseboard_fab2(sch_1):fp_nmi_btn_out_n"
				( objectStatus "FP_NMI_BTN_OUT_N" )
			)
			( signal "@baseboard_fab2_lib.baseboard_fab2(sch_1):fp_nmi_btn_out_r_n"
				( objectStatus "FP_NMI_BTN_OUT_R_N" )
			)
			( signal "@baseboard_fab2_lib.baseboard_fab2(sch_1):pwrgd_pvccio_cpu0_r"
				( objectStatus "PWRGD_PVCCIO_CPU0_R" )
			)
			( signal "@baseboard_fab2_lib.baseboard_fab2(sch_1):pwrgd_pvsa_cpu0_r"
				( objectStatus "PWRGD_PVSA_CPU0_R" )
			)
			( signal "@baseboard_fab2_lib.baseboard_fab2(sch_1):pwrgd_pvsa_cpu1_r"
				( objectStatus "PWRGD_PVSA_CPU1_R" )
			)
			( signal "@baseboard_fab2_lib.baseboard_fab2(sch_1):pwrgd_pvtt_abc_cpu0_r"
				( objectStatus "PWRGD_PVTT_ABC_CPU0_R" )
			)
			( signal "@baseboard_fab2_lib.baseboard_fab2(sch_1):pwrgd_pvtt_def_cpu0_r"
				( objectStatus "PWRGD_PVTT_DEF_CPU0_R" )
			)
			( signal "@baseboard_fab2_lib.baseboard_fab2(sch_1):pwrgd_pvtt_ghj_cpu1_r"
				( objectStatus "PWRGD_PVTT_GHJ_CPU1_R" )
			)
			( signal "@baseboard_fab2_lib.baseboard_fab2(sch_1):pwrgd_pvtt_klm_cpu1_r"
				( objectStatus "PWRGD_PVTT_KLM_CPU1_R" )
			)
			( signal "@baseboard_fab2_lib.baseboard_fab2(sch_1):irq_lvc3_wake_r_n"
				( objectStatus "IRQ_LVC3_WAKE_R_N" )
			)
			( signal "@baseboard_fab2_lib.baseboard_fab2(sch_1):fm_prsnt_2_6_n"
				( objectStatus "FM_PRSNT_2_6_N" )
			)
			( signal "@baseboard_fab2_lib.baseboard_fab2(sch_1):irq_lpc_serirq_r"
				( objectStatus "IRQ_LPC_SERIRQ_R" )
			)
			( signal "@baseboard_fab2_lib.baseboard_fab2(sch_1):vid_pch_core_pvnn_aux_vid_1"
				( objectStatus "VID_PCH_CORE_PVNN_AUX_VID_1" )
			)
			( signal "@baseboard_fab2_lib.baseboard_fab2(sch_1):pwrgd_p12v_r"
				( objectStatus "PWRGD_P12V_R" )
			)
			( signal "@baseboard_fab2_lib.baseboard_fab2(sch_1):fm_prsnt_2_3_n"
				( objectStatus "FM_PRSNT_2_3_N" )
			)
			( signal "@baseboard_fab2_lib.baseboard_fab2(sch_1):fm_prsnt_2_4_n"
				( objectStatus "FM_PRSNT_2_4_N" )
			)
			( signal "@baseboard_fab2_lib.baseboard_fab2(sch_1):fm_prsnt_2_5_n"
				( objectStatus "FM_PRSNT_2_5_N" )
			)
			( signal "@baseboard_fab2_lib.baseboard_fab2(sch_1):irq_force_nm_throttle_n"
				( objectStatus "IRQ_FORCE_NM_THROTTLE_N" )
			)
			( signal "@baseboard_fab2_lib.baseboard_fab2(sch_1):xtal_24mhz_in_r"
				( objectStatus "XTAL_24MHZ_IN_R" )
			)
			( signal "@baseboard_fab2_lib.baseboard_fab2(sch_1):irq_pirqa_spi_tpm_n"
				( objectStatus "IRQ_PIRQA_SPI_TPM_N" )
			)
			( signal "@baseboard_fab2_lib.baseboard_fab2(sch_1):xtal_24mhz_out_r"
				( objectStatus "XTAL_24MHZ_OUT_R" )
			)
			( signal "@baseboard_fab2_lib.baseboard_fab2(sch_1):xtal_24mhz_pi7c9x1172_in"
				( objectStatus "XTAL_24MHZ_PI7C9X1172_IN" )
			)
			( signal "@baseboard_fab2_lib.baseboard_fab2(sch_1):irq_spi_tpm_n_r"
				( objectStatus "IRQ_SPI_TPM_N_R" )
			)
			( signal "@baseboard_fab2_lib.baseboard_fab2(sch_1):xtal_24mhz_pi7c9x1172_out"
				( objectStatus "XTAL_24MHZ_PI7C9X1172_OUT" )
			)
			( signal "@baseboard_fab2_lib.baseboard_fab2(sch_1):smb_host_stby_lvc3_scl"
				( objectStatus "SMB_HOST_STBY_LVC3_SCL" )
			)
			( signal "@baseboard_fab2_lib.baseboard_fab2(sch_1):smb_host_stby_lvc3_scl_r1"
				( objectStatus "SMB_HOST_STBY_LVC3_SCL_R1" )
			)
			( signal "@baseboard_fab2_lib.baseboard_fab2(sch_1):smb_host_stby_lvc3_sda"
				( objectStatus "SMB_HOST_STBY_LVC3_SDA" )
			)
			( signal "@baseboard_fab2_lib.baseboard_fab2(sch_1):smb_host_stby_lvc3_sda_r1"
				( objectStatus "SMB_HOST_STBY_LVC3_SDA_R1" )
			)
			( signal "@baseboard_fab2_lib.baseboard_fab2(sch_1):fm_fast_prochot_and_out_0_n"
				( objectStatus "FM_FAST_PROCHOT_AND_OUT_0_N" )
			)
			( signal "@baseboard_fab2_lib.baseboard_fab2(sch_1):fm_fast_prochot_throttle_dly_buf_n"
				( objectStatus "FM_FAST_PROCHOT_THROTTLE_DLY_BU" )
			)
			( signal "@baseboard_fab2_lib.baseboard_fab2(sch_1):fm_fast_prochot_throttle_dly_n"
				( objectStatus "FM_FAST_PROCHOT_THROTTLE_DLY_N" )
			)
			( signal "@baseboard_fab2_lib.baseboard_fab2(sch_1):fm_slp_sus_n"
				( objectStatus "FM_SLP_SUS_N" )
			)
			( signal "@baseboard_fab2_lib.baseboard_fab2(sch_1):fm_ie_disable_n"
				( objectStatus "FM_IE_DISABLE_N" )
			)
			( signal "@baseboard_fab2_lib.baseboard_fab2(sch_1):fm_sol_uart_ch_sel"
				( objectStatus "FM_SOL_UART_CH_SEL" )
			)
			( signal "@baseboard_fab2_lib.baseboard_fab2(sch_1):fm_sys_throttle_lvc3"
				( objectStatus "FM_SYS_THROTTLE_LVC3" )
			)
			( signal "@baseboard_fab2_lib.baseboard_fab2(sch_1):fm_mp_ps_fail_n"
				( objectStatus "FM_MP_PS_FAIL_N" )
			)
			( signal "@baseboard_fab2_lib.baseboard_fab2(sch_1):fm_thermtrip_dly"
				( objectStatus "FM_THERMTRIP_DLY" )
			)
			( signal "@baseboard_fab2_lib.baseboard_fab2(sch_1):fm_fast_prochot_and_out_1_n"
				( objectStatus "FM_FAST_PROCHOT_AND_OUT_1_N" )
			)
			( signal "@baseboard_fab2_lib.baseboard_fab2(sch_1):fm_throttle_n"
				( objectStatus "FM_THROTTLE_N" )
			)
			( signal "@baseboard_fab2_lib.baseboard_fab2(sch_1):fm_tpm_pres_n"
				( objectStatus "FM_TPM_PRES_N" )
			)
			( signal "@baseboard_fab2_lib.baseboard_fab2(sch_1):pwrgd_p5v_stby_r"
				( objectStatus "PWRGD_P5V_STBY_R" )
			)
			( signal "@baseboard_fab2_lib.baseboard_fab2(sch_1):fm_oc0_usb_n"
				( objectStatus "FM_OC0_USB_N" )
			)
			( signal "@baseboard_fab2_lib.baseboard_fab2(sch_1):fm_uv_adr_trigger_en"
				( objectStatus "FM_UV_ADR_TRIGGER_EN" )
			)
			( signal "@baseboard_fab2_lib.baseboard_fab2(sch_1):pwrgd_pvtt_cpu0"
				( objectStatus "PWRGD_PVTT_CPU0" )
			)
			( signal "@baseboard_fab2_lib.baseboard_fab2(sch_1):fm_xrc_present_n"
				( objectStatus "FM_XRC_PRESENT_N" )
			)
			( signal "@baseboard_fab2_lib.baseboard_fab2(sch_1):fm_xrc_ready_n"
				( objectStatus "FM_XRC_READY_N" )
			)
			( signal "@baseboard_fab2_lib.baseboard_fab2(sch_1):fm_10gbe_lom_disable_n"
				( objectStatus "FM_10GBE_LOM_DISABLE_N" )
			)
			( signal "@baseboard_fab2_lib.baseboard_fab2(sch_1):fm_roma(0)"
				( objectStatus "FM_ROMA<0>" )
			)
			( signal "@baseboard_fab2_lib.baseboard_fab2(sch_1):fm_roma(1)"
				( objectStatus "FM_ROMA<1>" )
			)
			( signal "@baseboard_fab2_lib.baseboard_fab2(sch_1):fm_roma(2)"
				( objectStatus "FM_ROMA<2>" )
			)
			( signal "@baseboard_fab2_lib.baseboard_fab2(sch_1):fm_roma(3)"
				( objectStatus "FM_ROMA<3>" )
			)
			( signal "@baseboard_fab2_lib.baseboard_fab2(sch_1):fm_roma(4)"
				( objectStatus "FM_ROMA<4>" )
			)
			( signal "@baseboard_fab2_lib.baseboard_fab2(sch_1):fm_roma(5)"
				( objectStatus "FM_ROMA<5>" )
			)
			( signal "@baseboard_fab2_lib.baseboard_fab2(sch_1):fm_roma(6)"
				( objectStatus "FM_ROMA<6>" )
			)
			( signal "@baseboard_fab2_lib.baseboard_fab2(sch_1):fm_roma(7)"
				( objectStatus "FM_ROMA<7>" )
			)
			( signal "@baseboard_fab2_lib.baseboard_fab2(sch_1):fm_roma(8)"
				( objectStatus "FM_ROMA<8>" )
			)
			( signal "@baseboard_fab2_lib.baseboard_fab2(sch_1):fm_roma(9)"
				( objectStatus "FM_ROMA<9>" )
			)
			( signal "@baseboard_fab2_lib.baseboard_fab2(sch_1):fm_roma(10)"
				( objectStatus "FM_ROMA<10>" )
			)
			( signal "@baseboard_fab2_lib.baseboard_fab2(sch_1):fm_roma(11)"
				( objectStatus "FM_ROMA<11>" )
			)
			( signal "@baseboard_fab2_lib.baseboard_fab2(sch_1):fm_roma(12)"
				( objectStatus "FM_ROMA<12>" )
			)
			( signal "@baseboard_fab2_lib.baseboard_fab2(sch_1):fm_roma(13)"
				( objectStatus "FM_ROMA<13>" )
			)
			( signal "@baseboard_fab2_lib.baseboard_fab2(sch_1):fm_roma(14)"
				( objectStatus "FM_ROMA<14>" )
			)
			( signal "@baseboard_fab2_lib.baseboard_fab2(sch_1):fm_roma(15)"
				( objectStatus "FM_ROMA<15>" )
			)
			( signal "@baseboard_fab2_lib.baseboard_fab2(sch_1):fm_roma(16)"
				( objectStatus "FM_ROMA<16>" )
			)
			( signal "@baseboard_fab2_lib.baseboard_fab2(sch_1):fm_roma(17)"
				( objectStatus "FM_ROMA<17>" )
			)
			( signal "@baseboard_fab2_lib.baseboard_fab2(sch_1):fm_roma(18)"
				( objectStatus "FM_ROMA<18>" )
			)
			( signal "@baseboard_fab2_lib.baseboard_fab2(sch_1):fm_roma(19)"
				( objectStatus "FM_ROMA<19>" )
			)
			( signal "@baseboard_fab2_lib.baseboard_fab2(sch_1):fm_roma(20)"
				( objectStatus "FM_ROMA<20>" )
			)
			( signal "@baseboard_fab2_lib.baseboard_fab2(sch_1):fm_roma(21)"
				( objectStatus "FM_ROMA<21>" )
			)
			( signal "@baseboard_fab2_lib.baseboard_fab2(sch_1):fm_roma(22)"
				( objectStatus "FM_ROMA<22>" )
			)
			( signal "@baseboard_fab2_lib.baseboard_fab2(sch_1):fm_roma(23)"
				( objectStatus "FM_ROMA<23>" )
			)
			( signal "@baseboard_fab2_lib.baseboard_fab2(sch_1):pwrgd_p3v3_r1"
				( objectStatus "PWRGD_P3V3_R1" )
			)
			( signal "@baseboard_fab2_lib.baseboard_fab2(sch_1):pwrgd_p5v"
				( objectStatus "PWRGD_P5V" )
			)
			( signal "@baseboard_fab2_lib.baseboard_fab2(sch_1):pwrgd_p5v_r"
				( objectStatus "PWRGD_P5V_R" )
			)
			( signal "@baseboard_fab2_lib.baseboard_fab2(sch_1):pwrgd_p12v_hsc_dly"
				( objectStatus "PWRGD_P12V_HSC_DLY" )
			)
			( signal "@baseboard_fab2_lib.baseboard_fab2(sch_1):pwrgd_p12v_hsc_dly_r"
				( objectStatus "PWRGD_P12V_HSC_DLY_R" )
			)
			( signal "@baseboard_fab2_lib.baseboard_fab2(sch_1):irq_board_bmc_alert_n"
				( objectStatus "IRQ_BOARD_BMC_ALERT_N" )
			)
			( signal "@baseboard_fab2_lib.baseboard_fab2(sch_1):fm_jtag_pld_en_debug"
				( objectStatus "FM_JTAG_PLD_EN_DEBUG" )
			)
			( signal "@baseboard_fab2_lib.baseboard_fab2(sch_1):fm_modprst_hfi0_cpu0_lvt2_n"
				( objectStatus "FM_MODPRST_HFI0_CPU0_LVT2_N" )
			)
			( signal "@baseboard_fab2_lib.baseboard_fab2(sch_1):fm_oc_detect_n"
				( objectStatus "FM_OC_DETECT_N" )
			)
			( signal "@baseboard_fab2_lib.baseboard_fab2(sch_1):fm_db1200_pwrgd"
				( objectStatus "FM_DB1200_PWRGD" )
			)
			( signal "@baseboard_fab2_lib.baseboard_fab2(sch_1):pwrgd_pvtt_cpu1"
				( objectStatus "PWRGD_PVTT_CPU1" )
			)
			( signal "@baseboard_fab2_lib.baseboard_fab2(sch_1):fm_bmc_cpld_gpo"
				( objectStatus "FM_BMC_CPLD_GPO" )
			)
			( signal "@baseboard_fab2_lib.baseboard_fab2(sch_1):fm_fast_prochot_throttle_in_n"
				( objectStatus "FM_FAST_PROCHOT_THROTTLE_IN_N" )
			)
			( signal "@baseboard_fab2_lib.baseboard_fab2(sch_1):fm_speaker_pch_n"
				( objectStatus "FM_SPEAKER_PCH_N" )
			)
			( signal "@baseboard_fab2_lib.baseboard_fab2(sch_1):fp_id_led_xor_r"
				( objectStatus "FP_ID_LED_XOR_R" )
			)
			( signal "@baseboard_fab2_lib.baseboard_fab2(sch_1):fm_bmc_fault_led_n"
				( objectStatus "FM_BMC_FAULT_LED_N" )
			)
			( signal "@baseboard_fab2_lib.baseboard_fab2(sch_1):fp_nmi_btn_n"
				( objectStatus "FP_NMI_BTN_N" )
			)
			( signal "@baseboard_fab2_lib.baseboard_fab2(sch_1):fp_pwr_btn_buf1_n"
				( objectStatus "FP_PWR_BTN_BUF1_N" )
			)
			( signal "@baseboard_fab2_lib.baseboard_fab2(sch_1):fp_pwr_id_led_n"
				( objectStatus "FP_PWR_ID_LED_N" )
			)
			( signal "@baseboard_fab2_lib.baseboard_fab2(sch_1):fm_modprst_hfi1_cpu0_lvt2_n"
				( objectStatus "FM_MODPRST_HFI1_CPU0_LVT2_N" )
			)
			( signal "@baseboard_fab2_lib.baseboard_fab2(sch_1):led_gbe_p3_1"
				( objectStatus "LED_GBE_P3_1" )
			)
			( signal "@baseboard_fab2_lib.baseboard_fab2(sch_1):fp_rst_btn_buf1_n"
				( objectStatus "FP_RST_BTN_BUF1_N" )
			)
			( signal "@baseboard_fab2_lib.baseboard_fab2(sch_1):fm_hsc_timer_exp_n"
				( objectStatus "FM_HSC_TIMER_EXP_N" )
			)
			( signal "@baseboard_fab2_lib.baseboard_fab2(sch_1):fm_intruder_hdr_pch_n"
				( objectStatus "FM_INTRUDER_HDR_PCH_N" )
			)
			( signal "@baseboard_fab2_lib.baseboard_fab2(sch_1):fm_mated_in_d1_n"
				( objectStatus "FM_MATED_IN_D1_N" )
			)
			( signal "@baseboard_fab2_lib.baseboard_fab2(sch_1):fm_mated_in_d2_n"
				( objectStatus "FM_MATED_IN_D2_N" )
			)
			( signal "@baseboard_fab2_lib.baseboard_fab2(sch_1):fm_mated_in_n"
				( objectStatus "FM_MATED_IN_N" )
			)
			( signal "@baseboard_fab2_lib.baseboard_fab2(sch_1):fm_mb_slot_id0"
				( objectStatus "FM_MB_SLOT_ID0" )
			)
			( signal "@baseboard_fab2_lib.baseboard_fab2(sch_1):fm_mb_slot_id1"
				( objectStatus "FM_MB_SLOT_ID1" )
			)
			( signal "@baseboard_fab2_lib.baseboard_fab2(sch_1):fm_mb_slot_id2"
				( objectStatus "FM_MB_SLOT_ID2" )
			)
			( signal "@baseboard_fab2_lib.baseboard_fab2(sch_1):vr_pvccio_cpu0_ocset"
				( objectStatus "VR_PVCCIO_CPU0_OCSET" )
			)
			( signal "@baseboard_fab2_lib.baseboard_fab2(sch_1):fm_mezz_prsntb1_n"
				( objectStatus "FM_MEZZ_PRSNTB1_N" )
			)
			( signal "@baseboard_fab2_lib.baseboard_fab2(sch_1):fm_mezza_prsnt1_n"
				( objectStatus "FM_MEZZA_PRSNT1_N" )
			)
			( signal "@baseboard_fab2_lib.baseboard_fab2(sch_1):fm_me_recover_n"
				( objectStatus "FM_ME_RECOVER_N" )
			)
			( signal "@baseboard_fab2_lib.baseboard_fab2(sch_1):fm_cpu0_and_cpu1_mcp_pres"
				( objectStatus "FM_CPU0_AND_CPU1_MCP_PRES" )
			)
			( signal "@baseboard_fab2_lib.baseboard_fab2(sch_1):fm_m2_ssd_pedet"
				( objectStatus "FM_M2_SSD_PEDET" )
			)
			( signal "@baseboard_fab2_lib.baseboard_fab2(sch_1):fm_ocp_mezza_pres_n"
				( objectStatus "FM_OCP_MEZZA_PRES_N" )
			)
			( signal "@baseboard_fab2_lib.baseboard_fab2(sch_1):fm_oc_detect_en"
				( objectStatus "FM_OC_DETECT_EN" )
			)
			( signal "@baseboard_fab2_lib.baseboard_fab2(sch_1):fm_password_clear_n"
				( objectStatus "FM_PASSWORD_CLEAR_N" )
			)
			( signal "@baseboard_fab2_lib.baseboard_fab2(sch_1):fm_pch_lvc1_thermtrip_n"
				( objectStatus "FM_PCH_LVC1_THERMTRIP_N" )
			)
			( signal "@baseboard_fab2_lib.baseboard_fab2(sch_1):fm_pch_prsnt_n"
				( objectStatus "FM_PCH_PRSNT_N" )
			)
			( signal "@baseboard_fab2_lib.baseboard_fab2(sch_1):fm_pch_pwrbtn_n"
				( objectStatus "FM_PCH_PWRBTN_N" )
			)
			( signal "@baseboard_fab2_lib.baseboard_fab2(sch_1):fm_wbg_prsnt_n"
				( objectStatus "FM_WBG_PRSNT_N" )
			)
			( signal "@baseboard_fab2_lib.baseboard_fab2(sch_1):rst_hfi0_cpu0_lvt2_n"
				( objectStatus "RST_HFI0_CPU0_LVT2_N" )
			)
			( signal "@baseboard_fab2_lib.baseboard_fab2(sch_1):fm_pld_debug_mode_n"
				( objectStatus "FM_PLD_DEBUG_MODE_N" )
			)
			( signal "@baseboard_fab2_lib.baseboard_fab2(sch_1):fm_pmbus_alert_buf_en"
				( objectStatus "FM_PMBUS_ALERT_BUF_EN" )
			)
			( signal "@baseboard_fab2_lib.baseboard_fab2(sch_1):fm_post_card_pres_bmc_n"
				( objectStatus "FM_POST_CARD_PRES_BMC_N" )
			)
			( signal "@baseboard_fab2_lib.baseboard_fab2(sch_1):fm_ps_en"
				( objectStatus "FM_PS_EN" )
			)
			( signal "@baseboard_fab2_lib.baseboard_fab2(sch_1):fm_adr_mode_sel"
				( objectStatus "FM_ADR_MODE_SEL" )
			)
			( signal "@baseboard_fab2_lib.baseboard_fab2(sch_1):fm_pvccin_cpu0_pwr_in_alert_n"
				( objectStatus "FM_PVCCIN_CPU0_PWR_IN_ALERT_N" )
			)
			( signal "@baseboard_fab2_lib.baseboard_fab2(sch_1):fm_pvccin_cpu1_pwr_in_alert_n"
				( objectStatus "FM_PVCCIN_CPU1_PWR_IN_ALERT_N" )
			)
			( signal "@baseboard_fab2_lib.baseboard_fab2(sch_1):fm_pvccio_cpu0_en"
				( objectStatus "FM_PVCCIO_CPU0_EN" )
			)
			( signal "@baseboard_fab2_lib.baseboard_fab2(sch_1):fm_pvccio_cpu1_en"
				( objectStatus "FM_PVCCIO_CPU1_EN" )
			)
			( signal "@baseboard_fab2_lib.baseboard_fab2(sch_1):clk_24m_25m_bmc_clkin"
				( objectStatus "CLK_24M_25M_BMC_CLKIN" )
			)
			( signal "@baseboard_fab2_lib.baseboard_fab2(sch_1):fm_pvccmcp_cpu1_en"
				( objectStatus "FM_PVCCMCP_CPU1_EN" )
			)
			( signal "@baseboard_fab2_lib.baseboard_fab2(sch_1):fm_cpld_adr_trigger_n"
				( objectStatus "FM_CPLD_ADR_TRIGGER_N" )
			)
			( signal "@baseboard_fab2_lib.baseboard_fab2(sch_1):fm_p3v3_cpld_en"
				( objectStatus "FM_P3V3_CPLD_EN" )
			)
			( signal "@baseboard_fab2_lib.baseboard_fab2(sch_1):fm_mp_ps_redundant_lost_n"
				( objectStatus "FM_MP_PS_REDUNDANT_LOST_N" )
			)
			( signal "@baseboard_fab2_lib.baseboard_fab2(sch_1):fm_cpu0_cd_pres"
				( objectStatus "FM_CPU0_CD_PRES" )
			)
			( signal "@baseboard_fab2_lib.baseboard_fab2(sch_1):fm_p12v_hotswap0_en"
				( objectStatus "FM_P12V_HOTSWAP0_EN" )
			)
			( signal "@baseboard_fab2_lib.baseboard_fab2(sch_1):fm_p12v_hsc_adr1"
				( objectStatus "FM_P12V_HSC_ADR1" )
			)
			( signal "@baseboard_fab2_lib.baseboard_fab2(sch_1):fm_p12v_hsc_adr2"
				( objectStatus "FM_P12V_HSC_ADR2" )
			)
			( signal "@baseboard_fab2_lib.baseboard_fab2(sch_1):fm_p12v_main_sw_en"
				( objectStatus "FM_P12V_MAIN_SW_EN" )
			)
			( signal "@baseboard_fab2_lib.baseboard_fab2(sch_1):fm_qat_en_n"
				( objectStatus "FM_QAT_EN_N" )
			)
			( signal "@baseboard_fab2_lib.baseboard_fab2(sch_1):fm_slps3_n"
				( objectStatus "FM_SLPS3_N" )
			)
			( signal "@baseboard_fab2_lib.baseboard_fab2(sch_1):fm_slps4_n"
				( objectStatus "FM_SLPS4_N" )
			)
			( signal "@baseboard_fab2_lib.baseboard_fab2(sch_1):pwrgd_p12v_main"
				( objectStatus "PWRGD_P12V_MAIN" )
			)
			( signal "@baseboard_fab2_lib.baseboard_fab2(sch_1):pd_cpu0_rsvd_test_1"
				( objectStatus "PD_CPU0_RSVD_TEST_1" )
			)
			( signal "@baseboard_fab2_lib.baseboard_fab2(sch_1):pd_cpu0_rsvd_test_2"
				( objectStatus "PD_CPU0_RSVD_TEST_2" )
			)
			( signal "@baseboard_fab2_lib.baseboard_fab2(sch_1):tp_cpu0_rsvd_test_4"
				( objectStatus "TP_CPU0_RSVD_TEST_4" )
			)
			( signal "@baseboard_fab2_lib.baseboard_fab2(sch_1):tp_cpu1_rsvd_test_3"
				( objectStatus "TP_CPU1_RSVD_TEST_3" )
			)
			( signal "@baseboard_fab2_lib.baseboard_fab2(sch_1):pd_cpu1_rsvd_test_1"
				( objectStatus "PD_CPU1_RSVD_TEST_1" )
			)
			( signal "@baseboard_fab2_lib.baseboard_fab2(sch_1):pd_cpu1_rsvd_test_2"
				( objectStatus "PD_CPU1_RSVD_TEST_2" )
			)
			( signal "@baseboard_fab2_lib.baseboard_fab2(sch_1):tp_cpu1_rsvd_test_4"
				( objectStatus "TP_CPU1_RSVD_TEST_4" )
			)
			( signal "@baseboard_fab2_lib.baseboard_fab2(sch_1):xdp_pch_pwr_debug_n"
				( objectStatus "XDP_PCH_PWR_DEBUG_N" )
			)
			( signal "@baseboard_fab2_lib.baseboard_fab2(sch_1):fm_pch_pwrbtn_r_n"
				( objectStatus "FM_PCH_PWRBTN_R_N" )
			)
			( signal "@baseboard_fab2_lib.baseboard_fab2(sch_1):irq_force_nm_throttle_r_n"
				( objectStatus "IRQ_FORCE_NM_THROTTLE_R_N" )
			)
			( signal "@baseboard_fab2_lib.baseboard_fab2(sch_1):rst_bmc_srst_r2_n"
				( objectStatus "RST_BMC_SRST_R2_N" )
			)
			( signal "@baseboard_fab2_lib.baseboard_fab2(sch_1):smb_host_stby_lvc3_sda_r2"
				( objectStatus "SMB_HOST_STBY_LVC3_SDA_R2" )
			)
			( signal "@baseboard_fab2_lib.baseboard_fab2(sch_1):smb_sensor_stby_lvc3_scl_r2"
				( objectStatus "SMB_SENSOR_STBY_LVC3_SCL_R2" )
			)
			( signal "@baseboard_fab2_lib.baseboard_fab2(sch_1):smb_sensor_stby_lvc3_sda_r2"
				( objectStatus "SMB_SENSOR_STBY_LVC3_SDA_R2" )
			)
			( signal "@baseboard_fab2_lib.baseboard_fab2(sch_1):fm_uartsw_lsb_n"
				( objectStatus "FM_UARTSW_LSB_N" )
			)
			( signal "@baseboard_fab2_lib.baseboard_fab2(sch_1):fm_uartsw_lsb_r_n"
				( objectStatus "FM_UARTSW_LSB_R_N" )
			)
			( signal "@baseboard_fab2_lib.baseboard_fab2(sch_1):fm_pi7c9x1172_a0"
				( objectStatus "FM_PI7C9X1172_A0" )
			)
			( signal "@baseboard_fab2_lib.baseboard_fab2(sch_1):rst_bmc_sysrst_btn_out_b_n"
				( objectStatus "RST_BMC_SYSRST_BTN_OUT_B_N" )
			)
			( signal "@baseboard_fab2_lib.baseboard_fab2(sch_1):rst_cd_cpu0_por_n"
				( objectStatus "RST_CD_CPU0_POR_N" )
			)
			( signal "@baseboard_fab2_lib.baseboard_fab2(sch_1):rst_cd_cpu1_por_n"
				( objectStatus "RST_CD_CPU1_POR_N" )
			)
			( signal "@baseboard_fab2_lib.baseboard_fab2(sch_1):fm_uartsw_msb_n"
				( objectStatus "FM_UARTSW_MSB_N" )
			)
			( signal "@baseboard_fab2_lib.baseboard_fab2(sch_1):fm_uartsw_msb_r_n"
				( objectStatus "FM_UARTSW_MSB_R_N" )
			)
			( signal "@baseboard_fab2_lib.baseboard_fab2(sch_1):fm_pe_bmc_wake_n"
				( objectStatus "FM_PE_BMC_WAKE_N" )
			)
			( signal "@baseboard_fab2_lib.baseboard_fab2(sch_1):fm_pe_m2_wake_n"
				( objectStatus "FM_PE_M2_WAKE_N" )
			)
			( signal "@baseboard_fab2_lib.baseboard_fab2(sch_1):fm_pe_ocp_wake_n"
				( objectStatus "FM_PE_OCP_WAKE_N" )
			)
			( signal "@baseboard_fab2_lib.baseboard_fab2(sch_1):fm_pe_slotx24_wake_n"
				( objectStatus "FM_PE_SLOTX24_WAKE_N" )
			)
			( signal "@baseboard_fab2_lib.baseboard_fab2(sch_1):fm_pe_sprv_wake_n"
				( objectStatus "FM_PE_SPRV_WAKE_N" )
			)
			( signal "@baseboard_fab2_lib.baseboard_fab2(sch_1):fm_adc128_a0"
				( objectStatus "FM_ADC128_A0" )
			)
			( signal "@baseboard_fab2_lib.baseboard_fab2(sch_1):fm_adc128_a1"
				( objectStatus "FM_ADC128_A1" )
			)
			( signal "@baseboard_fab2_lib.baseboard_fab2(sch_1):fm_adr_complete"
				( objectStatus "FM_ADR_COMPLETE" )
			)
			( signal "@baseboard_fab2_lib.baseboard_fab2(sch_1):fm_adr_smi_gpio_n"
				( objectStatus "FM_ADR_SMI_GPIO_N" )
			)
			( signal "@baseboard_fab2_lib.baseboard_fab2(sch_1):fm_all_wake_n"
				( objectStatus "FM_ALL_WAKE_N" )
			)
			( signal "@baseboard_fab2_lib.baseboard_fab2(sch_1):fm_backup_bios_sel_n"
				( objectStatus "FM_BACKUP_BIOS_SEL_N" )
			)
			( signal "@baseboard_fab2_lib.baseboard_fab2(sch_1):fm_battery_sense_en"
				( objectStatus "FM_BATTERY_SENSE_EN" )
			)
			( signal "@baseboard_fab2_lib.baseboard_fab2(sch_1):fm_beep_led_p"
				( objectStatus "FM_BEEP_LED_P" )
			)
			( signal "@baseboard_fab2_lib.baseboard_fab2(sch_1):rst_hfi1_cpu0_lvt2_n"
				( objectStatus "RST_HFI1_CPU0_LVT2_N" )
			)
			( signal "@baseboard_fab2_lib.baseboard_fab2(sch_1):tp_gpior5_roma25_vpor7"
				( objectStatus "TP_GPIOR5_ROMA25_VPOR7" )
			)
			( signal "@baseboard_fab2_lib.baseboard_fab2(sch_1):fm_bios_mrc_debug_msg_dis_n"
				( objectStatus "FM_BIOS_MRC_DEBUG_MSG_DIS_N" )
			)
			( signal "@baseboard_fab2_lib.baseboard_fab2(sch_1):fm_bios_post_cmplt_n"
				( objectStatus "FM_BIOS_POST_CMPLT_N" )
			)
			( signal "@baseboard_fab2_lib.baseboard_fab2(sch_1):fm_bios_prefrb2_good"
				( objectStatus "FM_BIOS_PREFRB2_GOOD" )
			)
			( signal "@baseboard_fab2_lib.baseboard_fab2(sch_1):fm_bios_smi_active_n"
				( objectStatus "FM_BIOS_SMI_ACTIVE_N" )
			)
			( signal "@baseboard_fab2_lib.baseboard_fab2(sch_1):fm_bios_spi_bmc_ctrl"
				( objectStatus "FM_BIOS_SPI_BMC_CTRL" )
			)
			( signal "@baseboard_fab2_lib.baseboard_fab2(sch_1):fm_bmc_heartbeat_n"
				( objectStatus "FM_BMC_HEARTBEAT_N" )
			)
			( signal "@baseboard_fab2_lib.baseboard_fab2(sch_1):fm_bmc_onctl_n"
				( objectStatus "FM_BMC_ONCTL_N" )
			)
			( signal "@baseboard_fab2_lib.baseboard_fab2(sch_1):fm_bmc_onctl_r_n"
				( objectStatus "FM_BMC_ONCTL_R_N" )
			)
			( signal "@baseboard_fab2_lib.baseboard_fab2(sch_1):fm_dimm_event_cod_n"
				( objectStatus "FM_DIMM_EVENT_COD_N" )
			)
			( signal "@baseboard_fab2_lib.baseboard_fab2(sch_1):fm_ocp_mezzb_pres_n"
				( objectStatus "FM_OCP_MEZZB_PRES_N" )
			)
			( signal "@baseboard_fab2_lib.baseboard_fab2(sch_1):fm_bmc_pwrbtn_out_n"
				( objectStatus "FM_BMC_PWRBTN_OUT_N" )
			)
			( signal "@baseboard_fab2_lib.baseboard_fab2(sch_1):fm_bmc_ready_n"
				( objectStatus "FM_BMC_READY_N" )
			)
			( signal "@baseboard_fab2_lib.baseboard_fab2(sch_1):fm_board_rev_id0"
				( objectStatus "FM_BOARD_REV_ID0" )
			)
			( signal "@baseboard_fab2_lib.baseboard_fab2(sch_1):fm_board_rev_id1"
				( objectStatus "FM_BOARD_REV_ID1" )
			)
			( signal "@baseboard_fab2_lib.baseboard_fab2(sch_1):fm_board_rev_id2"
				( objectStatus "FM_BOARD_REV_ID2" )
			)
			( signal "@baseboard_fab2_lib.baseboard_fab2(sch_1):fm_board_sku_id0"
				( objectStatus "FM_BOARD_SKU_ID0" )
			)
			( signal "@baseboard_fab2_lib.baseboard_fab2(sch_1):fm_board_sku_id1"
				( objectStatus "FM_BOARD_SKU_ID1" )
			)
			( signal "@baseboard_fab2_lib.baseboard_fab2(sch_1):fm_board_sku_id2"
				( objectStatus "FM_BOARD_SKU_ID2" )
			)
			( signal "@baseboard_fab2_lib.baseboard_fab2(sch_1):fm_board_sku_id3"
				( objectStatus "FM_BOARD_SKU_ID3" )
			)
			( signal "@baseboard_fab2_lib.baseboard_fab2(sch_1):fm_board_sku_id4"
				( objectStatus "FM_BOARD_SKU_ID4" )
			)
			( signal "@baseboard_fab2_lib.baseboard_fab2(sch_1):fm_bios_usb_recovery"
				( objectStatus "FM_BIOS_USB_RECOVERY" )
			)
			( signal "@baseboard_fab2_lib.baseboard_fab2(sch_1):fm_cpu_caterr_dly_lvt3_r_n"
				( objectStatus "FM_CPU_CATERR_DLY_LVT3_R_N" )
			)
			( signal "@baseboard_fab2_lib.baseboard_fab2(sch_1):fm_force_adr_n"
				( objectStatus "FM_FORCE_ADR_N" )
			)
			( signal "@baseboard_fab2_lib.baseboard_fab2(sch_1):fm_pi7c9x1172_a1"
				( objectStatus "FM_PI7C9X1172_A1" )
			)
			( signal "@baseboard_fab2_lib.baseboard_fab2(sch_1):fm_cpu0_pkgid0"
				( objectStatus "FM_CPU0_PKGID0" )
			)
			( signal "@baseboard_fab2_lib.baseboard_fab2(sch_1):fm_cpu0_pkgid1"
				( objectStatus "FM_CPU0_PKGID1" )
			)
			( signal "@baseboard_fab2_lib.baseboard_fab2(sch_1):fm_cpu0_pkgid2"
				( objectStatus "FM_CPU0_PKGID2" )
			)
			( signal "@baseboard_fab2_lib.baseboard_fab2(sch_1):fm_cpu0_proc_id0"
				( objectStatus "FM_CPU0_PROC_ID0" )
			)
			( signal "@baseboard_fab2_lib.baseboard_fab2(sch_1):fm_cpu0_proc_id1"
				( objectStatus "FM_CPU0_PROC_ID1" )
			)
			( signal "@baseboard_fab2_lib.baseboard_fab2(sch_1):rst_pcie_midplane_n"
				( objectStatus "RST_PCIE_MIDPLANE_N" )
			)
			( signal "@baseboard_fab2_lib.baseboard_fab2(sch_1):fm_cpu0_sktocc_lvt3_n"
				( objectStatus "FM_CPU0_SKTOCC_LVT3_N" )
			)
			( signal "@baseboard_fab2_lib.baseboard_fab2(sch_1):irq_vm_int_n"
				( objectStatus "IRQ_VM_INT_N" )
			)
			( signal "@baseboard_fab2_lib.baseboard_fab2(sch_1):smb_cpu1_pe_hp_gtl_r_scl"
				( objectStatus "SMB_CPU1_PE_HP_GTL_R_SCL" )
			)
			( signal "@baseboard_fab2_lib.baseboard_fab2(sch_1):tp_cpu0_rsvd_287"
				( objectStatus "TP_CPU0_RSVD_287" )
			)
			( signal "@baseboard_fab2_lib.baseboard_fab2(sch_1):tp_cpu0_rsvd_298"
				( objectStatus "TP_CPU0_RSVD_298" )
			)
			( signal "@baseboard_fab2_lib.baseboard_fab2(sch_1):smb_cpu1_pe_hp_gtl_r_sda"
				( objectStatus "SMB_CPU1_PE_HP_GTL_R_SDA" )
			)
			( signal "@baseboard_fab2_lib.baseboard_fab2(sch_1):tp_cpu0_rsvd_299"
				( objectStatus "TP_CPU0_RSVD_299" )
			)
			( signal "@baseboard_fab2_lib.baseboard_fab2(sch_1):fm_heartbeat_led"
				( objectStatus "FM_HEARTBEAT_LED" )
			)
			( signal "@baseboard_fab2_lib.baseboard_fab2(sch_1):tp_cpu0_rsvd_303"
				( objectStatus "TP_CPU0_RSVD_303" )
			)
			( signal "@baseboard_fab2_lib.baseboard_fab2(sch_1):tp_cpu0_rsvd_304"
				( objectStatus "TP_CPU0_RSVD_304" )
			)
			( signal "@baseboard_fab2_lib.baseboard_fab2(sch_1):tp_cpu1_rsvd_275"
				( objectStatus "TP_CPU1_RSVD_275" )
			)
			( signal "@baseboard_fab2_lib.baseboard_fab2(sch_1):irq_lom_alert_n"
				( objectStatus "IRQ_LOM_ALERT_N" )
			)
			( signal "@baseboard_fab2_lib.baseboard_fab2(sch_1):tp_cpu1_rsvd_282"
				( objectStatus "TP_CPU1_RSVD_282" )
			)
			( signal "@baseboard_fab2_lib.baseboard_fab2(sch_1):fm_throttle_r_n"
				( objectStatus "FM_THROTTLE_R_N" )
			)
			( signal "@baseboard_fab2_lib.baseboard_fab2(sch_1):fm_throttle_r1_n"
				( objectStatus "FM_THROTTLE_R1_N" )
			)
			( signal "@baseboard_fab2_lib.baseboard_fab2(sch_1):tp_cpu1_rsvd_283"
				( objectStatus "TP_CPU1_RSVD_283" )
			)
			( signal "@baseboard_fab2_lib.baseboard_fab2(sch_1):irq_sml1_pmbus_alert_buf_n"
				( objectStatus "IRQ_SML1_PMBUS_ALERT_BUF_N" )
			)
			( signal "@baseboard_fab2_lib.baseboard_fab2(sch_1):fm_cpu1_pkgid2"
				( objectStatus "FM_CPU1_PKGID2" )
			)
			( signal "@baseboard_fab2_lib.baseboard_fab2(sch_1):pwrgd_p12v_hsc"
				( objectStatus "PWRGD_P12V_HSC" )
			)
			( signal "@baseboard_fab2_lib.baseboard_fab2(sch_1):lpc_lad2_io2"
				( objectStatus "LPC_LAD2_IO2" )
			)
			( signal "@baseboard_fab2_lib.baseboard_fab2(sch_1):pwrgd_sys_pwrok"
				( objectStatus "PWRGD_SYS_PWROK" )
			)
			( signal "@baseboard_fab2_lib.baseboard_fab2(sch_1):fm_uv_adr_trigger_n"
				( objectStatus "FM_UV_ADR_TRIGGER_N" )
			)
			( signal "@baseboard_fab2_lib.baseboard_fab2(sch_1):irq_bmc_pch_nmi_stby_n"
				( objectStatus "IRQ_BMC_PCH_NMI_STBY_N" )
			)
			( signal "@baseboard_fab2_lib.baseboard_fab2(sch_1):irq_bmc_pch_smi_lpc_n"
				( objectStatus "IRQ_BMC_PCH_SMI_LPC_N" )
			)
			( signal "@baseboard_fab2_lib.baseboard_fab2(sch_1):irq_hfi0_cpu0_lvt2_n"
				( objectStatus "IRQ_HFI0_CPU0_LVT2_N" )
			)
			( signal "@baseboard_fab2_lib.baseboard_fab2(sch_1):irq_cpu0_vrhot"
				( objectStatus "IRQ_CPU0_VRHOT" )
			)
			( signal "@baseboard_fab2_lib.baseboard_fab2(sch_1):irq_hfi1_cpu0_lvt2_n"
				( objectStatus "IRQ_HFI1_CPU0_LVT2_N" )
			)
			( signal "@baseboard_fab2_lib.baseboard_fab2(sch_1):irq_cpu1_vrhot"
				( objectStatus "IRQ_CPU1_VRHOT" )
			)
			( signal "@baseboard_fab2_lib.baseboard_fab2(sch_1):fm_dimm_event_fet"
				( objectStatus "FM_DIMM_EVENT_FET" )
			)
			( signal "@baseboard_fab2_lib.baseboard_fab2(sch_1):irq_lpc_serirq_n"
				( objectStatus "IRQ_LPC_SERIRQ_N" )
			)
			( signal "@baseboard_fab2_lib.baseboard_fab2(sch_1):irq_lvc3_wake_n"
				( objectStatus "IRQ_LVC3_WAKE_N" )
			)
			( signal "@baseboard_fab2_lib.baseboard_fab2(sch_1):irq_pvccin_cpu0_vrhot_lvc3_n"
				( objectStatus "IRQ_PVCCIN_CPU0_VRHOT_LVC3_N" )
			)
			( signal "@baseboard_fab2_lib.baseboard_fab2(sch_1):irq_pvccin_cpu1_vrhot_lvc3_n"
				( objectStatus "IRQ_PVCCIN_CPU1_VRHOT_LVC3_N" )
			)
			( signal "@baseboard_fab2_lib.baseboard_fab2(sch_1):irq_cpu0_prochot_g_n"
				( objectStatus "IRQ_CPU0_PROCHOT_G_N" )
			)
			( signal "@baseboard_fab2_lib.baseboard_fab2(sch_1):irq_pvddq_abc_vrhot_lvt3_n"
				( objectStatus "IRQ_PVDDQ_ABC_VRHOT_LVT3_N" )
			)
			( signal "@baseboard_fab2_lib.baseboard_fab2(sch_1):irq_pvddq_def_vrhot_lvt3_n"
				( objectStatus "IRQ_PVDDQ_DEF_VRHOT_LVT3_N" )
			)
			( signal "@baseboard_fab2_lib.baseboard_fab2(sch_1):irq_pvddq_ghj_vrhot_lvt3_n"
				( objectStatus "IRQ_PVDDQ_GHJ_VRHOT_LVT3_N" )
			)
			( signal "@baseboard_fab2_lib.baseboard_fab2(sch_1):irq_pvddq_klm_vrhot_lvt3_n"
				( objectStatus "IRQ_PVDDQ_KLM_VRHOT_LVT3_N" )
			)
			( signal "@baseboard_fab2_lib.baseboard_fab2(sch_1):lpc_lad1_io1_r"
				( objectStatus "LPC_LAD1_IO1_R" )
			)
			( signal "@baseboard_fab2_lib.baseboard_fab2(sch_1):irq_sml0_alert_n"
				( objectStatus "IRQ_SML0_ALERT_N" )
			)
			( signal "@baseboard_fab2_lib.baseboard_fab2(sch_1):tp_cpu1_rsvd_298"
				( objectStatus "TP_CPU1_RSVD_298" )
			)
			( signal "@baseboard_fab2_lib.baseboard_fab2(sch_1):irq_sml1_pmbus_alert_n"
				( objectStatus "IRQ_SML1_PMBUS_ALERT_N" )
			)
			( signal "@baseboard_fab2_lib.baseboard_fab2(sch_1):irq_cpu1_prochot_g_n"
				( objectStatus "IRQ_CPU1_PROCHOT_G_N" )
			)
			( signal "@baseboard_fab2_lib.baseboard_fab2(sch_1):fm_cpu1_cd_pres"
				( objectStatus "FM_CPU1_CD_PRES" )
			)
			( signal "@baseboard_fab2_lib.baseboard_fab2(sch_1):fm_ocp_mezzc_pres_n"
				( objectStatus "FM_OCP_MEZZC_PRES_N" )
			)
			( signal "@baseboard_fab2_lib.baseboard_fab2(sch_1):fm_mem_event_func"
				( objectStatus "FM_MEM_EVENT_FUNC" )
			)
			( signal "@baseboard_fab2_lib.baseboard_fab2(sch_1):lpc_lad1_io1"
				( objectStatus "LPC_LAD1_IO1" )
			)
			( signal "@baseboard_fab2_lib.baseboard_fab2(sch_1):tp_shared_kr_mdio_0"
				( objectStatus "TP_SHARED_KR_MDIO_0" )
			)
			( signal "@baseboard_fab2_lib.baseboard_fab2(sch_1):fm_cpu1_pkgid0"
				( objectStatus "FM_CPU1_PKGID0" )
			)
			( signal "@baseboard_fab2_lib.baseboard_fab2(sch_1):fm_cpu0_or_cpu1_mcp_pres"
				( objectStatus "FM_CPU0_OR_CPU1_MCP_PRES" )
			)
			( signal "@baseboard_fab2_lib.baseboard_fab2(sch_1):rst_bmc_srst_r_n"
				( objectStatus "RST_BMC_SRST_R_N" )
			)
			( signal "@baseboard_fab2_lib.baseboard_fab2(sch_1):tp_cpu1_rsvd_299"
				( objectStatus "TP_CPU1_RSVD_299" )
			)
			( signal "@baseboard_fab2_lib.baseboard_fab2(sch_1):tp_cpu1_rsvd_303"
				( objectStatus "TP_CPU1_RSVD_303" )
			)
			( signal "@baseboard_fab2_lib.baseboard_fab2(sch_1):pwrgd_pvcciomcp_cpu0"
				( objectStatus "PWRGD_PVCCIOMCP_CPU0" )
			)
			( signal "@baseboard_fab2_lib.baseboard_fab2(sch_1):tp_cpld1_pt17c"
				( objectStatus "TP_CPLD1_PT17C" )
			)
			( signal "@baseboard_fab2_lib.baseboard_fab2(sch_1):fm_cpu1_pkgid1"
				( objectStatus "FM_CPU1_PKGID1" )
			)
			( signal "@baseboard_fab2_lib.baseboard_fab2(sch_1):xtal_ck_mng_in"
				( objectStatus "XTAL_CK_MNG_IN" )
			)
			( signal "@baseboard_fab2_lib.baseboard_fab2(sch_1):xtal_ck_mng_out"
				( objectStatus "XTAL_CK_MNG_OUT" )
			)
			( signal "@baseboard_fab2_lib.baseboard_fab2(sch_1):xtal_kr_25m_in"
				( objectStatus "XTAL_KR_25M_IN" )
			)
			( signal "@baseboard_fab2_lib.baseboard_fab2(sch_1):xtal_kr_25m_out"
				( objectStatus "XTAL_KR_25M_OUT" )
			)
			( signal "@baseboard_fab2_lib.baseboard_fab2(sch_1):tp_cpu1_rsvd_287"
				( objectStatus "TP_CPU1_RSVD_287" )
			)
			( signal "@baseboard_fab2_lib.baseboard_fab2(sch_1):tp_cpu1_rsvd_304"
				( objectStatus "TP_CPU1_RSVD_304" )
			)
			( signal "@baseboard_fab2_lib.baseboard_fab2(sch_1):xtal_25mhz_out"
				( objectStatus "XTAL_25MHZ_OUT" )
			)
			( signal "@baseboard_fab2_lib.baseboard_fab2(sch_1):lpc_lad2_io2_r"
				( objectStatus "LPC_LAD2_IO2_R" )
			)
			( signal "@baseboard_fab2_lib.baseboard_fab2(sch_1):pu_pirom_cpu1_addr0"
				( objectStatus "PU_PIROM_CPU1_ADDR0" )
			)
			( signal "@baseboard_fab2_lib.baseboard_fab2(sch_1):pd_pirom_cpu0_addr0"
				( objectStatus "PD_PIROM_CPU0_ADDR0" )
			)
			( signal "@baseboard_fab2_lib.baseboard_fab2(sch_1):pd_pirom_cpu0_addr1"
				( objectStatus "PD_PIROM_CPU0_ADDR1" )
			)
			( signal "@baseboard_fab2_lib.baseboard_fab2(sch_1):pd_pirom_cpu0_addr2"
				( objectStatus "PD_PIROM_CPU0_ADDR2" )
			)
			( signal "@baseboard_fab2_lib.baseboard_fab2(sch_1):pu_m2_clk_req_n"
				( objectStatus "PU_M2_CLK_REQ_N" )
			)
			( signal "@baseboard_fab2_lib.baseboard_fab2(sch_1):pd_pirom_cpu1_addr1"
				( objectStatus "PD_PIROM_CPU1_ADDR1" )
			)
			( signal "@baseboard_fab2_lib.baseboard_fab2(sch_1):pd_pirom_cpu1_addr2"
				( objectStatus "PD_PIROM_CPU1_ADDR2" )
			)
			( signal "@baseboard_fab2_lib.baseboard_fab2(sch_1):smb_pirom_cpu0_scl"
				( objectStatus "SMB_PIROM_CPU0_SCL" )
			)
			( signal "@baseboard_fab2_lib.baseboard_fab2(sch_1):smb_pirom_cpu0_sda"
				( objectStatus "SMB_PIROM_CPU0_SDA" )
			)
			( signal "@baseboard_fab2_lib.baseboard_fab2(sch_1):fm_cpu1_prochot_lvt3_r_n"
				( objectStatus "FM_CPU1_PROCHOT_LVT3_R_N" )
			)
			( signal "@baseboard_fab2_lib.baseboard_fab2(sch_1):smb_pirom_cpu1_scl"
				( objectStatus "SMB_PIROM_CPU1_SCL" )
			)
			( signal "@baseboard_fab2_lib.baseboard_fab2(sch_1):rst_pcie_m2_dev_n"
				( objectStatus "RST_PCIE_M2_DEV_N" )
			)
			( signal "@baseboard_fab2_lib.baseboard_fab2(sch_1):lpc_lad0_io0_r"
				( objectStatus "LPC_LAD0_IO0_R" )
			)
			( signal "@baseboard_fab2_lib.baseboard_fab2(sch_1):smb_cpu1_pe_hp_gtl_scl"
				( objectStatus "SMB_CPU1_PE_HP_GTL_SCL" )
			)
			( signal "@baseboard_fab2_lib.baseboard_fab2(sch_1):smb_cpu1_pe_hp_gtl_sda"
				( objectStatus "SMB_CPU1_PE_HP_GTL_SDA" )
			)
			( signal "@baseboard_fab2_lib.baseboard_fab2(sch_1):smb_pirom_cpu1_sda"
				( objectStatus "SMB_PIROM_CPU1_SDA" )
			)
			( signal "@baseboard_fab2_lib.baseboard_fab2(sch_1):lpc_lad0_io0"
				( objectStatus "LPC_LAD0_IO0" )
			)
			( signal "@baseboard_fab2_lib.baseboard_fab2(sch_1):vr_vrrdy_pvccin_cpu0"
				( attribute "VOLTAGE" "3.3"
					( Units "uVoltage" "V" 1.000000)
					( Origin gFrontEnd )
				)
				( objectStatus "VR_VRRDY_PVCCIN_CPU0" )
			)
			( signal "@baseboard_fab2_lib.baseboard_fab2(sch_1):vr_vrrdy_pvccin_cpu1"
				( attribute "VOLTAGE" "1 V"
					( Units "uVoltage" "V" 1.000000)
					( Origin gBackEnd )
				)
				( objectStatus "VR_VRRDY_PVCCIN_CPU1" )
			)
			( signal "@baseboard_fab2_lib.baseboard_fab2(sch_1):pwrgd_pvpp_abc_r"
				( objectStatus "PWRGD_PVPP_ABC_R" )
			)
			( signal "@baseboard_fab2_lib.baseboard_fab2(sch_1):pwrgd_p1v8_pch_stby_r"
				( objectStatus "PWRGD_P1V8_PCH_STBY_R" )
			)
			( signal "@baseboard_fab2_lib.baseboard_fab2(sch_1):pwrgd_cpu0_drampwrok_abc_g"
				( objectStatus "PWRGD_CPU0_DRAMPWROK_ABC_G" )
			)
			( signal "@baseboard_fab2_lib.baseboard_fab2(sch_1):vr_pvddq_abc_ph1_ocset"
				( attribute "RATSNEST_SCHEDULE" "MIN_DAISY_CHAIN"
					( Origin gBackEnd )
				)
				( attribute "VOLTAGE" "3.6"
					( Units "uVoltage" "V" 1.000000)
					( Origin gFrontEnd )
				)
				( objectStatus "VR_PVDDQ_ABC_PH1_OCSET" )
			)
			( signal "@baseboard_fab2_lib.baseboard_fab2(sch_1):pwrgd_cpu0_drampwrok_def_g"
				( objectStatus "PWRGD_CPU0_DRAMPWROK_DEF_G" )
			)
			( signal "@baseboard_fab2_lib.baseboard_fab2(sch_1):smb_host_stby_lvc3_sda_r"
				( objectStatus "SMB_HOST_STBY_LVC3_SDA_R" )
			)
			( signal "@baseboard_fab2_lib.baseboard_fab2(sch_1):pwrgd_cpu0_g"
				( objectStatus "PWRGD_CPU0_G" )
			)
			( signal "@baseboard_fab2_lib.baseboard_fab2(sch_1):pwrgd_cpu0_lvc3"
				( objectStatus "PWRGD_CPU0_LVC3" )
			)
			( signal "@baseboard_fab2_lib.baseboard_fab2(sch_1):irq_dimm_save_lvt3"
				( objectStatus "IRQ_DIMM_SAVE_LVT3" )
			)
			( signal "@baseboard_fab2_lib.baseboard_fab2(sch_1):pwrgd_cpu1_drampwrok_ghj_g"
				( objectStatus "PWRGD_CPU1_DRAMPWROK_GHJ_G" )
			)
			( signal "@baseboard_fab2_lib.baseboard_fab2(sch_1):pwrgd_cpu1_drampwrok_klm_g"
				( objectStatus "PWRGD_CPU1_DRAMPWROK_KLM_G" )
			)
			( signal "@baseboard_fab2_lib.baseboard_fab2(sch_1):irq_dimm_save_lvt3_n"
				( objectStatus "IRQ_DIMM_SAVE_LVT3_N" )
			)
			( signal "@baseboard_fab2_lib.baseboard_fab2(sch_1):pwrgd_cpu1_g"
				( objectStatus "PWRGD_CPU1_G" )
			)
			( signal "@baseboard_fab2_lib.baseboard_fab2(sch_1):pwrgd_cpu1_lvc3"
				( objectStatus "PWRGD_CPU1_LVC3" )
			)
			( signal "@baseboard_fab2_lib.baseboard_fab2(sch_1):pwrgd_pvpp_klm_r"
				( objectStatus "PWRGD_PVPP_KLM_R" )
			)
			( signal "@baseboard_fab2_lib.baseboard_fab2(sch_1):pwrgd_drampwrgd"
				( objectStatus "PWRGD_DRAMPWRGD" )
			)
			( signal "@baseboard_fab2_lib.baseboard_fab2(sch_1):pwrgd_dsw_pwrok"
				( objectStatus "PWRGD_DSW_PWROK" )
			)
			( signal "@baseboard_fab2_lib.baseboard_fab2(sch_1):fm_db_uart_sel4_n"
				( objectStatus "FM_DB_UART_SEL4_N" )
			)
			( signal "@baseboard_fab2_lib.baseboard_fab2(sch_1):pwrgd_pch_pwrok"
				( objectStatus "PWRGD_PCH_PWROK" )
			)
			( signal "@baseboard_fab2_lib.baseboard_fab2(sch_1):smb_host_stby_lvc3_scl_r"
				( objectStatus "SMB_HOST_STBY_LVC3_SCL_R" )
			)
			( signal "@baseboard_fab2_lib.baseboard_fab2(sch_1):lpc_lad3_io3_r"
				( objectStatus "LPC_LAD3_IO3_R" )
			)
			( signal "@baseboard_fab2_lib.baseboard_fab2(sch_1):lpc_lframe_n_cs0_r_n"
				( objectStatus "LPC_LFRAME_N_CS0_R_N" )
			)
			( signal "@baseboard_fab2_lib.baseboard_fab2(sch_1):pwrgd_pvccin_cpu0"
				( objectStatus "PWRGD_PVCCIN_CPU0" )
			)
			( signal "@baseboard_fab2_lib.baseboard_fab2(sch_1):pwrgd_pvccin_cpu1"
				( objectStatus "PWRGD_PVCCIN_CPU1" )
			)
			( signal "@baseboard_fab2_lib.baseboard_fab2(sch_1):fm_cpu1_proc_id1"
				( objectStatus "FM_CPU1_PROC_ID1" )
			)
			( signal "@baseboard_fab2_lib.baseboard_fab2(sch_1):vr_pvddq_abc_ph2_ocset"
				( attribute "RATSNEST_SCHEDULE" "MIN_DAISY_CHAIN"
					( Origin gBackEnd )
				)
				( attribute "VOLTAGE" "3.6"
					( Units "uVoltage" "V" 1.000000)
					( Origin gFrontEnd )
				)
				( objectStatus "VR_PVDDQ_ABC_PH2_OCSET" )
			)
			( signal "@baseboard_fab2_lib.baseboard_fab2(sch_1):fm_cpu1_sktocc_lvt3_n"
				( objectStatus "FM_CPU1_SKTOCC_LVT3_N" )
			)
			( signal "@baseboard_fab2_lib.baseboard_fab2(sch_1):pwrgd_pvddq_abc"
				( objectStatus "PWRGD_PVDDQ_ABC" )
			)
			( signal "@baseboard_fab2_lib.baseboard_fab2(sch_1):pwrgd_pvddq_abc_r"
				( objectStatus "PWRGD_PVDDQ_ABC_R" )
			)
			( signal "@baseboard_fab2_lib.baseboard_fab2(sch_1):pwrgd_pvddq_def"
				( objectStatus "PWRGD_PVDDQ_DEF" )
			)
			( signal "@baseboard_fab2_lib.baseboard_fab2(sch_1):pwrgd_pvddq_def_r"
				( objectStatus "PWRGD_PVDDQ_DEF_R" )
			)
			( signal "@baseboard_fab2_lib.baseboard_fab2(sch_1):pwrgd_pvddq_ghj"
				( objectStatus "PWRGD_PVDDQ_GHJ" )
			)
			( signal "@baseboard_fab2_lib.baseboard_fab2(sch_1):pwrgd_pvddq_ghj_r"
				( objectStatus "PWRGD_PVDDQ_GHJ_R" )
			)
			( signal "@baseboard_fab2_lib.baseboard_fab2(sch_1):pwrgd_pvddq_klm"
				( objectStatus "PWRGD_PVDDQ_KLM" )
			)
			( signal "@baseboard_fab2_lib.baseboard_fab2(sch_1):pwrgd_pvddq_klm_r"
				( objectStatus "PWRGD_PVDDQ_KLM_R" )
			)
			( signal "@baseboard_fab2_lib.baseboard_fab2(sch_1):vr_pvddq_def_ph1_ocset"
				( attribute "RATSNEST_SCHEDULE" "MIN_DAISY_CHAIN"
					( Origin gBackEnd )
				)
				( attribute "VOLTAGE" "3.6"
					( Units "uVoltage" "V" 1.000000)
					( Origin gFrontEnd )
				)
				( objectStatus "VR_PVDDQ_DEF_PH1_OCSET" )
			)
			( signal "@baseboard_fab2_lib.baseboard_fab2(sch_1):vr_pvccio_cpu1_ocset"
				( objectStatus "VR_PVCCIO_CPU1_OCSET" )
			)
			( signal "@baseboard_fab2_lib.baseboard_fab2(sch_1):lpc_lframe_n_cs0_n"
				( objectStatus "LPC_LFRAME_N_CS0_N" )
			)
			( signal "@baseboard_fab2_lib.baseboard_fab2(sch_1):fm_cpu1_proc_id0"
				( objectStatus "FM_CPU1_PROC_ID0" )
			)
			( signal "@baseboard_fab2_lib.baseboard_fab2(sch_1):vr_pvddq_def_ph2_ocset"
				( attribute "RATSNEST_SCHEDULE" "MIN_DAISY_CHAIN"
					( Origin gBackEnd )
				)
				( attribute "VOLTAGE" "3.6"
					( Units "uVoltage" "V" 1.000000)
					( Origin gFrontEnd )
				)
				( objectStatus "VR_PVDDQ_DEF_PH2_OCSET" )
			)
			( signal "@baseboard_fab2_lib.baseboard_fab2(sch_1):pwrgd_pvpp_abc"
				( objectStatus "PWRGD_PVPP_ABC" )
			)
			( signal "@baseboard_fab2_lib.baseboard_fab2(sch_1):pwrgd_pvpp_def"
				( objectStatus "PWRGD_PVPP_DEF" )
			)
			( signal "@baseboard_fab2_lib.baseboard_fab2(sch_1):pwrgd_pvpp_ghj"
				( objectStatus "PWRGD_PVPP_GHJ" )
			)
			( signal "@baseboard_fab2_lib.baseboard_fab2(sch_1):pwrgd_pvpp_klm"
				( objectStatus "PWRGD_PVPP_KLM" )
			)
			( signal "@baseboard_fab2_lib.baseboard_fab2(sch_1):fm_db_uart_sel3_n"
				( objectStatus "FM_DB_UART_SEL3_N" )
			)
			( signal "@baseboard_fab2_lib.baseboard_fab2(sch_1):fm_db_uart_sel1_n"
				( objectStatus "FM_DB_UART_SEL1_N" )
			)
			( signal "@baseboard_fab2_lib.baseboard_fab2(sch_1):vr_pvddq_ghj_ph1_ocset"
				( attribute "RATSNEST_SCHEDULE" "MIN_DAISY_CHAIN"
					( Origin gBackEnd )
				)
				( attribute "VOLTAGE" "3.6"
					( Units "uVoltage" "V" 1.000000)
					( Origin gFrontEnd )
				)
				( objectStatus "VR_PVDDQ_GHJ_PH1_OCSET" )
			)
			( signal "@baseboard_fab2_lib.baseboard_fab2(sch_1):pwrgd_pvsa_cpu0"
				( objectStatus "PWRGD_PVSA_CPU0" )
			)
			( signal "@baseboard_fab2_lib.baseboard_fab2(sch_1):pwrgd_pvsa_cpu1"
				( objectStatus "PWRGD_PVSA_CPU1" )
			)
			( signal "@baseboard_fab2_lib.baseboard_fab2(sch_1):vr_pvddq_ghj_ph2_ocset"
				( attribute "RATSNEST_SCHEDULE" "MIN_DAISY_CHAIN"
					( Origin gBackEnd )
				)
				( attribute "VOLTAGE" "3.6"
					( Units "uVoltage" "V" 1.000000)
					( Origin gFrontEnd )
				)
				( objectStatus "VR_PVDDQ_GHJ_PH2_OCSET" )
			)
			( signal "@baseboard_fab2_lib.baseboard_fab2(sch_1):pwrgd_p1v26_bmc_stby_r"
				( objectStatus "PWRGD_P1V26_BMC_STBY_R" )
			)
			( signal "@baseboard_fab2_lib.baseboard_fab2(sch_1):vr_pvddq_klm_ph1_ocset"
				( attribute "RATSNEST_SCHEDULE" "MIN_DAISY_CHAIN"
					( Origin gBackEnd )
				)
				( attribute "VOLTAGE" "3.6"
					( Units "uVoltage" "V" 1.000000)
					( Origin gFrontEnd )
				)
				( objectStatus "VR_PVDDQ_KLM_PH1_OCSET" )
			)
			( signal "@baseboard_fab2_lib.baseboard_fab2(sch_1):pwrgd_p1v538_bmc_stby_r"
				( objectStatus "PWRGD_P1V538_BMC_STBY_R" )
			)
			( signal "@baseboard_fab2_lib.baseboard_fab2(sch_1):vr_pvddq_klm_ph2_ocset"
				( attribute "RATSNEST_SCHEDULE" "MIN_DAISY_CHAIN"
					( Origin gBackEnd )
				)
				( attribute "VOLTAGE" "3.6"
					( Units "uVoltage" "V" 1.000000)
					( Origin gFrontEnd )
				)
				( objectStatus "VR_PVDDQ_KLM_PH2_OCSET" )
			)
			( signal "@baseboard_fab2_lib.baseboard_fab2(sch_1):pwrgd_p3v3_stby_r"
				( objectStatus "PWRGD_P3V3_STBY_R" )
			)
			( signal "@baseboard_fab2_lib.baseboard_fab2(sch_1):vr_pvnn_pch_stby_ocset"
				( objectStatus "VR_PVNN_PCH_STBY_OCSET" )
			)
			( signal "@baseboard_fab2_lib.baseboard_fab2(sch_1):irq_oc_detect_n"
				( objectStatus "IRQ_OC_DETECT_N" )
			)
			( signal "@baseboard_fab2_lib.baseboard_fab2(sch_1):vr_pvsa_cpu0_ocset"
				( objectStatus "VR_PVSA_CPU0_OCSET" )
			)
			( signal "@baseboard_fab2_lib.baseboard_fab2(sch_1):pwrgd_pvnn_p1v05_pch"
				( objectStatus "PWRGD_PVNN_P1V05_PCH" )
			)
			( signal "@baseboard_fab2_lib.baseboard_fab2(sch_1):tp_jtag_mcp_io8_rsvd"
				( objectStatus "TP_JTAG_MCP_IO8_RSVD" )
			)
			( signal "@baseboard_fab2_lib.baseboard_fab2(sch_1):vr_pvsa_cpu1_ocset"
				( objectStatus "VR_PVSA_CPU1_OCSET" )
			)
			( signal "@baseboard_fab2_lib.baseboard_fab2(sch_1):vr_pvccin_cpu0_ph1_ocset"
				( objectStatus "VR_PVCCIN_CPU0_PH1_OCSET" )
			)
			( signal "@baseboard_fab2_lib.baseboard_fab2(sch_1):lpc_lad3_io3"
				( objectStatus "LPC_LAD3_IO3" )
			)
			( signal "@baseboard_fab2_lib.baseboard_fab2(sch_1):pwrgd_p1v8_pch_stby"
				( objectStatus "PWRGD_P1V8_PCH_STBY" )
			)
			( signal "@baseboard_fab2_lib.baseboard_fab2(sch_1):vr_pvccin_cpu0_ph2_ocset"
				( attribute "VOLTAGE" "3.6"
					( Units "uVoltage" "V" 1.000000)
					( Origin gFrontEnd )
				)
				( objectStatus "VR_PVCCIN_CPU0_PH2_OCSET" )
			)
			( signal "@baseboard_fab2_lib.baseboard_fab2(sch_1):fm_db_present"
				( objectStatus "FM_DB_PRESENT" )
			)
			( signal "@baseboard_fab2_lib.baseboard_fab2(sch_1):pwrgd_pvpp_def_r"
				( objectStatus "PWRGD_PVPP_DEF_R" )
			)
			( signal "@baseboard_fab2_lib.baseboard_fab2(sch_1):pwrgd_pvpp_ghj_r"
				( objectStatus "PWRGD_PVPP_GHJ_R" )
			)
			( signal "@baseboard_fab2_lib.baseboard_fab2(sch_1):pwrgd_pvnn_pch_r"
				( objectStatus "PWRGD_PVNN_PCH_R" )
			)
			( signal "@baseboard_fab2_lib.baseboard_fab2(sch_1):pwrgd_p1v26_bmc_stby"
				( objectStatus "PWRGD_P1V26_BMC_STBY" )
			)
			( signal "@baseboard_fab2_lib.baseboard_fab2(sch_1):vr_pvccin_cpu0_ph3_ocset"
				( attribute "RATSNEST_SCHEDULE" "MIN_DAISY_CHAIN"
					( Origin gBackEnd )
				)
				( attribute "VOLTAGE" "3.6"
					( Units "uVoltage" "V" 1.000000)
					( Origin gFrontEnd )
				)
				( objectStatus "VR_PVCCIN_CPU0_PH3_OCSET" )
			)
			( signal "@baseboard_fab2_lib.baseboard_fab2(sch_1):pwrgd_p1v538_bmc_stby"
				( objectStatus "PWRGD_P1V538_BMC_STBY" )
			)
			( signal "@baseboard_fab2_lib.baseboard_fab2(sch_1):fm_db_uart_sel2_n"
				( objectStatus "FM_DB_UART_SEL2_N" )
			)
			( signal "@baseboard_fab2_lib.baseboard_fab2(sch_1):pwrgd_p3v3_stby"
				( objectStatus "PWRGD_P3V3_STBY" )
			)
			( signal "@baseboard_fab2_lib.baseboard_fab2(sch_1):vr_pvccin_cpu0_ph4_ocset"
				( attribute "RATSNEST_SCHEDULE" "MIN_DAISY_CHAIN"
					( Origin gBackEnd )
				)
				( attribute "VOLTAGE" "3.6"
					( Units "uVoltage" "V" 1.000000)
					( Origin gFrontEnd )
				)
				( objectStatus "VR_PVCCIN_CPU0_PH4_OCSET" )
			)
			( signal "@baseboard_fab2_lib.baseboard_fab2(sch_1):pwrgd_p5v_stby"
				( objectStatus "PWRGD_P5V_STBY" )
			)
			( signal "@baseboard_fab2_lib.baseboard_fab2(sch_1):irq_uv_detect_n"
				( objectStatus "IRQ_UV_DETECT_N" )
			)
			( signal "@baseboard_fab2_lib.baseboard_fab2(sch_1):pwrgd_p3v3"
				( objectStatus "PWRGD_P3V3" )
			)
			( signal "@baseboard_fab2_lib.baseboard_fab2(sch_1):rst_bmc_ddr3_n"
				( objectStatus "RST_BMC_DDR3_N" )
			)
			( signal "@baseboard_fab2_lib.baseboard_fab2(sch_1):rst_bmc_ddr3_r_n"
				( objectStatus "RST_BMC_DDR3_R_N" )
			)
			( signal "@baseboard_fab2_lib.baseboard_fab2(sch_1):rst_bmc_lvc3_n"
				( objectStatus "RST_BMC_LVC3_N" )
			)
			( signal "@baseboard_fab2_lib.baseboard_fab2(sch_1):rst_bmc_sysrst_btn_out_n"
				( objectStatus "RST_BMC_SYSRST_BTN_OUT_N" )
			)
			( signal "@baseboard_fab2_lib.baseboard_fab2(sch_1):fm_disable_fan_n"
				( objectStatus "FM_DISABLE_FAN_N" )
			)
			( signal "@baseboard_fab2_lib.baseboard_fab2(sch_1):rst_cpu0_g_n"
				( objectStatus "RST_CPU0_G_N" )
			)
			( signal "@baseboard_fab2_lib.baseboard_fab2(sch_1):rst_cpu0_lvc3_n"
				( objectStatus "RST_CPU0_LVC3_N" )
			)
			( signal "@baseboard_fab2_lib.baseboard_fab2(sch_1):rst_cpu1_g_n"
				( objectStatus "RST_CPU1_G_N" )
			)
			( signal "@baseboard_fab2_lib.baseboard_fab2(sch_1):rst_cpu1_lvc3_n"
				( objectStatus "RST_CPU1_LVC3_N" )
			)
			( signal "@baseboard_fab2_lib.baseboard_fab2(sch_1):rst_pcie_riser1_perst_n"
				( objectStatus "RST_PCIE_RISER1_PERST_N" )
			)
			( signal "@baseboard_fab2_lib.baseboard_fab2(sch_1):fm_db1200_smb_sa1"
				( objectStatus "FM_DB1200_SMB_SA1" )
			)
			( signal "@baseboard_fab2_lib.baseboard_fab2(sch_1):rst_pcie_cpu_dev0_n"
				( objectStatus "RST_PCIE_CPU_DEV0_N" )
			)
			( signal "@baseboard_fab2_lib.baseboard_fab2(sch_1):rst_pcie_cpu_dev0_r_n"
				( objectStatus "RST_PCIE_CPU_DEV0_R_N" )
			)
			( signal "@baseboard_fab2_lib.baseboard_fab2(sch_1):rst_pcie_cpu_dev1_n"
				( objectStatus "RST_PCIE_CPU_DEV1_N" )
			)
			( signal "@baseboard_fab2_lib.baseboard_fab2(sch_1):rst_pcie_cpu_dev1_r_n"
				( objectStatus "RST_PCIE_CPU_DEV1_R_N" )
			)
			( signal "@baseboard_fab2_lib.baseboard_fab2(sch_1):rst_pcie_cpu_dev2_n"
				( objectStatus "RST_PCIE_CPU_DEV2_N" )
			)
			( signal "@baseboard_fab2_lib.baseboard_fab2(sch_1):rst_pcie_cpu_dev2_r_n"
				( objectStatus "RST_PCIE_CPU_DEV2_R_N" )
			)
			( signal "@baseboard_fab2_lib.baseboard_fab2(sch_1):rst_pcie_cpu_dev3_n"
				( objectStatus "RST_PCIE_CPU_DEV3_N" )
			)
			( signal "@baseboard_fab2_lib.baseboard_fab2(sch_1):rst_pcie_cpu_dev3_r_n"
				( objectStatus "RST_PCIE_CPU_DEV3_R_N" )
			)
			( signal "@baseboard_fab2_lib.baseboard_fab2(sch_1):rst_pcie_pch_perst_n"
				( objectStatus "RST_PCIE_PCH_PERST_N" )
			)
			( signal "@baseboard_fab2_lib.baseboard_fab2(sch_1):rst_pltrst_buf_n"
				( objectStatus "RST_PLTRST_BUF_N" )
			)
			( signal "@baseboard_fab2_lib.baseboard_fab2(sch_1):rst_pltrst_n"
				( objectStatus "RST_PLTRST_N" )
			)
			( signal "@baseboard_fab2_lib.baseboard_fab2(sch_1):vr_pvccin_cpu1_ph1_ocset"
				( objectStatus "VR_PVCCIN_CPU1_PH1_OCSET" )
			)
			( signal "@baseboard_fab2_lib.baseboard_fab2(sch_1):vr_p1v05_pch_stby_ocset"
				( objectStatus "VR_P1V05_PCH_STBY_OCSET" )
			)
			( signal "@baseboard_fab2_lib.baseboard_fab2(sch_1):fm_hbw_bypass_lowbw_n"
				( objectStatus "FM_HBW_BYPASS_LOWBW_N" )
			)
			( signal "@baseboard_fab2_lib.baseboard_fab2(sch_1):fm_heartbeat_led_a"
				( objectStatus "FM_HEARTBEAT_LED_A" )
			)
			( signal "@baseboard_fab2_lib.baseboard_fab2(sch_1):fm_heartbeat_led_k"
				( objectStatus "FM_HEARTBEAT_LED_K" )
			)
			( signal "@baseboard_fab2_lib.baseboard_fab2(sch_1):rst_rtcrst_n"
				( objectStatus "RST_RTCRST_N" )
			)
			( signal "@baseboard_fab2_lib.baseboard_fab2(sch_1):rst_srtcrst_n"
				( objectStatus "RST_SRTCRST_N" )
			)
			( signal "@baseboard_fab2_lib.baseboard_fab2(sch_1):rst_system_btn_n"
				( objectStatus "RST_SYSTEM_BTN_N" )
			)
			( signal "@baseboard_fab2_lib.baseboard_fab2(sch_1):fm_fast_prochot_en"
				( objectStatus "FM_FAST_PROCHOT_EN" )
			)
			( signal "@baseboard_fab2_lib.baseboard_fab2(sch_1):rst_pltrst_sprv_r_n"
				( objectStatus "RST_PLTRST_SPRV_R_N" )
			)
			( signal "@baseboard_fab2_lib.baseboard_fab2(sch_1):fm_dis_adr_dly"
				( objectStatus "FM_DIS_ADR_DLY" )
			)
			( signal "@baseboard_fab2_lib.baseboard_fab2(sch_1):pwrgd_p3v3_r"
				( objectStatus "PWRGD_P3V3_R" )
			)
			( signal "@baseboard_fab2_lib.baseboard_fab2(sch_1):sgpio_bmc_din"
				( objectStatus "SGPIO_BMC_DIN" )
			)
			( signal "@baseboard_fab2_lib.baseboard_fab2(sch_1):sgpio_bmc_din_r"
				( objectStatus "SGPIO_BMC_DIN_R" )
			)
			( signal "@baseboard_fab2_lib.baseboard_fab2(sch_1):vr_pvccin_cpu0_ph5_ocset"
				( attribute "RATSNEST_SCHEDULE" "MIN_DAISY_CHAIN"
					( Origin gBackEnd )
				)
				( attribute "VOLTAGE" "3.6"
					( Units "uVoltage" "V" 1.000000)
					( Origin gFrontEnd )
				)
				( objectStatus "VR_PVCCIN_CPU0_PH5_OCSET" )
			)
			( signal "@baseboard_fab2_lib.baseboard_fab2(sch_1):fm_db1200_smb_sa0"
				( objectStatus "FM_DB1200_SMB_SA0" )
			)
			( signal "@baseboard_fab2_lib.baseboard_fab2(sch_1):irq_bmc_pch_sci_lpc_n"
				( objectStatus "IRQ_BMC_PCH_SCI_LPC_N" )
			)
			( signal "@baseboard_fab2_lib.baseboard_fab2(sch_1):irq_hsc_fault_n"
				( objectStatus "IRQ_HSC_FAULT_N" )
			)
			( signal "@baseboard_fab2_lib.baseboard_fab2(sch_1):fm_enable_fan_power"
				( objectStatus "FM_ENABLE_FAN_POWER" )
			)
			( signal "@baseboard_fab2_lib.baseboard_fab2(sch_1):fm_dual_bios_sel_n"
				( objectStatus "FM_DUAL_BIOS_SEL_N" )
			)
			( signal "@baseboard_fab2_lib.baseboard_fab2(sch_1):irq_mezz_lan_alert_n"
				( objectStatus "IRQ_MEZZ_LAN_ALERT_N" )
			)
			( signal "@baseboard_fab2_lib.baseboard_fab2(sch_1):irq_pvccio_cpu0_vrhot_n"
				( objectStatus "IRQ_PVCCIO_CPU0_VRHOT_N" )
			)
			( signal "@baseboard_fab2_lib.baseboard_fab2(sch_1):irq_pvccio_cpu1_vrhot_n"
				( objectStatus "IRQ_PVCCIO_CPU1_VRHOT_N" )
			)
			( signal "@baseboard_fab2_lib.baseboard_fab2(sch_1):irq_pvnn_pch_vrhot_n"
				( objectStatus "IRQ_PVNN_PCH_VRHOT_N" )
			)
			( signal "@baseboard_fab2_lib.baseboard_fab2(sch_1):fm_gbe_lom_disable_n"
				( objectStatus "FM_GBE_LOM_DISABLE_N" )
			)
			( signal "@baseboard_fab2_lib.baseboard_fab2(sch_1):sgpio_bmc_dout"
				( objectStatus "SGPIO_BMC_DOUT" )
			)
			( signal "@baseboard_fab2_lib.baseboard_fab2(sch_1):sgpio_bmc_dout_r"
				( objectStatus "SGPIO_BMC_DOUT_R" )
			)
			( signal "@baseboard_fab2_lib.baseboard_fab2(sch_1):pwrgd_cpupwrgd"
				( objectStatus "PWRGD_CPUPWRGD" )
			)
			( signal "@baseboard_fab2_lib.baseboard_fab2(sch_1):pwrgd_cpupwrgd_gtl"
				( objectStatus "PWRGD_CPUPWRGD_GTL" )
			)
			( signal "@baseboard_fab2_lib.baseboard_fab2(sch_1):rst_cpu0_lvc3_r1_n"
				( objectStatus "RST_CPU0_LVC3_R1_N" )
			)
			( signal "@baseboard_fab2_lib.baseboard_fab2(sch_1):rst_cpu1_lvc3_r1_n"
				( objectStatus "RST_CPU1_LVC3_R1_N" )
			)
			( signal "@baseboard_fab2_lib.baseboard_fab2(sch_1):pwrgd_cpupwrgd_r1"
				( objectStatus "PWRGD_CPUPWRGD_R1" )
			)
			( signal "@baseboard_fab2_lib.baseboard_fab2(sch_1):jtag_mcp_tms_r1"
				( objectStatus "JTAG_MCP_TMS_R1" )
			)
			( signal "@baseboard_fab2_lib.baseboard_fab2(sch_1):jtag_mcp_tms"
				( objectStatus "JTAG_MCP_TMS" )
			)
			( signal "@baseboard_fab2_lib.baseboard_fab2(sch_1):vr_p5v_stby_en"
				( objectStatus "VR_P5V_STBY_EN" )
			)
			( signal "@baseboard_fab2_lib.baseboard_fab2(sch_1):p3e_cpu0_pe3_ocp_rxp(0)"
				( pinPairRef "@baseboard_fab2_lib.baseboard_fab2(sch_1):\PP3073\" )
				( objectStatus "P3E_CPU0_PE3_OCP_RXP<0>" )
			)
			( signal "@baseboard_fab2_lib.baseboard_fab2(sch_1):p3e_cpu0_pe3_ocp_rxn(0)"
				( pinPairRef "@baseboard_fab2_lib.baseboard_fab2(sch_1):\PP3071\" )
				( objectStatus "P3E_CPU0_PE3_OCP_RXN<0>" )
			)
			( signal "@baseboard_fab2_lib.baseboard_fab2(sch_1):p3e_cpu0_pe3_ocp_rxp(1)"
				( pinPairRef "@baseboard_fab2_lib.baseboard_fab2(sch_1):\PP3074\" )
				( objectStatus "P3E_CPU0_PE3_OCP_RXP<1>" )
			)
			( signal "@baseboard_fab2_lib.baseboard_fab2(sch_1):p3e_cpu0_pe3_ocp_rxn(1)"
				( pinPairRef "@baseboard_fab2_lib.baseboard_fab2(sch_1):\PP3072\" )
				( objectStatus "P3E_CPU0_PE3_OCP_RXN<1>" )
			)
			( signal "@baseboard_fab2_lib.baseboard_fab2(sch_1):p3e_cpu0_pe3_ocp_rxp(2)"
				( pinPairRef "@baseboard_fab2_lib.baseboard_fab2(sch_1):\PP3069\" )
				( objectStatus "P3E_CPU0_PE3_OCP_RXP<2>" )
			)
			( signal "@baseboard_fab2_lib.baseboard_fab2(sch_1):p3e_cpu0_pe3_ocp_rxn(2)"
				( pinPairRef "@baseboard_fab2_lib.baseboard_fab2(sch_1):\PP3067\" )
				( objectStatus "P3E_CPU0_PE3_OCP_RXN<2>" )
			)
			( signal "@baseboard_fab2_lib.baseboard_fab2(sch_1):p3e_cpu0_pe3_ocp_rxp(3)"
				( pinPairRef "@baseboard_fab2_lib.baseboard_fab2(sch_1):\PP3070\" )
				( objectStatus "P3E_CPU0_PE3_OCP_RXP<3>" )
			)
			( signal "@baseboard_fab2_lib.baseboard_fab2(sch_1):p3e_cpu0_pe3_ocp_rxn(3)"
				( pinPairRef "@baseboard_fab2_lib.baseboard_fab2(sch_1):\PP3068\" )
				( objectStatus "P3E_CPU0_PE3_OCP_RXN<3>" )
			)
			( signal "@baseboard_fab2_lib.baseboard_fab2(sch_1):p3e_cpu0_pe3_ocp_rxp(6)"
				( pinPairRef "@baseboard_fab2_lib.baseboard_fab2(sch_1):\PP3061\" )
				( objectStatus "P3E_CPU0_PE3_OCP_RXP<6>" )
			)
			( signal "@baseboard_fab2_lib.baseboard_fab2(sch_1):p3e_cpu0_pe3_ocp_rxn(6)"
				( pinPairRef "@baseboard_fab2_lib.baseboard_fab2(sch_1):\PP3059\" )
				( objectStatus "P3E_CPU0_PE3_OCP_RXN<6>" )
			)
			( signal "@baseboard_fab2_lib.baseboard_fab2(sch_1):p3e_cpu0_pe3_ocp_rxp(7)"
				( pinPairRef "@baseboard_fab2_lib.baseboard_fab2(sch_1):\PP3062\" )
				( objectStatus "P3E_CPU0_PE3_OCP_RXP<7>" )
			)
			( signal "@baseboard_fab2_lib.baseboard_fab2(sch_1):p3e_cpu0_pe3_ocp_rxn(7)"
				( pinPairRef "@baseboard_fab2_lib.baseboard_fab2(sch_1):\PP3060\" )
				( objectStatus "P3E_CPU0_PE3_OCP_RXN<7>" )
			)
			( signal "@baseboard_fab2_lib.baseboard_fab2(sch_1):p3e_cpu0_pe3_ocp_rxp(8)"
				( pinPairRef "@baseboard_fab2_lib.baseboard_fab2(sch_1):\PP3057\" )
				( objectStatus "P3E_CPU0_PE3_OCP_RXP<8>" )
			)
			( signal "@baseboard_fab2_lib.baseboard_fab2(sch_1):p3e_cpu0_pe3_ocp_rxn(8)"
				( pinPairRef "@baseboard_fab2_lib.baseboard_fab2(sch_1):\PP3055\" )
				( objectStatus "P3E_CPU0_PE3_OCP_RXN<8>" )
			)
			( signal "@baseboard_fab2_lib.baseboard_fab2(sch_1):p3e_cpu0_pe3_ocp_rxp(9)"
				( pinPairRef "@baseboard_fab2_lib.baseboard_fab2(sch_1):\PP3058\" )
				( objectStatus "P3E_CPU0_PE3_OCP_RXP<9>" )
			)
			( signal "@baseboard_fab2_lib.baseboard_fab2(sch_1):p3e_cpu0_pe3_ocp_rxn(9)"
				( pinPairRef "@baseboard_fab2_lib.baseboard_fab2(sch_1):\PP3056\" )
				( objectStatus "P3E_CPU0_PE3_OCP_RXN<9>" )
			)
			( signal "@baseboard_fab2_lib.baseboard_fab2(sch_1):p3e_cpu0_pe3_ocp_rxp(10)"
				( pinPairRef "@baseboard_fab2_lib.baseboard_fab2(sch_1):\PP3053\" )
				( objectStatus "P3E_CPU0_PE3_OCP_RXP<10>" )
			)
			( signal "@baseboard_fab2_lib.baseboard_fab2(sch_1):p3e_cpu0_pe3_ocp_rxn(10)"
				( pinPairRef "@baseboard_fab2_lib.baseboard_fab2(sch_1):\PP3051\" )
				( objectStatus "P3E_CPU0_PE3_OCP_RXN<10>" )
			)
			( signal "@baseboard_fab2_lib.baseboard_fab2(sch_1):p3e_cpu0_pe3_ocp_rxp(11)"
				( pinPairRef "@baseboard_fab2_lib.baseboard_fab2(sch_1):\PP3054\" )
				( objectStatus "P3E_CPU0_PE3_OCP_RXP<11>" )
			)
			( signal "@baseboard_fab2_lib.baseboard_fab2(sch_1):p3e_cpu0_pe3_ocp_rxn(11)"
				( pinPairRef "@baseboard_fab2_lib.baseboard_fab2(sch_1):\PP3052\" )
				( objectStatus "P3E_CPU0_PE3_OCP_RXN<11>" )
			)
			( signal "@baseboard_fab2_lib.baseboard_fab2(sch_1):p3e_cpu0_pe3_ocp_rxp(12)"
				( pinPairRef "@baseboard_fab2_lib.baseboard_fab2(sch_1):\PP3049\" )
				( objectStatus "P3E_CPU0_PE3_OCP_RXP<12>" )
			)
			( signal "@baseboard_fab2_lib.baseboard_fab2(sch_1):p3e_cpu0_pe3_ocp_rxn(12)"
				( pinPairRef "@baseboard_fab2_lib.baseboard_fab2(sch_1):\PP3047\" )
				( objectStatus "P3E_CPU0_PE3_OCP_RXN<12>" )
			)
			( signal "@baseboard_fab2_lib.baseboard_fab2(sch_1):p3e_cpu0_pe3_ocp_rxp(13)"
				( pinPairRef "@baseboard_fab2_lib.baseboard_fab2(sch_1):\PP3050\" )
				( objectStatus "P3E_CPU0_PE3_OCP_RXP<13>" )
			)
			( signal "@baseboard_fab2_lib.baseboard_fab2(sch_1):p3e_cpu0_pe3_ocp_rxn(13)"
				( pinPairRef "@baseboard_fab2_lib.baseboard_fab2(sch_1):\PP3048\" )
				( objectStatus "P3E_CPU0_PE3_OCP_RXN<13>" )
			)
			( signal "@baseboard_fab2_lib.baseboard_fab2(sch_1):p3e_cpu0_pe3_ocp_rxp(14)"
				( pinPairRef "@baseboard_fab2_lib.baseboard_fab2(sch_1):\PP3045\" )
				( objectStatus "P3E_CPU0_PE3_OCP_RXP<14>" )
			)
			( signal "@baseboard_fab2_lib.baseboard_fab2(sch_1):p3e_cpu0_pe3_ocp_rxn(14)"
				( pinPairRef "@baseboard_fab2_lib.baseboard_fab2(sch_1):\PP3043\" )
				( objectStatus "P3E_CPU0_PE3_OCP_RXN<14>" )
			)
			( signal "@baseboard_fab2_lib.baseboard_fab2(sch_1):p3e_cpu0_pe3_ocp_rxp(15)"
				( pinPairRef "@baseboard_fab2_lib.baseboard_fab2(sch_1):\PP3046\" )
				( objectStatus "P3E_CPU0_PE3_OCP_RXP<15>" )
			)
			( signal "@baseboard_fab2_lib.baseboard_fab2(sch_1):p3e_cpu0_pe3_ocp_rxn(15)"
				( pinPairRef "@baseboard_fab2_lib.baseboard_fab2(sch_1):\PP3044\" )
				( objectStatus "P3E_CPU0_PE3_OCP_RXN<15>" )
			)
			( signal "@baseboard_fab2_lib.baseboard_fab2(sch_1):p3e_cpu1_pe3_mp_txn(10)"
				( pinPairRef "@baseboard_fab2_lib.baseboard_fab2(sch_1):\PP3037\" )
				( objectStatus "P3E_CPU1_PE3_MP_TXN<10>" )
			)
			( signal "@baseboard_fab2_lib.baseboard_fab2(sch_1):p3e_cpu1_pe3_mp_c_txn(10)"
				( pinPairRef "@baseboard_fab2_lib.baseboard_fab2(sch_1):\PP3038\" )
				( objectStatus "P3E_CPU1_PE3_MP_C_TXN<10>" )
			)
			( signal "@baseboard_fab2_lib.baseboard_fab2(sch_1):p3e_cpu1_pe3_mp_c_txp(10)"
				( pinPairRef "@baseboard_fab2_lib.baseboard_fab2(sch_1):\PP3035\" )
				( objectStatus "P3E_CPU1_PE3_MP_C_TXP<10>" )
			)
			( signal "@baseboard_fab2_lib.baseboard_fab2(sch_1):p3e_cpu1_pe3_mp_txp(10)"
				( pinPairRef "@baseboard_fab2_lib.baseboard_fab2(sch_1):\PP3036\" )
				( objectStatus "P3E_CPU1_PE3_MP_TXP<10>" )
			)
			( signal "@baseboard_fab2_lib.baseboard_fab2(sch_1):usb3_p01_fb_rxn"
				( pinPairRef "@baseboard_fab2_lib.baseboard_fab2(sch_1):\PP5692\" )
				( pinPairRef "@baseboard_fab2_lib.baseboard_fab2(sch_1):\PP5693\" )
				( objectStatus "USB3_P01_FB_RXN" )
			)
			( signal "@baseboard_fab2_lib.baseboard_fab2(sch_1):usb3_p01_rxn"
				( objectStatus "USB3_P01_RXN" )
			)
			( signal "@baseboard_fab2_lib.baseboard_fab2(sch_1):usb3_p01_rxp"
				( objectStatus "USB3_P01_RXP" )
			)
			( signal "@baseboard_fab2_lib.baseboard_fab2(sch_1):usb3_p01_fb_rxp"
				( pinPairRef "@baseboard_fab2_lib.baseboard_fab2(sch_1):\PP5694\" )
				( pinPairRef "@baseboard_fab2_lib.baseboard_fab2(sch_1):\PP5695\" )
				( objectStatus "USB3_P01_FB_RXP" )
			)
			( signal "@baseboard_fab2_lib.baseboard_fab2(sch_1):p3e_cpu0_pe3_ocp_rxn(4)"
				( pinPairRef "@baseboard_fab2_lib.baseboard_fab2(sch_1):\PP3063\" )
				( objectStatus "P3E_CPU0_PE3_OCP_RXN<4>" )
			)
			( signal "@baseboard_fab2_lib.baseboard_fab2(sch_1):p3e_cpu0_pe3_ocp_rxp(4)"
				( pinPairRef "@baseboard_fab2_lib.baseboard_fab2(sch_1):\PP3065\" )
				( objectStatus "P3E_CPU0_PE3_OCP_RXP<4>" )
			)
			( signal "@baseboard_fab2_lib.baseboard_fab2(sch_1):p3e_cpu0_pe3_ocp_rxn(5)"
				( pinPairRef "@baseboard_fab2_lib.baseboard_fab2(sch_1):\PP3064\" )
				( objectStatus "P3E_CPU0_PE3_OCP_RXN<5>" )
			)
			( signal "@baseboard_fab2_lib.baseboard_fab2(sch_1):p3e_cpu0_pe3_ocp_rxp(5)"
				( pinPairRef "@baseboard_fab2_lib.baseboard_fab2(sch_1):\PP3066\" )
				( objectStatus "P3E_CPU0_PE3_OCP_RXP<5>" )
			)
			( signal "@baseboard_fab2_lib.baseboard_fab2(sch_1):p3e_cpu0_pe1_pch_r_rxn(10)"
				( pinPairRef "@baseboard_fab2_lib.baseboard_fab2(sch_1):\PP2993\" )
				( objectStatus "P3E_CPU0_PE1_PCH_R_RXN<10>" )
			)
			( signal "@baseboard_fab2_lib.baseboard_fab2(sch_1):p3e_cpu0_pe1_pch_rxn(10)"
				( pinPairRef "@baseboard_fab2_lib.baseboard_fab2(sch_1):\PP2994\" )
				( objectStatus "P3E_CPU0_PE1_PCH_RXN<10>" )
			)
			( signal "@baseboard_fab2_lib.baseboard_fab2(sch_1):p3e_cpu0_pe1_pch_r_rxp(10)"
				( pinPairRef "@baseboard_fab2_lib.baseboard_fab2(sch_1):\PP2991\" )
				( objectStatus "P3E_CPU0_PE1_PCH_R_RXP<10>" )
			)
			( signal "@baseboard_fab2_lib.baseboard_fab2(sch_1):p3e_cpu0_pe1_pch_rxp(10)"
				( pinPairRef "@baseboard_fab2_lib.baseboard_fab2(sch_1):\PP2992\" )
				( objectStatus "P3E_CPU0_PE1_PCH_RXP<10>" )
			)
			( signal "@baseboard_fab2_lib.baseboard_fab2(sch_1):p3e_cpu0_pe1_pch_r_rxn(11)"
				( pinPairRef "@baseboard_fab2_lib.baseboard_fab2(sch_1):\PP2989\" )
				( objectStatus "P3E_CPU0_PE1_PCH_R_RXN<11>" )
			)
			( signal "@baseboard_fab2_lib.baseboard_fab2(sch_1):p3e_cpu0_pe1_pch_rxn(11)"
				( pinPairRef "@baseboard_fab2_lib.baseboard_fab2(sch_1):\PP2990\" )
				( objectStatus "P3E_CPU0_PE1_PCH_RXN<11>" )
			)
			( signal "@baseboard_fab2_lib.baseboard_fab2(sch_1):p3e_cpu0_pe1_pch_r_rxp(11)"
				( pinPairRef "@baseboard_fab2_lib.baseboard_fab2(sch_1):\PP2987\" )
				( objectStatus "P3E_CPU0_PE1_PCH_R_RXP<11>" )
			)
			( signal "@baseboard_fab2_lib.baseboard_fab2(sch_1):p3e_cpu0_pe1_pch_rxp(11)"
				( pinPairRef "@baseboard_fab2_lib.baseboard_fab2(sch_1):\PP2988\" )
				( objectStatus "P3E_CPU0_PE1_PCH_RXP<11>" )
			)
			( signal "@baseboard_fab2_lib.baseboard_fab2(sch_1):p3e_cpu0_pe1_pch_r_rxn(12)"
				( pinPairRef "@baseboard_fab2_lib.baseboard_fab2(sch_1):\PP2985\" )
				( objectStatus "P3E_CPU0_PE1_PCH_R_RXN<12>" )
			)
			( signal "@baseboard_fab2_lib.baseboard_fab2(sch_1):p3e_cpu0_pe1_pch_rxn(12)"
				( pinPairRef "@baseboard_fab2_lib.baseboard_fab2(sch_1):\PP2986\" )
				( objectStatus "P3E_CPU0_PE1_PCH_RXN<12>" )
			)
			( signal "@baseboard_fab2_lib.baseboard_fab2(sch_1):p3e_cpu0_pe1_pch_r_rxp(12)"
				( pinPairRef "@baseboard_fab2_lib.baseboard_fab2(sch_1):\PP2983\" )
				( objectStatus "P3E_CPU0_PE1_PCH_R_RXP<12>" )
			)
			( signal "@baseboard_fab2_lib.baseboard_fab2(sch_1):p3e_cpu0_pe1_pch_rxp(12)"
				( pinPairRef "@baseboard_fab2_lib.baseboard_fab2(sch_1):\PP2984\" )
				( objectStatus "P3E_CPU0_PE1_PCH_RXP<12>" )
			)
			( signal "@baseboard_fab2_lib.baseboard_fab2(sch_1):p3e_cpu0_pe1_pch_r_rxn(13)"
				( pinPairRef "@baseboard_fab2_lib.baseboard_fab2(sch_1):\PP2981\" )
				( objectStatus "P3E_CPU0_PE1_PCH_R_RXN<13>" )
			)
			( signal "@baseboard_fab2_lib.baseboard_fab2(sch_1):p3e_cpu0_pe1_pch_rxn(13)"
				( pinPairRef "@baseboard_fab2_lib.baseboard_fab2(sch_1):\PP2982\" )
				( objectStatus "P3E_CPU0_PE1_PCH_RXN<13>" )
			)
			( signal "@baseboard_fab2_lib.baseboard_fab2(sch_1):p3e_cpu0_pe1_pch_r_rxp(13)"
				( pinPairRef "@baseboard_fab2_lib.baseboard_fab2(sch_1):\PP2979\" )
				( objectStatus "P3E_CPU0_PE1_PCH_R_RXP<13>" )
			)
			( signal "@baseboard_fab2_lib.baseboard_fab2(sch_1):p3e_cpu0_pe1_pch_rxp(13)"
				( pinPairRef "@baseboard_fab2_lib.baseboard_fab2(sch_1):\PP2980\" )
				( objectStatus "P3E_CPU0_PE1_PCH_RXP<13>" )
			)
			( signal "@baseboard_fab2_lib.baseboard_fab2(sch_1):p3e_cpu0_pe1_pch_r_rxn(14)"
				( pinPairRef "@baseboard_fab2_lib.baseboard_fab2(sch_1):\PP2977\" )
				( objectStatus "P3E_CPU0_PE1_PCH_R_RXN<14>" )
			)
			( signal "@baseboard_fab2_lib.baseboard_fab2(sch_1):p3e_cpu0_pe1_pch_rxn(14)"
				( pinPairRef "@baseboard_fab2_lib.baseboard_fab2(sch_1):\PP2978\" )
				( objectStatus "P3E_CPU0_PE1_PCH_RXN<14>" )
			)
			( signal "@baseboard_fab2_lib.baseboard_fab2(sch_1):p3e_cpu0_pe1_pch_r_rxp(14)"
				( pinPairRef "@baseboard_fab2_lib.baseboard_fab2(sch_1):\PP2975\" )
				( objectStatus "P3E_CPU0_PE1_PCH_R_RXP<14>" )
			)
			( signal "@baseboard_fab2_lib.baseboard_fab2(sch_1):p3e_cpu0_pe1_pch_rxp(14)"
				( pinPairRef "@baseboard_fab2_lib.baseboard_fab2(sch_1):\PP2976\" )
				( objectStatus "P3E_CPU0_PE1_PCH_RXP<14>" )
			)
			( signal "@baseboard_fab2_lib.baseboard_fab2(sch_1):p3e_cpu0_pe1_pch_r_rxn(15)"
				( pinPairRef "@baseboard_fab2_lib.baseboard_fab2(sch_1):\PP2973\" )
				( objectStatus "P3E_CPU0_PE1_PCH_R_RXN<15>" )
			)
			( signal "@baseboard_fab2_lib.baseboard_fab2(sch_1):p3e_cpu0_pe1_pch_rxn(15)"
				( pinPairRef "@baseboard_fab2_lib.baseboard_fab2(sch_1):\PP2974\" )
				( objectStatus "P3E_CPU0_PE1_PCH_RXN<15>" )
			)
			( signal "@baseboard_fab2_lib.baseboard_fab2(sch_1):p3e_cpu0_pe1_pch_r_rxp(15)"
				( pinPairRef "@baseboard_fab2_lib.baseboard_fab2(sch_1):\PP2971\" )
				( objectStatus "P3E_CPU0_PE1_PCH_R_RXP<15>" )
			)
			( signal "@baseboard_fab2_lib.baseboard_fab2(sch_1):p3e_cpu0_pe1_pch_rxp(15)"
				( pinPairRef "@baseboard_fab2_lib.baseboard_fab2(sch_1):\PP2972\" )
				( objectStatus "P3E_CPU0_PE1_PCH_RXP<15>" )
			)
			( signal "@baseboard_fab2_lib.baseboard_fab2(sch_1):p3e_cpu1_pe3_mp_txn(8)"
				( pinPairRef "@baseboard_fab2_lib.baseboard_fab2(sch_1):\PP3041\" )
				( objectStatus "P3E_CPU1_PE3_MP_TXN<8>" )
			)
			( signal "@baseboard_fab2_lib.baseboard_fab2(sch_1):p3e_cpu1_pe3_mp_c_txn(8)"
				( pinPairRef "@baseboard_fab2_lib.baseboard_fab2(sch_1):\PP3042\" )
				( objectStatus "P3E_CPU1_PE3_MP_C_TXN<8>" )
			)
			( signal "@baseboard_fab2_lib.baseboard_fab2(sch_1):p3e_cpu1_pe3_mp_c_txp(8)"
				( pinPairRef "@baseboard_fab2_lib.baseboard_fab2(sch_1):\PP3039\" )
				( objectStatus "P3E_CPU1_PE3_MP_C_TXP<8>" )
			)
			( signal "@baseboard_fab2_lib.baseboard_fab2(sch_1):p3e_cpu1_pe3_mp_txp(8)"
				( pinPairRef "@baseboard_fab2_lib.baseboard_fab2(sch_1):\PP3040\" )
				( objectStatus "P3E_CPU1_PE3_MP_TXP<8>" )
			)
			( signal "@baseboard_fab2_lib.baseboard_fab2(sch_1):pe_pch_sprv_rx_dn"
				( objectStatus "PE_PCH_SPRV_RX_DN" )
			)
			( signal "@baseboard_fab2_lib.baseboard_fab2(sch_1):pe_pch_sprv_rx_c_dn"
				( objectStatus "PE_PCH_SPRV_RX_C_DN" )
			)
			( signal "@baseboard_fab2_lib.baseboard_fab2(sch_1):pe_pch_sprv_rx_dp"
				( objectStatus "PE_PCH_SPRV_RX_DP" )
			)
			( signal "@baseboard_fab2_lib.baseboard_fab2(sch_1):pe_pch_sprv_rx_c_dp"
				( objectStatus "PE_PCH_SPRV_RX_C_DP" )
			)
			( signal "@baseboard_fab2_lib.baseboard_fab2(sch_1):p3e_cpu0_pe1_pch_rxn(7)"
				( pinPairRef "@baseboard_fab2_lib.baseboard_fab2(sch_1):\PP163\" )
				( objectStatus "P3E_CPU0_PE1_PCH_RXN<7>" )
			)
			( signal "@baseboard_fab2_lib.baseboard_fab2(sch_1):p3e_cpu0_pe1_ss_rxn(7)"
				( objectStatus "P3E_CPU0_PE1_SS_RXN<7>" )
			)
			( signal "@baseboard_fab2_lib.baseboard_fab2(sch_1):p3e_cpu0_pe1_ss_r_rxn(7)"
				( pinPairRef "@baseboard_fab2_lib.baseboard_fab2(sch_1):\PP164\" )
				( objectStatus "P3E_CPU0_PE1_SS_R_RXN<7>" )
			)
			( signal "@baseboard_fab2_lib.baseboard_fab2(sch_1):p3e_cpu0_pe1_ss_r_rxp(7)"
				( pinPairRef "@baseboard_fab2_lib.baseboard_fab2(sch_1):\PP165\" )
				( objectStatus "P3E_CPU0_PE1_SS_R_RXP<7>" )
			)
			( signal "@baseboard_fab2_lib.baseboard_fab2(sch_1):p3e_cpu0_pe1_ss_rxp(7)"
				( objectStatus "P3E_CPU0_PE1_SS_RXP<7>" )
			)
			( signal "@baseboard_fab2_lib.baseboard_fab2(sch_1):p3e_cpu0_pe1_pch_rxp(7)"
				( pinPairRef "@baseboard_fab2_lib.baseboard_fab2(sch_1):\PP166\" )
				( objectStatus "P3E_CPU0_PE1_PCH_RXP<7>" )
			)
			( signal "@baseboard_fab2_lib.baseboard_fab2(sch_1):p3e_cpu0_pe1_pch_txn(8)"
				( pinPairRef "@baseboard_fab2_lib.baseboard_fab2(sch_1):\PP387\" )
				( objectStatus "P3E_CPU0_PE1_PCH_TXN<8>" )
			)
			( signal "@baseboard_fab2_lib.baseboard_fab2(sch_1):p3e_cpu0_pe1_pch_c_txn(8)"
				( pinPairRef "@baseboard_fab2_lib.baseboard_fab2(sch_1):\PP388\" )
				( objectStatus "P3E_CPU0_PE1_PCH_C_TXN<8>" )
			)
			( signal "@baseboard_fab2_lib.baseboard_fab2(sch_1):p3e_cpu0_pe1_pch_c_txp(8)"
				( pinPairRef "@baseboard_fab2_lib.baseboard_fab2(sch_1):\PP389\" )
				( objectStatus "P3E_CPU0_PE1_PCH_C_TXP<8>" )
			)
			( signal "@baseboard_fab2_lib.baseboard_fab2(sch_1):p3e_cpu0_pe1_pch_txp(8)"
				( pinPairRef "@baseboard_fab2_lib.baseboard_fab2(sch_1):\PP390\" )
				( objectStatus "P3E_CPU0_PE1_PCH_TXP<8>" )
			)
			( signal "@baseboard_fab2_lib.baseboard_fab2(sch_1):p3e_cpu0_pe1_pch_txn(9)"
				( pinPairRef "@baseboard_fab2_lib.baseboard_fab2(sch_1):\PP383\" )
				( objectStatus "P3E_CPU0_PE1_PCH_TXN<9>" )
			)
			( signal "@baseboard_fab2_lib.baseboard_fab2(sch_1):p3e_cpu0_pe1_pch_c_txn(9)"
				( pinPairRef "@baseboard_fab2_lib.baseboard_fab2(sch_1):\PP384\" )
				( objectStatus "P3E_CPU0_PE1_PCH_C_TXN<9>" )
			)
			( signal "@baseboard_fab2_lib.baseboard_fab2(sch_1):p3e_cpu0_pe1_pch_c_txp(9)"
				( pinPairRef "@baseboard_fab2_lib.baseboard_fab2(sch_1):\PP385\" )
				( objectStatus "P3E_CPU0_PE1_PCH_C_TXP<9>" )
			)
			( signal "@baseboard_fab2_lib.baseboard_fab2(sch_1):p3e_cpu0_pe1_pch_txp(9)"
				( pinPairRef "@baseboard_fab2_lib.baseboard_fab2(sch_1):\PP386\" )
				( objectStatus "P3E_CPU0_PE1_PCH_TXP<9>" )
			)
			( signal "@baseboard_fab2_lib.baseboard_fab2(sch_1):p3e_cpu0_pe1_pch_txn(10)"
				( pinPairRef "@baseboard_fab2_lib.baseboard_fab2(sch_1):\PP379\" )
				( objectStatus "P3E_CPU0_PE1_PCH_TXN<10>" )
			)
			( signal "@baseboard_fab2_lib.baseboard_fab2(sch_1):p3e_cpu0_pe1_pch_c_txn(10)"
				( pinPairRef "@baseboard_fab2_lib.baseboard_fab2(sch_1):\PP380\" )
				( objectStatus "P3E_CPU0_PE1_PCH_C_TXN<10>" )
			)
			( signal "@baseboard_fab2_lib.baseboard_fab2(sch_1):p3e_cpu0_pe1_pch_c_txp(10)"
				( pinPairRef "@baseboard_fab2_lib.baseboard_fab2(sch_1):\PP381\" )
				( objectStatus "P3E_CPU0_PE1_PCH_C_TXP<10>" )
			)
			( signal "@baseboard_fab2_lib.baseboard_fab2(sch_1):p3e_cpu0_pe1_pch_txp(10)"
				( pinPairRef "@baseboard_fab2_lib.baseboard_fab2(sch_1):\PP382\" )
				( objectStatus "P3E_CPU0_PE1_PCH_TXP<10>" )
			)
			( signal "@baseboard_fab2_lib.baseboard_fab2(sch_1):p3e_cpu0_pe1_pch_txn(11)"
				( pinPairRef "@baseboard_fab2_lib.baseboard_fab2(sch_1):\PP375\" )
				( objectStatus "P3E_CPU0_PE1_PCH_TXN<11>" )
			)
			( signal "@baseboard_fab2_lib.baseboard_fab2(sch_1):p3e_cpu0_pe1_pch_c_txn(11)"
				( pinPairRef "@baseboard_fab2_lib.baseboard_fab2(sch_1):\PP376\" )
				( objectStatus "P3E_CPU0_PE1_PCH_C_TXN<11>" )
			)
			( signal "@baseboard_fab2_lib.baseboard_fab2(sch_1):p3e_cpu0_pe1_pch_c_txp(11)"
				( pinPairRef "@baseboard_fab2_lib.baseboard_fab2(sch_1):\PP377\" )
				( objectStatus "P3E_CPU0_PE1_PCH_C_TXP<11>" )
			)
			( signal "@baseboard_fab2_lib.baseboard_fab2(sch_1):p3e_cpu0_pe1_pch_txp(11)"
				( pinPairRef "@baseboard_fab2_lib.baseboard_fab2(sch_1):\PP378\" )
				( objectStatus "P3E_CPU0_PE1_PCH_TXP<11>" )
			)
			( signal "@baseboard_fab2_lib.baseboard_fab2(sch_1):p3e_cpu0_pe1_pch_txn(12)"
				( pinPairRef "@baseboard_fab2_lib.baseboard_fab2(sch_1):\PP371\" )
				( objectStatus "P3E_CPU0_PE1_PCH_TXN<12>" )
			)
			( signal "@baseboard_fab2_lib.baseboard_fab2(sch_1):p3e_cpu0_pe1_pch_c_txn(12)"
				( pinPairRef "@baseboard_fab2_lib.baseboard_fab2(sch_1):\PP372\" )
				( objectStatus "P3E_CPU0_PE1_PCH_C_TXN<12>" )
			)
			( signal "@baseboard_fab2_lib.baseboard_fab2(sch_1):p3e_cpu0_pe1_pch_c_txp(12)"
				( pinPairRef "@baseboard_fab2_lib.baseboard_fab2(sch_1):\PP373\" )
				( objectStatus "P3E_CPU0_PE1_PCH_C_TXP<12>" )
			)
			( signal "@baseboard_fab2_lib.baseboard_fab2(sch_1):p3e_cpu0_pe1_pch_txp(12)"
				( pinPairRef "@baseboard_fab2_lib.baseboard_fab2(sch_1):\PP374\" )
				( objectStatus "P3E_CPU0_PE1_PCH_TXP<12>" )
			)
			( signal "@baseboard_fab2_lib.baseboard_fab2(sch_1):p3e_cpu0_pe1_pch_txn(13)"
				( pinPairRef "@baseboard_fab2_lib.baseboard_fab2(sch_1):\PP367\" )
				( objectStatus "P3E_CPU0_PE1_PCH_TXN<13>" )
			)
			( signal "@baseboard_fab2_lib.baseboard_fab2(sch_1):p3e_cpu0_pe1_pch_c_txn(13)"
				( pinPairRef "@baseboard_fab2_lib.baseboard_fab2(sch_1):\PP368\" )
				( objectStatus "P3E_CPU0_PE1_PCH_C_TXN<13>" )
			)
			( signal "@baseboard_fab2_lib.baseboard_fab2(sch_1):p3e_cpu0_pe1_pch_c_txp(13)"
				( pinPairRef "@baseboard_fab2_lib.baseboard_fab2(sch_1):\PP369\" )
				( objectStatus "P3E_CPU0_PE1_PCH_C_TXP<13>" )
			)
			( signal "@baseboard_fab2_lib.baseboard_fab2(sch_1):p3e_cpu0_pe1_pch_txp(13)"
				( pinPairRef "@baseboard_fab2_lib.baseboard_fab2(sch_1):\PP370\" )
				( objectStatus "P3E_CPU0_PE1_PCH_TXP<13>" )
			)
			( signal "@baseboard_fab2_lib.baseboard_fab2(sch_1):p3e_cpu0_pe1_pch_txn(14)"
				( pinPairRef "@baseboard_fab2_lib.baseboard_fab2(sch_1):\PP363\" )
				( objectStatus "P3E_CPU0_PE1_PCH_TXN<14>" )
			)
			( signal "@baseboard_fab2_lib.baseboard_fab2(sch_1):p3e_cpu0_pe1_pch_c_txn(14)"
				( pinPairRef "@baseboard_fab2_lib.baseboard_fab2(sch_1):\PP364\" )
				( objectStatus "P3E_CPU0_PE1_PCH_C_TXN<14>" )
			)
			( signal "@baseboard_fab2_lib.baseboard_fab2(sch_1):p3e_cpu0_pe1_pch_c_txp(14)"
				( pinPairRef "@baseboard_fab2_lib.baseboard_fab2(sch_1):\PP365\" )
				( objectStatus "P3E_CPU0_PE1_PCH_C_TXP<14>" )
			)
			( signal "@baseboard_fab2_lib.baseboard_fab2(sch_1):p3e_cpu0_pe1_pch_txp(14)"
				( pinPairRef "@baseboard_fab2_lib.baseboard_fab2(sch_1):\PP366\" )
				( objectStatus "P3E_CPU0_PE1_PCH_TXP<14>" )
			)
			( signal "@baseboard_fab2_lib.baseboard_fab2(sch_1):p3e_cpu0_pe1_pch_txn(15)"
				( pinPairRef "@baseboard_fab2_lib.baseboard_fab2(sch_1):\PP359\" )
				( objectStatus "P3E_CPU0_PE1_PCH_TXN<15>" )
			)
			( signal "@baseboard_fab2_lib.baseboard_fab2(sch_1):p3e_cpu0_pe1_pch_c_txn(15)"
				( pinPairRef "@baseboard_fab2_lib.baseboard_fab2(sch_1):\PP360\" )
				( objectStatus "P3E_CPU0_PE1_PCH_C_TXN<15>" )
			)
			( signal "@baseboard_fab2_lib.baseboard_fab2(sch_1):p3e_cpu0_pe1_pch_c_txp(15)"
				( pinPairRef "@baseboard_fab2_lib.baseboard_fab2(sch_1):\PP361\" )
				( objectStatus "P3E_CPU0_PE1_PCH_C_TXP<15>" )
			)
			( signal "@baseboard_fab2_lib.baseboard_fab2(sch_1):p3e_cpu0_pe1_pch_txp(15)"
				( pinPairRef "@baseboard_fab2_lib.baseboard_fab2(sch_1):\PP362\" )
				( objectStatus "P3E_CPU0_PE1_PCH_TXP<15>" )
			)
			( signal "@baseboard_fab2_lib.baseboard_fab2(sch_1):p3e_cpu0_pe1_ss_txn(0)"
				( objectStatus "P3E_CPU0_PE1_SS_TXN<0>" )
			)
			( signal "@baseboard_fab2_lib.baseboard_fab2(sch_1):p3e_cpu0_pe1_pch_txn(0)"
				( pinPairRef "@baseboard_fab2_lib.baseboard_fab2(sch_1):\PP355\" )
				( objectStatus "P3E_CPU0_PE1_PCH_TXN<0>" )
			)
			( signal "@baseboard_fab2_lib.baseboard_fab2(sch_1):p3e_cpu0_pe1_ss_c_txn(0)"
				( pinPairRef "@baseboard_fab2_lib.baseboard_fab2(sch_1):\PP356\" )
				( objectStatus "P3E_CPU0_PE1_SS_C_TXN<0>" )
			)
			( signal "@baseboard_fab2_lib.baseboard_fab2(sch_1):p3e_cpu0_pe1_ss_c_txp(0)"
				( pinPairRef "@baseboard_fab2_lib.baseboard_fab2(sch_1):\PP357\" )
				( objectStatus "P3E_CPU0_PE1_SS_C_TXP<0>" )
			)
			( signal "@baseboard_fab2_lib.baseboard_fab2(sch_1):p3e_cpu0_pe1_ss_txp(0)"
				( objectStatus "P3E_CPU0_PE1_SS_TXP<0>" )
			)
			( signal "@baseboard_fab2_lib.baseboard_fab2(sch_1):p3e_cpu0_pe1_pch_txp(0)"
				( pinPairRef "@baseboard_fab2_lib.baseboard_fab2(sch_1):\PP358\" )
				( objectStatus "P3E_CPU0_PE1_PCH_TXP<0>" )
			)
			( signal "@baseboard_fab2_lib.baseboard_fab2(sch_1):p3e_cpu0_pe1_ss_txn(1)"
				( objectStatus "P3E_CPU0_PE1_SS_TXN<1>" )
			)
			( signal "@baseboard_fab2_lib.baseboard_fab2(sch_1):p3e_cpu0_pe1_pch_txn(1)"
				( pinPairRef "@baseboard_fab2_lib.baseboard_fab2(sch_1):\PP351\" )
				( objectStatus "P3E_CPU0_PE1_PCH_TXN<1>" )
			)
			( signal "@baseboard_fab2_lib.baseboard_fab2(sch_1):p3e_cpu0_pe1_ss_c_txn(1)"
				( pinPairRef "@baseboard_fab2_lib.baseboard_fab2(sch_1):\PP352\" )
				( objectStatus "P3E_CPU0_PE1_SS_C_TXN<1>" )
			)
			( signal "@baseboard_fab2_lib.baseboard_fab2(sch_1):p3e_cpu0_pe1_ss_c_txp(1)"
				( pinPairRef "@baseboard_fab2_lib.baseboard_fab2(sch_1):\PP353\" )
				( objectStatus "P3E_CPU0_PE1_SS_C_TXP<1>" )
			)
			( signal "@baseboard_fab2_lib.baseboard_fab2(sch_1):p3e_cpu0_pe1_ss_txp(1)"
				( objectStatus "P3E_CPU0_PE1_SS_TXP<1>" )
			)
			( signal "@baseboard_fab2_lib.baseboard_fab2(sch_1):p3e_cpu0_pe1_pch_txp(1)"
				( pinPairRef "@baseboard_fab2_lib.baseboard_fab2(sch_1):\PP354\" )
				( objectStatus "P3E_CPU0_PE1_PCH_TXP<1>" )
			)
			( signal "@baseboard_fab2_lib.baseboard_fab2(sch_1):p3e_cpu0_pe1_ss_txn(2)"
				( objectStatus "P3E_CPU0_PE1_SS_TXN<2>" )
			)
			( signal "@baseboard_fab2_lib.baseboard_fab2(sch_1):p3e_cpu0_pe1_ss_c_txn(2)"
				( pinPairRef "@baseboard_fab2_lib.baseboard_fab2(sch_1):\PP347\" )
				( objectStatus "P3E_CPU0_PE1_SS_C_TXN<2>" )
			)
			( signal "@baseboard_fab2_lib.baseboard_fab2(sch_1):p3e_cpu0_pe1_pch_txn(2)"
				( pinPairRef "@baseboard_fab2_lib.baseboard_fab2(sch_1):\PP348\" )
				( objectStatus "P3E_CPU0_PE1_PCH_TXN<2>" )
			)
			( signal "@baseboard_fab2_lib.baseboard_fab2(sch_1):p3e_cpu0_pe1_ss_c_txp(2)"
				( pinPairRef "@baseboard_fab2_lib.baseboard_fab2(sch_1):\PP349\" )
				( objectStatus "P3E_CPU0_PE1_SS_C_TXP<2>" )
			)
			( signal "@baseboard_fab2_lib.baseboard_fab2(sch_1):p3e_cpu0_pe1_ss_txp(2)"
				( objectStatus "P3E_CPU0_PE1_SS_TXP<2>" )
			)
			( signal "@baseboard_fab2_lib.baseboard_fab2(sch_1):p3e_cpu0_pe1_pch_txp(2)"
				( pinPairRef "@baseboard_fab2_lib.baseboard_fab2(sch_1):\PP350\" )
				( objectStatus "P3E_CPU0_PE1_PCH_TXP<2>" )
			)
			( signal "@baseboard_fab2_lib.baseboard_fab2(sch_1):p3e_cpu0_pe1_ss_txn(3)"
				( objectStatus "P3E_CPU0_PE1_SS_TXN<3>" )
			)
			( signal "@baseboard_fab2_lib.baseboard_fab2(sch_1):p3e_cpu0_pe1_ss_c_txn(3)"
				( pinPairRef "@baseboard_fab2_lib.baseboard_fab2(sch_1):\PP343\" )
				( objectStatus "P3E_CPU0_PE1_SS_C_TXN<3>" )
			)
			( signal "@baseboard_fab2_lib.baseboard_fab2(sch_1):p3e_cpu0_pe1_pch_txn(3)"
				( pinPairRef "@baseboard_fab2_lib.baseboard_fab2(sch_1):\PP344\" )
				( objectStatus "P3E_CPU0_PE1_PCH_TXN<3>" )
			)
			( signal "@baseboard_fab2_lib.baseboard_fab2(sch_1):p3e_cpu0_pe1_ss_c_txp(3)"
				( pinPairRef "@baseboard_fab2_lib.baseboard_fab2(sch_1):\PP345\" )
				( objectStatus "P3E_CPU0_PE1_SS_C_TXP<3>" )
			)
			( signal "@baseboard_fab2_lib.baseboard_fab2(sch_1):p3e_cpu0_pe1_ss_txp(3)"
				( objectStatus "P3E_CPU0_PE1_SS_TXP<3>" )
			)
			( signal "@baseboard_fab2_lib.baseboard_fab2(sch_1):p3e_cpu0_pe1_pch_txp(3)"
				( pinPairRef "@baseboard_fab2_lib.baseboard_fab2(sch_1):\PP346\" )
				( objectStatus "P3E_CPU0_PE1_PCH_TXP<3>" )
			)
			( signal "@baseboard_fab2_lib.baseboard_fab2(sch_1):p3e_cpu0_pe1_ss_txn(4)"
				( objectStatus "P3E_CPU0_PE1_SS_TXN<4>" )
			)
			( signal "@baseboard_fab2_lib.baseboard_fab2(sch_1):p3e_cpu0_pe1_pch_txn(4)"
				( pinPairRef "@baseboard_fab2_lib.baseboard_fab2(sch_1):\PP339\" )
				( objectStatus "P3E_CPU0_PE1_PCH_TXN<4>" )
			)
			( signal "@baseboard_fab2_lib.baseboard_fab2(sch_1):p3e_cpu0_pe1_ss_c_txn(4)"
				( pinPairRef "@baseboard_fab2_lib.baseboard_fab2(sch_1):\PP340\" )
				( objectStatus "P3E_CPU0_PE1_SS_C_TXN<4>" )
			)
			( signal "@baseboard_fab2_lib.baseboard_fab2(sch_1):p3e_cpu0_pe1_ss_c_txp(4)"
				( pinPairRef "@baseboard_fab2_lib.baseboard_fab2(sch_1):\PP341\" )
				( objectStatus "P3E_CPU0_PE1_SS_C_TXP<4>" )
			)
			( signal "@baseboard_fab2_lib.baseboard_fab2(sch_1):p3e_cpu0_pe1_ss_txp(4)"
				( objectStatus "P3E_CPU0_PE1_SS_TXP<4>" )
			)
			( signal "@baseboard_fab2_lib.baseboard_fab2(sch_1):p3e_cpu0_pe1_pch_txp(4)"
				( pinPairRef "@baseboard_fab2_lib.baseboard_fab2(sch_1):\PP342\" )
				( objectStatus "P3E_CPU0_PE1_PCH_TXP<4>" )
			)
			( signal "@baseboard_fab2_lib.baseboard_fab2(sch_1):p3e_cpu0_pe1_ss_txn(5)"
				( objectStatus "P3E_CPU0_PE1_SS_TXN<5>" )
			)
			( signal "@baseboard_fab2_lib.baseboard_fab2(sch_1):p3e_cpu0_pe1_ss_c_txn(5)"
				( pinPairRef "@baseboard_fab2_lib.baseboard_fab2(sch_1):\PP335\" )
				( objectStatus "P3E_CPU0_PE1_SS_C_TXN<5>" )
			)
			( signal "@baseboard_fab2_lib.baseboard_fab2(sch_1):p3e_cpu0_pe1_pch_txn(5)"
				( pinPairRef "@baseboard_fab2_lib.baseboard_fab2(sch_1):\PP336\" )
				( objectStatus "P3E_CPU0_PE1_PCH_TXN<5>" )
			)
			( signal "@baseboard_fab2_lib.baseboard_fab2(sch_1):p3e_cpu0_pe1_ss_c_txp(5)"
				( pinPairRef "@baseboard_fab2_lib.baseboard_fab2(sch_1):\PP337\" )
				( objectStatus "P3E_CPU0_PE1_SS_C_TXP<5>" )
			)
			( signal "@baseboard_fab2_lib.baseboard_fab2(sch_1):p3e_cpu0_pe1_ss_txp(5)"
				( objectStatus "P3E_CPU0_PE1_SS_TXP<5>" )
			)
			( signal "@baseboard_fab2_lib.baseboard_fab2(sch_1):p3e_cpu0_pe1_pch_txp(5)"
				( pinPairRef "@baseboard_fab2_lib.baseboard_fab2(sch_1):\PP338\" )
				( objectStatus "P3E_CPU0_PE1_PCH_TXP<5>" )
			)
			( signal "@baseboard_fab2_lib.baseboard_fab2(sch_1):p3e_cpu0_pe1_ss_txn(6)"
				( objectStatus "P3E_CPU0_PE1_SS_TXN<6>" )
			)
			( signal "@baseboard_fab2_lib.baseboard_fab2(sch_1):p3e_cpu0_pe1_ss_c_txn(6)"
				( pinPairRef "@baseboard_fab2_lib.baseboard_fab2(sch_1):\PP331\" )
				( objectStatus "P3E_CPU0_PE1_SS_C_TXN<6>" )
			)
			( signal "@baseboard_fab2_lib.baseboard_fab2(sch_1):p3e_cpu0_pe1_pch_txn(6)"
				( pinPairRef "@baseboard_fab2_lib.baseboard_fab2(sch_1):\PP332\" )
				( objectStatus "P3E_CPU0_PE1_PCH_TXN<6>" )
			)
			( signal "@baseboard_fab2_lib.baseboard_fab2(sch_1):p3e_cpu0_pe1_ss_c_txp(6)"
				( pinPairRef "@baseboard_fab2_lib.baseboard_fab2(sch_1):\PP333\" )
				( objectStatus "P3E_CPU0_PE1_SS_C_TXP<6>" )
			)
			( signal "@baseboard_fab2_lib.baseboard_fab2(sch_1):p3e_cpu0_pe1_ss_txp(6)"
				( objectStatus "P3E_CPU0_PE1_SS_TXP<6>" )
			)
			( signal "@baseboard_fab2_lib.baseboard_fab2(sch_1):p3e_cpu0_pe1_pch_txp(6)"
				( pinPairRef "@baseboard_fab2_lib.baseboard_fab2(sch_1):\PP334\" )
				( objectStatus "P3E_CPU0_PE1_PCH_TXP<6>" )
			)
			( signal "@baseboard_fab2_lib.baseboard_fab2(sch_1):p3e_cpu0_pe1_ss_txn(7)"
				( objectStatus "P3E_CPU0_PE1_SS_TXN<7>" )
			)
			( signal "@baseboard_fab2_lib.baseboard_fab2(sch_1):p3e_cpu0_pe1_ss_c_txn(7)"
				( pinPairRef "@baseboard_fab2_lib.baseboard_fab2(sch_1):\PP327\" )
				( objectStatus "P3E_CPU0_PE1_SS_C_TXN<7>" )
			)
			( signal "@baseboard_fab2_lib.baseboard_fab2(sch_1):p3e_cpu0_pe1_pch_txn(7)"
				( pinPairRef "@baseboard_fab2_lib.baseboard_fab2(sch_1):\PP328\" )
				( objectStatus "P3E_CPU0_PE1_PCH_TXN<7>" )
			)
			( signal "@baseboard_fab2_lib.baseboard_fab2(sch_1):p3e_cpu0_pe1_ss_c_txp(7)"
				( pinPairRef "@baseboard_fab2_lib.baseboard_fab2(sch_1):\PP329\" )
				( objectStatus "P3E_CPU0_PE1_SS_C_TXP<7>" )
			)
			( signal "@baseboard_fab2_lib.baseboard_fab2(sch_1):p3e_cpu0_pe1_ss_txp(7)"
				( objectStatus "P3E_CPU0_PE1_SS_TXP<7>" )
			)
			( signal "@baseboard_fab2_lib.baseboard_fab2(sch_1):p3e_cpu0_pe1_pch_txp(7)"
				( pinPairRef "@baseboard_fab2_lib.baseboard_fab2(sch_1):\PP330\" )
				( objectStatus "P3E_CPU0_PE1_PCH_TXP<7>" )
			)
			( signal "@baseboard_fab2_lib.baseboard_fab2(sch_1):p3e_cpu0_pe2_ss_txn(0)"
				( pinPairRef "@baseboard_fab2_lib.baseboard_fab2(sch_1):\PP323\" )
				( objectStatus "P3E_CPU0_PE2_SS_TXN<0>" )
			)
			( signal "@baseboard_fab2_lib.baseboard_fab2(sch_1):p3e_cpu0_pe2_ss_c_txn(0)"
				( pinPairRef "@baseboard_fab2_lib.baseboard_fab2(sch_1):\PP324\" )
				( objectStatus "P3E_CPU0_PE2_SS_C_TXN<0>" )
			)
			( signal "@baseboard_fab2_lib.baseboard_fab2(sch_1):p3e_cpu0_pe2_ss_c_txp(0)"
				( pinPairRef "@baseboard_fab2_lib.baseboard_fab2(sch_1):\PP325\" )
				( objectStatus "P3E_CPU0_PE2_SS_C_TXP<0>" )
			)
			( signal "@baseboard_fab2_lib.baseboard_fab2(sch_1):p3e_cpu0_pe2_ss_txp(0)"
				( pinPairRef "@baseboard_fab2_lib.baseboard_fab2(sch_1):\PP326\" )
				( objectStatus "P3E_CPU0_PE2_SS_TXP<0>" )
			)
			( signal "@baseboard_fab2_lib.baseboard_fab2(sch_1):p3e_cpu0_pe2_ss_txn(1)"
				( pinPairRef "@baseboard_fab2_lib.baseboard_fab2(sch_1):\PP319\" )
				( objectStatus "P3E_CPU0_PE2_SS_TXN<1>" )
			)
			( signal "@baseboard_fab2_lib.baseboard_fab2(sch_1):p3e_cpu0_pe2_ss_c_txn(1)"
				( pinPairRef "@baseboard_fab2_lib.baseboard_fab2(sch_1):\PP320\" )
				( objectStatus "P3E_CPU0_PE2_SS_C_TXN<1>" )
			)
			( signal "@baseboard_fab2_lib.baseboard_fab2(sch_1):p3e_cpu0_pe2_ss_c_txp(1)"
				( pinPairRef "@baseboard_fab2_lib.baseboard_fab2(sch_1):\PP321\" )
				( objectStatus "P3E_CPU0_PE2_SS_C_TXP<1>" )
			)
			( signal "@baseboard_fab2_lib.baseboard_fab2(sch_1):p3e_cpu0_pe2_ss_txp(1)"
				( pinPairRef "@baseboard_fab2_lib.baseboard_fab2(sch_1):\PP322\" )
				( objectStatus "P3E_CPU0_PE2_SS_TXP<1>" )
			)
			( signal "@baseboard_fab2_lib.baseboard_fab2(sch_1):p3e_cpu0_pe2_ss_txn(2)"
				( pinPairRef "@baseboard_fab2_lib.baseboard_fab2(sch_1):\PP315\" )
				( objectStatus "P3E_CPU0_PE2_SS_TXN<2>" )
			)
			( signal "@baseboard_fab2_lib.baseboard_fab2(sch_1):p3e_cpu0_pe2_ss_c_txn(2)"
				( pinPairRef "@baseboard_fab2_lib.baseboard_fab2(sch_1):\PP316\" )
				( objectStatus "P3E_CPU0_PE2_SS_C_TXN<2>" )
			)
			( signal "@baseboard_fab2_lib.baseboard_fab2(sch_1):p3e_cpu0_pe2_ss_c_txp(2)"
				( pinPairRef "@baseboard_fab2_lib.baseboard_fab2(sch_1):\PP317\" )
				( objectStatus "P3E_CPU0_PE2_SS_C_TXP<2>" )
			)
			( signal "@baseboard_fab2_lib.baseboard_fab2(sch_1):p3e_cpu0_pe2_ss_txp(2)"
				( pinPairRef "@baseboard_fab2_lib.baseboard_fab2(sch_1):\PP318\" )
				( objectStatus "P3E_CPU0_PE2_SS_TXP<2>" )
			)
			( signal "@baseboard_fab2_lib.baseboard_fab2(sch_1):p3e_cpu0_pe2_ss_txn(3)"
				( pinPairRef "@baseboard_fab2_lib.baseboard_fab2(sch_1):\PP311\" )
				( objectStatus "P3E_CPU0_PE2_SS_TXN<3>" )
			)
			( signal "@baseboard_fab2_lib.baseboard_fab2(sch_1):p3e_cpu0_pe2_ss_c_txn(3)"
				( pinPairRef "@baseboard_fab2_lib.baseboard_fab2(sch_1):\PP312\" )
				( objectStatus "P3E_CPU0_PE2_SS_C_TXN<3>" )
			)
			( signal "@baseboard_fab2_lib.baseboard_fab2(sch_1):p3e_cpu0_pe2_ss_c_txp(3)"
				( pinPairRef "@baseboard_fab2_lib.baseboard_fab2(sch_1):\PP313\" )
				( objectStatus "P3E_CPU0_PE2_SS_C_TXP<3>" )
			)
			( signal "@baseboard_fab2_lib.baseboard_fab2(sch_1):p3e_cpu0_pe2_ss_txp(3)"
				( pinPairRef "@baseboard_fab2_lib.baseboard_fab2(sch_1):\PP314\" )
				( objectStatus "P3E_CPU0_PE2_SS_TXP<3>" )
			)
			( signal "@baseboard_fab2_lib.baseboard_fab2(sch_1):p3e_cpu0_pe2_ss_txn(4)"
				( pinPairRef "@baseboard_fab2_lib.baseboard_fab2(sch_1):\PP307\" )
				( objectStatus "P3E_CPU0_PE2_SS_TXN<4>" )
			)
			( signal "@baseboard_fab2_lib.baseboard_fab2(sch_1):p3e_cpu0_pe2_ss_c_txn(4)"
				( pinPairRef "@baseboard_fab2_lib.baseboard_fab2(sch_1):\PP308\" )
				( objectStatus "P3E_CPU0_PE2_SS_C_TXN<4>" )
			)
			( signal "@baseboard_fab2_lib.baseboard_fab2(sch_1):p3e_cpu0_pe2_ss_c_txp(4)"
				( pinPairRef "@baseboard_fab2_lib.baseboard_fab2(sch_1):\PP309\" )
				( objectStatus "P3E_CPU0_PE2_SS_C_TXP<4>" )
			)
			( signal "@baseboard_fab2_lib.baseboard_fab2(sch_1):p3e_cpu0_pe2_ss_txp(4)"
				( pinPairRef "@baseboard_fab2_lib.baseboard_fab2(sch_1):\PP310\" )
				( objectStatus "P3E_CPU0_PE2_SS_TXP<4>" )
			)
			( signal "@baseboard_fab2_lib.baseboard_fab2(sch_1):p3e_cpu0_pe2_ss_txn(5)"
				( pinPairRef "@baseboard_fab2_lib.baseboard_fab2(sch_1):\PP303\" )
				( objectStatus "P3E_CPU0_PE2_SS_TXN<5>" )
			)
			( signal "@baseboard_fab2_lib.baseboard_fab2(sch_1):p3e_cpu0_pe2_ss_c_txn(5)"
				( pinPairRef "@baseboard_fab2_lib.baseboard_fab2(sch_1):\PP304\" )
				( objectStatus "P3E_CPU0_PE2_SS_C_TXN<5>" )
			)
			( signal "@baseboard_fab2_lib.baseboard_fab2(sch_1):p3e_cpu0_pe2_ss_c_txp(5)"
				( pinPairRef "@baseboard_fab2_lib.baseboard_fab2(sch_1):\PP305\" )
				( objectStatus "P3E_CPU0_PE2_SS_C_TXP<5>" )
			)
			( signal "@baseboard_fab2_lib.baseboard_fab2(sch_1):p3e_cpu0_pe2_ss_txp(5)"
				( pinPairRef "@baseboard_fab2_lib.baseboard_fab2(sch_1):\PP306\" )
				( objectStatus "P3E_CPU0_PE2_SS_TXP<5>" )
			)
			( signal "@baseboard_fab2_lib.baseboard_fab2(sch_1):p3e_cpu0_pe2_ss_txn(6)"
				( pinPairRef "@baseboard_fab2_lib.baseboard_fab2(sch_1):\PP299\" )
				( objectStatus "P3E_CPU0_PE2_SS_TXN<6>" )
			)
			( signal "@baseboard_fab2_lib.baseboard_fab2(sch_1):p3e_cpu0_pe2_ss_c_txn(6)"
				( pinPairRef "@baseboard_fab2_lib.baseboard_fab2(sch_1):\PP300\" )
				( objectStatus "P3E_CPU0_PE2_SS_C_TXN<6>" )
			)
			( signal "@baseboard_fab2_lib.baseboard_fab2(sch_1):p3e_cpu0_pe2_ss_c_txp(6)"
				( pinPairRef "@baseboard_fab2_lib.baseboard_fab2(sch_1):\PP301\" )
				( objectStatus "P3E_CPU0_PE2_SS_C_TXP<6>" )
			)
			( signal "@baseboard_fab2_lib.baseboard_fab2(sch_1):p3e_cpu0_pe2_ss_txp(6)"
				( pinPairRef "@baseboard_fab2_lib.baseboard_fab2(sch_1):\PP302\" )
				( objectStatus "P3E_CPU0_PE2_SS_TXP<6>" )
			)
			( signal "@baseboard_fab2_lib.baseboard_fab2(sch_1):p3e_cpu0_pe2_ss_txn(7)"
				( pinPairRef "@baseboard_fab2_lib.baseboard_fab2(sch_1):\PP295\" )
				( objectStatus "P3E_CPU0_PE2_SS_TXN<7>" )
			)
			( signal "@baseboard_fab2_lib.baseboard_fab2(sch_1):p3e_cpu0_pe2_ss_c_txn(7)"
				( pinPairRef "@baseboard_fab2_lib.baseboard_fab2(sch_1):\PP296\" )
				( objectStatus "P3E_CPU0_PE2_SS_C_TXN<7>" )
			)
			( signal "@baseboard_fab2_lib.baseboard_fab2(sch_1):p3e_cpu0_pe2_ss_c_txp(7)"
				( pinPairRef "@baseboard_fab2_lib.baseboard_fab2(sch_1):\PP297\" )
				( objectStatus "P3E_CPU0_PE2_SS_C_TXP<7>" )
			)
			( signal "@baseboard_fab2_lib.baseboard_fab2(sch_1):p3e_cpu0_pe2_ss_txp(7)"
				( pinPairRef "@baseboard_fab2_lib.baseboard_fab2(sch_1):\PP298\" )
				( objectStatus "P3E_CPU0_PE2_SS_TXP<7>" )
			)
			( signal "@baseboard_fab2_lib.baseboard_fab2(sch_1):p3e_cpu0_pe2_ss_txn(8)"
				( pinPairRef "@baseboard_fab2_lib.baseboard_fab2(sch_1):\PP291\" )
				( objectStatus "P3E_CPU0_PE2_SS_TXN<8>" )
			)
			( signal "@baseboard_fab2_lib.baseboard_fab2(sch_1):p3e_cpu0_pe2_ss_c_txn(8)"
				( pinPairRef "@baseboard_fab2_lib.baseboard_fab2(sch_1):\PP292\" )
				( objectStatus "P3E_CPU0_PE2_SS_C_TXN<8>" )
			)
			( signal "@baseboard_fab2_lib.baseboard_fab2(sch_1):p3e_cpu0_pe2_ss_c_txp(8)"
				( pinPairRef "@baseboard_fab2_lib.baseboard_fab2(sch_1):\PP293\" )
				( objectStatus "P3E_CPU0_PE2_SS_C_TXP<8>" )
			)
			( signal "@baseboard_fab2_lib.baseboard_fab2(sch_1):p3e_cpu0_pe2_ss_txp(8)"
				( pinPairRef "@baseboard_fab2_lib.baseboard_fab2(sch_1):\PP294\" )
				( objectStatus "P3E_CPU0_PE2_SS_TXP<8>" )
			)
			( signal "@baseboard_fab2_lib.baseboard_fab2(sch_1):p3e_cpu0_pe2_ss_txn(9)"
				( pinPairRef "@baseboard_fab2_lib.baseboard_fab2(sch_1):\PP287\" )
				( objectStatus "P3E_CPU0_PE2_SS_TXN<9>" )
			)
			( signal "@baseboard_fab2_lib.baseboard_fab2(sch_1):p3e_cpu0_pe2_ss_c_txn(9)"
				( pinPairRef "@baseboard_fab2_lib.baseboard_fab2(sch_1):\PP288\" )
				( objectStatus "P3E_CPU0_PE2_SS_C_TXN<9>" )
			)
			( signal "@baseboard_fab2_lib.baseboard_fab2(sch_1):p3e_cpu0_pe2_ss_c_txp(9)"
				( pinPairRef "@baseboard_fab2_lib.baseboard_fab2(sch_1):\PP289\" )
				( objectStatus "P3E_CPU0_PE2_SS_C_TXP<9>" )
			)
			( signal "@baseboard_fab2_lib.baseboard_fab2(sch_1):p3e_cpu0_pe2_ss_txp(9)"
				( pinPairRef "@baseboard_fab2_lib.baseboard_fab2(sch_1):\PP290\" )
				( objectStatus "P3E_CPU0_PE2_SS_TXP<9>" )
			)
			( signal "@baseboard_fab2_lib.baseboard_fab2(sch_1):p3e_cpu0_pe2_ss_txn(10)"
				( pinPairRef "@baseboard_fab2_lib.baseboard_fab2(sch_1):\PP283\" )
				( objectStatus "P3E_CPU0_PE2_SS_TXN<10>" )
			)
			( signal "@baseboard_fab2_lib.baseboard_fab2(sch_1):p3e_cpu0_pe2_ss_c_txn(10)"
				( pinPairRef "@baseboard_fab2_lib.baseboard_fab2(sch_1):\PP284\" )
				( objectStatus "P3E_CPU0_PE2_SS_C_TXN<10>" )
			)
			( signal "@baseboard_fab2_lib.baseboard_fab2(sch_1):p3e_cpu0_pe2_ss_c_txp(10)"
				( pinPairRef "@baseboard_fab2_lib.baseboard_fab2(sch_1):\PP285\" )
				( objectStatus "P3E_CPU0_PE2_SS_C_TXP<10>" )
			)
			( signal "@baseboard_fab2_lib.baseboard_fab2(sch_1):p3e_cpu0_pe2_ss_txp(10)"
				( pinPairRef "@baseboard_fab2_lib.baseboard_fab2(sch_1):\PP286\" )
				( objectStatus "P3E_CPU0_PE2_SS_TXP<10>" )
			)
			( signal "@baseboard_fab2_lib.baseboard_fab2(sch_1):p3e_cpu0_pe2_ss_txn(11)"
				( pinPairRef "@baseboard_fab2_lib.baseboard_fab2(sch_1):\PP279\" )
				( objectStatus "P3E_CPU0_PE2_SS_TXN<11>" )
			)
			( signal "@baseboard_fab2_lib.baseboard_fab2(sch_1):p3e_cpu0_pe2_ss_c_txn(11)"
				( pinPairRef "@baseboard_fab2_lib.baseboard_fab2(sch_1):\PP280\" )
				( objectStatus "P3E_CPU0_PE2_SS_C_TXN<11>" )
			)
			( signal "@baseboard_fab2_lib.baseboard_fab2(sch_1):p3e_cpu0_pe2_ss_c_txp(11)"
				( pinPairRef "@baseboard_fab2_lib.baseboard_fab2(sch_1):\PP281\" )
				( objectStatus "P3E_CPU0_PE2_SS_C_TXP<11>" )
			)
			( signal "@baseboard_fab2_lib.baseboard_fab2(sch_1):p3e_cpu0_pe2_ss_txp(11)"
				( pinPairRef "@baseboard_fab2_lib.baseboard_fab2(sch_1):\PP282\" )
				( objectStatus "P3E_CPU0_PE2_SS_TXP<11>" )
			)
			( signal "@baseboard_fab2_lib.baseboard_fab2(sch_1):p3e_cpu0_pe2_ss_txn(12)"
				( pinPairRef "@baseboard_fab2_lib.baseboard_fab2(sch_1):\PP275\" )
				( objectStatus "P3E_CPU0_PE2_SS_TXN<12>" )
			)
			( signal "@baseboard_fab2_lib.baseboard_fab2(sch_1):p3e_cpu0_pe2_ss_c_txn(12)"
				( pinPairRef "@baseboard_fab2_lib.baseboard_fab2(sch_1):\PP276\" )
				( objectStatus "P3E_CPU0_PE2_SS_C_TXN<12>" )
			)
			( signal "@baseboard_fab2_lib.baseboard_fab2(sch_1):p3e_cpu0_pe2_ss_c_txp(12)"
				( pinPairRef "@baseboard_fab2_lib.baseboard_fab2(sch_1):\PP277\" )
				( objectStatus "P3E_CPU0_PE2_SS_C_TXP<12>" )
			)
			( signal "@baseboard_fab2_lib.baseboard_fab2(sch_1):p3e_cpu0_pe2_ss_txp(12)"
				( pinPairRef "@baseboard_fab2_lib.baseboard_fab2(sch_1):\PP278\" )
				( objectStatus "P3E_CPU0_PE2_SS_TXP<12>" )
			)
			( signal "@baseboard_fab2_lib.baseboard_fab2(sch_1):p3e_cpu0_pe2_ss_txn(13)"
				( pinPairRef "@baseboard_fab2_lib.baseboard_fab2(sch_1):\PP271\" )
				( objectStatus "P3E_CPU0_PE2_SS_TXN<13>" )
			)
			( signal "@baseboard_fab2_lib.baseboard_fab2(sch_1):p3e_cpu0_pe2_ss_c_txn(13)"
				( pinPairRef "@baseboard_fab2_lib.baseboard_fab2(sch_1):\PP272\" )
				( objectStatus "P3E_CPU0_PE2_SS_C_TXN<13>" )
			)
			( signal "@baseboard_fab2_lib.baseboard_fab2(sch_1):p3e_cpu0_pe2_ss_c_txp(13)"
				( pinPairRef "@baseboard_fab2_lib.baseboard_fab2(sch_1):\PP273\" )
				( objectStatus "P3E_CPU0_PE2_SS_C_TXP<13>" )
			)
			( signal "@baseboard_fab2_lib.baseboard_fab2(sch_1):p3e_cpu0_pe2_ss_txp(13)"
				( pinPairRef "@baseboard_fab2_lib.baseboard_fab2(sch_1):\PP274\" )
				( objectStatus "P3E_CPU0_PE2_SS_TXP<13>" )
			)
			( signal "@baseboard_fab2_lib.baseboard_fab2(sch_1):p3e_cpu0_pe2_ss_txn(14)"
				( pinPairRef "@baseboard_fab2_lib.baseboard_fab2(sch_1):\PP267\" )
				( objectStatus "P3E_CPU0_PE2_SS_TXN<14>" )
			)
			( signal "@baseboard_fab2_lib.baseboard_fab2(sch_1):p3e_cpu0_pe2_ss_c_txn(14)"
				( pinPairRef "@baseboard_fab2_lib.baseboard_fab2(sch_1):\PP268\" )
				( objectStatus "P3E_CPU0_PE2_SS_C_TXN<14>" )
			)
			( signal "@baseboard_fab2_lib.baseboard_fab2(sch_1):p3e_cpu0_pe2_ss_c_txp(14)"
				( pinPairRef "@baseboard_fab2_lib.baseboard_fab2(sch_1):\PP269\" )
				( objectStatus "P3E_CPU0_PE2_SS_C_TXP<14>" )
			)
			( signal "@baseboard_fab2_lib.baseboard_fab2(sch_1):p3e_cpu0_pe2_ss_txp(14)"
				( pinPairRef "@baseboard_fab2_lib.baseboard_fab2(sch_1):\PP270\" )
				( objectStatus "P3E_CPU0_PE2_SS_TXP<14>" )
			)
			( signal "@baseboard_fab2_lib.baseboard_fab2(sch_1):p3e_cpu0_pe2_ss_txn(15)"
				( pinPairRef "@baseboard_fab2_lib.baseboard_fab2(sch_1):\PP263\" )
				( objectStatus "P3E_CPU0_PE2_SS_TXN<15>" )
			)
			( signal "@baseboard_fab2_lib.baseboard_fab2(sch_1):p3e_cpu0_pe2_ss_c_txn(15)"
				( pinPairRef "@baseboard_fab2_lib.baseboard_fab2(sch_1):\PP264\" )
				( objectStatus "P3E_CPU0_PE2_SS_C_TXN<15>" )
			)
			( signal "@baseboard_fab2_lib.baseboard_fab2(sch_1):p3e_cpu0_pe2_ss_c_txp(15)"
				( pinPairRef "@baseboard_fab2_lib.baseboard_fab2(sch_1):\PP265\" )
				( objectStatus "P3E_CPU0_PE2_SS_C_TXP<15>" )
			)
			( signal "@baseboard_fab2_lib.baseboard_fab2(sch_1):p3e_cpu0_pe2_ss_txp(15)"
				( pinPairRef "@baseboard_fab2_lib.baseboard_fab2(sch_1):\PP266\" )
				( objectStatus "P3E_CPU0_PE2_SS_TXP<15>" )
			)
			( signal "@baseboard_fab2_lib.baseboard_fab2(sch_1):p3e_cpu0_pe3_ocp_txn(0)"
				( pinPairRef "@baseboard_fab2_lib.baseboard_fab2(sch_1):\PP259\" )
				( objectStatus "P3E_CPU0_PE3_OCP_TXN<0>" )
			)
			( signal "@baseboard_fab2_lib.baseboard_fab2(sch_1):p3e_ocp_cpu0_pe3_c_txn(0)"
				( pinPairRef "@baseboard_fab2_lib.baseboard_fab2(sch_1):\PP260\" )
				( objectStatus "P3E_OCP_CPU0_PE3_C_TXN<0>" )
			)
			( signal "@baseboard_fab2_lib.baseboard_fab2(sch_1):p3e_ocp_cpu0_pe3_c_txp(0)"
				( pinPairRef "@baseboard_fab2_lib.baseboard_fab2(sch_1):\PP261\" )
				( objectStatus "P3E_OCP_CPU0_PE3_C_TXP<0>" )
			)
			( signal "@baseboard_fab2_lib.baseboard_fab2(sch_1):p3e_cpu0_pe3_ocp_txp(0)"
				( pinPairRef "@baseboard_fab2_lib.baseboard_fab2(sch_1):\PP262\" )
				( objectStatus "P3E_CPU0_PE3_OCP_TXP<0>" )
			)
			( signal "@baseboard_fab2_lib.baseboard_fab2(sch_1):p3e_cpu0_pe3_ocp_txn(1)"
				( pinPairRef "@baseboard_fab2_lib.baseboard_fab2(sch_1):\PP255\" )
				( objectStatus "P3E_CPU0_PE3_OCP_TXN<1>" )
			)
			( signal "@baseboard_fab2_lib.baseboard_fab2(sch_1):p3e_ocp_cpu0_pe3_c_txn(1)"
				( pinPairRef "@baseboard_fab2_lib.baseboard_fab2(sch_1):\PP256\" )
				( objectStatus "P3E_OCP_CPU0_PE3_C_TXN<1>" )
			)
			( signal "@baseboard_fab2_lib.baseboard_fab2(sch_1):p3e_ocp_cpu0_pe3_c_txp(1)"
				( pinPairRef "@baseboard_fab2_lib.baseboard_fab2(sch_1):\PP257\" )
				( objectStatus "P3E_OCP_CPU0_PE3_C_TXP<1>" )
			)
			( signal "@baseboard_fab2_lib.baseboard_fab2(sch_1):p3e_cpu0_pe3_ocp_txp(1)"
				( pinPairRef "@baseboard_fab2_lib.baseboard_fab2(sch_1):\PP258\" )
				( objectStatus "P3E_CPU0_PE3_OCP_TXP<1>" )
			)
			( signal "@baseboard_fab2_lib.baseboard_fab2(sch_1):p3e_cpu0_pe3_ocp_txn(2)"
				( pinPairRef "@baseboard_fab2_lib.baseboard_fab2(sch_1):\PP251\" )
				( objectStatus "P3E_CPU0_PE3_OCP_TXN<2>" )
			)
			( signal "@baseboard_fab2_lib.baseboard_fab2(sch_1):p3e_ocp_cpu0_pe3_c_txn(2)"
				( pinPairRef "@baseboard_fab2_lib.baseboard_fab2(sch_1):\PP252\" )
				( objectStatus "P3E_OCP_CPU0_PE3_C_TXN<2>" )
			)
			( signal "@baseboard_fab2_lib.baseboard_fab2(sch_1):p3e_ocp_cpu0_pe3_c_txp(2)"
				( pinPairRef "@baseboard_fab2_lib.baseboard_fab2(sch_1):\PP253\" )
				( objectStatus "P3E_OCP_CPU0_PE3_C_TXP<2>" )
			)
			( signal "@baseboard_fab2_lib.baseboard_fab2(sch_1):p3e_cpu0_pe3_ocp_txp(2)"
				( pinPairRef "@baseboard_fab2_lib.baseboard_fab2(sch_1):\PP254\" )
				( objectStatus "P3E_CPU0_PE3_OCP_TXP<2>" )
			)
			( signal "@baseboard_fab2_lib.baseboard_fab2(sch_1):p3e_cpu0_pe3_ocp_txn(3)"
				( pinPairRef "@baseboard_fab2_lib.baseboard_fab2(sch_1):\PP247\" )
				( objectStatus "P3E_CPU0_PE3_OCP_TXN<3>" )
			)
			( signal "@baseboard_fab2_lib.baseboard_fab2(sch_1):p3e_ocp_cpu0_pe3_c_txn(3)"
				( pinPairRef "@baseboard_fab2_lib.baseboard_fab2(sch_1):\PP248\" )
				( objectStatus "P3E_OCP_CPU0_PE3_C_TXN<3>" )
			)
			( signal "@baseboard_fab2_lib.baseboard_fab2(sch_1):p3e_ocp_cpu0_pe3_c_txp(3)"
				( pinPairRef "@baseboard_fab2_lib.baseboard_fab2(sch_1):\PP249\" )
				( objectStatus "P3E_OCP_CPU0_PE3_C_TXP<3>" )
			)
			( signal "@baseboard_fab2_lib.baseboard_fab2(sch_1):p3e_cpu0_pe3_ocp_txp(3)"
				( pinPairRef "@baseboard_fab2_lib.baseboard_fab2(sch_1):\PP250\" )
				( objectStatus "P3E_CPU0_PE3_OCP_TXP<3>" )
			)
			( signal "@baseboard_fab2_lib.baseboard_fab2(sch_1):p3e_cpu0_pe3_ocp_txn(4)"
				( pinPairRef "@baseboard_fab2_lib.baseboard_fab2(sch_1):\PP243\" )
				( objectStatus "P3E_CPU0_PE3_OCP_TXN<4>" )
			)
			( signal "@baseboard_fab2_lib.baseboard_fab2(sch_1):p3e_ocp_cpu0_pe3_c_txn(4)"
				( pinPairRef "@baseboard_fab2_lib.baseboard_fab2(sch_1):\PP244\" )
				( objectStatus "P3E_OCP_CPU0_PE3_C_TXN<4>" )
			)
			( signal "@baseboard_fab2_lib.baseboard_fab2(sch_1):p3e_ocp_cpu0_pe3_c_txp(4)"
				( pinPairRef "@baseboard_fab2_lib.baseboard_fab2(sch_1):\PP245\" )
				( objectStatus "P3E_OCP_CPU0_PE3_C_TXP<4>" )
			)
			( signal "@baseboard_fab2_lib.baseboard_fab2(sch_1):p3e_cpu0_pe3_ocp_txp(4)"
				( pinPairRef "@baseboard_fab2_lib.baseboard_fab2(sch_1):\PP246\" )
				( objectStatus "P3E_CPU0_PE3_OCP_TXP<4>" )
			)
			( signal "@baseboard_fab2_lib.baseboard_fab2(sch_1):p3e_cpu0_pe3_ocp_txn(5)"
				( pinPairRef "@baseboard_fab2_lib.baseboard_fab2(sch_1):\PP239\" )
				( objectStatus "P3E_CPU0_PE3_OCP_TXN<5>" )
			)
			( signal "@baseboard_fab2_lib.baseboard_fab2(sch_1):p3e_ocp_cpu0_pe3_c_txn(5)"
				( pinPairRef "@baseboard_fab2_lib.baseboard_fab2(sch_1):\PP240\" )
				( objectStatus "P3E_OCP_CPU0_PE3_C_TXN<5>" )
			)
			( signal "@baseboard_fab2_lib.baseboard_fab2(sch_1):p3e_ocp_cpu0_pe3_c_txp(5)"
				( pinPairRef "@baseboard_fab2_lib.baseboard_fab2(sch_1):\PP241\" )
				( objectStatus "P3E_OCP_CPU0_PE3_C_TXP<5>" )
			)
			( signal "@baseboard_fab2_lib.baseboard_fab2(sch_1):p3e_cpu0_pe3_ocp_txp(5)"
				( pinPairRef "@baseboard_fab2_lib.baseboard_fab2(sch_1):\PP242\" )
				( objectStatus "P3E_CPU0_PE3_OCP_TXP<5>" )
			)
			( signal "@baseboard_fab2_lib.baseboard_fab2(sch_1):p3e_cpu0_pe3_ocp_txn(6)"
				( pinPairRef "@baseboard_fab2_lib.baseboard_fab2(sch_1):\PP235\" )
				( objectStatus "P3E_CPU0_PE3_OCP_TXN<6>" )
			)
			( signal "@baseboard_fab2_lib.baseboard_fab2(sch_1):p3e_ocp_cpu0_pe3_c_txn(6)"
				( pinPairRef "@baseboard_fab2_lib.baseboard_fab2(sch_1):\PP236\" )
				( objectStatus "P3E_OCP_CPU0_PE3_C_TXN<6>" )
			)
			( signal "@baseboard_fab2_lib.baseboard_fab2(sch_1):p3e_ocp_cpu0_pe3_c_txp(6)"
				( pinPairRef "@baseboard_fab2_lib.baseboard_fab2(sch_1):\PP237\" )
				( objectStatus "P3E_OCP_CPU0_PE3_C_TXP<6>" )
			)
			( signal "@baseboard_fab2_lib.baseboard_fab2(sch_1):p3e_cpu0_pe3_ocp_txp(6)"
				( pinPairRef "@baseboard_fab2_lib.baseboard_fab2(sch_1):\PP238\" )
				( objectStatus "P3E_CPU0_PE3_OCP_TXP<6>" )
			)
			( signal "@baseboard_fab2_lib.baseboard_fab2(sch_1):p3e_cpu0_pe3_ocp_txn(7)"
				( pinPairRef "@baseboard_fab2_lib.baseboard_fab2(sch_1):\PP231\" )
				( objectStatus "P3E_CPU0_PE3_OCP_TXN<7>" )
			)
			( signal "@baseboard_fab2_lib.baseboard_fab2(sch_1):p3e_ocp_cpu0_pe3_c_txn(7)"
				( pinPairRef "@baseboard_fab2_lib.baseboard_fab2(sch_1):\PP232\" )
				( objectStatus "P3E_OCP_CPU0_PE3_C_TXN<7>" )
			)
			( signal "@baseboard_fab2_lib.baseboard_fab2(sch_1):p3e_ocp_cpu0_pe3_c_txp(7)"
				( pinPairRef "@baseboard_fab2_lib.baseboard_fab2(sch_1):\PP233\" )
				( objectStatus "P3E_OCP_CPU0_PE3_C_TXP<7>" )
			)
			( signal "@baseboard_fab2_lib.baseboard_fab2(sch_1):p3e_cpu0_pe3_ocp_txp(7)"
				( pinPairRef "@baseboard_fab2_lib.baseboard_fab2(sch_1):\PP234\" )
				( objectStatus "P3E_CPU0_PE3_OCP_TXP<7>" )
			)
			( signal "@baseboard_fab2_lib.baseboard_fab2(sch_1):p3e_cpu0_pe3_ocp_txn(8)"
				( pinPairRef "@baseboard_fab2_lib.baseboard_fab2(sch_1):\PP127\" )
				( objectStatus "P3E_CPU0_PE3_OCP_TXN<8>" )
			)
			( signal "@baseboard_fab2_lib.baseboard_fab2(sch_1):p3e_ocp_cpu0_pe3_c_txn(8)"
				( pinPairRef "@baseboard_fab2_lib.baseboard_fab2(sch_1):\PP128\" )
				( objectStatus "P3E_OCP_CPU0_PE3_C_TXN<8>" )
			)
			( signal "@baseboard_fab2_lib.baseboard_fab2(sch_1):p3e_ocp_cpu0_pe3_c_txp(8)"
				( pinPairRef "@baseboard_fab2_lib.baseboard_fab2(sch_1):\PP129\" )
				( objectStatus "P3E_OCP_CPU0_PE3_C_TXP<8>" )
			)
			( signal "@baseboard_fab2_lib.baseboard_fab2(sch_1):p3e_cpu0_pe3_ocp_txp(8)"
				( pinPairRef "@baseboard_fab2_lib.baseboard_fab2(sch_1):\PP130\" )
				( objectStatus "P3E_CPU0_PE3_OCP_TXP<8>" )
			)
			( signal "@baseboard_fab2_lib.baseboard_fab2(sch_1):p3e_cpu0_pe3_ocp_txn(9)"
				( pinPairRef "@baseboard_fab2_lib.baseboard_fab2(sch_1):\PP131\" )
				( objectStatus "P3E_CPU0_PE3_OCP_TXN<9>" )
			)
			( signal "@baseboard_fab2_lib.baseboard_fab2(sch_1):p3e_ocp_cpu0_pe3_c_txn(9)"
				( pinPairRef "@baseboard_fab2_lib.baseboard_fab2(sch_1):\PP132\" )
				( objectStatus "P3E_OCP_CPU0_PE3_C_TXN<9>" )
			)
			( signal "@baseboard_fab2_lib.baseboard_fab2(sch_1):p3e_ocp_cpu0_pe3_c_txp(9)"
				( pinPairRef "@baseboard_fab2_lib.baseboard_fab2(sch_1):\PP133\" )
				( objectStatus "P3E_OCP_CPU0_PE3_C_TXP<9>" )
			)
			( signal "@baseboard_fab2_lib.baseboard_fab2(sch_1):p3e_cpu0_pe3_ocp_txp(9)"
				( pinPairRef "@baseboard_fab2_lib.baseboard_fab2(sch_1):\PP134\" )
				( objectStatus "P3E_CPU0_PE3_OCP_TXP<9>" )
			)
			( signal "@baseboard_fab2_lib.baseboard_fab2(sch_1):p3e_cpu0_pe3_ocp_txn(10)"
				( pinPairRef "@baseboard_fab2_lib.baseboard_fab2(sch_1):\PP103\" )
				( objectStatus "P3E_CPU0_PE3_OCP_TXN<10>" )
			)
			( signal "@baseboard_fab2_lib.baseboard_fab2(sch_1):p3e_ocp_cpu0_pe3_c_txn(10)"
				( pinPairRef "@baseboard_fab2_lib.baseboard_fab2(sch_1):\PP104\" )
				( objectStatus "P3E_OCP_CPU0_PE3_C_TXN<10>" )
			)
			( signal "@baseboard_fab2_lib.baseboard_fab2(sch_1):p3e_ocp_cpu0_pe3_c_txp(10)"
				( pinPairRef "@baseboard_fab2_lib.baseboard_fab2(sch_1):\PP105\" )
				( objectStatus "P3E_OCP_CPU0_PE3_C_TXP<10>" )
			)
			( signal "@baseboard_fab2_lib.baseboard_fab2(sch_1):p3e_cpu0_pe3_ocp_txp(10)"
				( pinPairRef "@baseboard_fab2_lib.baseboard_fab2(sch_1):\PP106\" )
				( objectStatus "P3E_CPU0_PE3_OCP_TXP<10>" )
			)
			( signal "@baseboard_fab2_lib.baseboard_fab2(sch_1):p3e_cpu0_pe3_ocp_txn(11)"
				( pinPairRef "@baseboard_fab2_lib.baseboard_fab2(sch_1):\PP107\" )
				( objectStatus "P3E_CPU0_PE3_OCP_TXN<11>" )
			)
			( signal "@baseboard_fab2_lib.baseboard_fab2(sch_1):p3e_ocp_cpu0_pe3_c_txn(11)"
				( pinPairRef "@baseboard_fab2_lib.baseboard_fab2(sch_1):\PP108\" )
				( objectStatus "P3E_OCP_CPU0_PE3_C_TXN<11>" )
			)
			( signal "@baseboard_fab2_lib.baseboard_fab2(sch_1):p3e_ocp_cpu0_pe3_c_txp(11)"
				( pinPairRef "@baseboard_fab2_lib.baseboard_fab2(sch_1):\PP109\" )
				( objectStatus "P3E_OCP_CPU0_PE3_C_TXP<11>" )
			)
			( signal "@baseboard_fab2_lib.baseboard_fab2(sch_1):p3e_cpu0_pe3_ocp_txp(11)"
				( pinPairRef "@baseboard_fab2_lib.baseboard_fab2(sch_1):\PP110\" )
				( objectStatus "P3E_CPU0_PE3_OCP_TXP<11>" )
			)
			( signal "@baseboard_fab2_lib.baseboard_fab2(sch_1):p3e_cpu0_pe3_ocp_txn(12)"
				( pinPairRef "@baseboard_fab2_lib.baseboard_fab2(sch_1):\PP111\" )
				( objectStatus "P3E_CPU0_PE3_OCP_TXN<12>" )
			)
			( signal "@baseboard_fab2_lib.baseboard_fab2(sch_1):p3e_ocp_cpu0_pe3_c_txn(12)"
				( pinPairRef "@baseboard_fab2_lib.baseboard_fab2(sch_1):\PP112\" )
				( objectStatus "P3E_OCP_CPU0_PE3_C_TXN<12>" )
			)
			( signal "@baseboard_fab2_lib.baseboard_fab2(sch_1):p3e_ocp_cpu0_pe3_c_txp(12)"
				( pinPairRef "@baseboard_fab2_lib.baseboard_fab2(sch_1):\PP113\" )
				( objectStatus "P3E_OCP_CPU0_PE3_C_TXP<12>" )
			)
			( signal "@baseboard_fab2_lib.baseboard_fab2(sch_1):p3e_cpu0_pe3_ocp_txp(12)"
				( pinPairRef "@baseboard_fab2_lib.baseboard_fab2(sch_1):\PP114\" )
				( objectStatus "P3E_CPU0_PE3_OCP_TXP<12>" )
			)
			( signal "@baseboard_fab2_lib.baseboard_fab2(sch_1):p3e_cpu0_pe3_ocp_txn(13)"
				( pinPairRef "@baseboard_fab2_lib.baseboard_fab2(sch_1):\PP115\" )
				( objectStatus "P3E_CPU0_PE3_OCP_TXN<13>" )
			)
			( signal "@baseboard_fab2_lib.baseboard_fab2(sch_1):p3e_ocp_cpu0_pe3_c_txn(13)"
				( pinPairRef "@baseboard_fab2_lib.baseboard_fab2(sch_1):\PP116\" )
				( objectStatus "P3E_OCP_CPU0_PE3_C_TXN<13>" )
			)
			( signal "@baseboard_fab2_lib.baseboard_fab2(sch_1):p3e_ocp_cpu0_pe3_c_txp(13)"
				( pinPairRef "@baseboard_fab2_lib.baseboard_fab2(sch_1):\PP117\" )
				( objectStatus "P3E_OCP_CPU0_PE3_C_TXP<13>" )
			)
			( signal "@baseboard_fab2_lib.baseboard_fab2(sch_1):p3e_cpu0_pe3_ocp_txp(13)"
				( pinPairRef "@baseboard_fab2_lib.baseboard_fab2(sch_1):\PP118\" )
				( objectStatus "P3E_CPU0_PE3_OCP_TXP<13>" )
			)
			( signal "@baseboard_fab2_lib.baseboard_fab2(sch_1):p3e_cpu0_pe3_ocp_txn(14)"
				( pinPairRef "@baseboard_fab2_lib.baseboard_fab2(sch_1):\PP119\" )
				( objectStatus "P3E_CPU0_PE3_OCP_TXN<14>" )
			)
			( signal "@baseboard_fab2_lib.baseboard_fab2(sch_1):p3e_ocp_cpu0_pe3_c_txn(14)"
				( pinPairRef "@baseboard_fab2_lib.baseboard_fab2(sch_1):\PP120\" )
				( objectStatus "P3E_OCP_CPU0_PE3_C_TXN<14>" )
			)
			( signal "@baseboard_fab2_lib.baseboard_fab2(sch_1):p3e_ocp_cpu0_pe3_c_txp(14)"
				( pinPairRef "@baseboard_fab2_lib.baseboard_fab2(sch_1):\PP121\" )
				( objectStatus "P3E_OCP_CPU0_PE3_C_TXP<14>" )
			)
			( signal "@baseboard_fab2_lib.baseboard_fab2(sch_1):p3e_cpu0_pe3_ocp_txp(14)"
				( pinPairRef "@baseboard_fab2_lib.baseboard_fab2(sch_1):\PP122\" )
				( objectStatus "P3E_CPU0_PE3_OCP_TXP<14>" )
			)
			( signal "@baseboard_fab2_lib.baseboard_fab2(sch_1):p3e_cpu0_pe3_ocp_txn(15)"
				( pinPairRef "@baseboard_fab2_lib.baseboard_fab2(sch_1):\PP123\" )
				( objectStatus "P3E_CPU0_PE3_OCP_TXN<15>" )
			)
			( signal "@baseboard_fab2_lib.baseboard_fab2(sch_1):p3e_ocp_cpu0_pe3_c_txn(15)"
				( pinPairRef "@baseboard_fab2_lib.baseboard_fab2(sch_1):\PP124\" )
				( objectStatus "P3E_OCP_CPU0_PE3_C_TXN<15>" )
			)
			( signal "@baseboard_fab2_lib.baseboard_fab2(sch_1):p3e_ocp_cpu0_pe3_c_txp(15)"
				( pinPairRef "@baseboard_fab2_lib.baseboard_fab2(sch_1):\PP125\" )
				( objectStatus "P3E_OCP_CPU0_PE3_C_TXP<15>" )
			)
			( signal "@baseboard_fab2_lib.baseboard_fab2(sch_1):p3e_cpu0_pe3_ocp_txp(15)"
				( pinPairRef "@baseboard_fab2_lib.baseboard_fab2(sch_1):\PP126\" )
				( objectStatus "P3E_CPU0_PE3_OCP_TXP<15>" )
			)
			( signal "@baseboard_fab2_lib.baseboard_fab2(sch_1):p3e_cpu1_pe3_mp_txn(0)"
				( pinPairRef "@baseboard_fab2_lib.baseboard_fab2(sch_1):\PP227\" )
				( objectStatus "P3E_CPU1_PE3_MP_TXN<0>" )
			)
			( signal "@baseboard_fab2_lib.baseboard_fab2(sch_1):p3e_cpu1_pe3_mp_c_txn(0)"
				( pinPairRef "@baseboard_fab2_lib.baseboard_fab2(sch_1):\PP228\" )
				( objectStatus "P3E_CPU1_PE3_MP_C_TXN<0>" )
			)
			( signal "@baseboard_fab2_lib.baseboard_fab2(sch_1):p3e_cpu1_pe3_mp_txp(0)"
				( pinPairRef "@baseboard_fab2_lib.baseboard_fab2(sch_1):\PP229\" )
				( objectStatus "P3E_CPU1_PE3_MP_TXP<0>" )
			)
			( signal "@baseboard_fab2_lib.baseboard_fab2(sch_1):p3e_cpu1_pe3_mp_c_txp(0)"
				( pinPairRef "@baseboard_fab2_lib.baseboard_fab2(sch_1):\PP230\" )
				( objectStatus "P3E_CPU1_PE3_MP_C_TXP<0>" )
			)
			( signal "@baseboard_fab2_lib.baseboard_fab2(sch_1):p3e_cpu1_pe3_mp_txn(1)"
				( pinPairRef "@baseboard_fab2_lib.baseboard_fab2(sch_1):\PP223\" )
				( objectStatus "P3E_CPU1_PE3_MP_TXN<1>" )
			)
			( signal "@baseboard_fab2_lib.baseboard_fab2(sch_1):p3e_cpu1_pe3_mp_c_txn(1)"
				( pinPairRef "@baseboard_fab2_lib.baseboard_fab2(sch_1):\PP224\" )
				( objectStatus "P3E_CPU1_PE3_MP_C_TXN<1>" )
			)
			( signal "@baseboard_fab2_lib.baseboard_fab2(sch_1):p3e_cpu1_pe3_mp_txp(1)"
				( pinPairRef "@baseboard_fab2_lib.baseboard_fab2(sch_1):\PP225\" )
				( objectStatus "P3E_CPU1_PE3_MP_TXP<1>" )
			)
			( signal "@baseboard_fab2_lib.baseboard_fab2(sch_1):p3e_cpu1_pe3_mp_c_txp(1)"
				( pinPairRef "@baseboard_fab2_lib.baseboard_fab2(sch_1):\PP226\" )
				( objectStatus "P3E_CPU1_PE3_MP_C_TXP<1>" )
			)
			( signal "@baseboard_fab2_lib.baseboard_fab2(sch_1):p3e_cpu0_pe1_ss_r_rxn(0)"
				( pinPairRef "@baseboard_fab2_lib.baseboard_fab2(sch_1):\PP135\" )
				( objectStatus "P3E_CPU0_PE1_SS_R_RXN<0>" )
			)
			( signal "@baseboard_fab2_lib.baseboard_fab2(sch_1):p3e_cpu0_pe1_ss_rxn(0)"
				( objectStatus "P3E_CPU0_PE1_SS_RXN<0>" )
			)
			( signal "@baseboard_fab2_lib.baseboard_fab2(sch_1):p3e_cpu0_pe1_pch_rxn(0)"
				( pinPairRef "@baseboard_fab2_lib.baseboard_fab2(sch_1):\PP136\" )
				( objectStatus "P3E_CPU0_PE1_PCH_RXN<0>" )
			)
			( signal "@baseboard_fab2_lib.baseboard_fab2(sch_1):p3e_cpu0_pe1_ss_r_rxp(0)"
				( pinPairRef "@baseboard_fab2_lib.baseboard_fab2(sch_1):\PP137\" )
				( objectStatus "P3E_CPU0_PE1_SS_R_RXP<0>" )
			)
			( signal "@baseboard_fab2_lib.baseboard_fab2(sch_1):p3e_cpu0_pe1_ss_rxp(0)"
				( objectStatus "P3E_CPU0_PE1_SS_RXP<0>" )
			)
			( signal "@baseboard_fab2_lib.baseboard_fab2(sch_1):p3e_cpu0_pe1_pch_rxp(0)"
				( pinPairRef "@baseboard_fab2_lib.baseboard_fab2(sch_1):\PP138\" )
				( objectStatus "P3E_CPU0_PE1_PCH_RXP<0>" )
			)
			( signal "@baseboard_fab2_lib.baseboard_fab2(sch_1):p3e_cpu0_pe1_ss_r_rxn(1)"
				( pinPairRef "@baseboard_fab2_lib.baseboard_fab2(sch_1):\PP139\" )
				( objectStatus "P3E_CPU0_PE1_SS_R_RXN<1>" )
			)
			( signal "@baseboard_fab2_lib.baseboard_fab2(sch_1):p3e_cpu0_pe1_ss_rxn(1)"
				( objectStatus "P3E_CPU0_PE1_SS_RXN<1>" )
			)
			( signal "@baseboard_fab2_lib.baseboard_fab2(sch_1):p3e_cpu0_pe1_pch_rxn(1)"
				( pinPairRef "@baseboard_fab2_lib.baseboard_fab2(sch_1):\PP140\" )
				( objectStatus "P3E_CPU0_PE1_PCH_RXN<1>" )
			)
			( signal "@baseboard_fab2_lib.baseboard_fab2(sch_1):p3e_cpu0_pe1_ss_r_rxp(1)"
				( pinPairRef "@baseboard_fab2_lib.baseboard_fab2(sch_1):\PP141\" )
				( objectStatus "P3E_CPU0_PE1_SS_R_RXP<1>" )
			)
			( signal "@baseboard_fab2_lib.baseboard_fab2(sch_1):p3e_cpu0_pe1_ss_rxp(1)"
				( objectStatus "P3E_CPU0_PE1_SS_RXP<1>" )
			)
			( signal "@baseboard_fab2_lib.baseboard_fab2(sch_1):p3e_cpu0_pe1_pch_rxp(1)"
				( pinPairRef "@baseboard_fab2_lib.baseboard_fab2(sch_1):\PP142\" )
				( objectStatus "P3E_CPU0_PE1_PCH_RXP<1>" )
			)
			( signal "@baseboard_fab2_lib.baseboard_fab2(sch_1):p3e_cpu0_pe1_ss_r_rxn(2)"
				( pinPairRef "@baseboard_fab2_lib.baseboard_fab2(sch_1):\PP143\" )
				( objectStatus "P3E_CPU0_PE1_SS_R_RXN<2>" )
			)
			( signal "@baseboard_fab2_lib.baseboard_fab2(sch_1):p3e_cpu0_pe1_ss_rxn(2)"
				( objectStatus "P3E_CPU0_PE1_SS_RXN<2>" )
			)
			( signal "@baseboard_fab2_lib.baseboard_fab2(sch_1):p3e_cpu0_pe1_pch_rxn(2)"
				( pinPairRef "@baseboard_fab2_lib.baseboard_fab2(sch_1):\PP144\" )
				( objectStatus "P3E_CPU0_PE1_PCH_RXN<2>" )
			)
			( signal "@baseboard_fab2_lib.baseboard_fab2(sch_1):p3e_cpu0_pe1_ss_r_rxp(2)"
				( pinPairRef "@baseboard_fab2_lib.baseboard_fab2(sch_1):\PP145\" )
				( objectStatus "P3E_CPU0_PE1_SS_R_RXP<2>" )
			)
			( signal "@baseboard_fab2_lib.baseboard_fab2(sch_1):p3e_cpu0_pe1_ss_rxp(2)"
				( objectStatus "P3E_CPU0_PE1_SS_RXP<2>" )
			)
			( signal "@baseboard_fab2_lib.baseboard_fab2(sch_1):p3e_cpu0_pe1_pch_rxp(2)"
				( pinPairRef "@baseboard_fab2_lib.baseboard_fab2(sch_1):\PP146\" )
				( objectStatus "P3E_CPU0_PE1_PCH_RXP<2>" )
			)
			( signal "@baseboard_fab2_lib.baseboard_fab2(sch_1):p3e_cpu0_pe1_ss_r_rxn(3)"
				( pinPairRef "@baseboard_fab2_lib.baseboard_fab2(sch_1):\PP147\" )
				( objectStatus "P3E_CPU0_PE1_SS_R_RXN<3>" )
			)
			( signal "@baseboard_fab2_lib.baseboard_fab2(sch_1):p3e_cpu0_pe1_ss_rxn(3)"
				( objectStatus "P3E_CPU0_PE1_SS_RXN<3>" )
			)
			( signal "@baseboard_fab2_lib.baseboard_fab2(sch_1):p3e_cpu0_pe1_pch_rxn(3)"
				( pinPairRef "@baseboard_fab2_lib.baseboard_fab2(sch_1):\PP148\" )
				( objectStatus "P3E_CPU0_PE1_PCH_RXN<3>" )
			)
			( signal "@baseboard_fab2_lib.baseboard_fab2(sch_1):p3e_cpu0_pe1_ss_r_rxp(3)"
				( pinPairRef "@baseboard_fab2_lib.baseboard_fab2(sch_1):\PP149\" )
				( objectStatus "P3E_CPU0_PE1_SS_R_RXP<3>" )
			)
			( signal "@baseboard_fab2_lib.baseboard_fab2(sch_1):p3e_cpu0_pe1_ss_rxp(3)"
				( objectStatus "P3E_CPU0_PE1_SS_RXP<3>" )
			)
			( signal "@baseboard_fab2_lib.baseboard_fab2(sch_1):p3e_cpu0_pe1_pch_rxp(3)"
				( pinPairRef "@baseboard_fab2_lib.baseboard_fab2(sch_1):\PP150\" )
				( objectStatus "P3E_CPU0_PE1_PCH_RXP<3>" )
			)
			( signal "@baseboard_fab2_lib.baseboard_fab2(sch_1):p3e_cpu0_pe1_ss_r_rxn(4)"
				( pinPairRef "@baseboard_fab2_lib.baseboard_fab2(sch_1):\PP151\" )
				( objectStatus "P3E_CPU0_PE1_SS_R_RXN<4>" )
			)
			( signal "@baseboard_fab2_lib.baseboard_fab2(sch_1):p3e_cpu0_pe1_ss_rxn(4)"
				( objectStatus "P3E_CPU0_PE1_SS_RXN<4>" )
			)
			( signal "@baseboard_fab2_lib.baseboard_fab2(sch_1):p3e_cpu0_pe1_pch_rxn(4)"
				( pinPairRef "@baseboard_fab2_lib.baseboard_fab2(sch_1):\PP152\" )
				( objectStatus "P3E_CPU0_PE1_PCH_RXN<4>" )
			)
			( signal "@baseboard_fab2_lib.baseboard_fab2(sch_1):p3e_cpu0_pe1_ss_r_rxp(4)"
				( pinPairRef "@baseboard_fab2_lib.baseboard_fab2(sch_1):\PP153\" )
				( objectStatus "P3E_CPU0_PE1_SS_R_RXP<4>" )
			)
			( signal "@baseboard_fab2_lib.baseboard_fab2(sch_1):p3e_cpu0_pe1_ss_rxp(4)"
				( objectStatus "P3E_CPU0_PE1_SS_RXP<4>" )
			)
			( signal "@baseboard_fab2_lib.baseboard_fab2(sch_1):p3e_cpu0_pe1_pch_rxp(4)"
				( pinPairRef "@baseboard_fab2_lib.baseboard_fab2(sch_1):\PP154\" )
				( objectStatus "P3E_CPU0_PE1_PCH_RXP<4>" )
			)
			( signal "@baseboard_fab2_lib.baseboard_fab2(sch_1):p3e_cpu0_pe1_ss_r_rxn(5)"
				( pinPairRef "@baseboard_fab2_lib.baseboard_fab2(sch_1):\PP155\" )
				( objectStatus "P3E_CPU0_PE1_SS_R_RXN<5>" )
			)
			( signal "@baseboard_fab2_lib.baseboard_fab2(sch_1):p3e_cpu0_pe1_ss_rxn(5)"
				( objectStatus "P3E_CPU0_PE1_SS_RXN<5>" )
			)
			( signal "@baseboard_fab2_lib.baseboard_fab2(sch_1):p3e_cpu0_pe1_pch_rxn(5)"
				( pinPairRef "@baseboard_fab2_lib.baseboard_fab2(sch_1):\PP156\" )
				( objectStatus "P3E_CPU0_PE1_PCH_RXN<5>" )
			)
			( signal "@baseboard_fab2_lib.baseboard_fab2(sch_1):p3e_cpu0_pe1_ss_r_rxp(5)"
				( pinPairRef "@baseboard_fab2_lib.baseboard_fab2(sch_1):\PP157\" )
				( objectStatus "P3E_CPU0_PE1_SS_R_RXP<5>" )
			)
			( signal "@baseboard_fab2_lib.baseboard_fab2(sch_1):p3e_cpu0_pe1_ss_rxp(5)"
				( objectStatus "P3E_CPU0_PE1_SS_RXP<5>" )
			)
			( signal "@baseboard_fab2_lib.baseboard_fab2(sch_1):p3e_cpu0_pe1_pch_rxp(5)"
				( pinPairRef "@baseboard_fab2_lib.baseboard_fab2(sch_1):\PP158\" )
				( objectStatus "P3E_CPU0_PE1_PCH_RXP<5>" )
			)
			( signal "@baseboard_fab2_lib.baseboard_fab2(sch_1):p3e_cpu0_pe1_ss_r_rxn(6)"
				( pinPairRef "@baseboard_fab2_lib.baseboard_fab2(sch_1):\PP159\" )
				( objectStatus "P3E_CPU0_PE1_SS_R_RXN<6>" )
			)
			( signal "@baseboard_fab2_lib.baseboard_fab2(sch_1):p3e_cpu0_pe1_ss_rxn(6)"
				( objectStatus "P3E_CPU0_PE1_SS_RXN<6>" )
			)
			( signal "@baseboard_fab2_lib.baseboard_fab2(sch_1):p3e_cpu0_pe1_pch_rxn(6)"
				( pinPairRef "@baseboard_fab2_lib.baseboard_fab2(sch_1):\PP160\" )
				( objectStatus "P3E_CPU0_PE1_PCH_RXN<6>" )
			)
			( signal "@baseboard_fab2_lib.baseboard_fab2(sch_1):p3e_cpu0_pe1_ss_r_rxp(6)"
				( pinPairRef "@baseboard_fab2_lib.baseboard_fab2(sch_1):\PP161\" )
				( objectStatus "P3E_CPU0_PE1_SS_R_RXP<6>" )
			)
			( signal "@baseboard_fab2_lib.baseboard_fab2(sch_1):p3e_cpu0_pe1_ss_rxp(6)"
				( objectStatus "P3E_CPU0_PE1_SS_RXP<6>" )
			)
			( signal "@baseboard_fab2_lib.baseboard_fab2(sch_1):p3e_cpu0_pe1_pch_rxp(6)"
				( pinPairRef "@baseboard_fab2_lib.baseboard_fab2(sch_1):\PP162\" )
				( objectStatus "P3E_CPU0_PE1_PCH_RXP<6>" )
			)
			( signal "@baseboard_fab2_lib.baseboard_fab2(sch_1):p3e_cpu0_pe1_pch_r_rxn(8)"
				( pinPairRef "@baseboard_fab2_lib.baseboard_fab2(sch_1):\PP3001\" )
				( objectStatus "P3E_CPU0_PE1_PCH_R_RXN<8>" )
			)
			( signal "@baseboard_fab2_lib.baseboard_fab2(sch_1):p3e_cpu0_pe1_pch_rxn(8)"
				( pinPairRef "@baseboard_fab2_lib.baseboard_fab2(sch_1):\PP3002\" )
				( objectStatus "P3E_CPU0_PE1_PCH_RXN<8>" )
			)
			( signal "@baseboard_fab2_lib.baseboard_fab2(sch_1):p3e_cpu0_pe1_pch_r_rxp(8)"
				( pinPairRef "@baseboard_fab2_lib.baseboard_fab2(sch_1):\PP2999\" )
				( objectStatus "P3E_CPU0_PE1_PCH_R_RXP<8>" )
			)
			( signal "@baseboard_fab2_lib.baseboard_fab2(sch_1):p3e_cpu0_pe1_pch_rxp(8)"
				( pinPairRef "@baseboard_fab2_lib.baseboard_fab2(sch_1):\PP3000\" )
				( objectStatus "P3E_CPU0_PE1_PCH_RXP<8>" )
			)
			( signal "@baseboard_fab2_lib.baseboard_fab2(sch_1):p3e_cpu0_pe1_pch_r_rxn(9)"
				( pinPairRef "@baseboard_fab2_lib.baseboard_fab2(sch_1):\PP2997\" )
				( objectStatus "P3E_CPU0_PE1_PCH_R_RXN<9>" )
			)
			( signal "@baseboard_fab2_lib.baseboard_fab2(sch_1):p3e_cpu0_pe1_pch_rxn(9)"
				( pinPairRef "@baseboard_fab2_lib.baseboard_fab2(sch_1):\PP2998\" )
				( objectStatus "P3E_CPU0_PE1_PCH_RXN<9>" )
			)
			( signal "@baseboard_fab2_lib.baseboard_fab2(sch_1):p3e_cpu0_pe1_pch_r_rxp(9)"
				( pinPairRef "@baseboard_fab2_lib.baseboard_fab2(sch_1):\PP2995\" )
				( objectStatus "P3E_CPU0_PE1_PCH_R_RXP<9>" )
			)
			( signal "@baseboard_fab2_lib.baseboard_fab2(sch_1):p3e_cpu0_pe1_pch_rxp(9)"
				( pinPairRef "@baseboard_fab2_lib.baseboard_fab2(sch_1):\PP2996\" )
				( objectStatus "P3E_CPU0_PE1_PCH_RXP<9>" )
			)
			( signal "@baseboard_fab2_lib.baseboard_fab2(sch_1):p3e_cpu1_pe3_mp_txn(2)"
				( pinPairRef "@baseboard_fab2_lib.baseboard_fab2(sch_1):\PP219\" )
				( objectStatus "P3E_CPU1_PE3_MP_TXN<2>" )
			)
			( signal "@baseboard_fab2_lib.baseboard_fab2(sch_1):p3e_cpu1_pe3_mp_c_txn(2)"
				( pinPairRef "@baseboard_fab2_lib.baseboard_fab2(sch_1):\PP220\" )
				( objectStatus "P3E_CPU1_PE3_MP_C_TXN<2>" )
			)
			( signal "@baseboard_fab2_lib.baseboard_fab2(sch_1):p3e_cpu1_pe3_mp_txp(2)"
				( pinPairRef "@baseboard_fab2_lib.baseboard_fab2(sch_1):\PP221\" )
				( objectStatus "P3E_CPU1_PE3_MP_TXP<2>" )
			)
			( signal "@baseboard_fab2_lib.baseboard_fab2(sch_1):p3e_cpu1_pe3_mp_c_txp(2)"
				( pinPairRef "@baseboard_fab2_lib.baseboard_fab2(sch_1):\PP222\" )
				( objectStatus "P3E_CPU1_PE3_MP_C_TXP<2>" )
			)
			( signal "@baseboard_fab2_lib.baseboard_fab2(sch_1):p3e_cpu1_pe3_mp_txn(3)"
				( pinPairRef "@baseboard_fab2_lib.baseboard_fab2(sch_1):\PP215\" )
				( objectStatus "P3E_CPU1_PE3_MP_TXN<3>" )
			)
			( signal "@baseboard_fab2_lib.baseboard_fab2(sch_1):p3e_cpu1_pe3_mp_c_txn(3)"
				( pinPairRef "@baseboard_fab2_lib.baseboard_fab2(sch_1):\PP216\" )
				( objectStatus "P3E_CPU1_PE3_MP_C_TXN<3>" )
			)
			( signal "@baseboard_fab2_lib.baseboard_fab2(sch_1):p3e_cpu1_pe3_mp_txp(3)"
				( pinPairRef "@baseboard_fab2_lib.baseboard_fab2(sch_1):\PP217\" )
				( objectStatus "P3E_CPU1_PE3_MP_TXP<3>" )
			)
			( signal "@baseboard_fab2_lib.baseboard_fab2(sch_1):p3e_cpu1_pe3_mp_c_txp(3)"
				( pinPairRef "@baseboard_fab2_lib.baseboard_fab2(sch_1):\PP218\" )
				( objectStatus "P3E_CPU1_PE3_MP_C_TXP<3>" )
			)
			( signal "@baseboard_fab2_lib.baseboard_fab2(sch_1):p3e_cpu1_pe3_mp_txn(4)"
				( pinPairRef "@baseboard_fab2_lib.baseboard_fab2(sch_1):\PP211\" )
				( objectStatus "P3E_CPU1_PE3_MP_TXN<4>" )
			)
			( signal "@baseboard_fab2_lib.baseboard_fab2(sch_1):p3e_cpu1_pe3_mp_c_txn(4)"
				( pinPairRef "@baseboard_fab2_lib.baseboard_fab2(sch_1):\PP212\" )
				( objectStatus "P3E_CPU1_PE3_MP_C_TXN<4>" )
			)
			( signal "@baseboard_fab2_lib.baseboard_fab2(sch_1):p3e_cpu1_pe3_mp_txp(4)"
				( pinPairRef "@baseboard_fab2_lib.baseboard_fab2(sch_1):\PP213\" )
				( objectStatus "P3E_CPU1_PE3_MP_TXP<4>" )
			)
			( signal "@baseboard_fab2_lib.baseboard_fab2(sch_1):p3e_cpu1_pe3_mp_c_txp(4)"
				( pinPairRef "@baseboard_fab2_lib.baseboard_fab2(sch_1):\PP214\" )
				( objectStatus "P3E_CPU1_PE3_MP_C_TXP<4>" )
			)
			( signal "@baseboard_fab2_lib.baseboard_fab2(sch_1):p3e_cpu1_pe3_mp_txn(5)"
				( pinPairRef "@baseboard_fab2_lib.baseboard_fab2(sch_1):\PP207\" )
				( objectStatus "P3E_CPU1_PE3_MP_TXN<5>" )
			)
			( signal "@baseboard_fab2_lib.baseboard_fab2(sch_1):p3e_cpu1_pe3_mp_c_txn(5)"
				( pinPairRef "@baseboard_fab2_lib.baseboard_fab2(sch_1):\PP208\" )
				( objectStatus "P3E_CPU1_PE3_MP_C_TXN<5>" )
			)
			( signal "@baseboard_fab2_lib.baseboard_fab2(sch_1):p3e_cpu1_pe3_mp_txp(5)"
				( pinPairRef "@baseboard_fab2_lib.baseboard_fab2(sch_1):\PP209\" )
				( objectStatus "P3E_CPU1_PE3_MP_TXP<5>" )
			)
			( signal "@baseboard_fab2_lib.baseboard_fab2(sch_1):p3e_cpu1_pe3_mp_c_txp(5)"
				( pinPairRef "@baseboard_fab2_lib.baseboard_fab2(sch_1):\PP210\" )
				( objectStatus "P3E_CPU1_PE3_MP_C_TXP<5>" )
			)
			( signal "@baseboard_fab2_lib.baseboard_fab2(sch_1):p3e_cpu1_pe3_mp_txn(6)"
				( pinPairRef "@baseboard_fab2_lib.baseboard_fab2(sch_1):\PP203\" )
				( objectStatus "P3E_CPU1_PE3_MP_TXN<6>" )
			)
			( signal "@baseboard_fab2_lib.baseboard_fab2(sch_1):p3e_cpu1_pe3_mp_c_txn(6)"
				( pinPairRef "@baseboard_fab2_lib.baseboard_fab2(sch_1):\PP204\" )
				( objectStatus "P3E_CPU1_PE3_MP_C_TXN<6>" )
			)
			( signal "@baseboard_fab2_lib.baseboard_fab2(sch_1):p3e_cpu1_pe3_mp_txp(6)"
				( pinPairRef "@baseboard_fab2_lib.baseboard_fab2(sch_1):\PP205\" )
				( objectStatus "P3E_CPU1_PE3_MP_TXP<6>" )
			)
			( signal "@baseboard_fab2_lib.baseboard_fab2(sch_1):p3e_cpu1_pe3_mp_c_txp(6)"
				( pinPairRef "@baseboard_fab2_lib.baseboard_fab2(sch_1):\PP206\" )
				( objectStatus "P3E_CPU1_PE3_MP_C_TXP<6>" )
			)
			( signal "@baseboard_fab2_lib.baseboard_fab2(sch_1):p3e_cpu1_pe3_mp_txn(11)"
				( pinPairRef "@baseboard_fab2_lib.baseboard_fab2(sch_1):\PP199\" )
				( objectStatus "P3E_CPU1_PE3_MP_TXN<11>" )
			)
			( signal "@baseboard_fab2_lib.baseboard_fab2(sch_1):p3e_cpu1_pe3_mp_c_txn(11)"
				( pinPairRef "@baseboard_fab2_lib.baseboard_fab2(sch_1):\PP200\" )
				( objectStatus "P3E_CPU1_PE3_MP_C_TXN<11>" )
			)
			( signal "@baseboard_fab2_lib.baseboard_fab2(sch_1):p3e_cpu1_pe3_mp_c_txp(11)"
				( pinPairRef "@baseboard_fab2_lib.baseboard_fab2(sch_1):\PP201\" )
				( objectStatus "P3E_CPU1_PE3_MP_C_TXP<11>" )
			)
			( signal "@baseboard_fab2_lib.baseboard_fab2(sch_1):p3e_cpu1_pe3_mp_txp(11)"
				( pinPairRef "@baseboard_fab2_lib.baseboard_fab2(sch_1):\PP202\" )
				( objectStatus "P3E_CPU1_PE3_MP_TXP<11>" )
			)
			( signal "@baseboard_fab2_lib.baseboard_fab2(sch_1):p3e_cpu1_pe3_mp_txn(12)"
				( pinPairRef "@baseboard_fab2_lib.baseboard_fab2(sch_1):\PP195\" )
				( objectStatus "P3E_CPU1_PE3_MP_TXN<12>" )
			)
			( signal "@baseboard_fab2_lib.baseboard_fab2(sch_1):p3e_cpu1_pe3_mp_c_txn(12)"
				( pinPairRef "@baseboard_fab2_lib.baseboard_fab2(sch_1):\PP196\" )
				( objectStatus "P3E_CPU1_PE3_MP_C_TXN<12>" )
			)
			( signal "@baseboard_fab2_lib.baseboard_fab2(sch_1):p3e_cpu1_pe3_mp_c_txp(12)"
				( pinPairRef "@baseboard_fab2_lib.baseboard_fab2(sch_1):\PP197\" )
				( objectStatus "P3E_CPU1_PE3_MP_C_TXP<12>" )
			)
			( signal "@baseboard_fab2_lib.baseboard_fab2(sch_1):p3e_cpu1_pe3_mp_txp(12)"
				( pinPairRef "@baseboard_fab2_lib.baseboard_fab2(sch_1):\PP198\" )
				( objectStatus "P3E_CPU1_PE3_MP_TXP<12>" )
			)
			( signal "@baseboard_fab2_lib.baseboard_fab2(sch_1):p3e_cpu1_pe3_mp_txn(13)"
				( pinPairRef "@baseboard_fab2_lib.baseboard_fab2(sch_1):\PP191\" )
				( objectStatus "P3E_CPU1_PE3_MP_TXN<13>" )
			)
			( signal "@baseboard_fab2_lib.baseboard_fab2(sch_1):p3e_cpu1_pe3_mp_c_txn(13)"
				( pinPairRef "@baseboard_fab2_lib.baseboard_fab2(sch_1):\PP192\" )
				( objectStatus "P3E_CPU1_PE3_MP_C_TXN<13>" )
			)
			( signal "@baseboard_fab2_lib.baseboard_fab2(sch_1):p3e_cpu1_pe3_mp_c_txp(13)"
				( pinPairRef "@baseboard_fab2_lib.baseboard_fab2(sch_1):\PP193\" )
				( objectStatus "P3E_CPU1_PE3_MP_C_TXP<13>" )
			)
			( signal "@baseboard_fab2_lib.baseboard_fab2(sch_1):p3e_cpu1_pe3_mp_txp(13)"
				( pinPairRef "@baseboard_fab2_lib.baseboard_fab2(sch_1):\PP194\" )
				( objectStatus "P3E_CPU1_PE3_MP_TXP<13>" )
			)
			( signal "@baseboard_fab2_lib.baseboard_fab2(sch_1):p3e_cpu1_pe3_mp_txn(14)"
				( pinPairRef "@baseboard_fab2_lib.baseboard_fab2(sch_1):\PP187\" )
				( objectStatus "P3E_CPU1_PE3_MP_TXN<14>" )
			)
			( signal "@baseboard_fab2_lib.baseboard_fab2(sch_1):p3e_cpu1_pe3_mp_c_txn(14)"
				( pinPairRef "@baseboard_fab2_lib.baseboard_fab2(sch_1):\PP188\" )
				( objectStatus "P3E_CPU1_PE3_MP_C_TXN<14>" )
			)
			( signal "@baseboard_fab2_lib.baseboard_fab2(sch_1):p3e_cpu1_pe3_mp_c_txp(14)"
				( pinPairRef "@baseboard_fab2_lib.baseboard_fab2(sch_1):\PP189\" )
				( objectStatus "P3E_CPU1_PE3_MP_C_TXP<14>" )
			)
			( signal "@baseboard_fab2_lib.baseboard_fab2(sch_1):p3e_cpu1_pe3_mp_txp(14)"
				( pinPairRef "@baseboard_fab2_lib.baseboard_fab2(sch_1):\PP190\" )
				( objectStatus "P3E_CPU1_PE3_MP_TXP<14>" )
			)
			( signal "@baseboard_fab2_lib.baseboard_fab2(sch_1):p3e_cpu1_pe3_mp_txn(15)"
				( pinPairRef "@baseboard_fab2_lib.baseboard_fab2(sch_1):\PP175\" )
				( objectStatus "P3E_CPU1_PE3_MP_TXN<15>" )
			)
			( signal "@baseboard_fab2_lib.baseboard_fab2(sch_1):p3e_cpu1_pe3_mp_c_txn(15)"
				( pinPairRef "@baseboard_fab2_lib.baseboard_fab2(sch_1):\PP176\" )
				( objectStatus "P3E_CPU1_PE3_MP_C_TXN<15>" )
			)
			( signal "@baseboard_fab2_lib.baseboard_fab2(sch_1):p3e_cpu1_pe3_mp_c_txp(15)"
				( pinPairRef "@baseboard_fab2_lib.baseboard_fab2(sch_1):\PP177\" )
				( objectStatus "P3E_CPU1_PE3_MP_C_TXP<15>" )
			)
			( signal "@baseboard_fab2_lib.baseboard_fab2(sch_1):p3e_cpu1_pe3_mp_txp(15)"
				( pinPairRef "@baseboard_fab2_lib.baseboard_fab2(sch_1):\PP178\" )
				( objectStatus "P3E_CPU1_PE3_MP_TXP<15>" )
			)
			( signal "@baseboard_fab2_lib.baseboard_fab2(sch_1):p3e_cpu1_pe3_mp_txn(7)"
				( pinPairRef "@baseboard_fab2_lib.baseboard_fab2(sch_1):\PP183\" )
				( objectStatus "P3E_CPU1_PE3_MP_TXN<7>" )
			)
			( signal "@baseboard_fab2_lib.baseboard_fab2(sch_1):p3e_cpu1_pe3_mp_c_txn(7)"
				( pinPairRef "@baseboard_fab2_lib.baseboard_fab2(sch_1):\PP184\" )
				( objectStatus "P3E_CPU1_PE3_MP_C_TXN<7>" )
			)
			( signal "@baseboard_fab2_lib.baseboard_fab2(sch_1):p3e_cpu1_pe3_mp_txp(7)"
				( pinPairRef "@baseboard_fab2_lib.baseboard_fab2(sch_1):\PP185\" )
				( objectStatus "P3E_CPU1_PE3_MP_TXP<7>" )
			)
			( signal "@baseboard_fab2_lib.baseboard_fab2(sch_1):p3e_cpu1_pe3_mp_c_txp(7)"
				( pinPairRef "@baseboard_fab2_lib.baseboard_fab2(sch_1):\PP186\" )
				( objectStatus "P3E_CPU1_PE3_MP_C_TXP<7>" )
			)
			( signal "@baseboard_fab2_lib.baseboard_fab2(sch_1):p3e_cpu1_pe3_mp_txn(9)"
				( pinPairRef "@baseboard_fab2_lib.baseboard_fab2(sch_1):\PP179\" )
				( objectStatus "P3E_CPU1_PE3_MP_TXN<9>" )
			)
			( signal "@baseboard_fab2_lib.baseboard_fab2(sch_1):p3e_cpu1_pe3_mp_c_txn(9)"
				( pinPairRef "@baseboard_fab2_lib.baseboard_fab2(sch_1):\PP180\" )
				( objectStatus "P3E_CPU1_PE3_MP_C_TXN<9>" )
			)
			( signal "@baseboard_fab2_lib.baseboard_fab2(sch_1):p3e_cpu1_pe3_mp_c_txp(9)"
				( pinPairRef "@baseboard_fab2_lib.baseboard_fab2(sch_1):\PP181\" )
				( objectStatus "P3E_CPU1_PE3_MP_C_TXP<9>" )
			)
			( signal "@baseboard_fab2_lib.baseboard_fab2(sch_1):p3e_cpu1_pe3_mp_txp(9)"
				( pinPairRef "@baseboard_fab2_lib.baseboard_fab2(sch_1):\PP182\" )
				( objectStatus "P3E_CPU1_PE3_MP_TXP<9>" )
			)
			( signal "@baseboard_fab2_lib.baseboard_fab2(sch_1):p3e_cpu1_pe3_mp_rxp(0)"
				( pinPairRef "@baseboard_fab2_lib.baseboard_fab2(sch_1):\PP3033\" )
				( objectStatus "P3E_CPU1_PE3_MP_RXP<0>" )
			)
			( signal "@baseboard_fab2_lib.baseboard_fab2(sch_1):p3e_cpu1_pe3_mp_rxn(0)"
				( pinPairRef "@baseboard_fab2_lib.baseboard_fab2(sch_1):\PP3031\" )
				( objectStatus "P3E_CPU1_PE3_MP_RXN<0>" )
			)
			( signal "@baseboard_fab2_lib.baseboard_fab2(sch_1):p3e_cpu1_pe3_mp_rxp(1)"
				( pinPairRef "@baseboard_fab2_lib.baseboard_fab2(sch_1):\PP3034\" )
				( objectStatus "P3E_CPU1_PE3_MP_RXP<1>" )
			)
			( signal "@baseboard_fab2_lib.baseboard_fab2(sch_1):p3e_cpu1_pe3_mp_rxn(1)"
				( pinPairRef "@baseboard_fab2_lib.baseboard_fab2(sch_1):\PP3032\" )
				( objectStatus "P3E_CPU1_PE3_MP_RXN<1>" )
			)
			( signal "@baseboard_fab2_lib.baseboard_fab2(sch_1):p3e_cpu1_pe3_mp_rxp(2)"
				( pinPairRef "@baseboard_fab2_lib.baseboard_fab2(sch_1):\PP3029\" )
				( objectStatus "P3E_CPU1_PE3_MP_RXP<2>" )
			)
			( signal "@baseboard_fab2_lib.baseboard_fab2(sch_1):p3e_cpu1_pe3_mp_rxn(2)"
				( pinPairRef "@baseboard_fab2_lib.baseboard_fab2(sch_1):\PP3027\" )
				( objectStatus "P3E_CPU1_PE3_MP_RXN<2>" )
			)
			( signal "@baseboard_fab2_lib.baseboard_fab2(sch_1):p3e_cpu1_pe3_mp_rxp(3)"
				( pinPairRef "@baseboard_fab2_lib.baseboard_fab2(sch_1):\PP3030\" )
				( objectStatus "P3E_CPU1_PE3_MP_RXP<3>" )
			)
			( signal "@baseboard_fab2_lib.baseboard_fab2(sch_1):p3e_cpu1_pe3_mp_rxn(3)"
				( pinPairRef "@baseboard_fab2_lib.baseboard_fab2(sch_1):\PP3028\" )
				( objectStatus "P3E_CPU1_PE3_MP_RXN<3>" )
			)
			( signal "@baseboard_fab2_lib.baseboard_fab2(sch_1):p3e_cpu1_pe3_mp_rxp(4)"
				( pinPairRef "@baseboard_fab2_lib.baseboard_fab2(sch_1):\PP3025\" )
				( objectStatus "P3E_CPU1_PE3_MP_RXP<4>" )
			)
			( signal "@baseboard_fab2_lib.baseboard_fab2(sch_1):p3e_cpu1_pe3_mp_rxn(4)"
				( pinPairRef "@baseboard_fab2_lib.baseboard_fab2(sch_1):\PP3023\" )
				( objectStatus "P3E_CPU1_PE3_MP_RXN<4>" )
			)
			( signal "@baseboard_fab2_lib.baseboard_fab2(sch_1):p3e_cpu1_pe3_mp_rxp(5)"
				( pinPairRef "@baseboard_fab2_lib.baseboard_fab2(sch_1):\PP3026\" )
				( objectStatus "P3E_CPU1_PE3_MP_RXP<5>" )
			)
			( signal "@baseboard_fab2_lib.baseboard_fab2(sch_1):p3e_cpu1_pe3_mp_rxn(5)"
				( pinPairRef "@baseboard_fab2_lib.baseboard_fab2(sch_1):\PP3024\" )
				( objectStatus "P3E_CPU1_PE3_MP_RXN<5>" )
			)
			( signal "@baseboard_fab2_lib.baseboard_fab2(sch_1):p3e_cpu1_pe3_mp_rxp(6)"
				( pinPairRef "@baseboard_fab2_lib.baseboard_fab2(sch_1):\PP3021\" )
				( objectStatus "P3E_CPU1_PE3_MP_RXP<6>" )
			)
			( signal "@baseboard_fab2_lib.baseboard_fab2(sch_1):p3e_cpu1_pe3_mp_rxn(6)"
				( pinPairRef "@baseboard_fab2_lib.baseboard_fab2(sch_1):\PP3019\" )
				( objectStatus "P3E_CPU1_PE3_MP_RXN<6>" )
			)
			( signal "@baseboard_fab2_lib.baseboard_fab2(sch_1):p3e_cpu1_pe3_mp_rxp(7)"
				( pinPairRef "@baseboard_fab2_lib.baseboard_fab2(sch_1):\PP3022\" )
				( objectStatus "P3E_CPU1_PE3_MP_RXP<7>" )
			)
			( signal "@baseboard_fab2_lib.baseboard_fab2(sch_1):p3e_cpu1_pe3_mp_rxn(7)"
				( pinPairRef "@baseboard_fab2_lib.baseboard_fab2(sch_1):\PP3020\" )
				( objectStatus "P3E_CPU1_PE3_MP_RXN<7>" )
			)
			( signal "@baseboard_fab2_lib.baseboard_fab2(sch_1):p3e_cpu0_pe2_ss_rxp(0)"
				( pinPairRef "@baseboard_fab2_lib.baseboard_fab2(sch_1):\PP3105\" )
				( objectStatus "P3E_CPU0_PE2_SS_RXP<0>" )
			)
			( signal "@baseboard_fab2_lib.baseboard_fab2(sch_1):p3e_cpu0_pe2_ss_rxn(0)"
				( pinPairRef "@baseboard_fab2_lib.baseboard_fab2(sch_1):\PP3103\" )
				( objectStatus "P3E_CPU0_PE2_SS_RXN<0>" )
			)
			( signal "@baseboard_fab2_lib.baseboard_fab2(sch_1):p3e_cpu0_pe2_ss_rxp(1)"
				( pinPairRef "@baseboard_fab2_lib.baseboard_fab2(sch_1):\PP3106\" )
				( objectStatus "P3E_CPU0_PE2_SS_RXP<1>" )
			)
			( signal "@baseboard_fab2_lib.baseboard_fab2(sch_1):p3e_cpu0_pe2_ss_rxn(1)"
				( pinPairRef "@baseboard_fab2_lib.baseboard_fab2(sch_1):\PP3104\" )
				( objectStatus "P3E_CPU0_PE2_SS_RXN<1>" )
			)
			( signal "@baseboard_fab2_lib.baseboard_fab2(sch_1):p3e_cpu0_pe2_ss_rxp(2)"
				( pinPairRef "@baseboard_fab2_lib.baseboard_fab2(sch_1):\PP3101\" )
				( objectStatus "P3E_CPU0_PE2_SS_RXP<2>" )
			)
			( signal "@baseboard_fab2_lib.baseboard_fab2(sch_1):p3e_cpu0_pe2_ss_rxn(2)"
				( pinPairRef "@baseboard_fab2_lib.baseboard_fab2(sch_1):\PP3099\" )
				( objectStatus "P3E_CPU0_PE2_SS_RXN<2>" )
			)
			( signal "@baseboard_fab2_lib.baseboard_fab2(sch_1):p3e_cpu0_pe2_ss_rxp(3)"
				( pinPairRef "@baseboard_fab2_lib.baseboard_fab2(sch_1):\PP3102\" )
				( objectStatus "P3E_CPU0_PE2_SS_RXP<3>" )
			)
			( signal "@baseboard_fab2_lib.baseboard_fab2(sch_1):p3e_cpu0_pe2_ss_rxn(3)"
				( pinPairRef "@baseboard_fab2_lib.baseboard_fab2(sch_1):\PP3100\" )
				( objectStatus "P3E_CPU0_PE2_SS_RXN<3>" )
			)
			( signal "@baseboard_fab2_lib.baseboard_fab2(sch_1):p3e_cpu0_pe2_ss_rxp(4)"
				( pinPairRef "@baseboard_fab2_lib.baseboard_fab2(sch_1):\PP3097\" )
				( objectStatus "P3E_CPU0_PE2_SS_RXP<4>" )
			)
			( signal "@baseboard_fab2_lib.baseboard_fab2(sch_1):p3e_cpu0_pe2_ss_rxn(4)"
				( pinPairRef "@baseboard_fab2_lib.baseboard_fab2(sch_1):\PP3095\" )
				( objectStatus "P3E_CPU0_PE2_SS_RXN<4>" )
			)
			( signal "@baseboard_fab2_lib.baseboard_fab2(sch_1):p3e_cpu0_pe2_ss_rxp(5)"
				( pinPairRef "@baseboard_fab2_lib.baseboard_fab2(sch_1):\PP3098\" )
				( objectStatus "P3E_CPU0_PE2_SS_RXP<5>" )
			)
			( signal "@baseboard_fab2_lib.baseboard_fab2(sch_1):p3e_cpu0_pe2_ss_rxn(5)"
				( pinPairRef "@baseboard_fab2_lib.baseboard_fab2(sch_1):\PP3096\" )
				( objectStatus "P3E_CPU0_PE2_SS_RXN<5>" )
			)
			( signal "@baseboard_fab2_lib.baseboard_fab2(sch_1):dmi_cpu0_pch_rx_dn(0)"
				( pinPairRef "@baseboard_fab2_lib.baseboard_fab2(sch_1):\PP54\" )
				( objectStatus "DMI_CPU0_PCH_RX_DN<0>" )
			)
			( signal "@baseboard_fab2_lib.baseboard_fab2(sch_1):dmi_cpu0_pch_rx_c_dn(0)"
				( pinPairRef "@baseboard_fab2_lib.baseboard_fab2(sch_1):\PP55\" )
				( objectStatus "DMI_CPU0_PCH_RX_C_DN<0>" )
			)
			( signal "@baseboard_fab2_lib.baseboard_fab2(sch_1):dmi_cpu0_pch_rx_dp(0)"
				( pinPairRef "@baseboard_fab2_lib.baseboard_fab2(sch_1):\PP52\" )
				( objectStatus "DMI_CPU0_PCH_RX_DP<0>" )
			)
			( signal "@baseboard_fab2_lib.baseboard_fab2(sch_1):dmi_cpu0_pch_rx_c_dp(0)"
				( pinPairRef "@baseboard_fab2_lib.baseboard_fab2(sch_1):\PP53\" )
				( objectStatus "DMI_CPU0_PCH_RX_C_DP<0>" )
			)
			( signal "@baseboard_fab2_lib.baseboard_fab2(sch_1):dmi_cpu0_pch_rx_dn(1)"
				( pinPairRef "@baseboard_fab2_lib.baseboard_fab2(sch_1):\PP58\" )
				( objectStatus "DMI_CPU0_PCH_RX_DN<1>" )
			)
			( signal "@baseboard_fab2_lib.baseboard_fab2(sch_1):dmi_cpu0_pch_rx_c_dn(1)"
				( pinPairRef "@baseboard_fab2_lib.baseboard_fab2(sch_1):\PP59\" )
				( objectStatus "DMI_CPU0_PCH_RX_C_DN<1>" )
			)
			( signal "@baseboard_fab2_lib.baseboard_fab2(sch_1):dmi_cpu0_pch_rx_dp(1)"
				( pinPairRef "@baseboard_fab2_lib.baseboard_fab2(sch_1):\PP56\" )
				( objectStatus "DMI_CPU0_PCH_RX_DP<1>" )
			)
			( signal "@baseboard_fab2_lib.baseboard_fab2(sch_1):dmi_cpu0_pch_rx_c_dp(1)"
				( pinPairRef "@baseboard_fab2_lib.baseboard_fab2(sch_1):\PP57\" )
				( objectStatus "DMI_CPU0_PCH_RX_C_DP<1>" )
			)
			( signal "@baseboard_fab2_lib.baseboard_fab2(sch_1):dmi_cpu0_pch_rx_dn(2)"
				( pinPairRef "@baseboard_fab2_lib.baseboard_fab2(sch_1):\PP62\" )
				( objectStatus "DMI_CPU0_PCH_RX_DN<2>" )
			)
			( signal "@baseboard_fab2_lib.baseboard_fab2(sch_1):dmi_cpu0_pch_rx_c_dn(2)"
				( pinPairRef "@baseboard_fab2_lib.baseboard_fab2(sch_1):\PP63\" )
				( objectStatus "DMI_CPU0_PCH_RX_C_DN<2>" )
			)
			( signal "@baseboard_fab2_lib.baseboard_fab2(sch_1):dmi_cpu0_pch_rx_dp(2)"
				( pinPairRef "@baseboard_fab2_lib.baseboard_fab2(sch_1):\PP60\" )
				( objectStatus "DMI_CPU0_PCH_RX_DP<2>" )
			)
			( signal "@baseboard_fab2_lib.baseboard_fab2(sch_1):dmi_cpu0_pch_rx_c_dp(2)"
				( pinPairRef "@baseboard_fab2_lib.baseboard_fab2(sch_1):\PP61\" )
				( objectStatus "DMI_CPU0_PCH_RX_C_DP<2>" )
			)
			( signal "@baseboard_fab2_lib.baseboard_fab2(sch_1):dmi_cpu0_pch_rx_dn(3)"
				( pinPairRef "@baseboard_fab2_lib.baseboard_fab2(sch_1):\PP66\" )
				( objectStatus "DMI_CPU0_PCH_RX_DN<3>" )
			)
			( signal "@baseboard_fab2_lib.baseboard_fab2(sch_1):dmi_cpu0_pch_rx_c_dn(3)"
				( pinPairRef "@baseboard_fab2_lib.baseboard_fab2(sch_1):\PP67\" )
				( objectStatus "DMI_CPU0_PCH_RX_C_DN<3>" )
			)
			( signal "@baseboard_fab2_lib.baseboard_fab2(sch_1):dmi_cpu0_pch_rx_dp(3)"
				( pinPairRef "@baseboard_fab2_lib.baseboard_fab2(sch_1):\PP64\" )
				( objectStatus "DMI_CPU0_PCH_RX_DP<3>" )
			)
			( signal "@baseboard_fab2_lib.baseboard_fab2(sch_1):dmi_cpu0_pch_rx_c_dp(3)"
				( pinPairRef "@baseboard_fab2_lib.baseboard_fab2(sch_1):\PP65\" )
				( objectStatus "DMI_CPU0_PCH_RX_C_DP<3>" )
			)
			( signal "@baseboard_fab2_lib.baseboard_fab2(sch_1):p3e_cpu0_pe2_ss_rxp(6)"
				( pinPairRef "@baseboard_fab2_lib.baseboard_fab2(sch_1):\PP3093\" )
				( objectStatus "P3E_CPU0_PE2_SS_RXP<6>" )
			)
			( signal "@baseboard_fab2_lib.baseboard_fab2(sch_1):p3e_cpu0_pe2_ss_rxn(6)"
				( pinPairRef "@baseboard_fab2_lib.baseboard_fab2(sch_1):\PP3091\" )
				( objectStatus "P3E_CPU0_PE2_SS_RXN<6>" )
			)
			( signal "@baseboard_fab2_lib.baseboard_fab2(sch_1):p2e_ssb_bmc_tx_c_dp"
				( objectStatus "P2E_SSB_BMC_TX_C_DP" )
			)
			( signal "@baseboard_fab2_lib.baseboard_fab2(sch_1):p2e_ssb_bmc_tx_c_dn"
				( objectStatus "P2E_SSB_BMC_TX_C_DN" )
			)
			( signal "@baseboard_fab2_lib.baseboard_fab2(sch_1):p2e_ssb_bmc_tx_dp"
				( objectStatus "P2E_SSB_BMC_TX_DP" )
			)
			( signal "@baseboard_fab2_lib.baseboard_fab2(sch_1):p2e_ssb_bmc_tx_dn"
				( objectStatus "P2E_SSB_BMC_TX_DN" )
			)
			( signal "@baseboard_fab2_lib.baseboard_fab2(sch_1):p2e_ssb_bmc_rx_dp"
				( objectStatus "P2E_SSB_BMC_RX_DP" )
			)
			( signal "@baseboard_fab2_lib.baseboard_fab2(sch_1):p2e_ssb_bmc_rx_dn"
				( objectStatus "P2E_SSB_BMC_RX_DN" )
			)
			( signal "@baseboard_fab2_lib.baseboard_fab2(sch_1):p2e_ssb_bmc_rx_c_dp"
				( objectStatus "P2E_SSB_BMC_RX_C_DP" )
			)
			( signal "@baseboard_fab2_lib.baseboard_fab2(sch_1):p2e_ssb_bmc_rx_c_dn"
				( objectStatus "P2E_SSB_BMC_RX_C_DN" )
			)
			( signal "@baseboard_fab2_lib.baseboard_fab2(sch_1):p3e_cpu0_pe2_ss_rxp(7)"
				( pinPairRef "@baseboard_fab2_lib.baseboard_fab2(sch_1):\PP3094\" )
				( objectStatus "P3E_CPU0_PE2_SS_RXP<7>" )
			)
			( signal "@baseboard_fab2_lib.baseboard_fab2(sch_1):p3e_cpu0_pe2_ss_rxn(7)"
				( pinPairRef "@baseboard_fab2_lib.baseboard_fab2(sch_1):\PP3092\" )
				( objectStatus "P3E_CPU0_PE2_SS_RXN<7>" )
			)
			( signal "@baseboard_fab2_lib.baseboard_fab2(sch_1):p3e_cpu0_pe2_ss_rxp(8)"
				( pinPairRef "@baseboard_fab2_lib.baseboard_fab2(sch_1):\PP3089\" )
				( objectStatus "P3E_CPU0_PE2_SS_RXP<8>" )
			)
			( signal "@baseboard_fab2_lib.baseboard_fab2(sch_1):p3e_cpu0_pe2_ss_rxn(8)"
				( pinPairRef "@baseboard_fab2_lib.baseboard_fab2(sch_1):\PP3087\" )
				( objectStatus "P3E_CPU0_PE2_SS_RXN<8>" )
			)
			( signal "@baseboard_fab2_lib.baseboard_fab2(sch_1):p3e_cpu0_pe2_ss_rxp(15)"
				( pinPairRef "@baseboard_fab2_lib.baseboard_fab2(sch_1):\PP3078\" )
				( objectStatus "P3E_CPU0_PE2_SS_RXP<15>" )
			)
			( signal "@baseboard_fab2_lib.baseboard_fab2(sch_1):p3e_cpu0_pe2_ss_rxn(15)"
				( pinPairRef "@baseboard_fab2_lib.baseboard_fab2(sch_1):\PP3076\" )
				( objectStatus "P3E_CPU0_PE2_SS_RXN<15>" )
			)
			( signal "@baseboard_fab2_lib.baseboard_fab2(sch_1):p3e_cpu0_pe2_ss_rxp(14)"
				( pinPairRef "@baseboard_fab2_lib.baseboard_fab2(sch_1):\PP3077\" )
				( objectStatus "P3E_CPU0_PE2_SS_RXP<14>" )
			)
			( signal "@baseboard_fab2_lib.baseboard_fab2(sch_1):p3e_cpu0_pe2_ss_rxn(14)"
				( pinPairRef "@baseboard_fab2_lib.baseboard_fab2(sch_1):\PP3075\" )
				( objectStatus "P3E_CPU0_PE2_SS_RXN<14>" )
			)
			( signal "@baseboard_fab2_lib.baseboard_fab2(sch_1):p3e_cpu0_pe2_ss_rxp(13)"
				( pinPairRef "@baseboard_fab2_lib.baseboard_fab2(sch_1):\PP3082\" )
				( objectStatus "P3E_CPU0_PE2_SS_RXP<13>" )
			)
			( signal "@baseboard_fab2_lib.baseboard_fab2(sch_1):p3e_cpu0_pe2_ss_rxn(13)"
				( pinPairRef "@baseboard_fab2_lib.baseboard_fab2(sch_1):\PP3080\" )
				( objectStatus "P3E_CPU0_PE2_SS_RXN<13>" )
			)
			( signal "@baseboard_fab2_lib.baseboard_fab2(sch_1):p3e_cpu0_pe2_ss_rxp(12)"
				( pinPairRef "@baseboard_fab2_lib.baseboard_fab2(sch_1):\PP3081\" )
				( objectStatus "P3E_CPU0_PE2_SS_RXP<12>" )
			)
			( signal "@baseboard_fab2_lib.baseboard_fab2(sch_1):p3e_cpu0_pe2_ss_rxn(12)"
				( pinPairRef "@baseboard_fab2_lib.baseboard_fab2(sch_1):\PP3079\" )
				( objectStatus "P3E_CPU0_PE2_SS_RXN<12>" )
			)
			( signal "@baseboard_fab2_lib.baseboard_fab2(sch_1):p3e_cpu0_pe2_ss_rxp(11)"
				( pinPairRef "@baseboard_fab2_lib.baseboard_fab2(sch_1):\PP3086\" )
				( objectStatus "P3E_CPU0_PE2_SS_RXP<11>" )
			)
			( signal "@baseboard_fab2_lib.baseboard_fab2(sch_1):p3e_cpu0_pe2_ss_rxn(11)"
				( pinPairRef "@baseboard_fab2_lib.baseboard_fab2(sch_1):\PP3084\" )
				( objectStatus "P3E_CPU0_PE2_SS_RXN<11>" )
			)
			( signal "@baseboard_fab2_lib.baseboard_fab2(sch_1):p3e_cpu0_pe2_ss_rxp(10)"
				( pinPairRef "@baseboard_fab2_lib.baseboard_fab2(sch_1):\PP3085\" )
				( objectStatus "P3E_CPU0_PE2_SS_RXP<10>" )
			)
			( signal "@baseboard_fab2_lib.baseboard_fab2(sch_1):p3e_cpu0_pe2_ss_rxn(10)"
				( pinPairRef "@baseboard_fab2_lib.baseboard_fab2(sch_1):\PP3083\" )
				( objectStatus "P3E_CPU0_PE2_SS_RXN<10>" )
			)
			( signal "@baseboard_fab2_lib.baseboard_fab2(sch_1):p3e_cpu0_pe2_ss_rxp(9)"
				( pinPairRef "@baseboard_fab2_lib.baseboard_fab2(sch_1):\PP3090\" )
				( objectStatus "P3E_CPU0_PE2_SS_RXP<9>" )
			)
			( signal "@baseboard_fab2_lib.baseboard_fab2(sch_1):p3e_cpu0_pe2_ss_rxn(9)"
				( pinPairRef "@baseboard_fab2_lib.baseboard_fab2(sch_1):\PP3088\" )
				( objectStatus "P3E_CPU0_PE2_SS_RXN<9>" )
			)
			( signal "@baseboard_fab2_lib.baseboard_fab2(sch_1):p3e_cpu1_pe3_mp_rxp(8)"
				( pinPairRef "@baseboard_fab2_lib.baseboard_fab2(sch_1):\PP3017\" )
				( objectStatus "P3E_CPU1_PE3_MP_RXP<8>" )
			)
			( signal "@baseboard_fab2_lib.baseboard_fab2(sch_1):p3e_cpu1_pe3_mp_rxn(8)"
				( pinPairRef "@baseboard_fab2_lib.baseboard_fab2(sch_1):\PP3015\" )
				( objectStatus "P3E_CPU1_PE3_MP_RXN<8>" )
			)
			( signal "@baseboard_fab2_lib.baseboard_fab2(sch_1):p3e_cpu1_pe3_mp_rxp(9)"
				( pinPairRef "@baseboard_fab2_lib.baseboard_fab2(sch_1):\PP3018\" )
				( objectStatus "P3E_CPU1_PE3_MP_RXP<9>" )
			)
			( signal "@baseboard_fab2_lib.baseboard_fab2(sch_1):p3e_cpu1_pe3_mp_rxn(9)"
				( pinPairRef "@baseboard_fab2_lib.baseboard_fab2(sch_1):\PP3016\" )
				( objectStatus "P3E_CPU1_PE3_MP_RXN<9>" )
			)
			( signal "@baseboard_fab2_lib.baseboard_fab2(sch_1):p3e_cpu1_pe3_mp_rxp(10)"
				( pinPairRef "@baseboard_fab2_lib.baseboard_fab2(sch_1):\PP3013\" )
				( objectStatus "P3E_CPU1_PE3_MP_RXP<10>" )
			)
			( signal "@baseboard_fab2_lib.baseboard_fab2(sch_1):p3e_cpu1_pe3_mp_rxn(10)"
				( pinPairRef "@baseboard_fab2_lib.baseboard_fab2(sch_1):\PP3011\" )
				( objectStatus "P3E_CPU1_PE3_MP_RXN<10>" )
			)
			( signal "@baseboard_fab2_lib.baseboard_fab2(sch_1):p3e_cpu1_pe3_mp_rxp(11)"
				( pinPairRef "@baseboard_fab2_lib.baseboard_fab2(sch_1):\PP3014\" )
				( objectStatus "P3E_CPU1_PE3_MP_RXP<11>" )
			)
			( signal "@baseboard_fab2_lib.baseboard_fab2(sch_1):p3e_cpu1_pe3_mp_rxn(11)"
				( pinPairRef "@baseboard_fab2_lib.baseboard_fab2(sch_1):\PP3012\" )
				( objectStatus "P3E_CPU1_PE3_MP_RXN<11>" )
			)
			( signal "@baseboard_fab2_lib.baseboard_fab2(sch_1):p3e_cpu1_pe3_mp_rxp(12)"
				( pinPairRef "@baseboard_fab2_lib.baseboard_fab2(sch_1):\PP3009\" )
				( objectStatus "P3E_CPU1_PE3_MP_RXP<12>" )
			)
			( signal "@baseboard_fab2_lib.baseboard_fab2(sch_1):p3e_cpu1_pe3_mp_rxn(12)"
				( pinPairRef "@baseboard_fab2_lib.baseboard_fab2(sch_1):\PP3007\" )
				( objectStatus "P3E_CPU1_PE3_MP_RXN<12>" )
			)
			( signal "@baseboard_fab2_lib.baseboard_fab2(sch_1):p3e_cpu1_pe3_mp_rxp(13)"
				( pinPairRef "@baseboard_fab2_lib.baseboard_fab2(sch_1):\PP3010\" )
				( objectStatus "P3E_CPU1_PE3_MP_RXP<13>" )
			)
			( signal "@baseboard_fab2_lib.baseboard_fab2(sch_1):p3e_cpu1_pe3_mp_rxn(13)"
				( pinPairRef "@baseboard_fab2_lib.baseboard_fab2(sch_1):\PP3008\" )
				( objectStatus "P3E_CPU1_PE3_MP_RXN<13>" )
			)
			( signal "@baseboard_fab2_lib.baseboard_fab2(sch_1):p3e_cpu1_pe3_mp_rxp(14)"
				( pinPairRef "@baseboard_fab2_lib.baseboard_fab2(sch_1):\PP3005\" )
				( objectStatus "P3E_CPU1_PE3_MP_RXP<14>" )
			)
			( signal "@baseboard_fab2_lib.baseboard_fab2(sch_1):p3e_cpu1_pe3_mp_rxn(14)"
				( pinPairRef "@baseboard_fab2_lib.baseboard_fab2(sch_1):\PP3003\" )
				( objectStatus "P3E_CPU1_PE3_MP_RXN<14>" )
			)
			( signal "@baseboard_fab2_lib.baseboard_fab2(sch_1):p3e_cpu1_pe3_mp_rxp(15)"
				( pinPairRef "@baseboard_fab2_lib.baseboard_fab2(sch_1):\PP3006\" )
				( objectStatus "P3E_CPU1_PE3_MP_RXP<15>" )
			)
			( signal "@baseboard_fab2_lib.baseboard_fab2(sch_1):p3e_cpu1_pe3_mp_rxn(15)"
				( pinPairRef "@baseboard_fab2_lib.baseboard_fab2(sch_1):\PP3004\" )
				( objectStatus "P3E_CPU1_PE3_MP_RXN<15>" )
			)
			( signal "@baseboard_fab2_lib.baseboard_fab2(sch_1):l1_z85_ms"
				( objectStatus "L1_Z85_MS" )
			)
			( signal "@baseboard_fab2_lib.baseboard_fab2(sch_1):l3_z85_sl"
				( objectStatus "L3_Z85_SL" )
			)
			( signal "@baseboard_fab2_lib.baseboard_fab2(sch_1):l12_z85_sl"
				( objectStatus "L12_Z85_SL" )
			)
			( signal "@baseboard_fab2_lib.baseboard_fab2(sch_1):l14_z85_ms"
				( objectStatus "L14_Z85_MS" )
			)
			( signal "@baseboard_fab2_lib.baseboard_fab2(sch_1):l1_z85_thru"
				( objectStatus "L1_Z85_THRU" )
			)
			( signal "@baseboard_fab2_lib.baseboard_fab2(sch_1):l5_z85_sl"
				( objectStatus "L5_Z85_SL" )
			)
			( signal "@baseboard_fab2_lib.baseboard_fab2(sch_1):l10_z85_sl"
				( objectStatus "L10_Z85_SL" )
			)
			( signal "@baseboard_fab2_lib.baseboard_fab2(sch_1):p5v"
				( attribute "VOLTAGE" "+5.0V"
					( Units "uVoltage" "V" 1.000000)
					( Origin gFrontEnd )
				)
				( objectStatus "P5V" )
			)
			( signal "@baseboard_fab2_lib.baseboard_fab2(sch_1):p5v_usb"
				( attribute "RATSNEST_SCHEDULE" "MIN_TREE"
					( Origin gBackEnd )
				)
				( attribute "VOLTAGE" "5V"
					( Units "uVoltage" "V" 1.000000)
					( Origin gFrontEnd )
				)
				( objectStatus "P5V_USB" )
			)
			( signal "@baseboard_fab2_lib.baseboard_fab2(sch_1):p12v"
				( attribute "RATSNEST_SCHEDULE" "MIN_TREE"
					( Origin gBackEnd )
				)
				( attribute "VOLTAGE" "+12."
					( Units "uVoltage" "V" 1.000000)
					( Origin gFrontEnd )
				)
				( objectStatus "P12V" )
			)
			( signal "@baseboard_fab2_lib.baseboard_fab2(sch_1):p3v_bat_source"
				( attribute "RATSNEST_SCHEDULE" "MIN_TREE"
					( Origin gBackEnd )
				)
				( attribute "VOLTAGE" "+3 V"
					( Units "uVoltage" "V" 1.000000)
					( Origin gFrontEnd )
				)
				( objectStatus "P3V_BAT_SOURCE" )
			)
			( signal "@baseboard_fab2_lib.baseboard_fab2(sch_1):p3v3"
				( attribute "RATSNEST_SCHEDULE" "MIN_DAISY_CHAIN"
					( Origin gBackEnd )
				)
				( attribute "VOLTAGE" "3.3V"
					( Units "uVoltage" "V" 1.000000)
					( Origin gFrontEnd )
				)
				( objectStatus "P3V3" )
			)
			( signal "@baseboard_fab2_lib.baseboard_fab2(sch_1):p5v_stby"
				( attribute "RATSNEST_SCHEDULE" "MIN_DAISY_CHAIN"
					( Origin gBackEnd )
				)
				( attribute "VOLTAGE" "+5.0V"
					( Units "uVoltage" "V" 1.000000)
					( Origin gFrontEnd )
				)
				( objectStatus "P5V_STBY" )
			)
			( signal "@baseboard_fab2_lib.baseboard_fab2(sch_1):p12v_stby"
				( attribute "RATSNEST_SCHEDULE" "MIN_TREE"
					( Origin gBackEnd )
				)
				( attribute "VOLTAGE" "12.0V"
					( Units "uVoltage" "V" 1.000000)
					( Origin gBackEnd )
				)
				( objectStatus "P12V_STBY" )
			)
			( signal "@baseboard_fab2_lib.baseboard_fab2(sch_1):p12v_hsc_senn0"
				( attribute "VOLTAGE" "+12V"
					( Units "uVoltage" "V" 1.000000)
					( Origin gFrontEnd )
				)
				( objectStatus "P12V_HSC_SENN0" )
			)
			( signal "@baseboard_fab2_lib.baseboard_fab2(sch_1):p12v_hsc_senn1"
				( attribute "VOLTAGE" "+12V"
					( Units "uVoltage" "V" 1.000000)
					( Origin gFrontEnd )
				)
				( objectStatus "P12V_HSC_SENN1" )
			)
			( signal "@baseboard_fab2_lib.baseboard_fab2(sch_1):p12v_hsc_senp0"
				( attribute "VOLTAGE" "+12V"
					( Units "uVoltage" "V" 1.000000)
					( Origin gFrontEnd )
				)
				( objectStatus "P12V_HSC_SENP0" )
			)
			( signal "@baseboard_fab2_lib.baseboard_fab2(sch_1):p12v_hsc_senp1"
				( attribute "VOLTAGE" "+12V"
					( Units "uVoltage" "V" 1.000000)
					( Origin gFrontEnd )
				)
				( objectStatus "P12V_HSC_SENP1" )
			)
			( signal "@baseboard_fab2_lib.baseboard_fab2(sch_1):p12v_mb0_sw"
				( attribute "VOLTAGE" "+12V"
					( Units "uVoltage" "V" 1.000000)
					( Origin gFrontEnd )
				)
				( objectStatus "P12V_MB0_SW" )
			)
			( signal "@baseboard_fab2_lib.baseboard_fab2(sch_1):p12v_psu"
				( attribute "RATSNEST_SCHEDULE" "MIN_TREE"
					( Origin gBackEnd )
				)
				( attribute "VOLTAGE" "12.0"
					( Units "uVoltage" "V" 1.000000)
					( Origin gFrontEnd )
				)
				( objectStatus "P12V_PSU" )
			)
			( signal "@baseboard_fab2_lib.baseboard_fab2(sch_1):pvddq_abc"
				( attribute "RATSNEST_SCHEDULE" "MIN_TREE"
					( Origin gBackEnd )
				)
				( attribute "VOLTAGE" "1.2V"
					( Units "uVoltage" "V" 1.000000)
					( Origin gFrontEnd )
				)
				( objectStatus "PVDDQ_ABC" )
			)
			( signal "@baseboard_fab2_lib.baseboard_fab2(sch_1):pvddq_def"
				( attribute "RATSNEST_SCHEDULE" "MIN_DAISY_CHAIN"
					( Origin gBackEnd )
				)
				( attribute "VOLTAGE" "1.2V"
					( Units "uVoltage" "V" 1.000000)
					( Origin gFrontEnd )
				)
				( objectStatus "PVDDQ_DEF" )
			)
			( signal "@baseboard_fab2_lib.baseboard_fab2(sch_1):pvddq_ghj"
				( attribute "RATSNEST_SCHEDULE" "MIN_DAISY_CHAIN"
					( Origin gBackEnd )
				)
				( attribute "VOLTAGE" "1.2V"
					( Units "uVoltage" "V" 1.000000)
					( Origin gFrontEnd )
				)
				( objectStatus "PVDDQ_GHJ" )
			)
			( signal "@baseboard_fab2_lib.baseboard_fab2(sch_1):pvddq_klm"
				( attribute "RATSNEST_SCHEDULE" "MIN_DAISY_CHAIN"
					( Origin gBackEnd )
				)
				( attribute "VOLTAGE" "1.2V"
					( Units "uVoltage" "V" 1.000000)
					( Origin gFrontEnd )
				)
				( objectStatus "PVDDQ_KLM" )
			)
			( signal "@baseboard_fab2_lib.baseboard_fab2(sch_1):pvsa_cpu0"
				( attribute "VOLTAGE" "1.1V"
					( Units "uVoltage" "V" 1.000000)
					( Origin gFrontEnd )
				)
				( objectStatus "PVSA_CPU0" )
			)
			( signal "@baseboard_fab2_lib.baseboard_fab2(sch_1):pvsa_cpu1"
				( attribute "VOLTAGE" "1.1V"
					( Units "uVoltage" "V" 1.000000)
					( Origin gFrontEnd )
				)
				( objectStatus "PVSA_CPU1" )
			)
			( signal "@baseboard_fab2_lib.baseboard_fab2(sch_1):pvtt_abc"
				( attribute "RATSNEST_SCHEDULE" "MIN_TREE"
					( Origin gBackEnd )
				)
				( attribute "VOLTAGE" "0.6V"
					( Units "uVoltage" "V" 1.000000)
					( Origin gFrontEnd )
				)
				( objectStatus "PVTT_ABC" )
			)
			( signal "@baseboard_fab2_lib.baseboard_fab2(sch_1):pvtt_def"
				( attribute "RATSNEST_SCHEDULE" "MIN_TREE"
					( Origin gBackEnd )
				)
				( attribute "VOLTAGE" "0.6V"
					( Units "uVoltage" "V" 1.000000)
					( Origin gFrontEnd )
				)
				( objectStatus "PVTT_DEF" )
			)
			( signal "@baseboard_fab2_lib.baseboard_fab2(sch_1):pvtt_ghj"
				( attribute "RATSNEST_SCHEDULE" "MIN_TREE"
					( Origin gBackEnd )
				)
				( attribute "VOLTAGE" "0.6V"
					( Units "uVoltage" "V" 1.000000)
					( Origin gFrontEnd )
				)
				( objectStatus "PVTT_GHJ" )
			)
			( signal "@baseboard_fab2_lib.baseboard_fab2(sch_1):pvtt_klm"
				( attribute "RATSNEST_SCHEDULE" "MIN_TREE"
					( Origin gBackEnd )
				)
				( attribute "VOLTAGE" "0.6V"
					( Units "uVoltage" "V" 1.000000)
					( Origin gFrontEnd )
				)
				( objectStatus "PVTT_KLM" )
			)
			( signal "@baseboard_fab2_lib.baseboard_fab2(sch_1):pvpp_abc"
				( attribute "RATSNEST_SCHEDULE" "MIN_TREE"
					( Origin gBackEnd )
				)
				( attribute "VOLTAGE" "2.5V"
					( Units "uVoltage" "V" 1.000000)
					( Origin gFrontEnd )
				)
				( objectStatus "PVPP_ABC" )
			)
			( signal "@baseboard_fab2_lib.baseboard_fab2(sch_1):pvpp_def"
				( attribute "RATSNEST_SCHEDULE" "MIN_TREE"
					( Origin gBackEnd )
				)
				( attribute "VOLTAGE" "2.5V"
					( Units "uVoltage" "V" 1.000000)
					( Origin gFrontEnd )
				)
				( objectStatus "PVPP_DEF" )
			)
			( signal "@baseboard_fab2_lib.baseboard_fab2(sch_1):pvpp_ghj"
				( attribute "RATSNEST_SCHEDULE" "MIN_TREE"
					( Origin gBackEnd )
				)
				( attribute "VOLTAGE" "2.5V"
					( Units "uVoltage" "V" 1.000000)
					( Origin gFrontEnd )
				)
				( objectStatus "PVPP_GHJ" )
			)
			( signal "@baseboard_fab2_lib.baseboard_fab2(sch_1):pvpp_klm"
				( attribute "RATSNEST_SCHEDULE" "MIN_TREE"
					( Origin gBackEnd )
				)
				( attribute "VOLTAGE" "2.5V"
					( Units "uVoltage" "V" 1.000000)
					( Origin gFrontEnd )
				)
				( objectStatus "PVPP_KLM" )
			)
			( signal "@baseboard_fab2_lib.baseboard_fab2(sch_1):p12v_nvdimm_abc"
				( attribute "RATSNEST_SCHEDULE" "MIN_DAISY_CHAIN"
					( Origin gBackEnd )
				)
				( attribute "VOLTAGE" "12.0"
					( Units "uVoltage" "V" 1.000000)
					( Origin gFrontEnd )
				)
				( objectStatus "P12V_NVDIMM_ABC" )
			)
			( signal "@baseboard_fab2_lib.baseboard_fab2(sch_1):p12v_nvdimm_def"
				( attribute "RATSNEST_SCHEDULE" "MIN_DAISY_CHAIN"
					( Origin gBackEnd )
				)
				( attribute "VOLTAGE" "12.0"
					( Units "uVoltage" "V" 1.000000)
					( Origin gFrontEnd )
				)
				( objectStatus "P12V_NVDIMM_DEF" )
			)
			( signal "@baseboard_fab2_lib.baseboard_fab2(sch_1):p12v_nvdimm_ghj"
				( attribute "RATSNEST_SCHEDULE" "MIN_DAISY_CHAIN"
					( Origin gBackEnd )
				)
				( attribute "VOLTAGE" "12.0"
					( Units "uVoltage" "V" 1.000000)
					( Origin gFrontEnd )
				)
				( objectStatus "P12V_NVDIMM_GHJ" )
			)
			( signal "@baseboard_fab2_lib.baseboard_fab2(sch_1):p12v_nvdimm_klm"
				( attribute "RATSNEST_SCHEDULE" "MIN_DAISY_CHAIN"
					( Origin gBackEnd )
				)
				( attribute "VOLTAGE" "12.0"
					( Units "uVoltage" "V" 1.000000)
					( Origin gFrontEnd )
				)
				( objectStatus "P12V_NVDIMM_KLM" )
			)
			( signal "@baseboard_fab2_lib.baseboard_fab2(sch_1):p3v3_stby"
				( attribute "RATSNEST_SCHEDULE" "MIN_DAISY_CHAIN"
					( Origin gBackEnd )
				)
				( attribute "VOLTAGE" "3.3V"
					( Units "uVoltage" "V" 1.000000)
					( Origin gFrontEnd )
				)
				( objectStatus "P3V3_STBY" )
			)
			( signal "@baseboard_fab2_lib.baseboard_fab2(sch_1):pvccin_cpu0"
				( attribute "RATSNEST_SCHEDULE" "MIN_TREE"
					( Origin gBackEnd )
				)
				( attribute "VOLTAGE" "2.0V"
					( Units "uVoltage" "V" 1.000000)
					( Origin gFrontEnd )
				)
				( objectStatus "PVCCIN_CPU0" )
			)
			( signal "@baseboard_fab2_lib.baseboard_fab2(sch_1):pvccin_cpu1"
				( attribute "RATSNEST_SCHEDULE" "MIN_TREE"
					( Origin gBackEnd )
				)
				( attribute "VOLTAGE" "2.0V"
					( Units "uVoltage" "V" 1.000000)
					( Origin gFrontEnd )
				)
				( objectStatus "PVCCIN_CPU1" )
			)
			( signal "@baseboard_fab2_lib.baseboard_fab2(sch_1):pvccin_pvsa_cpu0_iinsen"
				( attribute "RATSNEST_SCHEDULE" "MIN_DAISY_CHAIN"
					( Origin gBackEnd )
				)
				( attribute "VOLTAGE" "+3.3V"
					( Units "uVoltage" "V" 1.000000)
					( Origin gFrontEnd )
				)
				( objectStatus "PVCCIN_PVSA_CPU0_IINSEN" )
			)
			( signal "@baseboard_fab2_lib.baseboard_fab2(sch_1):pvccin_pvsa_cpu1_iinsen"
				( attribute "VOLTAGE" "+1.5V"
					( Units "uVoltage" "V" 1.000000)
					( Origin gFrontEnd )
				)
				( objectStatus "PVCCIN_PVSA_CPU1_IINSEN" )
			)
			( signal "@baseboard_fab2_lib.baseboard_fab2(sch_1):pvccio_cpu0"
				( attribute "RATSNEST_SCHEDULE" "MIN_DAISY_CHAIN"
					( Origin gBackEnd )
				)
				( attribute "VOLTAGE" "1.1V"
					( Units "uVoltage" "V" 1.000000)
					( Origin gFrontEnd )
				)
				( objectStatus "PVCCIO_CPU0" )
			)
			( signal "@baseboard_fab2_lib.baseboard_fab2(sch_1):pvccio_cpu1"
				( attribute "RATSNEST_SCHEDULE" "MIN_TREE"
					( Origin gBackEnd )
				)
				( attribute "VOLTAGE" "1.1V"
					( Units "uVoltage" "V" 1.000000)
					( Origin gFrontEnd )
				)
				( objectStatus "PVCCIO_CPU1" )
			)
			( signal "@baseboard_fab2_lib.baseboard_fab2(sch_1):pvnn_pch_stby"
				( attribute "RATSNEST_SCHEDULE" "MIN_DAISY_CHAIN"
					( Origin gBackEnd )
				)
				( attribute "VOLTAGE" "1.0V"
					( Units "uVoltage" "V" 1.000000)
					( Origin gFrontEnd )
				)
				( objectStatus "PVNN_PCH_STBY" )
			)
			( signal "@baseboard_fab2_lib.baseboard_fab2(sch_1):p12v_fan"
				( attribute "VOLTAGE" "12.0V"
					( Units "uVoltage" "V" 1.000000)
					( Origin gFrontEnd )
				)
				( objectStatus "P12V_FAN" )
			)
			( signal "@baseboard_fab2_lib.baseboard_fab2(sch_1):vr_pvccin_cpu1_vdd"
				( attribute "VOLTAGE" "3.3"
					( Units "uVoltage" "V" 1.000000)
					( Origin gFrontEnd )
				)
				( objectStatus "VR_PVCCIN_CPU1_VDD" )
			)
			( signal "@baseboard_fab2_lib.baseboard_fab2(sch_1):p0v9_lan"
				( attribute "VOLTAGE" "0.9V"
					( Units "uVoltage" "V" 1.000000)
					( Origin gFrontEnd )
				)
				( objectStatus "P0V9_LAN" )
			)
			( signal "@baseboard_fab2_lib.baseboard_fab2(sch_1):p1v5_lan"
				( attribute "VOLTAGE" "1.5V"
					( Units "uVoltage" "V" 1.000000)
					( Origin gFrontEnd )
				)
				( objectStatus "P1V5_LAN" )
			)
			( signal "@baseboard_fab2_lib.baseboard_fab2(sch_1):p1v8_pch_stby"
				( attribute "RATSNEST_SCHEDULE" "MIN_DAISY_CHAIN"
					( Origin gBackEnd )
				)
				( attribute "VOLTAGE" "1.8V"
					( Units "uVoltage" "V" 1.000000)
					( Origin gFrontEnd )
				)
				( objectStatus "P1V8_PCH_STBY" )
			)
			( signal "@baseboard_fab2_lib.baseboard_fab2(sch_1):p1v05_pch_stby"
				( attribute "RATSNEST_SCHEDULE" "MIN_TREE"
					( Origin gBackEnd )
				)
				( attribute "VOLTAGE" "1.05V"
					( Units "uVoltage" "V" 1.000000)
					( Origin gFrontEnd )
				)
				( objectStatus "P1V05_PCH_STBY" )
			)
			( signal "@baseboard_fab2_lib.baseboard_fab2(sch_1):p1v26_bmc_stby"
				( attribute "RATSNEST_SCHEDULE" "MIN_DAISY_CHAIN"
					( Origin gBackEnd )
				)
				( attribute "VOLTAGE" "+1.26"
					( Units "uVoltage" "V" 1.000000)
					( Origin gFrontEnd )
				)
				( objectStatus "P1V26_BMC_STBY" )
			)
			( signal "@baseboard_fab2_lib.baseboard_fab2(sch_1):p0v7_gtl2014_2"
				( attribute "VOLTAGE" "+0.7"
					( Units "uVoltage" "V" 1.000000)
					( Origin gFrontEnd )
				)
				( objectStatus "P0V7_GTL2014_2" )
			)
			( signal "@baseboard_fab2_lib.baseboard_fab2(sch_1):p1v8_bmc_stby_pcie"
				( attribute "VOLTAGE" "+1.8V"
					( Units "uVoltage" "V" 1.000000)
					( Origin gFrontEnd )
				)
				( objectStatus "P1V8_BMC_STBY_PCIE" )
			)
			( signal "@baseboard_fab2_lib.baseboard_fab2(sch_1):p1v8_bmc_stby_pciea"
				( attribute "VOLTAGE" "+1.8V"
					( Units "uVoltage" "V" 1.000000)
					( Origin gFrontEnd )
				)
				( objectStatus "P1V8_BMC_STBY_PCIEA" )
			)
			( signal "@baseboard_fab2_lib.baseboard_fab2(sch_1):p1v05_pch_stby_isclk_pll"
				( attribute "RATSNEST_SCHEDULE" "MIN_DAISY_CHAIN"
					( Origin gBackEnd )
				)
				( attribute "VOLTAGE" "1.05V"
					( Units "uVoltage" "V" 1.000000)
					( Origin gFrontEnd )
				)
				( objectStatus "P1V05_PCH_STBY_ISCLK_PLL" )
			)
			( signal "@baseboard_fab2_lib.baseboard_fab2(sch_1):p1v05_pch_stby_kr_pll"
				( attribute "RATSNEST_SCHEDULE" "MIN_DAISY_CHAIN"
					( Origin gBackEnd )
				)
				( attribute "VOLTAGE" "1.05V"
					( Units "uVoltage" "V" 1.000000)
					( Origin gFrontEnd )
				)
				( objectStatus "P1V05_PCH_STBY_KR_PLL" )
			)
			( signal "@baseboard_fab2_lib.baseboard_fab2(sch_1):p1v05_pch_stby_vcca_pll1"
				( attribute "RATSNEST_SCHEDULE" "MIN_DAISY_CHAIN"
					( Origin gBackEnd )
				)
				( attribute "VOLTAGE" "1.05V"
					( Units "uVoltage" "V" 1.000000)
					( Origin gFrontEnd )
				)
				( objectStatus "P1V05_PCH_STBY_VCCA_PLL1" )
			)
			( signal "@baseboard_fab2_lib.baseboard_fab2(sch_1):p1v05_pch_stby_vcca_pll0"
				( attribute "RATSNEST_SCHEDULE" "MIN_DAISY_CHAIN"
					( Origin gBackEnd )
				)
				( attribute "VOLTAGE" "1.05V"
					( Units "uVoltage" "V" 1.000000)
					( Origin gFrontEnd )
				)
				( objectStatus "P1V05_PCH_STBY_VCCA_PLL0" )
			)
			( signal "@baseboard_fab2_lib.baseboard_fab2(sch_1):p1v05_pch_stby_wm20_pll"
				( attribute "RATSNEST_SCHEDULE" "MIN_DAISY_CHAIN"
					( Origin gBackEnd )
				)
				( attribute "VOLTAGE" "1.05V"
					( Units "uVoltage" "V" 1.000000)
					( Origin gFrontEnd )
				)
				( objectStatus "P1V05_PCH_STBY_WM20_PLL" )
			)
			( signal "@baseboard_fab2_lib.baseboard_fab2(sch_1):p1v05_pch_stby_wm26_pll"
				( attribute "RATSNEST_SCHEDULE" "MIN_DAISY_CHAIN"
					( Origin gBackEnd )
				)
				( attribute "VOLTAGE" "1.05V"
					( Units "uVoltage" "V" 1.000000)
					( Origin gFrontEnd )
				)
				( objectStatus "P1V05_PCH_STBY_WM26_PLL" )
			)
			( signal "@baseboard_fab2_lib.baseboard_fab2(sch_1):p1v26_bmc_stby_v1pllav12"
				( attribute "VOLTAGE" "+1.26V"
					( Units "uVoltage" "V" 1.000000)
					( Origin gFrontEnd )
				)
				( objectStatus "P1V26_BMC_STBY_V1PLLAV12" )
			)
			( signal "@baseboard_fab2_lib.baseboard_fab2(sch_1):p1v538_bmc_stby"
				( attribute "VOLTAGE" "+1.538V"
					( Units "uVoltage" "V" 1.000000)
					( Origin gFrontEnd )
				)
				( objectStatus "P1V538_BMC_STBY" )
			)
			( signal "@baseboard_fab2_lib.baseboard_fab2(sch_1):p3v3_db1200"
				( attribute "VOLTAGE" "5"
					( Units "uVoltage" "V" 1.000000)
					( Origin gFrontEnd )
				)
				( objectStatus "P3V3_DB1200" )
			)
			( signal "@baseboard_fab2_lib.baseboard_fab2(sch_1):p3v3_db1200_a"
				( attribute "VOLTAGE" "+3.3V"
					( Units "uVoltage" "V" 1.000000)
					( Origin gFrontEnd )
				)
				( objectStatus "P3V3_DB1200_A" )
			)
			( signal "@baseboard_fab2_lib.baseboard_fab2(sch_1):p3v3_db1200_r"
				( attribute "VOLTAGE" "+3.3V"
					( Units "uVoltage" "V" 1.000000)
					( Origin gFrontEnd )
				)
				( objectStatus "P3V3_DB1200_R" )
			)
			( signal "@baseboard_fab2_lib.baseboard_fab2(sch_1):p3v_bat_source_r"
				( attribute "RATSNEST_SCHEDULE" "MIN_TREE"
					( Origin gBackEnd )
				)
				( attribute "VOLTAGE" "+3V"
					( Units "uVoltage" "V" 1.000000)
					( Origin gFrontEnd )
				)
				( objectStatus "P3V_BAT_SOURCE_R" )
			)
			( signal "@baseboard_fab2_lib.baseboard_fab2(sch_1):p3v3_stby_bmc_adcav33"
				( attribute "VOLTAGE" "+3.3V"
					( Units "uVoltage" "V" 1.000000)
					( Origin gFrontEnd )
				)
				( objectStatus "P3V3_STBY_BMC_ADCAV33" )
			)
			( signal "@baseboard_fab2_lib.baseboard_fab2(sch_1):p3v3_stby_bmc_hpllav33"
				( attribute "VOLTAGE" "+3.3V"
					( Units "uVoltage" "V" 1.000000)
					( Origin gFrontEnd )
				)
				( objectStatus "P3V3_STBY_BMC_HPLLAV33" )
			)
			( signal "@baseboard_fab2_lib.baseboard_fab2(sch_1):p3v3_stby_mng"
				( attribute "VOLTAGE" "5"
					( Units "uVoltage" "V" 1.000000)
					( Origin gFrontEnd )
				)
				( objectStatus "P3V3_STBY_MNG" )
			)
			( signal "@baseboard_fab2_lib.baseboard_fab2(sch_1):p3v3_stby_mng_cpu"
				( attribute "VOLTAGE" "3.3"
					( Units "uVoltage" "V" 1.000000)
					( Origin gFrontEnd )
				)
				( objectStatus "P3V3_STBY_MNG_CPU" )
			)
			( signal "@baseboard_fab2_lib.baseboard_fab2(sch_1):p3v3_stby_mng_rgmii"
				( attribute "VOLTAGE" "3.3"
					( Units "uVoltage" "V" 1.000000)
					( Origin gFrontEnd )
				)
				( objectStatus "P3V3_STBY_MNG_RGMII" )
			)
			( signal "@baseboard_fab2_lib.baseboard_fab2(sch_1):p3v3_stby_mng_rmii"
				( attribute "VOLTAGE" "3.3"
					( Units "uVoltage" "V" 1.000000)
					( Origin gFrontEnd )
				)
				( objectStatus "P3V3_STBY_MNG_RMII" )
			)
			( signal "@baseboard_fab2_lib.baseboard_fab2(sch_1):p3v3_stby_pld_d"
				( attribute "VOLTAGE" "3.3"
					( Units "uVoltage" "V" 1.000000)
					( Origin gFrontEnd )
				)
				( objectStatus "P3V3_STBY_PLD_D" )
			)
			( signal "@baseboard_fab2_lib.baseboard_fab2(sch_1):p5v_hdd_sata"
				( attribute "VOLTAGE" "5"
					( Units "uVoltage" "V" 1.000000)
					( Origin gFrontEnd )
				)
				( objectStatus "P5V_HDD_SATA" )
			)
			( signal "@baseboard_fab2_lib.baseboard_fab2(sch_1):p12v_hdd_sata"
				( attribute "VOLTAGE" "12"
					( Units "uVoltage" "V" 1.000000)
					( Origin gFrontEnd )
				)
				( objectStatus "P12V_HDD_SATA" )
			)
			( signal "@baseboard_fab2_lib.baseboard_fab2(sch_1):p12v_switch_g"
				( attribute "VOLTAGE" "+3.3V"
					( Units "uVoltage" "V" 1.000000)
					( Origin gFrontEnd )
				)
				( objectStatus "P12V_SWITCH_G" )
			)
			( signal "@baseboard_fab2_lib.baseboard_fab2(sch_1):gnd_lan_trct1234_c"
				( objectStatus "GND_LAN_TRCT1234_C" )
			)
			( signal "@baseboard_fab2_lib.baseboard_fab2(sch_1):p12v_fan_switch_g"
				( attribute "VOLTAGE" "+5V"
					( Units "uVoltage" "V" 1.000000)
					( Origin gFrontEnd )
				)
				( objectStatus "P12V_FAN_SWITCH_G" )
			)
			( signal "@baseboard_fab2_lib.baseboard_fab2(sch_1):p3v3_switch_g"
				( attribute "VOLTAGE" "3.3"
					( Units "uVoltage" "V" 1.000000)
					( Origin gFrontEnd )
				)
				( objectStatus "P3V3_SWITCH_G" )
			)
			( signal "@baseboard_fab2_lib.baseboard_fab2(sch_1):p5v_stby_dbg"
				( attribute "VOLTAGE" "5"
					( Units "uVoltage" "V" 1.000000)
					( Origin gFrontEnd )
				)
				( objectStatus "P5V_STBY_DBG" )
			)
			( signal "@baseboard_fab2_lib.baseboard_fab2(sch_1):p5v_switch_g"
				( attribute "VOLTAGE" "+5V"
					( Units "uVoltage" "V" 1.000000)
					( Origin gFrontEnd )
				)
				( objectStatus "P5V_SWITCH_G" )
			)
			( signal "@baseboard_fab2_lib.baseboard_fab2(sch_1):p12v_hsc_vcc"
				( attribute "VOLTAGE" "+12V"
					( Units "uVoltage" "V" 1.000000)
					( Origin gFrontEnd )
				)
				( objectStatus "P12V_HSC_VCC" )
			)
			( signal "@baseboard_fab2_lib.baseboard_fab2(sch_1):spa_5v_sin_sw"
				( objectStatus "SPA_5V_SIN_SW" )
			)
			( signal "@baseboard_fab2_lib.baseboard_fab2(sch_1):p5v_stby_dgb_fs"
				( attribute "VOLTAGE" "5"
					( Units "uVoltage" "V" 1.000000)
					( Origin gFrontEnd )
				)
				( objectStatus "P5V_STBY_DGB_FS" )
			)
			( signal "@baseboard_fab2_lib.baseboard_fab2(sch_1):p1v05_pch_stby_vcca_xtal"
				( attribute "RATSNEST_SCHEDULE" "MIN_DAISY_CHAIN"
					( Origin gBackEnd )
				)
				( attribute "VOLTAGE" "1.05V"
					( Units "uVoltage" "V" 1.000000)
					( Origin gFrontEnd )
				)
				( objectStatus "P1V05_PCH_STBY_VCCA_XTAL" )
			)
			( signal "@baseboard_fab2_lib.baseboard_fab2(sch_1):p0v9_lan_i210"
				( attribute "VOLTAGE" "0.9"
					( Units "uVoltage" "V" 1.000000)
					( Origin gFrontEnd )
				)
				( objectStatus "P0V9_LAN_I210" )
			)
			( signal "@baseboard_fab2_lib.baseboard_fab2(sch_1):p1v5_lan_i210"
				( attribute "VOLTAGE" "1.5"
					( Units "uVoltage" "V" 1.000000)
					( Origin gFrontEnd )
				)
				( objectStatus "P1V5_LAN_I210" )
			)
			( signal "@baseboard_fab2_lib.baseboard_fab2(sch_1):p3v3_stby_p1v5_lan_i210"
				( attribute "VOLTAGE" "3.3"
					( Units "uVoltage" "V" 1.000000)
					( Origin gFrontEnd )
				)
				( objectStatus "P3V3_STBY_P1V5_LAN_I210" )
			)
			( signal "@baseboard_fab2_lib.baseboard_fab2(sch_1):p3v3_fb_adc128_vcc"
				( attribute "VOLTAGE" "+3.3V"
					( Units "uVoltage" "V" 1.000000)
					( Origin gFrontEnd )
				)
				( objectStatus "P3V3_FB_ADC128_VCC" )
			)
			( signal "@baseboard_fab2_lib.baseboard_fab2(sch_1):pvcciomcp_cpu0"
				( attribute "VOLTAGE" "+0.95"
					( Units "uVoltage" "V" 1.000000)
					( Origin gFrontEnd )
				)
				( objectStatus "PVCCIOMCP_CPU0" )
			)
			( signal "@baseboard_fab2_lib.baseboard_fab2(sch_1):pvcciomcp_cpu1"
				( attribute "VOLTAGE" "+0.95"
					( Units "uVoltage" "V" 1.000000)
					( Origin gFrontEnd )
				)
				( objectStatus "PVCCIOMCP_CPU1" )
			)
			( signal "@baseboard_fab2_lib.baseboard_fab2(sch_1):pvccmcp_cpu0"
				( attribute "VOLTAGE" "1.2V"
					( Units "uVoltage" "V" 1.000000)
					( Origin gFrontEnd )
				)
				( objectStatus "PVCCMCP_CPU0" )
			)
			( signal "@baseboard_fab2_lib.baseboard_fab2(sch_1):pvccmcp_cpu1"
				( attribute "VOLTAGE" "+0.95"
					( Units "uVoltage" "V" 1.000000)
					( Origin gFrontEnd )
				)
				( objectStatus "PVCCMCP_CPU1" )
			)
			( signal "@baseboard_fab2_lib.baseboard_fab2(sch_1):p1v8_mcp_cpu0"
				( attribute "RATSNEST_SCHEDULE" "MIN_DAISY_CHAIN"
					( Origin gBackEnd )
				)
				( attribute "VOLTAGE" "+1.8V"
					( Units "uVoltage" "V" 1.000000)
					( Origin gFrontEnd )
				)
				( objectStatus "P1V8_MCP_CPU0" )
			)
			( signal "@baseboard_fab2_lib.baseboard_fab2(sch_1):p1v8_mcp_cpu1"
				( attribute "RATSNEST_SCHEDULE" "MIN_DAISY_CHAIN"
					( Origin gBackEnd )
				)
				( attribute "VOLTAGE" "1.8"
					( Units "uVoltage" "V" 1.000000)
					( Origin gFrontEnd )
				)
				( objectStatus "P1V8_MCP_CPU1" )
			)
			( signal "@baseboard_fab2_lib.baseboard_fab2(sch_1):p3v3_rtc_stby"
				( attribute "VOLTAGE" "3.3V"
					( Units "uVoltage" "V" 1.000000)
					( Origin gBackEnd )
				)
				( objectStatus "P3V3_RTC_STBY" )
			)
			( signal "@baseboard_fab2_lib.baseboard_fab2(sch_1):gnd"
				( attribute "VOLTAGE" "0.0V"
					( Units "uVoltage" "V" 1.000000)
					( Origin gFrontEnd )
				)
				( objectStatus "GND" )
			)
			( signal "@baseboard_fab2_lib.baseboard_fab2(sch_1):agnd_hsc"
				( attribute "RATSNEST_SCHEDULE" "MIN_DAISY_CHAIN"
					( Origin gBackEnd )
				)
				( attribute "VOLTAGE" "0"
					( Units "uVoltage" "V" 1.000000)
					( Origin gFrontEnd )
				)
				( objectStatus "AGND_HSC" )
			)
			( signal "@baseboard_fab2_lib.baseboard_fab2(sch_1):agnd_pvpp_abc"
				( attribute "VOLTAGE" "0.0V"
					( Units "uVoltage" "V" 1.000000)
					( Origin gFrontEnd )
				)
				( objectStatus "AGND_PVPP_ABC" )
			)
			( signal "@baseboard_fab2_lib.baseboard_fab2(sch_1):agnd_pvpp_def"
				( attribute "VOLTAGE" "0.0V"
					( Units "uVoltage" "V" 1.000000)
					( Origin gFrontEnd )
				)
				( objectStatus "AGND_PVPP_DEF" )
			)
			( signal "@baseboard_fab2_lib.baseboard_fab2(sch_1):agnd_pvpp_ghj"
				( attribute "VOLTAGE" "0.0V"
					( Units "uVoltage" "V" 1.000000)
					( Origin gFrontEnd )
				)
				( objectStatus "AGND_PVPP_GHJ" )
			)
			( signal "@baseboard_fab2_lib.baseboard_fab2(sch_1):agnd_pvpp_klm"
				( attribute "VOLTAGE" "0.0V"
					( Units "uVoltage" "V" 1.000000)
					( Origin gFrontEnd )
				)
				( objectStatus "AGND_PVPP_KLM" )
			)
			( signal "@baseboard_fab2_lib.baseboard_fab2(sch_1):agnd_p3v3_stby"
				( attribute "VOLTAGE" "0V"
					( Units "uVoltage" "V" 1.000000)
					( Origin gFrontEnd )
				)
				( objectStatus "AGND_P3V3_STBY" )
			)
			( signal "@baseboard_fab2_lib.baseboard_fab2(sch_1):agnd_p5v_stby"
				( attribute "RATSNEST_SCHEDULE" "MIN_TREE"
					( Origin gBackEnd )
				)
				( attribute "VOLTAGE" "0"
					( Units "uVoltage" "V" 1.000000)
					( Origin gFrontEnd )
				)
				( objectStatus "AGND_P5V_STBY" )
			)
			( signal "@baseboard_fab2_lib.baseboard_fab2(sch_1):gnd_nic"
				( attribute "VOLTAGE" "0.0V"
					( Units "uVoltage" "V" 1.000000)
					( Origin gFrontEnd )
				)
				( objectStatus "GND_NIC" )
			)
			( signal "@baseboard_fab2_lib.baseboard_fab2(sch_1):gnd_signal1"
				( attribute "VOLTAGE" "0.0V"
					( Units "uVoltage" "V" 1.000000)
					( Origin gFrontEnd )
				)
				( objectStatus "GND_SIGNAL1" )
			)
			( signal "@baseboard_fab2_lib.baseboard_fab2(sch_1):gnd_signal2"
				( attribute "VOLTAGE" "0.0V"
					( Units "uVoltage" "V" 1.000000)
					( Origin gFrontEnd )
				)
				( objectStatus "GND_SIGNAL2" )
			)
			( signal "@baseboard_fab2_lib.baseboard_fab2(sch_1):rcc_dfx_1940_1"
				( attribute "NO_TEST" "1"
					( Origin gBackEnd )
				)
				( objectStatus "RCC_DFX_1940_1" )
			)
			( signal "@baseboard_fab2_lib.baseboard_fab2(sch_1):rcc_dfx_1940_2"
				( attribute "NO_TEST" "1"
					( Origin gBackEnd )
				)
				( objectStatus "RCC_DFX_1940_2" )
			)
			( signal "@baseboard_fab2_lib.baseboard_fab2(sch_1):rcc_dfx_1940_3"
				( objectStatus "RCC_DFX_1940_3" )
			)
			( signal "@baseboard_fab2_lib.baseboard_fab2(sch_1):rcc_dfx_1940_4"
				( attribute "NO_TEST" "1"
					( Origin gBackEnd )
				)
				( objectStatus "RCC_DFX_1940_4" )
			)
			( gate "@baseboard_fab2_lib.baseboard_fab2(sch_1):page113_i127"
				( objectStatus "F4206" )
				( pin "A"
					( objectStatus "U1M6.2" )
				)
				( pin "B"
					( objectStatus "U1M6.4" )
				)
			)
			( gate "@baseboard_fab2_lib.baseboard_fab2(sch_1):page113_i206"
				( objectStatus "F4205" )
			)
			( gate "@baseboard_fab2_lib.baseboard_fab2(sch_1):page113_i190"
				( objectStatus "F4204" )
			)
			( gate "@baseboard_fab2_lib.baseboard_fab2(sch_1):page118_i142"
				( objectStatus "F4203" )
			)
			( gate "@baseboard_fab2_lib.baseboard_fab2(sch_1):page113_i196"
				( objectStatus "F4202" )
			)
			( gate "@baseboard_fab2_lib.baseboard_fab2(sch_1):page113_i185"
				( objectStatus "F4201" )
			)
			( gate "@baseboard_fab2_lib.baseboard_fab2(sch_1):page112_i127"
				( objectStatus "F4200" )
				( pin "A"
					( objectStatus "U1M4.2" )
				)
				( pin "B"
					( objectStatus "U1M4.4" )
				)
			)
			( gate "@baseboard_fab2_lib.baseboard_fab2(sch_1):page113_i107"
				( objectStatus "F2005" )
			)
			( gate "@baseboard_fab2_lib.baseboard_fab2(sch_1):page112_i40"
				( objectStatus "F2004" )
				( pin "A"
					( objectStatus "U1M7.4" )
				)
				( pin "B0"
					( objectStatus "U1M7.3" )
				)
				( pin "B1"
					( objectStatus "U1M7.1" )
				)
			)
			( gate "@baseboard_fab2_lib.baseboard_fab2(sch_1):page113_i255"
				( objectStatus "F2003" )
			)
			( gate "@baseboard_fab2_lib.baseboard_fab2(sch_1):page199_i58"
				( objectStatus "F1994" )
			)
			( gate "@baseboard_fab2_lib.baseboard_fab2(sch_1):page168_i9"
				( objectStatus "F1993" )
			)
			( gate "@baseboard_fab2_lib.baseboard_fab2(sch_1):page168_i8"
				( objectStatus "F1992" )
			)
			( gate "@baseboard_fab2_lib.baseboard_fab2(sch_1):page157_i330"
				( objectStatus "F1991" )
			)
			( gate "@baseboard_fab2_lib.baseboard_fab2(sch_1):page181_i181"
				( objectStatus "F1990" )
			)
			( gate "@baseboard_fab2_lib.baseboard_fab2(sch_1):page154_i100"
				( objectStatus "F23" )
				( pin "B"
					( objectStatus "U2T2.2" )
				)
				( pin "Y"
					( objectStatus "U2T2.4" )
				)
			)
			( gate "@baseboard_fab2_lib.baseboard_fab2(sch_1):page154_i99"
				( objectStatus "F22" )
				( pin "B"
					( objectStatus "U2T3.2" )
				)
				( pin "Y"
					( objectStatus "U2T3.4" )
				)
			)
			( gate "@baseboard_fab2_lib.baseboard_fab2(sch_1):page112_i108(3)"
				( objectStatus "F12" )
				( pin "A(3)"
					( objectStatus "U1L1.2" )
				)
				( pin "B(3)"
					( objectStatus "U1L1.3" )
				)
			)
			( gate "@baseboard_fab2_lib.baseboard_fab2(sch_1):page112_i108(2)"
				( objectStatus "F11" )
				( pin "A(2)"
					( objectStatus "U1L1.5" )
				)
				( pin "B(2)"
					( objectStatus "U1L1.6" )
				)
			)
			( gate "@baseboard_fab2_lib.baseboard_fab2(sch_1):page112_i108(1)"
				( objectStatus "F10" )
				( pin "A(1)"
					( objectStatus "U1L1.9" )
				)
				( pin "B(1)"
					( objectStatus "U1L1.8" )
				)
			)
			( gate "@baseboard_fab2_lib.baseboard_fab2(sch_1):page112_i108(0)"
				( objectStatus "F9" )
				( pin "A(0)"
					( objectStatus "U1L1.12" )
				)
				( pin "B(0)"
					( objectStatus "U1L1.11" )
				)
			)
			( gate "@baseboard_fab2_lib.baseboard_fab2(sch_1):page112_i109(3)"
				( objectStatus "F8" )
				( pin "A(3)"
					( objectStatus "U1L5.2" )
				)
				( pin "B(3)"
					( objectStatus "U1L5.3" )
				)
			)
			( gate "@baseboard_fab2_lib.baseboard_fab2(sch_1):page112_i109(2)"
				( objectStatus "F7" )
				( pin "A(2)"
					( objectStatus "U1L5.5" )
				)
				( pin "B(2)"
					( objectStatus "U1L5.6" )
				)
			)
			( gate "@baseboard_fab2_lib.baseboard_fab2(sch_1):page112_i109(1)"
				( objectStatus "F6" )
				( pin "A(1)"
					( objectStatus "U1L5.9" )
				)
				( pin "B(1)"
					( objectStatus "U1L5.8" )
				)
			)
			( gate "@baseboard_fab2_lib.baseboard_fab2(sch_1):page112_i109(0)"
				( objectStatus "F5" )
				( pin "A(0)"
					( objectStatus "U1L5.12" )
				)
				( pin "B(0)"
					( objectStatus "U1L5.11" )
				)
			)
			( gate "@baseboard_fab2_lib.baseboard_fab2(sch_1):page237_i81"
				( objectStatus "F364" )
			)
			( gate "@baseboard_fab2_lib.baseboard_fab2(sch_1):page199_i124"
				( objectStatus "F136" )
			)
			( gate "@baseboard_fab2_lib.baseboard_fab2(sch_1):page234_i184"
				( objectStatus "F2002" )
			)
			( gate "@baseboard_fab2_lib.baseboard_fab2(sch_1):page233_i225"
				( objectStatus "F2001" )
			)
			( gate "@baseboard_fab2_lib.baseboard_fab2(sch_1):page232_i214"
				( objectStatus "F2000" )
			)
			( gate "@baseboard_fab2_lib.baseboard_fab2(sch_1):page231_i193"
				( objectStatus "F1999" )
			)
			( gate "@baseboard_fab2_lib.baseboard_fab2(sch_1):page193_i46"
				( objectStatus "F239" )
				( pin "IOA19"
					( objectStatus "J4B2.A19" )
				)
				( pin "IOA20"
					( objectStatus "J4B2.A20" )
				)
				( pin "IOB19"
					( objectStatus "J4B2.B19" )
				)
				( pin "IOB20"
					( objectStatus "J4B2.B20" )
				)
				( pin "IOE20"
					( objectStatus "J4B2.E20" )
				)
				( pin "IOF20"
					( objectStatus "J4B2.F20" )
				)
			)
			( gate "@baseboard_fab2_lib.baseboard_fab2(sch_1):page193_i45"
				( objectStatus "F238" )
			)
			( gate "@baseboard_fab2_lib.baseboard_fab2(sch_1):page194_i56"
				( objectStatus "F237" )
				( pin "IOA18"
					( objectStatus "J6B1.A18" )
				)
				( pin "IOA19"
					( objectStatus "J6B1.A19" )
				)
				( pin "IOA20"
					( objectStatus "J6B1.A20" )
				)
				( pin "IOB18"
					( objectStatus "J6B1.B18" )
				)
				( pin "IOB19"
					( objectStatus "J6B1.B19" )
				)
				( pin "IOB20"
					( objectStatus "J6B1.B20" )
				)
				( pin "IOE20"
					( objectStatus "J6B1.E20" )
				)
				( pin "IOF20"
					( objectStatus "J6B1.F20" )
				)
			)
			( gate "@baseboard_fab2_lib.baseboard_fab2(sch_1):page194_i55"
				( objectStatus "F236" )
			)
			( gate "@baseboard_fab2_lib.baseboard_fab2(sch_1):page209_i52"
				( objectStatus "F4196" )
			)
			( gate "@baseboard_fab2_lib.baseboard_fab2(sch_1):page204_i53"
				( objectStatus "F4195" )
			)
			( gate "@baseboard_fab2_lib.baseboard_fab2(sch_1):page149_i152"
				( objectStatus "F3757" )
			)
			( gate "@baseboard_fab2_lib.baseboard_fab2(sch_1):page149_i161"
				( objectStatus "F3756" )
			)
			( gate "@baseboard_fab2_lib.baseboard_fab2(sch_1):page149_i150"
				( objectStatus "F3092" )
			)
			( gate "@baseboard_fab2_lib.baseboard_fab2(sch_1):page149_i159"
				( objectStatus "F3091" )
			)
			( gate "@baseboard_fab2_lib.baseboard_fab2(sch_1):page139_i163"
				( objectStatus "F3068" )
			)
			( gate "@baseboard_fab2_lib.baseboard_fab2(sch_1):page139_i241"
				( objectStatus "F3067" )
			)
			( gate "@baseboard_fab2_lib.baseboard_fab2(sch_1):page149_i153"
				( objectStatus "F2190" )
			)
			( gate "@baseboard_fab2_lib.baseboard_fab2(sch_1):page149_i163"
				( objectStatus "F2189" )
			)
			( gate "@baseboard_fab2_lib.baseboard_fab2(sch_1):page145_i250"
				( objectStatus "F1987" )
			)
			( gate "@baseboard_fab2_lib.baseboard_fab2(sch_1):page188_i27"
				( objectStatus "F134" )
				( pin "IO11"
					( objectStatus "J8E4.11" )
				)
				( pin "IO12"
					( objectStatus "J8E4.12" )
				)
				( pin "IO40"
					( objectStatus "J8E4.40" )
				)
				( pin "IO41"
					( objectStatus "J8E4.41" )
				)
				( pin "IO46"
					( objectStatus "J8E4.46" )
				)
				( pin "IO47"
					( objectStatus "J8E4.47" )
				)
				( pin "IO5"
					( objectStatus "J8E4.5" )
				)
				( pin "IO58"
					( objectStatus "J8E4.58" )
				)
				( pin "IO59"
					( objectStatus "J8E4.59" )
				)
				( pin "IO6"
					( objectStatus "J8E4.6" )
				)
			)
			( gate "@baseboard_fab2_lib.baseboard_fab2(sch_1):page176_i113"
				( objectStatus "F4103" )
			)
			( gate "@baseboard_fab2_lib.baseboard_fab2(sch_1):page198_i86"
				( objectStatus "F2017" )
			)
			( gate "@baseboard_fab2_lib.baseboard_fab2(sch_1):page198_i88"
				( objectStatus "F2016" )
			)
			( gate "@baseboard_fab2_lib.baseboard_fab2(sch_1):page198_i87"
				( objectStatus "F2015" )
			)
			( gate "@baseboard_fab2_lib.baseboard_fab2(sch_1):page198_i85"
				( objectStatus "F2014" )
			)
			( gate "@baseboard_fab2_lib.baseboard_fab2(sch_1):page166_i32"
				( objectStatus "F660" )
			)
			( gate "@baseboard_fab2_lib.baseboard_fab2(sch_1):page107_i417"
				( objectStatus "F4052" )
				( pin "B"
					( objectStatus "C3P10.2" )
				)
			)
			( gate "@baseboard_fab2_lib.baseboard_fab2(sch_1):page107_i415"
				( objectStatus "F4051" )
				( pin "B"
					( objectStatus "C3P12.2" )
				)
			)
			( gate "@baseboard_fab2_lib.baseboard_fab2(sch_1):page107_i431"
				( objectStatus "F4050" )
				( pin "B"
					( objectStatus "C3P14.2" )
				)
			)
			( gate "@baseboard_fab2_lib.baseboard_fab2(sch_1):page107_i422"
				( objectStatus "F4049" )
				( pin "B"
					( objectStatus "C3P16.2" )
				)
			)
			( gate "@baseboard_fab2_lib.baseboard_fab2(sch_1):page107_i427"
				( objectStatus "F4048" )
				( pin "B"
					( objectStatus "C3P19.2" )
				)
			)
			( gate "@baseboard_fab2_lib.baseboard_fab2(sch_1):page107_i423"
				( objectStatus "F4047" )
				( pin "B"
					( objectStatus "C3P21.2" )
				)
			)
			( gate "@baseboard_fab2_lib.baseboard_fab2(sch_1):page107_i435"
				( objectStatus "F4046" )
				( pin "B"
					( objectStatus "C3P22.2" )
				)
			)
			( gate "@baseboard_fab2_lib.baseboard_fab2(sch_1):page107_i424"
				( objectStatus "F4045" )
				( pin "B"
					( objectStatus "C3P24.2" )
				)
			)
			( gate "@baseboard_fab2_lib.baseboard_fab2(sch_1):page107_i444"
				( objectStatus "F4044" )
				( pin "B"
					( objectStatus "C3P26.2" )
				)
			)
			( gate "@baseboard_fab2_lib.baseboard_fab2(sch_1):page107_i437"
				( objectStatus "F4043" )
				( pin "B"
					( objectStatus "C3P29.2" )
				)
			)
			( gate "@baseboard_fab2_lib.baseboard_fab2(sch_1):page107_i452"
				( objectStatus "F4042" )
				( pin "B"
					( objectStatus "C3P31.2" )
				)
			)
			( gate "@baseboard_fab2_lib.baseboard_fab2(sch_1):page107_i439"
				( objectStatus "F4041" )
				( pin "B"
					( objectStatus "C3P33.2" )
				)
			)
			( gate "@baseboard_fab2_lib.baseboard_fab2(sch_1):page107_i447"
				( objectStatus "F4040" )
				( pin "B"
					( objectStatus "C3P34.2" )
				)
			)
			( gate "@baseboard_fab2_lib.baseboard_fab2(sch_1):page107_i438"
				( objectStatus "F4039" )
				( pin "B"
					( objectStatus "C3P36.2" )
				)
			)
			( gate "@baseboard_fab2_lib.baseboard_fab2(sch_1):page107_i455"
				( objectStatus "F4038" )
				( pin "B"
					( objectStatus "C3P38.2" )
				)
			)
			( gate "@baseboard_fab2_lib.baseboard_fab2(sch_1):page107_i448"
				( objectStatus "F4037" )
				( pin "B"
					( objectStatus "C3P41.2" )
				)
			)
			( gate "@baseboard_fab2_lib.baseboard_fab2(sch_1):page161_i32"
				( objectStatus "F2242" )
				( pin "IO3"
					( objectStatus "J1B2.3" )
				)
				( pin "IO4"
					( objectStatus "J1B2.4" )
				)
			)
			( gate "@baseboard_fab2_lib.baseboard_fab2(sch_1):page161_i1"
				( objectStatus "F2241" )
				( pin "IO3"
					( objectStatus "J1F2.3" )
				)
			)
			( gate "@baseboard_fab2_lib.baseboard_fab2(sch_1):page114_i40"
				( objectStatus "F2055" )
				( pin "CLKOUT_ITPXDPN"
					( objectStatus "U7C1.A39" )
				)
				( pin "CLKOUT_ITPXDPP"
					( objectStatus "U7C1.C39" )
				)
				( pin "CLKOUT_SRCN(0)"
					( objectStatus "U7C1.K38" )
				)
				( pin "CLKOUT_SRCN(10)"
					( objectStatus "U7C1.B23" )
				)
				( pin "CLKOUT_SRCN(11)"
					( objectStatus "U7C1.B21" )
				)
				( pin "CLKOUT_SRCN(14)"
					( objectStatus "U7C1.C20" )
				)
				( pin "CLKOUT_SRCN(15)"
					( objectStatus "U7C1.K27" )
				)
				( pin "CLKOUT_SRCN(2)"
					( objectStatus "U7C1.J33" )
				)
				( pin "CLKOUT_SRCN(3)"
					( objectStatus "U7C1.K42" )
				)
				( pin "CLKOUT_SRCN(4)"
					( objectStatus "U7C1.A28" )
				)
				( pin "CLKOUT_SRCN(5)"
					( objectStatus "U7C1.J40" )
				)
				( pin "CLKOUT_SRCN(6)"
					( objectStatus "U7C1.D33" )
				)
				( pin "CLKOUT_SRCN(7)"
					( objectStatus "U7C1.H31" )
				)
				( pin "CLKOUT_SRCN(8)"
					( objectStatus "U7C1.D31" )
				)
				( pin "CLKOUT_SRCN(9)"
					( objectStatus "U7C1.J26" )
				)
				( pin "CLKOUT_SRCP(0)"
					( objectStatus "U7C1.H38" )
				)
				( pin "CLKOUT_SRCP(10)"
					( objectStatus "U7C1.D23" )
				)
				( pin "CLKOUT_SRCP(11)"
					( objectStatus "U7C1.D21" )
				)
				( pin "CLKOUT_SRCP(14)"
					( objectStatus "U7C1.A20" )
				)
				( pin "CLKOUT_SRCP(15)"
					( objectStatus "U7C1.H27" )
				)
				( pin "CLKOUT_SRCP(2)"
					( objectStatus "U7C1.G33" )
				)
				( pin "CLKOUT_SRCP(3)"
					( objectStatus "U7C1.H42" )
				)
				( pin "CLKOUT_SRCP(4)"
					( objectStatus "U7C1.C28" )
				)
				( pin "CLKOUT_SRCP(5)"
					( objectStatus "U7C1.G40" )
				)
				( pin "CLKOUT_SRCP(6)"
					( objectStatus "U7C1.B33" )
				)
				( pin "CLKOUT_SRCP(7)"
					( objectStatus "U7C1.K31" )
				)
				( pin "CLKOUT_SRCP(8)"
					( objectStatus "U7C1.B31" )
				)
				( pin "CLKOUT_SRCP(9)"
					( objectStatus "U7C1.G26" )
				)
			)
			( gate "@baseboard_fab2_lib.baseboard_fab2(sch_1):page115_i74"
				( objectStatus "F2054" )
				( pin "USB2N_4"
					( objectStatus "U7C1.BY62" )
				)
				( pin "USB2N_5"
					( objectStatus "U7C1.BY58" )
				)
				( pin "USB2P_4"
					( objectStatus "U7C1.BV62" )
				)
				( pin "USB2P_5"
					( objectStatus "U7C1.BV58" )
				)
				( pin "USB3_1_RXN"
					( objectStatus "U7C1.BK71" )
				)
				( pin "USB3_1_RXP"
					( objectStatus "U7C1.BK69" )
				)
			)
			( gate "@baseboard_fab2_lib.baseboard_fab2(sch_1):page116_i220"
				( objectStatus "F2053" )
				( pin "PCIE10_SSATA4_RXN"
					( objectStatus "U7C1.AV63" )
				)
				( pin "PCIE10_SSATA4_RXP"
					( objectStatus "U7C1.AU65" )
				)
				( pin "PCIE10_SSATA4_TXN"
					( objectStatus "U7C1.AD70" )
				)
				( pin "PCIE10_SSATA4_TXP"
					( objectStatus "U7C1.AD72" )
				)
				( pin "PCIE11_SSATA5_GBE_RXN"
					( objectStatus "U7C1.AT66" )
				)
				( pin "PCIE11_SSATA5_GBE_RXP"
					( objectStatus "U7C1.AV66" )
				)
				( pin "PCIE11_SSATA5_GBE_TXN"
					( objectStatus "U7C1.AC69" )
				)
				( pin "PCIE11_SSATA5_GBE_TXP"
					( objectStatus "U7C1.AC71" )
				)
				( pin "PCIE12_UP0_SATA0_RXN"
					( objectStatus "U7C1.AR61" )
				)
				( pin "PCIE12_UP0_SATA0_RXP"
					( objectStatus "U7C1.AT63" )
				)
				( pin "PCIE12_UP0_SATA0_TXN"
					( objectStatus "U7C1.W69" )
				)
				( pin "PCIE12_UP0_SATA0_TXP"
					( objectStatus "U7C1.W71" )
				)
				( pin "PCIE13_UP1_SATA1_RXN"
					( objectStatus "U7C1.AL66" )
				)
				( pin "PCIE13_UP1_SATA1_RXP"
					( objectStatus "U7C1.AN65" )
				)
				( pin "PCIE13_UP1_SATA1_TXN"
					( objectStatus "U7C1.V70" )
				)
				( pin "PCIE13_UP1_SATA1_TXP"
					( objectStatus "U7C1.V72" )
				)
				( pin "PCIE14_UP2_SATA2_RXN"
					( objectStatus "U7C1.AK65" )
				)
				( pin "PCIE14_UP2_SATA2_RXP"
					( objectStatus "U7C1.AJ63" )
				)
				( pin "PCIE14_UP2_SATA2_TXN"
					( objectStatus "U7C1.T69" )
				)
				( pin "PCIE14_UP2_SATA2_TXP"
					( objectStatus "U7C1.T71" )
				)
				( pin "PCIE15_UP3_SATA3_RXN"
					( objectStatus "U7C1.AP63" )
				)
				( pin "PCIE15_UP3_SATA3_RXP"
					( objectStatus "U7C1.AL63" )
				)
				( pin "PCIE15_UP3_SATA3_TXN"
					( objectStatus "U7C1.R70" )
				)
				( pin "PCIE15_UP3_SATA3_TXP"
					( objectStatus "U7C1.R72" )
				)
				( pin "PCIE16_UP4_SATA4_RXN"
					( objectStatus "U7C1.AF65" )
				)
				( pin "PCIE16_UP4_SATA4_RXP"
					( objectStatus "U7C1.AH65" )
				)
				( pin "PCIE16_UP4_SATA4_TXN"
					( objectStatus "U7C1.P69" )
				)
				( pin "PCIE16_UP4_SATA4_TXP"
					( objectStatus "U7C1.P71" )
				)
				( pin "PCIE17_UP5_SATA5_RXN"
					( objectStatus "U7C1.AH61" )
				)
				( pin "PCIE17_UP5_SATA5_RXP"
					( objectStatus "U7C1.AG63" )
				)
				( pin "PCIE17_UP5_SATA5_TXN"
					( objectStatus "U7C1.N70" )
				)
				( pin "PCIE17_UP5_SATA5_TXP"
					( objectStatus "U7C1.N72" )
				)
				( pin "PCIE18_UP6_SATA6_RXN"
					( objectStatus "U7C1.AP59" )
				)
				( pin "PCIE18_UP6_SATA6_RXP"
					( objectStatus "U7C1.AN61" )
				)
				( pin "PCIE18_UP6_SATA6_TXN"
					( objectStatus "U7C1.M69" )
				)
				( pin "PCIE18_UP6_SATA6_TXP"
					( objectStatus "U7C1.M71" )
				)
				( pin "PCIE19_UP7_SATA7_RXN"
					( objectStatus "U7C1.AA61" )
				)
				( pin "PCIE19_UP7_SATA7_RXP"
					( objectStatus "U7C1.AD61" )
				)
				( pin "PCIE19_UP7_SATA7_TXN"
					( objectStatus "U7C1.L70" )
				)
				( pin "PCIE19_UP7_SATA7_TXP"
					( objectStatus "U7C1.L72" )
				)
				( pin "PCIE6_SSATA0_RXN"
					( objectStatus "U7C1.BB63" )
				)
				( pin "PCIE6_SSATA0_RXP"
					( objectStatus "U7C1.BD61" )
				)
				( pin "PCIE6_SSATA0_TXN"
					( objectStatus "U7C1.AJ70" )
				)
				( pin "PCIE6_SSATA0_TXP"
					( objectStatus "U7C1.AJ72" )
				)
				( pin "PCIE7_SSATA1_TXN"
					( objectStatus "U7C1.AH69" )
				)
				( pin "PCIE7_SSATA1_TXP"
					( objectStatus "U7C1.AH71" )
				)
				( pin "PCIE8_SSATA2_GBE_RXN"
					( objectStatus "U7C1.BA65" )
				)
				( pin "PCIE8_SSATA2_GBE_RXP"
					( objectStatus "U7C1.BD65" )
				)
				( pin "PCIE8_SSATA2_GBE_TXN"
					( objectStatus "U7C1.AF70" )
				)
				( pin "PCIE8_SSATA2_GBE_TXP"
					( objectStatus "U7C1.AF72" )
				)
				( pin "PCIE9_SSATA3_RXN"
					( objectStatus "U7C1.AW65" )
				)
				( pin "PCIE9_SSATA3_RXP"
					( objectStatus "U7C1.AY66" )
				)
				( pin "PCIE9_SSATA3_TXN"
					( objectStatus "U7C1.AE69" )
				)
				( pin "PCIE9_SSATA3_TXP"
					( objectStatus "U7C1.AE71" )
				)
				( pin "USB3_10_PCIE3_GBE_RXN"
					( objectStatus "U7C1.AV72" )
				)
				( pin "USB3_10_PCIE3_GBE_RXP"
					( objectStatus "U7C1.AV70" )
				)
				( pin "USB3_10_PCIE3_GBE_TXN"
					( objectStatus "U7C1.BH61" )
				)
				( pin "USB3_10_PCIE3_GBE_TXP"
					( objectStatus "U7C1.BK61" )
				)
				( pin "USB3_7_PCIE0_RXN"
					( objectStatus "U7C1.BA71" )
				)
				( pin "USB3_7_PCIE0_RXP"
					( objectStatus "U7C1.BA69" )
				)
				( pin "USB3_7_PCIE0_TXN"
					( objectStatus "U7C1.BR61" )
				)
				( pin "USB3_7_PCIE0_TXP"
					( objectStatus "U7C1.BN63" )
				)
				( pin "USB3_8_PCIE1_RXN"
					( objectStatus "U7C1.AY72" )
				)
				( pin "USB3_8_PCIE1_RXP"
					( objectStatus "U7C1.AY70" )
				)
				( pin "USB3_8_PCIE1_TXN"
					( objectStatus "U7C1.BM65" )
				)
				( pin "USB3_8_PCIE1_TXP"
					( objectStatus "U7C1.BR65" )
				)
				( pin "USB3_9_PCIE2_RXN"
					( objectStatus "U7C1.AW71" )
				)
				( pin "USB3_9_PCIE2_RXP"
					( objectStatus "U7C1.AW69" )
				)
				( pin "USB3_9_PCIE2_TXN"
					( objectStatus "U7C1.BK65" )
				)
				( pin "USB3_9_PCIE2_TXP"
					( objectStatus "U7C1.BL66" )
				)
			)
			( gate "@baseboard_fab2_lib.baseboard_fab2(sch_1):page117_i9"
				( objectStatus "F2052" )
				( pin "DMI_RXN(0)"
					( objectStatus "U7C1.D42" )
				)
				( pin "DMI_RXN(1)"
					( objectStatus "U7C1.C43" )
				)
				( pin "DMI_RXN(2)"
					( objectStatus "U7C1.D44" )
				)
				( pin "DMI_RXN(3)"
					( objectStatus "U7C1.C45" )
				)
				( pin "DMI_RXP(0)"
					( objectStatus "U7C1.B42" )
				)
				( pin "DMI_RXP(1)"
					( objectStatus "U7C1.A43" )
				)
				( pin "DMI_RXP(2)"
					( objectStatus "U7C1.B44" )
				)
				( pin "DMI_RXP(3)"
					( objectStatus "U7C1.A45" )
				)
				( pin "DMI_TXN(0)"
					( objectStatus "U7C1.H46" )
				)
				( pin "DMI_TXN(1)"
					( objectStatus "U7C1.J48" )
				)
				( pin "DMI_TXN(2)"
					( objectStatus "U7C1.K50" )
				)
				( pin "DMI_TXN(3)"
					( objectStatus "U7C1.P52" )
				)
				( pin "DMI_TXP(0)"
					( objectStatus "U7C1.K46" )
				)
				( pin "DMI_TXP(1)"
					( objectStatus "U7C1.H50" )
				)
				( pin "DMI_TXP(2)"
					( objectStatus "U7C1.M52" )
				)
				( pin "DMI_TXP(3)"
					( objectStatus "U7C1.N54" )
				)
				( pin "PCIEUP_0_RXN"
					( objectStatus "U7C1.C48" )
				)
				( pin "PCIEUP_0_RXP"
					( objectStatus "U7C1.A48" )
				)
				( pin "PCIEUP_0_TXN"
					( objectStatus "U7C1.J52" )
				)
				( pin "PCIEUP_0_TXP"
					( objectStatus "U7C1.G52" )
				)
				( pin "PCIEUP_10_RXN"
					( objectStatus "U7C1.C59" )
				)
				( pin "PCIEUP_10_RXP"
					( objectStatus "U7C1.A59" )
				)
				( pin "PCIEUP_10_TXN"
					( objectStatus "U7C1.N65" )
				)
				( pin "PCIEUP_10_TXP"
					( objectStatus "U7C1.P66" )
				)
				( pin "PCIEUP_11_RXN"
					( objectStatus "U7C1.D60" )
				)
				( pin "PCIEUP_11_RXP"
					( objectStatus "U7C1.B60" )
				)
				( pin "PCIEUP_11_TXN"
					( objectStatus "U7C1.T59" )
				)
				( pin "PCIEUP_11_TXP"
					( objectStatus "U7C1.V59" )
				)
				( pin "PCIEUP_12_RXN"
					( objectStatus "U7C1.C61" )
				)
				( pin "PCIEUP_12_RXP"
					( objectStatus "U7C1.A61" )
				)
				( pin "PCIEUP_12_TXN"
					( objectStatus "U7C1.R65" )
				)
				( pin "PCIEUP_12_TXP"
					( objectStatus "U7C1.U65" )
				)
				( pin "PCIEUP_13_RXN"
					( objectStatus "U7C1.D62" )
				)
				( pin "PCIEUP_13_RXP"
					( objectStatus "U7C1.B62" )
				)
				( pin "PCIEUP_13_TXN"
					( objectStatus "U7C1.T63" )
				)
				( pin "PCIEUP_13_TXP"
					( objectStatus "U7C1.U61" )
				)
				( pin "PCIEUP_14_RXN"
					( objectStatus "U7C1.C63" )
				)
				( pin "PCIEUP_14_RXP"
					( objectStatus "U7C1.A63" )
				)
				( pin "PCIEUP_14_TXN"
					( objectStatus "U7C1.W65" )
				)
				( pin "PCIEUP_14_TXP"
					( objectStatus "U7C1.V63" )
				)
				( pin "PCIEUP_15_RXN"
					( objectStatus "U7C1.D64" )
				)
				( pin "PCIEUP_15_RXP"
					( objectStatus "U7C1.B64" )
				)
				( pin "PCIEUP_15_TXN"
					( objectStatus "U7C1.Y66" )
				)
				( pin "PCIEUP_15_TXP"
					( objectStatus "U7C1.AA65" )
				)
				( pin "PCIEUP_1_RXN"
					( objectStatus "U7C1.D49" )
				)
				( pin "PCIEUP_1_RXP"
					( objectStatus "U7C1.B49" )
				)
				( pin "PCIEUP_1_TXN"
					( objectStatus "U7C1.P56" )
				)
				( pin "PCIEUP_1_TXP"
					( objectStatus "U7C1.M56" )
				)
				( pin "PCIEUP_2_RXN"
					( objectStatus "U7C1.C50" )
				)
				( pin "PCIEUP_2_RXP"
					( objectStatus "U7C1.A50" )
				)
				( pin "PCIEUP_2_TXN"
					( objectStatus "U7C1.H54" )
				)
				( pin "PCIEUP_2_TXP"
					( objectStatus "U7C1.G56" )
				)
				( pin "PCIEUP_3_RXN"
					( objectStatus "U7C1.D51" )
				)
				( pin "PCIEUP_3_RXP"
					( objectStatus "U7C1.B51" )
				)
				( pin "PCIEUP_3_TXN"
					( objectStatus "U7C1.J56" )
				)
				( pin "PCIEUP_3_TXP"
					( objectStatus "U7C1.K58" )
				)
				( pin "PCIEUP_4_RXN"
					( objectStatus "U7C1.C52" )
				)
				( pin "PCIEUP_4_RXP"
					( objectStatus "U7C1.A52" )
				)
				( pin "PCIEUP_4_TXN"
					( objectStatus "U7C1.N58" )
				)
				( pin "PCIEUP_4_TXP"
					( objectStatus "U7C1.M59" )
				)
				( pin "PCIEUP_5_RXN"
					( objectStatus "U7C1.D53" )
				)
				( pin "PCIEUP_5_RXP"
					( objectStatus "U7C1.B53" )
				)
				( pin "PCIEUP_5_TXN"
					( objectStatus "U7C1.N61" )
				)
				( pin "PCIEUP_5_TXP"
					( objectStatus "U7C1.K61" )
				)
				( pin "PCIEUP_6_RXN"
					( objectStatus "U7C1.C54" )
				)
				( pin "PCIEUP_6_RXP"
					( objectStatus "U7C1.A54" )
				)
				( pin "PCIEUP_6_TXN"
					( objectStatus "U7C1.H61" )
				)
				( pin "PCIEUP_6_TXP"
					( objectStatus "U7C1.J63" )
				)
				( pin "PCIEUP_7_RXN"
					( objectStatus "U7C1.D55" )
				)
				( pin "PCIEUP_7_RXP"
					( objectStatus "U7C1.B55" )
				)
				( pin "PCIEUP_7_TXN"
					( objectStatus "U7C1.P59" )
				)
				( pin "PCIEUP_7_TXP"
					( objectStatus "U7C1.R61" )
				)
				( pin "PCIEUP_8_RXN"
					( objectStatus "U7C1.C57" )
				)
				( pin "PCIEUP_8_RXP"
					( objectStatus "U7C1.A57" )
				)
				( pin "PCIEUP_8_TXN"
					( objectStatus "U7C1.K65" )
				)
				( pin "PCIEUP_8_TXP"
					( objectStatus "U7C1.M63" )
				)
				( pin "PCIEUP_9_RXN"
					( objectStatus "U7C1.D58" )
				)
				( pin "PCIEUP_9_RXP"
					( objectStatus "U7C1.B58" )
				)
				( pin "PCIEUP_9_TXN"
					( objectStatus "U7C1.J66" )
				)
				( pin "PCIEUP_9_TXP"
					( objectStatus "U7C1.M66" )
				)
			)
			( gate "@baseboard_fab2_lib.baseboard_fab2(sch_1):page118_i73"
				( objectStatus "F2051" )
				( pin "CPU_TRST_N"
					( objectStatus "U7C1.AT56" )
				)
				( pin "JTAGX"
					( objectStatus "U7C1.AF54" )
				)
				( pin "JTAG_TCK"
					( objectStatus "U7C1.AL56" )
				)
				( pin "JTAG_TDI"
					( objectStatus "U7C1.AN54" )
				)
				( pin "JTAG_TDO"
					( objectStatus "U7C1.AP56" )
				)
				( pin "JTAG_TMS"
					( objectStatus "U7C1.AH54" )
				)
				( pin "LAN_RX_P0N"
					( objectStatus "U7C1.BH31" )
				)
				( pin "LAN_RX_P0P"
					( objectStatus "U7C1.BF31" )
				)
				( pin "LAN_RX_P1N"
					( objectStatus "U7C1.BG29" )
				)
				( pin "LAN_RX_P1P"
					( objectStatus "U7C1.BJ29" )
				)
				( pin "LAN_RX_P2N"
					( objectStatus "U7C1.BJ37" )
				)
				( pin "LAN_RX_P2P"
					( objectStatus "U7C1.BG37" )
				)
				( pin "LAN_RX_P3N"
					( objectStatus "U7C1.BF35" )
				)
				( pin "LAN_RX_P3P"
					( objectStatus "U7C1.BH35" )
				)
				( pin "LAN_TX_P0N"
					( objectStatus "U7C1.BM27" )
				)
				( pin "LAN_TX_P0P"
					( objectStatus "U7C1.BR27" )
				)
				( pin "LAN_TX_P1N"
					( objectStatus "U7C1.BM24" )
				)
				( pin "LAN_TX_P1P"
					( objectStatus "U7C1.BR24" )
				)
				( pin "LAN_TX_P2N"
					( objectStatus "U7C1.BM35" )
				)
				( pin "LAN_TX_P2P"
					( objectStatus "U7C1.BR35" )
				)
				( pin "LAN_TX_P3N"
					( objectStatus "U7C1.BR31" )
				)
				( pin "LAN_TX_P3P"
					( objectStatus "U7C1.BM31" )
				)
				( pin "PECI"
					( objectStatus "U7C1.U9" )
				)
				( pin "PM_SYNC"
					( objectStatus "U7C1.U13" )
				)
				( pin "PRDY_N"
					( objectStatus "U7C1.AD54" )
				)
				( pin "PREQ_N"
					( objectStatus "U7C1.U54" )
				)
				( pin "RSMRST_N"
					( objectStatus "U7C1.P15" )
				)
			)
			( gate "@baseboard_fab2_lib.baseboard_fab2(sch_1):page119_i115"
				( objectStatus "F2050" )
				( pin "GPP_C3_SML0CLK_IE"
					( objectStatus "U7C1.BV29" )
				)
				( pin "GPP_C4_SML0DATA_IE"
					( objectStatus "U7C1.BW30" )
				)
				( pin "GPP_C6_SML1CLK_IE"
					( objectStatus "U7C1.CA28" )
				)
				( pin "GPP_C7_SML1DATA_IE"
					( objectStatus "U7C1.BV35" )
				)
				( pin "GPP_D13_SML0BCLK_IE"
					( objectStatus "U7C1.BY44" )
				)
				( pin "GPP_D14_SML0BDATA_IE"
					( objectStatus "U7C1.BL44" )
				)
			)
			( gate "@baseboard_fab2_lib.baseboard_fab2(sch_1):page120_i147"
				( objectStatus "F2049" )
				( pin "GPP_F19_LAN_SMBCLK"
					( objectStatus "U7C1.AU9" )
				)
				( pin "GPP_F20_LAN_SMBDATA"
					( objectStatus "U7C1.AU20" )
				)
				( pin "GPP_G0_FANTACH0_FANTACH0IE"
					( objectStatus "U7C1.AY11" )
				)
				( pin "GPP_G1_FANTACH1_FANTACH1IE"
					( objectStatus "U7C1.AV15" )
				)
				( pin "GPP_G2_FANTACH2_FANTACH2IE"
					( objectStatus "U7C1.BE22" )
				)
				( pin "GPP_G3_FANTACH3_FANTACH3IE"
					( objectStatus "U7C1.AY7" )
				)
				( pin "GPP_H10_SML2CLK_IE"
					( objectStatus "U7C1.BA4" )
				)
				( pin "GPP_H11_SML2DATA_IE"
					( objectStatus "U7C1.BD1" )
				)
				( pin "GPP_H13_SML3CLK_IE"
					( objectStatus "U7C1.AY1" )
				)
				( pin "GPP_H14_SML3DATA_IE"
					( objectStatus "U7C1.BC2" )
				)
				( pin "GPP_H16_SML4CLK_IE"
					( objectStatus "U7C1.BF1" )
				)
				( pin "GPP_H17_SML4DATA_IE"
					( objectStatus "U7C1.BE4" )
				)
			)
			( gate "@baseboard_fab2_lib.baseboard_fab2(sch_1):page121_i34"
				( objectStatus "F2048" )
				( pin "GPP_K1_LAN_NCSI_TXD0"
					( objectStatus "U7C1.AM2" )
				)
				( pin "GPP_K2_LAN_NCSI_TXD1"
					( objectStatus "U7C1.AK2" )
				)
				( pin "GPP_K3_LAN_NCSI_TX_EN"
					( objectStatus "U7C1.AL3" )
				)
				( pin "GPP_K4_LAN_NCSI_CRS_DV"
					( objectStatus "U7C1.AN3" )
				)
				( pin "GPP_K5_LAN_NCSI_RXD0"
					( objectStatus "U7C1.AL1" )
				)
				( pin "GPP_K6_LAN_NCSI_RXD1"
					( objectStatus "U7C1.AN1" )
				)
				( pin "SPI0_CLK"
					( objectStatus "U7C1.K2" )
				)
				( pin "SPI0_FLASH_CS0_N"
					( objectStatus "U7C1.J3" )
				)
				( pin "SPI0_IO2"
					( objectStatus "U7C1.F5" )
				)
				( pin "SPI0_IO3"
					( objectStatus "U7C1.L1" )
				)
				( pin "SPI0_MISO_IO1"
					( objectStatus "U7C1.L3" )
				)
				( pin "SPI0_MOSI_IO0"
					( objectStatus "U7C1.H4" )
				)
				( pin "SPI0_TPM_CS_N"
					( objectStatus "U7C1.K4" )
				)
			)
			( gate "@baseboard_fab2_lib.baseboard_fab2(sch_1):page122_i63"
				( objectStatus "F2047" )
			)
			( gate "@baseboard_fab2_lib.baseboard_fab2(sch_1):page123_i21"
				( objectStatus "F2046" )
			)
			( gate "@baseboard_fab2_lib.baseboard_fab2(sch_1):page123_i13"
				( objectStatus "F2045" )
			)
			( gate "@baseboard_fab2_lib.baseboard_fab2(sch_1):page124_i17"
				( objectStatus "F2044" )
			)
			( gate "@baseboard_fab2_lib.baseboard_fab2(sch_1):page124_i16"
				( objectStatus "F2043" )
			)
			( gate "@baseboard_fab2_lib.baseboard_fab2(sch_1):page124_i15"
				( objectStatus "F2042" )
			)
			( gate "@baseboard_fab2_lib.baseboard_fab2(sch_1):page134_i5"
				( objectStatus "F2258" )
				( pin "IO1"
					( objectStatus "J8G2.1" )
				)
				( pin "IO10"
					( objectStatus "J8G2.10" )
				)
				( pin "IO11"
					( objectStatus "J8G2.11" )
				)
				( pin "IO12"
					( objectStatus "J8G2.12" )
				)
				( pin "IO2"
					( objectStatus "J8G2.2" )
				)
				( pin "IO3"
					( objectStatus "J8G2.3" )
				)
				( pin "IO4"
					( objectStatus "J8G2.4" )
				)
				( pin "IO5"
					( objectStatus "J8G2.5" )
				)
				( pin "IO6"
					( objectStatus "J8G2.6" )
				)
				( pin "IO7"
					( objectStatus "J8G2.7" )
				)
				( pin "IO8"
					( objectStatus "J8G2.8" )
				)
				( pin "IO9"
					( objectStatus "J8G2.9" )
				)
			)
			( gate "@baseboard_fab2_lib.baseboard_fab2(sch_1):page136_i167"
				( objectStatus "F2257" )
				( pin "IO1"
					( objectStatus "J7G3.1" )
				)
				( pin "IO10"
					( objectStatus "J7G3.10" )
				)
				( pin "IO11"
					( objectStatus "J7G3.11" )
				)
				( pin "IO12"
					( objectStatus "J7G3.12" )
				)
				( pin "IO2"
					( objectStatus "J7G3.2" )
				)
				( pin "IO3"
					( objectStatus "J7G3.3" )
				)
				( pin "IO4"
					( objectStatus "J7G3.4" )
				)
				( pin "IO5"
					( objectStatus "J7G3.5" )
				)
				( pin "IO6"
					( objectStatus "J7G3.6" )
				)
				( pin "IO7"
					( objectStatus "J7G3.7" )
				)
				( pin "IO8"
					( objectStatus "J7G3.8" )
				)
				( pin "IO9"
					( objectStatus "J7G3.9" )
				)
			)
			( gate "@baseboard_fab2_lib.baseboard_fab2(sch_1):page137_i100"
				( objectStatus "F2256" )
				( pin "IO1"
					( objectStatus "J9G1.1" )
				)
				( pin "IO10"
					( objectStatus "J9G1.10" )
				)
				( pin "IO11"
					( objectStatus "J9G1.11" )
				)
				( pin "IO12"
					( objectStatus "J9G1.12" )
				)
				( pin "IO2"
					( objectStatus "J9G1.2" )
				)
				( pin "IO3"
					( objectStatus "J9G1.3" )
				)
				( pin "IO4"
					( objectStatus "J9G1.4" )
				)
				( pin "IO5"
					( objectStatus "J9G1.5" )
				)
				( pin "IO6"
					( objectStatus "J9G1.6" )
				)
				( pin "IO7"
					( objectStatus "J9G1.7" )
				)
				( pin "IO8"
					( objectStatus "J9G1.8" )
				)
				( pin "IO9"
					( objectStatus "J9G1.9" )
				)
			)
			( gate "@baseboard_fab2_lib.baseboard_fab2(sch_1):page177_i71"
				( objectStatus "F2035" )
			)
			( gate "@baseboard_fab2_lib.baseboard_fab2(sch_1):page199_i88"
				( objectStatus "F1157" )
			)
			( gate "@baseboard_fab2_lib.baseboard_fab2(sch_1):page199_i92"
				( objectStatus "F1156" )
			)
			( gate "@baseboard_fab2_lib.baseboard_fab2(sch_1):page199_i87"
				( objectStatus "F1155" )
			)
			( gate "@baseboard_fab2_lib.baseboard_fab2(sch_1):page199_i17"
				( objectStatus "F1154" )
			)
			( gate "@baseboard_fab2_lib.baseboard_fab2(sch_1):page199_i15"
				( objectStatus "F1153" )
			)
			( gate "@baseboard_fab2_lib.baseboard_fab2(sch_1):page199_i16"
				( objectStatus "F1152" )
			)
			( gate "@baseboard_fab2_lib.baseboard_fab2(sch_1):page155_i130"
				( objectStatus "F1151" )
			)
			( gate "@baseboard_fab2_lib.baseboard_fab2(sch_1):page147_i144"
				( objectStatus "F1150" )
			)
			( gate "@baseboard_fab2_lib.baseboard_fab2(sch_1):page147_i145"
				( objectStatus "F1149" )
			)
			( gate "@baseboard_fab2_lib.baseboard_fab2(sch_1):page147_i149"
				( objectStatus "F1148" )
			)
			( gate "@baseboard_fab2_lib.baseboard_fab2(sch_1):page147_i148"
				( objectStatus "F1147" )
			)
			( gate "@baseboard_fab2_lib.baseboard_fab2(sch_1):page144_i532"
				( objectStatus "F1146" )
			)
			( gate "@baseboard_fab2_lib.baseboard_fab2(sch_1):page116_i235"
				( objectStatus "F1145" )
			)
			( gate "@baseboard_fab2_lib.baseboard_fab2(sch_1):page116_i234"
				( objectStatus "F1144" )
			)
			( gate "@baseboard_fab2_lib.baseboard_fab2(sch_1):page198_i83"
				( objectStatus "F1143" )
			)
			( gate "@baseboard_fab2_lib.baseboard_fab2(sch_1):page145_i208"
				( objectStatus "F1142" )
			)
			( gate "@baseboard_fab2_lib.baseboard_fab2(sch_1):page145_i214"
				( objectStatus "F1141" )
			)
			( gate "@baseboard_fab2_lib.baseboard_fab2(sch_1):page145_i216"
				( objectStatus "F1140" )
			)
			( gate "@baseboard_fab2_lib.baseboard_fab2(sch_1):page145_i211"
				( objectStatus "F1139" )
			)
			( gate "@baseboard_fab2_lib.baseboard_fab2(sch_1):page145_i210"
				( objectStatus "F1138" )
			)
			( gate "@baseboard_fab2_lib.baseboard_fab2(sch_1):page145_i218"
				( objectStatus "F1137" )
			)
			( gate "@baseboard_fab2_lib.baseboard_fab2(sch_1):page169_i106"
				( objectStatus "F1136" )
			)
			( gate "@baseboard_fab2_lib.baseboard_fab2(sch_1):page199_i54"
				( objectStatus "F1135" )
			)
			( gate "@baseboard_fab2_lib.baseboard_fab2(sch_1):page199_i6"
				( objectStatus "F1134" )
			)
			( gate "@baseboard_fab2_lib.baseboard_fab2(sch_1):page199_i12"
				( objectStatus "F1133" )
			)
			( gate "@baseboard_fab2_lib.baseboard_fab2(sch_1):page196_i112"
				( objectStatus "F1132" )
			)
			( gate "@baseboard_fab2_lib.baseboard_fab2(sch_1):page200_i222"
				( objectStatus "F1131" )
			)
			( gate "@baseboard_fab2_lib.baseboard_fab2(sch_1):page200_i220"
				( objectStatus "F2218" )
			)
			( gate "@baseboard_fab2_lib.baseboard_fab2(sch_1):page211_i93"
				( objectStatus "F1976" )
				( pin "SCL"
					( objectStatus "EU3P1.7" )
				)
				( pin "SDA"
					( objectStatus "EU3P1.6" )
				)
				( pin "VALRT_N"
					( objectStatus "EU3P1.17" )
				)
				( pin "VCLK"
					( objectStatus "EU3P1.15" )
				)
				( pin "VDIO"
					( objectStatus "EU3P1.16" )
				)
			)
			( gate "@baseboard_fab2_lib.baseboard_fab2(sch_1):page213_i96"
				( objectStatus "F1975" )
				( pin "SCL"
					( objectStatus "EU4D5.7" )
				)
				( pin "SDA"
					( objectStatus "EU4D5.6" )
				)
				( pin "VALRT_N"
					( objectStatus "EU4D5.17" )
				)
				( pin "VCLK"
					( objectStatus "EU4D5.15" )
				)
				( pin "VDIO"
					( objectStatus "EU4D5.16" )
				)
			)
			( gate "@baseboard_fab2_lib.baseboard_fab2(sch_1):page235_i229"
				( objectStatus "F1974" )
				( pin "SCL"
					( objectStatus "EU8A1.7" )
				)
				( pin "SDA"
					( objectStatus "EU8A1.6" )
				)
			)
			( gate "@baseboard_fab2_lib.baseboard_fab2(sch_1):page226_i90"
				( objectStatus "F1971" )
				( pin "SCL"
					( objectStatus "EU1B1.7" )
				)
				( pin "SDA"
					( objectStatus "EU1B1.6" )
				)
				( pin "VALRT_N"
					( objectStatus "EU1B1.17" )
				)
				( pin "VCLK"
					( objectStatus "EU1B1.15" )
				)
				( pin "VDIO"
					( objectStatus "EU1B1.16" )
				)
			)
			( gate "@baseboard_fab2_lib.baseboard_fab2(sch_1):page223_i90"
				( objectStatus "F1970" )
				( pin "SCL"
					( objectStatus "EU1G2.7" )
				)
				( pin "SDA"
					( objectStatus "EU1G2.6" )
				)
				( pin "VALRT_N"
					( objectStatus "EU1G2.17" )
				)
				( pin "VCLK"
					( objectStatus "EU1G2.15" )
				)
				( pin "VDIO"
					( objectStatus "EU1G2.16" )
				)
			)
			( gate "@baseboard_fab2_lib.baseboard_fab2(sch_1):page218_i75"
				( objectStatus "F1969" )
				( pin "SCL"
					( objectStatus "EU7A5.7" )
				)
				( pin "SDA"
					( objectStatus "EU7A5.6" )
				)
				( pin "VALRT_N"
					( objectStatus "EU7A5.17" )
				)
				( pin "VCLK"
					( objectStatus "EU7A5.15" )
				)
				( pin "VDIO"
					( objectStatus "EU7A5.16" )
				)
			)
			( gate "@baseboard_fab2_lib.baseboard_fab2(sch_1):page215_i358"
				( objectStatus "F1968" )
				( pin "SCL"
					( objectStatus "EU7G1.7" )
				)
				( pin "SDA"
					( objectStatus "EU7G1.6" )
				)
				( pin "VALRT_N"
					( objectStatus "EU7G1.17" )
				)
				( pin "VCLK"
					( objectStatus "EU7G1.15" )
				)
				( pin "VDIO"
					( objectStatus "EU7G1.16" )
				)
			)
			( gate "@baseboard_fab2_lib.baseboard_fab2(sch_1):page206_i49"
				( objectStatus "F1130" )
			)
			( gate "@baseboard_fab2_lib.baseboard_fab2(sch_1):page218_i53"
				( objectStatus "F1129" )
			)
			( gate "@baseboard_fab2_lib.baseboard_fab2(sch_1):page211_i31"
				( objectStatus "F1128" )
			)
			( gate "@baseboard_fab2_lib.baseboard_fab2(sch_1):page201_i54"
				( objectStatus "F1127" )
			)
			( gate "@baseboard_fab2_lib.baseboard_fab2(sch_1):page213_i31"
				( objectStatus "F1126" )
			)
			( gate "@baseboard_fab2_lib.baseboard_fab2(sch_1):page215_i336"
				( objectStatus "F1125" )
			)
			( gate "@baseboard_fab2_lib.baseboard_fab2(sch_1):page235_i165"
				( objectStatus "F1124" )
			)
			( gate "@baseboard_fab2_lib.baseboard_fab2(sch_1):page226_i57"
				( objectStatus "F1123" )
			)
			( gate "@baseboard_fab2_lib.baseboard_fab2(sch_1):page223_i57"
				( objectStatus "F1122" )
			)
			( gate "@baseboard_fab2_lib.baseboard_fab2(sch_1):page226_i78"
				( objectStatus "F780" )
			)
			( gate "@baseboard_fab2_lib.baseboard_fab2(sch_1):page211_i52"
				( objectStatus "F779" )
			)
			( gate "@baseboard_fab2_lib.baseboard_fab2(sch_1):page213_i42"
				( objectStatus "F778" )
			)
			( gate "@baseboard_fab2_lib.baseboard_fab2(sch_1):page213_i65"
				( objectStatus "F777" )
			)
			( gate "@baseboard_fab2_lib.baseboard_fab2(sch_1):page218_i40"
				( objectStatus "F776" )
			)
			( gate "@baseboard_fab2_lib.baseboard_fab2(sch_1):page206_i111"
				( objectStatus "F775" )
			)
			( gate "@baseboard_fab2_lib.baseboard_fab2(sch_1):page193_i170"
				( objectStatus "F774" )
			)
			( gate "@baseboard_fab2_lib.baseboard_fab2(sch_1):page111_i26"
				( objectStatus "F135" )
				( pin "IO22"
					( objectStatus "J9A3.22" )
				)
				( pin "IO24"
					( objectStatus "J9A3.24" )
				)
				( pin "IO3"
					( objectStatus "J9A3.3" )
				)
				( pin "IO39"
					( objectStatus "J9A3.39" )
				)
				( pin "IO40"
					( objectStatus "J9A3.40" )
				)
				( pin "IO42"
					( objectStatus "J9A3.42" )
				)
				( pin "IO5"
					( objectStatus "J9A3.5" )
				)
				( pin "IO52"
					( objectStatus "J9A3.52" )
				)
				( pin "IO54"
					( objectStatus "J9A3.54" )
				)
				( pin "IO55"
					( objectStatus "J9A3.55" )
				)
				( pin "IO56"
					( objectStatus "J9A3.56" )
				)
				( pin "IO57"
					( objectStatus "J9A3.57" )
				)
				( pin "IO58"
					( objectStatus "J9A3.58" )
				)
				( pin "IO6"
					( objectStatus "J9A3.6" )
				)
			)
			( gate "@baseboard_fab2_lib.baseboard_fab2(sch_1):page162_i32"
				( objectStatus "F3" )
				( pin "CLK"
					( objectStatus "U8F2.16" )
				)
				( pin "CS_N"
					( objectStatus "U8F2.7" )
				)
				( pin "DI_IO(0)"
					( objectStatus "U8F2.15" )
				)
				( pin "DO_IO(1)"
					( objectStatus "U8F2.8" )
				)
			)
			( gate "@baseboard_fab2_lib.baseboard_fab2(sch_1):page206_i130"
				( objectStatus "F1973" )
				( pin "SCL"
					( objectStatus "EU1C2.9" )
				)
				( pin "SDA"
					( objectStatus "EU1C2.8" )
				)
				( pin "VALRT_N"
					( objectStatus "EU1C2.19" )
				)
				( pin "VCLK"
					( objectStatus "EU1C2.17" )
				)
				( pin "VDIO"
					( objectStatus "EU1C2.18" )
				)
			)
			( gate "@baseboard_fab2_lib.baseboard_fab2(sch_1):page201_i155"
				( objectStatus "F1972" )
				( pin "SCL"
					( objectStatus "EU4D4.9" )
				)
				( pin "SDA"
					( objectStatus "EU4D4.8" )
				)
				( pin "VALRT_N"
					( objectStatus "EU4D4.19" )
				)
				( pin "VCLK"
					( objectStatus "EU4D4.17" )
				)
				( pin "VDIO"
					( objectStatus "EU4D4.18" )
				)
			)
			( gate "@baseboard_fab2_lib.baseboard_fab2(sch_1):page196_i113"
				( objectStatus "F760" )
			)
			( gate "@baseboard_fab2_lib.baseboard_fab2(sch_1):page113_i175"
				( objectStatus "F242" )
			)
			( gate "@baseboard_fab2_lib.baseboard_fab2(sch_1):page227_i75"
				( objectStatus "F4076" )
			)
			( gate "@baseboard_fab2_lib.baseboard_fab2(sch_1):page227_i44"
				( objectStatus "F4075" )
			)
			( gate "@baseboard_fab2_lib.baseboard_fab2(sch_1):page210_i24"
				( objectStatus "F4074" )
			)
			( gate "@baseboard_fab2_lib.baseboard_fab2(sch_1):page209_i20"
				( objectStatus "F4073" )
			)
			( gate "@baseboard_fab2_lib.baseboard_fab2(sch_1):page208_i48"
				( objectStatus "F4072" )
			)
			( gate "@baseboard_fab2_lib.baseboard_fab2(sch_1):page208_i40"
				( objectStatus "F4071" )
			)
			( gate "@baseboard_fab2_lib.baseboard_fab2(sch_1):page224_i75"
				( objectStatus "F4068" )
			)
			( gate "@baseboard_fab2_lib.baseboard_fab2(sch_1):page224_i44"
				( objectStatus "F4067" )
			)
			( gate "@baseboard_fab2_lib.baseboard_fab2(sch_1):page205_i25"
				( objectStatus "F4066" )
			)
			( gate "@baseboard_fab2_lib.baseboard_fab2(sch_1):page204_i22"
				( objectStatus "F4065" )
			)
			( gate "@baseboard_fab2_lib.baseboard_fab2(sch_1):page203_i3"
				( objectStatus "F4064" )
			)
			( gate "@baseboard_fab2_lib.baseboard_fab2(sch_1):page203_i42"
				( objectStatus "F4063" )
			)
			( gate "@baseboard_fab2_lib.baseboard_fab2(sch_1):page202_i32"
				( objectStatus "F4062" )
			)
			( gate "@baseboard_fab2_lib.baseboard_fab2(sch_1):page202_i22"
				( objectStatus "F4061" )
			)
			( gate "@baseboard_fab2_lib.baseboard_fab2(sch_1):page214_i78"
				( objectStatus "F4060" )
			)
			( gate "@baseboard_fab2_lib.baseboard_fab2(sch_1):page236_i21"
				( objectStatus "F4059" )
			)
			( gate "@baseboard_fab2_lib.baseboard_fab2(sch_1):page236_i34"
				( objectStatus "F4058" )
			)
			( gate "@baseboard_fab2_lib.baseboard_fab2(sch_1):page219_i44"
				( objectStatus "F4057" )
			)
			( gate "@baseboard_fab2_lib.baseboard_fab2(sch_1):page219_i75"
				( objectStatus "F4056" )
			)
			( gate "@baseboard_fab2_lib.baseboard_fab2(sch_1):page212_i37"
				( objectStatus "F4055" )
			)
			( gate "@baseboard_fab2_lib.baseboard_fab2(sch_1):page216_i44"
				( objectStatus "F4054" )
			)
			( gate "@baseboard_fab2_lib.baseboard_fab2(sch_1):page216_i75"
				( objectStatus "F4053" )
			)
			( gate "@baseboard_fab2_lib.baseboard_fab2(sch_1):page207_i38"
				( objectStatus "F4070" )
			)
			( gate "@baseboard_fab2_lib.baseboard_fab2(sch_1):page207_i30"
				( objectStatus "F4069" )
			)
			( gate "@baseboard_fab2_lib.baseboard_fab2(sch_1):page172_i17"
				( objectStatus "F2237" )
				( pin "SATA_TXN"
					( objectStatus "J8A3.3" )
				)
				( pin "SATA_TXP"
					( objectStatus "J8A3.2" )
				)
			)
			( gate "@baseboard_fab2_lib.baseboard_fab2(sch_1):page172_i52"
				( objectStatus "F2236" )
			)
			( gate "@baseboard_fab2_lib.baseboard_fab2(sch_1):page214_i126"
				( objectStatus "F2060" )
			)
			( gate "@baseboard_fab2_lib.baseboard_fab2(sch_1):page236_i117"
				( objectStatus "F2059" )
			)
			( gate "@baseboard_fab2_lib.baseboard_fab2(sch_1):page236_i116"
				( objectStatus "F2058" )
			)
			( gate "@baseboard_fab2_lib.baseboard_fab2(sch_1):page212_i101"
				( objectStatus "F2057" )
			)
			( gate "@baseboard_fab2_lib.baseboard_fab2(sch_1):page210_i51"
				( objectStatus "F2062" )
			)
			( gate "@baseboard_fab2_lib.baseboard_fab2(sch_1):page205_i46"
				( objectStatus "F2061" )
			)
			( gate "@baseboard_fab2_lib.baseboard_fab2(sch_1):page37_i312"
				( objectStatus "F1334" )
			)
			( gate "@baseboard_fab2_lib.baseboard_fab2(sch_1):page71_i53"
				( objectStatus "F1333" )
			)
			( gate "@baseboard_fab2_lib.baseboard_fab2(sch_1):page205_i62"
				( objectStatus "F333" )
			)
			( gate "@baseboard_fab2_lib.baseboard_fab2(sch_1):page202_i67"
				( objectStatus "F332" )
			)
			( gate "@baseboard_fab2_lib.baseboard_fab2(sch_1):page202_i65"
				( objectStatus "F331" )
			)
			( gate "@baseboard_fab2_lib.baseboard_fab2(sch_1):page203_i89"
				( objectStatus "F330" )
			)
			( gate "@baseboard_fab2_lib.baseboard_fab2(sch_1):page203_i91"
				( objectStatus "F329" )
			)
			( gate "@baseboard_fab2_lib.baseboard_fab2(sch_1):page204_i83"
				( objectStatus "F328" )
			)
			( gate "@baseboard_fab2_lib.baseboard_fab2(sch_1):page212_i103"
				( objectStatus "F327" )
			)
			( gate "@baseboard_fab2_lib.baseboard_fab2(sch_1):page214_i127"
				( objectStatus "F326" )
			)
			( gate "@baseboard_fab2_lib.baseboard_fab2(sch_1):page216_i104"
				( objectStatus "F325" )
			)
			( gate "@baseboard_fab2_lib.baseboard_fab2(sch_1):page216_i106"
				( objectStatus "F324" )
			)
			( gate "@baseboard_fab2_lib.baseboard_fab2(sch_1):page219_i108"
				( objectStatus "F323" )
			)
			( gate "@baseboard_fab2_lib.baseboard_fab2(sch_1):page219_i110"
				( objectStatus "F322" )
			)
			( gate "@baseboard_fab2_lib.baseboard_fab2(sch_1):page224_i112"
				( objectStatus "F321" )
			)
			( gate "@baseboard_fab2_lib.baseboard_fab2(sch_1):page224_i114"
				( objectStatus "F320" )
			)
			( gate "@baseboard_fab2_lib.baseboard_fab2(sch_1):page227_i105"
				( objectStatus "F319" )
			)
			( gate "@baseboard_fab2_lib.baseboard_fab2(sch_1):page227_i103"
				( objectStatus "F318" )
			)
			( gate "@baseboard_fab2_lib.baseboard_fab2(sch_1):page236_i118"
				( objectStatus "F317" )
			)
			( gate "@baseboard_fab2_lib.baseboard_fab2(sch_1):page236_i120"
				( objectStatus "F316" )
			)
			( gate "@baseboard_fab2_lib.baseboard_fab2(sch_1):page207_i67"
				( objectStatus "F339" )
			)
			( gate "@baseboard_fab2_lib.baseboard_fab2(sch_1):page207_i68"
				( objectStatus "F338" )
			)
			( gate "@baseboard_fab2_lib.baseboard_fab2(sch_1):page208_i76"
				( objectStatus "F337" )
			)
			( gate "@baseboard_fab2_lib.baseboard_fab2(sch_1):page208_i75"
				( objectStatus "F336" )
			)
			( gate "@baseboard_fab2_lib.baseboard_fab2(sch_1):page209_i59"
				( objectStatus "F335" )
			)
			( gate "@baseboard_fab2_lib.baseboard_fab2(sch_1):page210_i52"
				( objectStatus "F334" )
			)
			( gate "@baseboard_fab2_lib.baseboard_fab2(sch_1):page37_i309"
				( objectStatus "F273" )
			)
			( gate "@baseboard_fab2_lib.baseboard_fab2(sch_1):page71_i49"
				( objectStatus "F272" )
			)
			( gate "@baseboard_fab2_lib.baseboard_fab2(sch_1):page227_i102"
				( objectStatus "F2080" )
			)
			( gate "@baseboard_fab2_lib.baseboard_fab2(sch_1):page227_i101"
				( objectStatus "F2079" )
			)
			( gate "@baseboard_fab2_lib.baseboard_fab2(sch_1):page224_i111"
				( objectStatus "F2073" )
			)
			( gate "@baseboard_fab2_lib.baseboard_fab2(sch_1):page224_i110"
				( objectStatus "F2072" )
			)
			( gate "@baseboard_fab2_lib.baseboard_fab2(sch_1):page219_i106"
				( objectStatus "F2066" )
			)
			( gate "@baseboard_fab2_lib.baseboard_fab2(sch_1):page219_i107"
				( objectStatus "F2065" )
			)
			( gate "@baseboard_fab2_lib.baseboard_fab2(sch_1):page216_i102"
				( objectStatus "F2064" )
			)
			( gate "@baseboard_fab2_lib.baseboard_fab2(sch_1):page216_i103"
				( objectStatus "F2063" )
			)
			( gate "@baseboard_fab2_lib.baseboard_fab2(sch_1):page202_i64"
				( objectStatus "F2068" )
			)
			( gate "@baseboard_fab2_lib.baseboard_fab2(sch_1):page209_i56"
				( objectStatus "F2078" )
			)
			( gate "@baseboard_fab2_lib.baseboard_fab2(sch_1):page208_i71"
				( objectStatus "F2077" )
			)
			( gate "@baseboard_fab2_lib.baseboard_fab2(sch_1):page203_i70"
				( objectStatus "F2069" )
			)
			( gate "@baseboard_fab2_lib.baseboard_fab2(sch_1):page203_i71"
				( objectStatus "F2070" )
			)
			( gate "@baseboard_fab2_lib.baseboard_fab2(sch_1):page204_i71"
				( objectStatus "F2071" )
			)
			( gate "@baseboard_fab2_lib.baseboard_fab2(sch_1):page202_i63"
				( objectStatus "F2067" )
			)
			( gate "@baseboard_fab2_lib.baseboard_fab2(sch_1):page208_i27"
				( objectStatus "F2076" )
			)
			( gate "@baseboard_fab2_lib.baseboard_fab2(sch_1):page207_i24"
				( objectStatus "F2075" )
			)
			( gate "@baseboard_fab2_lib.baseboard_fab2(sch_1):page207_i20"
				( objectStatus "F2074" )
			)
			( gate "@baseboard_fab2_lib.baseboard_fab2(sch_1):page104_i72"
				( objectStatus "F1989" )
			)
			( gate "@baseboard_fab2_lib.baseboard_fab2(sch_1):page104_i71"
				( objectStatus "F1988" )
			)
			( gate "@baseboard_fab2_lib.baseboard_fab2(sch_1):page170_i12"
				( objectStatus "F45" )
			)
			( gate "@baseboard_fab2_lib.baseboard_fab2(sch_1):page181_i243"
				( objectStatus "F44" )
			)
			( gate "@baseboard_fab2_lib.baseboard_fab2(sch_1):page170_i11"
				( objectStatus "F43" )
			)
			( gate "@baseboard_fab2_lib.baseboard_fab2(sch_1):page170_i10"
				( objectStatus "F42" )
			)
			( gate "@baseboard_fab2_lib.baseboard_fab2(sch_1):page161_i121"
				( objectStatus "F32" )
			)
			( gate "@baseboard_fab2_lib.baseboard_fab2(sch_1):page95_i117"
				( objectStatus "F31" )
			)
			( gate "@baseboard_fab2_lib.baseboard_fab2(sch_1):page95_i118"
				( objectStatus "F30" )
			)
			( gate "@baseboard_fab2_lib.baseboard_fab2(sch_1):page177_i70"
				( objectStatus "F29" )
			)
			( gate "@baseboard_fab2_lib.baseboard_fab2(sch_1):page200_i103"
				( objectStatus "F28" )
			)
			( gate "@baseboard_fab2_lib.baseboard_fab2(sch_1):page170_i20"
				( objectStatus "F27" )
			)
			( gate "@baseboard_fab2_lib.baseboard_fab2(sch_1):page170_i38"
				( objectStatus "F26" )
			)
			( gate "@baseboard_fab2_lib.baseboard_fab2(sch_1):page136_i130"
				( objectStatus "F25" )
			)
			( gate "@baseboard_fab2_lib.baseboard_fab2(sch_1):page142_i1"
				( objectStatus "F24" )
			)
			( gate "@baseboard_fab2_lib.baseboard_fab2(sch_1):page125_i60"
				( objectStatus "F292" )
			)
			( gate "@baseboard_fab2_lib.baseboard_fab2(sch_1):page110_i54"
				( objectStatus "F60" )
			)
			( gate "@baseboard_fab2_lib.baseboard_fab2(sch_1):page110_i58"
				( objectStatus "F59" )
			)
			( gate "@baseboard_fab2_lib.baseboard_fab2(sch_1):page110_i62"
				( objectStatus "F58" )
			)
			( gate "@baseboard_fab2_lib.baseboard_fab2(sch_1):page110_i16"
				( objectStatus "F57" )
			)
			( gate "@baseboard_fab2_lib.baseboard_fab2(sch_1):page110_i18"
				( objectStatus "F56" )
			)
			( gate "@baseboard_fab2_lib.baseboard_fab2(sch_1):page110_i22"
				( objectStatus "F55" )
			)
			( gate "@baseboard_fab2_lib.baseboard_fab2(sch_1):page110_i24"
				( objectStatus "F54" )
			)
			( gate "@baseboard_fab2_lib.baseboard_fab2(sch_1):page110_i53"
				( objectStatus "F53" )
			)
			( gate "@baseboard_fab2_lib.baseboard_fab2(sch_1):page110_i66"
				( objectStatus "F52" )
			)
			( gate "@baseboard_fab2_lib.baseboard_fab2(sch_1):page139_i237"
				( objectStatus "F281" )
			)
			( gate "@baseboard_fab2_lib.baseboard_fab2(sch_1):page139_i238"
				( objectStatus "F280" )
			)
			( gate "@baseboard_fab2_lib.baseboard_fab2(sch_1):page139_i239"
				( objectStatus "F279" )
			)
			( gate "@baseboard_fab2_lib.baseboard_fab2(sch_1):page139_i240"
				( objectStatus "F278" )
			)
			( gate "@baseboard_fab2_lib.baseboard_fab2(sch_1):page141_i109"
				( objectStatus "F2252" )
				( pin "TRD1N"
					( objectStatus "JA9G1.R10" )
				)
				( pin "TRD1P"
					( objectStatus "JA9G1.R11" )
				)
				( pin "TRD2N"
					( objectStatus "JA9G1.R5" )
				)
				( pin "TRD2P"
					( objectStatus "JA9G1.R4" )
				)
			)
			( gate "@baseboard_fab2_lib.baseboard_fab2(sch_1):page196_i80"
				( objectStatus "F4194" )
			)
			( gate "@baseboard_fab2_lib.baseboard_fab2(sch_1):page196_i89"
				( objectStatus "F4193" )
			)
			( gate "@baseboard_fab2_lib.baseboard_fab2(sch_1):page163_i1"
				( objectStatus "F1986" )
				( pin "SDAB"
					( objectStatus "U1B2.6" )
				)
			)
			( gate "@baseboard_fab2_lib.baseboard_fab2(sch_1):page99_i75"
				( objectStatus "F1985" )
				( pin "SCLA"
					( objectStatus "U3B1.2" )
				)
				( pin "SCLB"
					( objectStatus "U3B1.7" )
				)
				( pin "SDAB"
					( objectStatus "U3B1.6" )
				)
			)
			( gate "@baseboard_fab2_lib.baseboard_fab2(sch_1):page99_i63"
				( objectStatus "F1984" )
				( pin "SCLA"
					( objectStatus "U4G1.2" )
				)
				( pin "SCLB"
					( objectStatus "U4G1.7" )
				)
				( pin "SDAA"
					( objectStatus "U4G1.3" )
				)
				( pin "SDAB"
					( objectStatus "U4G1.6" )
				)
			)
			( gate "@baseboard_fab2_lib.baseboard_fab2(sch_1):page99_i15"
				( objectStatus "F1983" )
				( pin "SCLA"
					( objectStatus "U6F1.2" )
				)
				( pin "SCLB"
					( objectStatus "U6F1.7" )
				)
				( pin "SDAA"
					( objectStatus "U6F1.3" )
				)
				( pin "SDAB"
					( objectStatus "U6F1.6" )
				)
			)
			( gate "@baseboard_fab2_lib.baseboard_fab2(sch_1):page99_i61"
				( objectStatus "F1982" )
				( pin "SCLA"
					( objectStatus "U7E1.2" )
				)
				( pin "SCLB"
					( objectStatus "U7E1.7" )
				)
				( pin "SDAA"
					( objectStatus "U7E1.3" )
				)
				( pin "SDAB"
					( objectStatus "U7E1.6" )
				)
			)
			( gate "@baseboard_fab2_lib.baseboard_fab2(sch_1):page154_i75"
				( objectStatus "F1981" )
				( pin "IA0"
					( objectStatus "U2T1.2" )
				)
				( pin "IB0"
					( objectStatus "U2T1.5" )
				)
				( pin "YB"
					( objectStatus "U2T1.7" )
				)
			)
			( gate "@baseboard_fab2_lib.baseboard_fab2(sch_1):page154_i74"
				( objectStatus "F1980" )
				( pin "IA0"
					( objectStatus "U8F1.2" )
				)
				( pin "IA1"
					( objectStatus "U8F1.3" )
				)
				( pin "IB0"
					( objectStatus "U8F1.5" )
				)
				( pin "IB1"
					( objectStatus "U8F1.6" )
				)
				( pin "IC0"
					( objectStatus "U8F1.11" )
				)
				( pin "IC1"
					( objectStatus "U8F1.10" )
				)
				( pin "ID0"
					( objectStatus "U8F1.14" )
				)
				( pin "ID1"
					( objectStatus "U8F1.13" )
				)
				( pin "YA"
					( objectStatus "U8F1.4" )
				)
				( pin "YB"
					( objectStatus "U8F1.7" )
				)
				( pin "YC"
					( objectStatus "U8F1.9" )
				)
				( pin "YD"
					( objectStatus "U8F1.12" )
				)
			)
			( gate "@baseboard_fab2_lib.baseboard_fab2(sch_1):page94_i104"
				( objectStatus "F758" )
			)
			( gate "@baseboard_fab2_lib.baseboard_fab2(sch_1):page181_i111"
				( objectStatus "F2238" )
				( pin "GNDA2"
					( objectStatus "J1F1.A2" )
				)
				( pin "GNDA4"
					( objectStatus "J1F1.A4" )
				)
				( pin "GNDA6"
					( objectStatus "J1F1.A6" )
				)
				( pin "GNDA8"
					( objectStatus "J1F1.A8" )
				)
				( pin "GNDC1"
					( objectStatus "J1F1.C1" )
				)
				( pin "GNDC3"
					( objectStatus "J1F1.C3" )
				)
				( pin "GNDC5"
					( objectStatus "J1F1.C5" )
				)
				( pin "GNDC7"
					( objectStatus "J1F1.C7" )
				)
				( pin "GNDD2"
					( objectStatus "J1F1.D2" )
				)
				( pin "GNDD4"
					( objectStatus "J1F1.D4" )
				)
				( pin "GNDD6"
					( objectStatus "J1F1.D6" )
				)
				( pin "GNDD8"
					( objectStatus "J1F1.D8" )
				)
				( pin "GNDF1"
					( objectStatus "J1F1.F1" )
				)
				( pin "GNDF3"
					( objectStatus "J1F1.F3" )
				)
				( pin "GNDF5"
					( objectStatus "J1F1.F5" )
				)
				( pin "GNDF7"
					( objectStatus "J1F1.F7" )
				)
				( pin "GNDG2"
					( objectStatus "J1F1.G2" )
				)
				( pin "GNDG4"
					( objectStatus "J1F1.G4" )
				)
				( pin "GNDG6"
					( objectStatus "J1F1.G6" )
				)
				( pin "GNDG8"
					( objectStatus "J1F1.G8" )
				)
				( pin "GNDI1"
					( objectStatus "J1F1.I1" )
				)
				( pin "GNDI3"
					( objectStatus "J1F1.I3" )
				)
				( pin "GNDI5"
					( objectStatus "J1F1.I5" )
				)
				( pin "GNDI7"
					( objectStatus "J1F1.I7" )
				)
				( pin "GNDJ2"
					( objectStatus "J1F1.J2" )
				)
				( pin "GNDJ4"
					( objectStatus "J1F1.J4" )
				)
				( pin "GNDJ6"
					( objectStatus "J1F1.J6" )
				)
				( pin "GNDJ8"
					( objectStatus "J1F1.J8" )
				)
				( pin "IOA1"
					( attribute "PIN_DELAY" "313.89 MIL"
						( Units "uTimeLength" "mil" 1.000000)
						( Origin gBackEnd )
					)
					( objectStatus "J1F1.A1" )
				)
				( pin "IOA3"
					( attribute "PIN_DELAY" "313.89 MIL"
						( Units "uTimeLength" "mil" 1.000000)
						( Origin gBackEnd )
					)
					( objectStatus "J1F1.A3" )
				)
				( pin "IOA5"
					( attribute "PIN_DELAY" "313.89 MIL"
						( Units "uTimeLength" "mil" 1.000000)
						( Origin gBackEnd )
					)
					( objectStatus "J1F1.A5" )
				)
				( pin "IOA7"
					( attribute "PIN_DELAY" "313.89 MIL"
						( Units "uTimeLength" "mil" 1.000000)
						( Origin gBackEnd )
					)
					( objectStatus "J1F1.A7" )
				)
				( pin "IOB1"
					( attribute "PIN_DELAY" "341.67 MIL"
						( Units "uTimeLength" "mil" 1.000000)
						( Origin gBackEnd )
					)
					( objectStatus "J1F1.B1" )
				)
				( pin "IOB2"
					( attribute "PIN_DELAY" "352.78 MIL"
						( Units "uTimeLength" "mil" 1.000000)
						( Origin gBackEnd )
					)
					( objectStatus "J1F1.B2" )
				)
				( pin "IOB3"
					( attribute "PIN_DELAY" "341.67 MIL"
						( Units "uTimeLength" "mil" 1.000000)
						( Origin gBackEnd )
					)
					( objectStatus "J1F1.B3" )
				)
				( pin "IOB4"
					( objectStatus "J1F1.B4" )
				)
				( pin "IOB5"
					( attribute "PIN_DELAY" "341.67 MIL"
						( Units "uTimeLength" "mil" 1.000000)
						( Origin gBackEnd )
					)
					( objectStatus "J1F1.B5" )
				)
				( pin "IOB6"
					( attribute "PIN_DELAY" "352.78 MIL"
						( Units "uTimeLength" "mil" 1.000000)
						( Origin gBackEnd )
					)
					( objectStatus "J1F1.B6" )
				)
				( pin "IOB7"
					( attribute "PIN_DELAY" "341.67 MIL"
						( Units "uTimeLength" "mil" 1.000000)
						( Origin gBackEnd )
					)
					( objectStatus "J1F1.B7" )
				)
				( pin "IOB8"
					( attribute "PIN_DELAY" "352.78 MIL"
						( Units "uTimeLength" "mil" 1.000000)
						( Origin gBackEnd )
					)
					( objectStatus "J1F1.B8" )
				)
				( pin "IOC2"
					( attribute "PIN_DELAY" "383.33 MIL"
						( Units "uTimeLength" "mil" 1.000000)
						( Origin gBackEnd )
					)
					( objectStatus "J1F1.C2" )
				)
				( pin "IOC4"
					( objectStatus "J1F1.C4" )
				)
				( pin "IOC6"
					( attribute "PIN_DELAY" "383.33 MIL"
						( Units "uTimeLength" "mil" 1.000000)
						( Origin gBackEnd )
					)
					( objectStatus "J1F1.C6" )
				)
				( pin "IOC8"
					( attribute "PIN_DELAY" "383.33 MIL"
						( Units "uTimeLength" "mil" 1.000000)
						( Origin gBackEnd )
					)
					( objectStatus "J1F1.C8" )
				)
				( pin "IOD1"
					( attribute "PIN_DELAY" "452.78 MIL"
						( Units "uTimeLength" "mil" 1.000000)
						( Origin gBackEnd )
					)
					( objectStatus "J1F1.D1" )
				)
				( pin "IOD3"
					( attribute "PIN_DELAY" "452.78 MIL"
						( Units "uTimeLength" "mil" 1.000000)
						( Origin gBackEnd )
					)
					( objectStatus "J1F1.D3" )
				)
				( pin "IOD5"
					( attribute "PIN_DELAY" "452.78 MIL"
						( Units "uTimeLength" "mil" 1.000000)
						( Origin gBackEnd )
					)
					( objectStatus "J1F1.D5" )
				)
				( pin "IOD7"
					( attribute "PIN_DELAY" "452.78 MIL"
						( Units "uTimeLength" "mil" 1.000000)
						( Origin gBackEnd )
					)
					( objectStatus "J1F1.D7" )
				)
				( pin "IOE1"
					( attribute "PIN_DELAY" "475.00 MIL"
						( Units "uTimeLength" "mil" 1.000000)
						( Origin gBackEnd )
					)
					( objectStatus "J1F1.E1" )
				)
				( pin "IOE2"
					( attribute "PIN_DELAY" "505.56 MIL"
						( Units "uTimeLength" "mil" 1.000000)
						( Origin gBackEnd )
					)
					( objectStatus "J1F1.E2" )
				)
				( pin "IOE3"
					( attribute "PIN_DELAY" "475.00 MIL"
						( Units "uTimeLength" "mil" 1.000000)
						( Origin gBackEnd )
					)
					( objectStatus "J1F1.E3" )
				)
				( pin "IOE4"
					( objectStatus "J1F1.E4" )
				)
				( pin "IOE5"
					( attribute "PIN_DELAY" "475.00 MIL"
						( Units "uTimeLength" "mil" 1.000000)
						( Origin gBackEnd )
					)
					( objectStatus "J1F1.E5" )
				)
				( pin "IOE6"
					( attribute "PIN_DELAY" "505.56 MIL"
						( Units "uTimeLength" "mil" 1.000000)
						( Origin gBackEnd )
					)
					( objectStatus "J1F1.E6" )
				)
				( pin "IOE7"
					( attribute "PIN_DELAY" "475.00 MIL"
						( Units "uTimeLength" "mil" 1.000000)
						( Origin gBackEnd )
					)
					( objectStatus "J1F1.E7" )
				)
				( pin "IOE8"
					( attribute "PIN_DELAY" "505.56 MIL"
						( Units "uTimeLength" "mil" 1.000000)
						( Origin gBackEnd )
					)
					( objectStatus "J1F1.E8" )
				)
				( pin "IOF2"
					( attribute "PIN_DELAY" "522.22 MIL"
						( Units "uTimeLength" "mil" 1.000000)
						( Origin gBackEnd )
					)
					( objectStatus "J1F1.F2" )
				)
				( pin "IOF4"
					( objectStatus "J1F1.F4" )
				)
				( pin "IOF6"
					( attribute "PIN_DELAY" "522.22 MIL"
						( Units "uTimeLength" "mil" 1.000000)
						( Origin gBackEnd )
					)
					( objectStatus "J1F1.F6" )
				)
				( pin "IOF8"
					( attribute "PIN_DELAY" "522.22 MIL"
						( Units "uTimeLength" "mil" 1.000000)
						( Origin gBackEnd )
					)
					( objectStatus "J1F1.F8" )
				)
				( pin "IOG1"
					( attribute "PIN_DELAY" "519.44 MIL"
						( Units "uTimeLength" "mil" 1.000000)
						( Origin gBackEnd )
					)
					( objectStatus "J1F1.G1" )
				)
				( pin "IOG3"
					( objectStatus "J1F1.G3" )
				)
				( pin "IOG5"
					( attribute "PIN_DELAY" "519.44 MIL"
						( Units "uTimeLength" "mil" 1.000000)
						( Origin gBackEnd )
					)
					( objectStatus "J1F1.G5" )
				)
				( pin "IOG7"
					( attribute "PIN_DELAY" "519.44 MIL"
						( Units "uTimeLength" "mil" 1.000000)
						( Origin gBackEnd )
					)
					( objectStatus "J1F1.G7" )
				)
				( pin "IOH1"
					( attribute "PIN_DELAY" "538.89 MIL"
						( Units "uTimeLength" "mil" 1.000000)
						( Origin gBackEnd )
					)
					( objectStatus "J1F1.H1" )
				)
				( pin "IOH2"
					( attribute "PIN_DELAY" "561.11 MIL"
						( Units "uTimeLength" "mil" 1.000000)
						( Origin gBackEnd )
					)
					( objectStatus "J1F1.H2" )
				)
				( pin "IOH3"
					( objectStatus "J1F1.H3" )
				)
				( pin "IOH4"
					( objectStatus "J1F1.H4" )
				)
				( pin "IOH5"
					( attribute "PIN_DELAY" "538.89 MIL"
						( Units "uTimeLength" "mil" 1.000000)
						( Origin gBackEnd )
					)
					( objectStatus "J1F1.H5" )
				)
				( pin "IOH6"
					( attribute "PIN_DELAY" "561.11 MIL"
						( Units "uTimeLength" "mil" 1.000000)
						( Origin gBackEnd )
					)
					( objectStatus "J1F1.H6" )
				)
				( pin "IOH7"
					( attribute "PIN_DELAY" "538.89 MIL"
						( Units "uTimeLength" "mil" 1.000000)
						( Origin gBackEnd )
					)
					( objectStatus "J1F1.H7" )
				)
				( pin "IOH8"
					( attribute "PIN_DELAY" "561.11 MIL"
						( Units "uTimeLength" "mil" 1.000000)
						( Origin gBackEnd )
					)
					( objectStatus "J1F1.H8" )
				)
				( pin "IOI2"
					( attribute "PIN_DELAY" "600.00 MIL"
						( Units "uTimeLength" "mil" 1.000000)
						( Origin gBackEnd )
					)
					( objectStatus "J1F1.I2" )
				)
				( pin "IOI4"
					( objectStatus "J1F1.I4" )
				)
				( pin "IOI6"
					( attribute "PIN_DELAY" "600.00 MIL"
						( Units "uTimeLength" "mil" 1.000000)
						( Origin gBackEnd )
					)
					( objectStatus "J1F1.I6" )
				)
				( pin "IOI8"
					( attribute "PIN_DELAY" "600.00 MIL"
						( Units "uTimeLength" "mil" 1.000000)
						( Origin gBackEnd )
					)
					( objectStatus "J1F1.I8" )
				)
			)
			( gate "@baseboard_fab2_lib.baseboard_fab2(sch_1):page182_i18"
				( objectStatus "F2239" )
				( pin "GNDA2"
					( attribute "PIN_DELAY" "0.00 MIL"
						( Units "uTimeLength" "mil" 1.000000)
						( Origin gBackEnd )
					)
					( objectStatus "J1C1.A2" )
				)
				( pin "GNDA4"
					( attribute "PIN_DELAY" "0.00 MIL"
						( Units "uTimeLength" "mil" 1.000000)
						( Origin gBackEnd )
					)
					( objectStatus "J1C1.A4" )
				)
				( pin "GNDA6"
					( attribute "PIN_DELAY" "0.00 MIL"
						( Units "uTimeLength" "mil" 1.000000)
						( Origin gBackEnd )
					)
					( objectStatus "J1C1.A6" )
				)
				( pin "GNDA8"
					( attribute "PIN_DELAY" "0.00 MIL"
						( Units "uTimeLength" "mil" 1.000000)
						( Origin gBackEnd )
					)
					( objectStatus "J1C1.A8" )
				)
				( pin "GNDC1"
					( attribute "PIN_DELAY" "0.00 MIL"
						( Units "uTimeLength" "mil" 1.000000)
						( Origin gBackEnd )
					)
					( objectStatus "J1C1.C1" )
				)
				( pin "GNDC3"
					( attribute "PIN_DELAY" "0.00 MIL"
						( Units "uTimeLength" "mil" 1.000000)
						( Origin gBackEnd )
					)
					( objectStatus "J1C1.C3" )
				)
				( pin "GNDC5"
					( attribute "PIN_DELAY" "0.00 MIL"
						( Units "uTimeLength" "mil" 1.000000)
						( Origin gBackEnd )
					)
					( objectStatus "J1C1.C5" )
				)
				( pin "GNDC7"
					( attribute "PIN_DELAY" "0.00 MIL"
						( Units "uTimeLength" "mil" 1.000000)
						( Origin gBackEnd )
					)
					( objectStatus "J1C1.C7" )
				)
				( pin "GNDD2"
					( attribute "PIN_DELAY" "0.00 MIL"
						( Units "uTimeLength" "mil" 1.000000)
						( Origin gBackEnd )
					)
					( objectStatus "J1C1.D2" )
				)
				( pin "GNDD4"
					( attribute "PIN_DELAY" "0.00 MIL"
						( Units "uTimeLength" "mil" 1.000000)
						( Origin gBackEnd )
					)
					( objectStatus "J1C1.D4" )
				)
				( pin "GNDD6"
					( attribute "PIN_DELAY" "0.00 MIL"
						( Units "uTimeLength" "mil" 1.000000)
						( Origin gBackEnd )
					)
					( objectStatus "J1C1.D6" )
				)
				( pin "GNDD8"
					( attribute "PIN_DELAY" "0.00 MIL"
						( Units "uTimeLength" "mil" 1.000000)
						( Origin gBackEnd )
					)
					( objectStatus "J1C1.D8" )
				)
				( pin "GNDF1"
					( attribute "PIN_DELAY" "0.00 MIL"
						( Units "uTimeLength" "mil" 1.000000)
						( Origin gBackEnd )
					)
					( objectStatus "J1C1.F1" )
				)
				( pin "GNDF3"
					( attribute "PIN_DELAY" "0.00 MIL"
						( Units "uTimeLength" "mil" 1.000000)
						( Origin gBackEnd )
					)
					( objectStatus "J1C1.F3" )
				)
				( pin "GNDF5"
					( attribute "PIN_DELAY" "0.00 MIL"
						( Units "uTimeLength" "mil" 1.000000)
						( Origin gBackEnd )
					)
					( objectStatus "J1C1.F5" )
				)
				( pin "GNDF7"
					( attribute "PIN_DELAY" "0.00 MIL"
						( Units "uTimeLength" "mil" 1.000000)
						( Origin gBackEnd )
					)
					( objectStatus "J1C1.F7" )
				)
				( pin "GNDG2"
					( attribute "PIN_DELAY" "0.00 MIL"
						( Units "uTimeLength" "mil" 1.000000)
						( Origin gBackEnd )
					)
					( objectStatus "J1C1.G2" )
				)
				( pin "GNDG4"
					( attribute "PIN_DELAY" "0.00 MIL"
						( Units "uTimeLength" "mil" 1.000000)
						( Origin gBackEnd )
					)
					( objectStatus "J1C1.G4" )
				)
				( pin "GNDG6"
					( attribute "PIN_DELAY" "0.00 MIL"
						( Units "uTimeLength" "mil" 1.000000)
						( Origin gBackEnd )
					)
					( objectStatus "J1C1.G6" )
				)
				( pin "GNDG8"
					( attribute "PIN_DELAY" "0.00 MIL"
						( Units "uTimeLength" "mil" 1.000000)
						( Origin gBackEnd )
					)
					( objectStatus "J1C1.G8" )
				)
				( pin "GNDI1"
					( attribute "PIN_DELAY" "0.00 MIL"
						( Units "uTimeLength" "mil" 1.000000)
						( Origin gBackEnd )
					)
					( objectStatus "J1C1.I1" )
				)
				( pin "GNDI3"
					( attribute "PIN_DELAY" "0.00 MIL"
						( Units "uTimeLength" "mil" 1.000000)
						( Origin gBackEnd )
					)
					( objectStatus "J1C1.I3" )
				)
				( pin "GNDI5"
					( attribute "PIN_DELAY" "0.00 MIL"
						( Units "uTimeLength" "mil" 1.000000)
						( Origin gBackEnd )
					)
					( objectStatus "J1C1.I5" )
				)
				( pin "GNDI7"
					( attribute "PIN_DELAY" "0.00 MIL"
						( Units "uTimeLength" "mil" 1.000000)
						( Origin gBackEnd )
					)
					( objectStatus "J1C1.I7" )
				)
				( pin "GNDJ2"
					( objectStatus "J1C1.J2" )
				)
				( pin "GNDJ4"
					( objectStatus "J1C1.J4" )
				)
				( pin "GNDJ6"
					( objectStatus "J1C1.J6" )
				)
				( pin "GNDJ8"
					( objectStatus "J1C1.J8" )
				)
				( pin "IOA1"
					( attribute "PIN_DELAY" "313.89 MIL"
						( Units "uTimeLength" "mil" 1.000000)
						( Origin gBackEnd )
					)
					( objectStatus "J1C1.A1" )
				)
				( pin "IOA3"
					( attribute "PIN_DELAY" "376.67 MIL"
						( Units "uTimeLength" "mil" 1.000000)
						( Origin gBackEnd )
					)
					( objectStatus "J1C1.A3" )
				)
				( pin "IOA5"
					( attribute "PIN_DELAY" "313.89 MIL"
						( Units "uTimeLength" "mil" 1.000000)
						( Origin gBackEnd )
					)
					( objectStatus "J1C1.A5" )
				)
				( pin "IOA7"
					( attribute "PIN_DELAY" "313.89 MIL"
						( Units "uTimeLength" "mil" 1.000000)
						( Origin gBackEnd )
					)
					( objectStatus "J1C1.A7" )
				)
				( pin "IOB1"
					( attribute "PIN_DELAY" "341.67 MIL"
						( Units "uTimeLength" "mil" 1.000000)
						( Origin gBackEnd )
					)
					( objectStatus "J1C1.B1" )
				)
				( pin "IOB2"
					( attribute "PIN_DELAY" "352.78 MIL"
						( Units "uTimeLength" "mil" 1.000000)
						( Origin gBackEnd )
					)
					( objectStatus "J1C1.B2" )
				)
				( pin "IOB3"
					( attribute "PIN_DELAY" "410.00 MIL"
						( Units "uTimeLength" "mil" 1.000000)
						( Origin gBackEnd )
					)
					( objectStatus "J1C1.B3" )
				)
				( pin "IOB4"
					( attribute "PIN_DELAY" "352.78 MIL"
						( Units "uTimeLength" "mil" 1.000000)
						( Origin gBackEnd )
					)
					( objectStatus "J1C1.B4" )
				)
				( pin "IOB5"
					( attribute "PIN_DELAY" "341.67 MIL"
						( Units "uTimeLength" "mil" 1.000000)
						( Origin gBackEnd )
					)
					( objectStatus "J1C1.B5" )
				)
				( pin "IOB6"
					( attribute "PIN_DELAY" "352.78 MIL"
						( Units "uTimeLength" "mil" 1.000000)
						( Origin gBackEnd )
					)
					( objectStatus "J1C1.B6" )
				)
				( pin "IOB7"
					( attribute "PIN_DELAY" "341.67 MIL"
						( Units "uTimeLength" "mil" 1.000000)
						( Origin gBackEnd )
					)
					( objectStatus "J1C1.B7" )
				)
				( pin "IOB8"
					( attribute "PIN_DELAY" "423.33 MIL"
						( Units "uTimeLength" "mil" 1.000000)
						( Origin gBackEnd )
					)
					( objectStatus "J1C1.B8" )
				)
				( pin "IOC2"
					( attribute "PIN_DELAY" "383.33 MIL"
						( Units "uTimeLength" "mil" 1.000000)
						( Origin gBackEnd )
					)
					( objectStatus "J1C1.C2" )
				)
				( pin "IOC4"
					( attribute "PIN_DELAY" "383.33 MIL"
						( Units "uTimeLength" "mil" 1.000000)
						( Origin gBackEnd )
					)
					( objectStatus "J1C1.C4" )
				)
				( pin "IOC6"
					( attribute "PIN_DELAY" "383.33 MIL"
						( Units "uTimeLength" "mil" 1.000000)
						( Origin gBackEnd )
					)
					( objectStatus "J1C1.C6" )
				)
				( pin "IOC8"
					( attribute "PIN_DELAY" "460.00 MIL"
						( Units "uTimeLength" "mil" 1.000000)
						( Origin gBackEnd )
					)
					( objectStatus "J1C1.C8" )
				)
				( pin "IOD1"
					( attribute "PIN_DELAY" "452.78 MIL"
						( Units "uTimeLength" "mil" 1.000000)
						( Origin gBackEnd )
					)
					( objectStatus "J1C1.D1" )
				)
				( pin "IOD3"
					( attribute "PIN_DELAY" "452.78 MIL"
						( Units "uTimeLength" "mil" 1.000000)
						( Origin gBackEnd )
					)
					( objectStatus "J1C1.D3" )
				)
				( pin "IOD5"
					( attribute "PIN_DELAY" "452.78 MIL"
						( Units "uTimeLength" "mil" 1.000000)
						( Origin gBackEnd )
					)
					( objectStatus "J1C1.D5" )
				)
				( pin "IOD7"
					( attribute "PIN_DELAY" "543.33 MIL"
						( Units "uTimeLength" "mil" 1.000000)
						( Origin gBackEnd )
					)
					( objectStatus "J1C1.D7" )
				)
				( pin "IOE1"
					( attribute "PIN_DELAY" "475.00 MIL"
						( Units "uTimeLength" "mil" 1.000000)
						( Origin gBackEnd )
					)
					( objectStatus "J1C1.E1" )
				)
				( pin "IOE2"
					( attribute "PIN_DELAY" "505.56 MIL"
						( Units "uTimeLength" "mil" 1.000000)
						( Origin gBackEnd )
					)
					( objectStatus "J1C1.E2" )
				)
				( pin "IOE3"
					( attribute "PIN_DELAY" "475.00 MIL"
						( Units "uTimeLength" "mil" 1.000000)
						( Origin gBackEnd )
					)
					( objectStatus "J1C1.E3" )
				)
				( pin "IOE4"
					( attribute "PIN_DELAY" "505.56 MIL"
						( Units "uTimeLength" "mil" 1.000000)
						( Origin gBackEnd )
					)
					( objectStatus "J1C1.E4" )
				)
				( pin "IOE5"
					( attribute "PIN_DELAY" "475.00 MIL"
						( Units "uTimeLength" "mil" 1.000000)
						( Origin gBackEnd )
					)
					( objectStatus "J1C1.E5" )
				)
				( pin "IOE6"
					( attribute "PIN_DELAY" "606.67 MIL"
						( Units "uTimeLength" "mil" 1.000000)
						( Origin gBackEnd )
					)
					( objectStatus "J1C1.E6" )
				)
				( pin "IOE7"
					( attribute "PIN_DELAY" "570.00 MIL"
						( Units "uTimeLength" "mil" 1.000000)
						( Origin gBackEnd )
					)
					( objectStatus "J1C1.E7" )
				)
				( pin "IOE8"
					( attribute "PIN_DELAY" "606.67 MIL"
						( Units "uTimeLength" "mil" 1.000000)
						( Origin gBackEnd )
					)
					( objectStatus "J1C1.E8" )
				)
				( pin "IOF2"
					( attribute "PIN_DELAY" "522.22 MIL"
						( Units "uTimeLength" "mil" 1.000000)
						( Origin gBackEnd )
					)
					( objectStatus "J1C1.F2" )
				)
				( pin "IOF4"
					( attribute "PIN_DELAY" "522.22 MIL"
						( Units "uTimeLength" "mil" 1.000000)
						( Origin gBackEnd )
					)
					( objectStatus "J1C1.F4" )
				)
				( pin "IOF6"
					( attribute "PIN_DELAY" "626.67 MIL"
						( Units "uTimeLength" "mil" 1.000000)
						( Origin gBackEnd )
					)
					( objectStatus "J1C1.F6" )
				)
				( pin "IOF8"
					( attribute "PIN_DELAY" "626.67 MIL"
						( Units "uTimeLength" "mil" 1.000000)
						( Origin gBackEnd )
					)
					( objectStatus "J1C1.F8" )
				)
				( pin "IOG1"
					( attribute "PIN_DELAY" "519.44 MIL"
						( Units "uTimeLength" "mil" 1.000000)
						( Origin gBackEnd )
					)
					( objectStatus "J1C1.G1" )
				)
				( pin "IOG3"
					( attribute "PIN_DELAY" "519.44 MIL"
						( Units "uTimeLength" "mil" 1.000000)
						( Origin gBackEnd )
					)
					( objectStatus "J1C1.G3" )
				)
				( pin "IOG5"
					( attribute "PIN_DELAY" "519.44 MIL"
						( Units "uTimeLength" "mil" 1.000000)
						( Origin gBackEnd )
					)
					( objectStatus "J1C1.G5" )
				)
				( pin "IOG7"
					( attribute "PIN_DELAY" "519.44 MIL"
						( Units "uTimeLength" "mil" 1.000000)
						( Origin gBackEnd )
					)
					( objectStatus "J1C1.G7" )
				)
				( pin "IOH1"
					( attribute "PIN_DELAY" "538.89 MIL"
						( Units "uTimeLength" "mil" 1.000000)
						( Origin gBackEnd )
					)
					( objectStatus "J1C1.H1" )
				)
				( pin "IOH2"
					( attribute "PIN_DELAY" "673.33 MIL"
						( Units "uTimeLength" "mil" 1.000000)
						( Origin gBackEnd )
					)
					( objectStatus "J1C1.H2" )
				)
				( pin "IOH3"
					( attribute "PIN_DELAY" "538.89 MIL"
						( Units "uTimeLength" "mil" 1.000000)
						( Origin gBackEnd )
					)
					( objectStatus "J1C1.H3" )
				)
				( pin "IOH4"
					( attribute "PIN_DELAY" "561.11 MIL"
						( Units "uTimeLength" "mil" 1.000000)
						( Origin gBackEnd )
					)
					( objectStatus "J1C1.H4" )
				)
				( pin "IOH5"
					( attribute "PIN_DELAY" "538.89 MIL"
						( Units "uTimeLength" "mil" 1.000000)
						( Origin gBackEnd )
					)
					( objectStatus "J1C1.H5" )
				)
				( pin "IOH6"
					( attribute "PIN_DELAY" "561.11 MIL"
						( Units "uTimeLength" "mil" 1.000000)
						( Origin gBackEnd )
					)
					( objectStatus "J1C1.H6" )
				)
				( pin "IOH7"
					( attribute "PIN_DELAY" "538.89 MIL"
						( Units "uTimeLength" "mil" 1.000000)
						( Origin gBackEnd )
					)
					( objectStatus "J1C1.H7" )
				)
				( pin "IOH8"
					( attribute "PIN_DELAY" "561.11 MIL"
						( Units "uTimeLength" "mil" 1.000000)
						( Origin gBackEnd )
					)
					( objectStatus "J1C1.H8" )
				)
				( pin "IOI2"
					( attribute "PIN_DELAY" "720.00 MIL"
						( Units "uTimeLength" "mil" 1.000000)
						( Origin gBackEnd )
					)
					( objectStatus "J1C1.I2" )
				)
				( pin "IOI4"
					( attribute "PIN_DELAY" "600.00 MIL"
						( Units "uTimeLength" "mil" 1.000000)
						( Origin gBackEnd )
					)
					( objectStatus "J1C1.I4" )
				)
				( pin "IOI6"
					( attribute "PIN_DELAY" "600.00 MIL"
						( Units "uTimeLength" "mil" 1.000000)
						( Origin gBackEnd )
					)
					( objectStatus "J1C1.I6" )
				)
				( pin "IOI8"
					( attribute "PIN_DELAY" "600.00 MIL"
						( Units "uTimeLength" "mil" 1.000000)
						( Origin gBackEnd )
					)
					( objectStatus "J1C1.I8" )
				)
			)
			( gate "@baseboard_fab2_lib.baseboard_fab2(sch_1):page235_i235"
				( objectStatus "F1113" )
			)
			( gate "@baseboard_fab2_lib.baseboard_fab2(sch_1):page235_i236"
				( objectStatus "F1112" )
			)
			( gate "@baseboard_fab2_lib.baseboard_fab2(sch_1):page211_i88"
				( objectStatus "F1120" )
			)
			( gate "@baseboard_fab2_lib.baseboard_fab2(sch_1):page213_i91"
				( objectStatus "F1119" )
			)
			( gate "@baseboard_fab2_lib.baseboard_fab2(sch_1):page215_i315"
				( objectStatus "F1118" )
			)
			( gate "@baseboard_fab2_lib.baseboard_fab2(sch_1):page218_i35"
				( objectStatus "F1121" )
			)
			( gate "@baseboard_fab2_lib.baseboard_fab2(sch_1):page223_i85"
				( objectStatus "F1114" )
			)
			( gate "@baseboard_fab2_lib.baseboard_fab2(sch_1):page226_i85"
				( objectStatus "F1115" )
			)
			( gate "@baseboard_fab2_lib.baseboard_fab2(sch_1):page235_i222"
				( objectStatus "F1117" )
			)
			( gate "@baseboard_fab2_lib.baseboard_fab2(sch_1):page240_i177"
				( objectStatus "F1116" )
			)
			( gate "@baseboard_fab2_lib.baseboard_fab2(sch_1):page164_i29"
				( objectStatus "F982" )
			)
			( gate "@baseboard_fab2_lib.baseboard_fab2(sch_1):page164_i24"
				( objectStatus "F984" )
			)
			( gate "@baseboard_fab2_lib.baseboard_fab2(sch_1):page164_i27"
				( objectStatus "F983" )
			)
			( gate "@baseboard_fab2_lib.baseboard_fab2(sch_1):page164_i11"
				( objectStatus "F986" )
			)
			( gate "@baseboard_fab2_lib.baseboard_fab2(sch_1):page164_i13"
				( objectStatus "F985" )
			)
			( gate "@baseboard_fab2_lib.baseboard_fab2(sch_1):page111_i83"
				( objectStatus "F666" )
				( pin "A"
					( objectStatus "R9A2.1" )
				)
				( pin "B"
					( objectStatus "R9A2.2" )
				)
			)
			( gate "@baseboard_fab2_lib.baseboard_fab2(sch_1):page183_i20"
				( objectStatus "F3159" )
			)
			( gate "@baseboard_fab2_lib.baseboard_fab2(sch_1):page183_i21"
				( objectStatus "F3158" )
			)
			( gate "@baseboard_fab2_lib.baseboard_fab2(sch_1):page199_i123"
				( objectStatus "F2250" )
			)
			( gate "@baseboard_fab2_lib.baseboard_fab2(sch_1):page156_i281"
				( objectStatus "F2247" )
				( pin "IO1"
					( objectStatus "J9B2.1" )
				)
				( pin "IO2"
					( objectStatus "J9B2.2" )
				)
				( pin "IO3"
					( objectStatus "J9B2.3" )
				)
			)
			( gate "@baseboard_fab2_lib.baseboard_fab2(sch_1):page156_i285"
				( objectStatus "F2249" )
				( pin "IO1"
					( objectStatus "J8C1.1" )
				)
				( pin "IO2"
					( objectStatus "J8C1.2" )
				)
				( pin "IO3"
					( objectStatus "J8C1.3" )
				)
			)
			( gate "@baseboard_fab2_lib.baseboard_fab2(sch_1):page201_i122"
				( objectStatus "F2248" )
				( pin "IO1"
					( objectStatus "J8D4.1" )
				)
				( pin "IO2"
					( objectStatus "J8D4.2" )
				)
				( pin "IO3"
					( objectStatus "J8D4.3" )
				)
			)
			( gate "@baseboard_fab2_lib.baseboard_fab2(sch_1):page140_i1"
				( objectStatus "F2029" )
				( pin "C"
					( objectStatus "U9E1.6" )
				)
				( pin "DQ0"
					( objectStatus "U9E1.5" )
				)
				( pin "DQ1"
					( objectStatus "U9E1.2" )
				)
				( pin "S_N"
					( objectStatus "U9E1.1" )
				)
			)
			( gate "@baseboard_fab2_lib.baseboard_fab2(sch_1):page89_i35"
				( objectStatus "F1996" )
			)
			( gate "@baseboard_fab2_lib.baseboard_fab2(sch_1):page89_i36"
				( objectStatus "F1995" )
			)
			( gate "@baseboard_fab2_lib.baseboard_fab2(sch_1):page21_i259"
				( objectStatus "F101" )
				( pin "BCLK0_DN"
					( objectStatus "U5D1.AU24" )
				)
				( pin "BCLK0_DP"
					( objectStatus "U5D1.AW24" )
				)
				( pin "BCLK1_DN"
					( objectStatus "U5D1.CR26" )
				)
				( pin "BCLK1_DP"
					( objectStatus "U5D1.CP27" )
				)
				( pin "BCLK2_DN"
					( objectStatus "U5D1.CT25" )
				)
				( pin "BCLK2_DP"
					( objectStatus "U5D1.CU26" )
				)
				( pin "BPM_N(0)"
					( objectStatus "U5D1.AJ10" )
				)
				( pin "BPM_N(1)"
					( objectStatus "U5D1.AH11" )
				)
				( pin "CATERR_N"
					( objectStatus "U5D1.AL14" )
				)
				( pin "DDR012_SPDSCL"
					( objectStatus "U5D1.AJ18" )
				)
				( pin "DDR012_SPDSDA"
					( objectStatus "U5D1.AF17" )
				)
				( pin "DDR345_SPDSCL"
					( objectStatus "U5D1.AE18" )
				)
				( pin "DDR345_SPDSDA"
					( objectStatus "U5D1.AD17" )
				)
				( pin "MSMI_N"
					( objectStatus "U5D1.AN20" )
				)
				( pin "PMSYNC"
					( objectStatus "U5D1.AR14" )
				)
				( pin "PM_FAST_WAKE_N"
					( objectStatus "U5D1.AF15" )
				)
				( pin "SVIDALERT_N(0)"
					( objectStatus "U5D1.DE44" )
				)
				( pin "SVIDALERT_N(1)"
					( objectStatus "U5D1.DL44" )
				)
				( pin "SVIDCLK(0)"
					( objectStatus "U5D1.DC44" )
				)
				( pin "SVIDCLK(1)"
					( objectStatus "U5D1.DG44" )
				)
				( pin "SVIDDATA(0)"
					( objectStatus "U5D1.DB45" )
				)
				( pin "SVIDDATA(1)"
					( objectStatus "U5D1.DJ44" )
				)
				( pin "TDI"
					( objectStatus "U5D1.AC14" )
				)
				( pin "TDO"
					( objectStatus "U5D1.AE14" )
				)
			)
			( gate "@baseboard_fab2_lib.baseboard_fab2(sch_1):page22_i204"
				( objectStatus "F100" )
				( pin "FIVR_FAULT"
					( objectStatus "U5D1.AU14" )
				)
				( pin "RSVD(195)"
					( objectStatus "U5D1.AP27" )
				)
				( pin "RSVD(206)"
					( objectStatus "U5D1.AM27" )
				)
			)
			( gate "@baseboard_fab2_lib.baseboard_fab2(sch_1):page23_i172"
				( objectStatus "F99" )
				( pin "DDR0_ACT_N"
					( objectStatus "U5D1.J60" )
				)
				( pin "DDR0_BA(0)"
					( objectStatus "U5D1.C52" )
				)
				( pin "DDR0_BA(1)"
					( objectStatus "U5D1.G54" )
				)
				( pin "DDR0_BG(0)"
					( objectStatus "U5D1.D61" )
				)
				( pin "DDR0_BG(1)"
					( objectStatus "U5D1.F63" )
				)
				( pin "DDR0_CID(2)"
					( objectStatus "U5D1.G46" )
				)
				( pin "DDR0_CKE(0)"
					( objectStatus "U5D1.C62" )
				)
				( pin "DDR0_CKE(1)"
					( objectStatus "U5D1.C64" )
				)
				( pin "DDR0_CKE(2)"
					( objectStatus "U5D1.B63" )
				)
				( pin "DDR0_CKE(3)"
					( objectStatus "U5D1.D63" )
				)
				( pin "DDR0_CS_N(0)"
					( objectStatus "U5D1.G52" )
				)
				( pin "DDR0_CS_N(1)"
					( objectStatus "U5D1.F49" )
				)
				( pin "DDR0_CS_N(2)"
					( objectStatus "U5D1.D47" )
				)
				( pin "DDR0_CS_N(3)"
					( objectStatus "U5D1.F47" )
				)
				( pin "DDR0_CS_N(4)"
					( objectStatus "U5D1.B51" )
				)
				( pin "DDR0_CS_N(5)"
					( objectStatus "U5D1.D49" )
				)
				( pin "DDR0_CS_N(6)"
					( objectStatus "U5D1.F45" )
				)
				( pin "DDR0_CS_N(7)"
					( objectStatus "U5D1.K45" )
				)
				( pin "DDR0_DQ(0)"
					( objectStatus "U5D1.AN86" )
				)
				( pin "DDR0_DQ(10)"
					( objectStatus "U5D1.L86" )
				)
				( pin "DDR0_DQ(11)"
					( objectStatus "U5D1.L84" )
				)
				( pin "DDR0_DQ(12)"
					( objectStatus "U5D1.AA86" )
				)
				( pin "DDR0_DQ(13)"
					( objectStatus "U5D1.AA84" )
				)
				( pin "DDR0_DQ(14)"
					( objectStatus "U5D1.N86" )
				)
				( pin "DDR0_DQ(15)"
					( objectStatus "U5D1.N84" )
				)
				( pin "DDR0_DQ(16)"
					( objectStatus "U5D1.V81" )
				)
				( pin "DDR0_DQ(17)"
					( objectStatus "U5D1.T79" )
				)
				( pin "DDR0_DQ(18)"
					( objectStatus "U5D1.N82" )
				)
				( pin "DDR0_DQ(19)"
					( objectStatus "U5D1.M81" )
				)
				( pin "DDR0_DQ(1)"
					( objectStatus "U5D1.AN84" )
				)
				( pin "DDR0_DQ(20)"
					( objectStatus "U5D1.W80" )
				)
				( pin "DDR0_DQ(21)"
					( objectStatus "U5D1.V79" )
				)
				( pin "DDR0_DQ(22)"
					( objectStatus "U5D1.R82" )
				)
				( pin "DDR0_DQ(23)"
					( objectStatus "U5D1.N80" )
				)
				( pin "DDR0_DQ(24)"
					( objectStatus "U5D1.L76" )
				)
				( pin "DDR0_DQ(25)"
					( objectStatus "U5D1.R76" )
				)
				( pin "DDR0_DQ(26)"
					( objectStatus "U5D1.M73" )
				)
				( pin "DDR0_DQ(27)"
					( objectStatus "U5D1.P73" )
				)
				( pin "DDR0_DQ(28)"
					( objectStatus "U5D1.M77" )
				)
				( pin "DDR0_DQ(29)"
					( objectStatus "U5D1.P77" )
				)
				( pin "DDR0_DQ(2)"
					( objectStatus "U5D1.AE86" )
				)
				( pin "DDR0_DQ(30)"
					( objectStatus "U5D1.L74" )
				)
				( pin "DDR0_DQ(31)"
					( objectStatus "U5D1.R74" )
				)
				( pin "DDR0_DQ(32)"
					( objectStatus "U5D1.C42" )
				)
				( pin "DDR0_DQ(33)"
					( objectStatus "U5D1.B41" )
				)
				( pin "DDR0_DQ(34)"
					( objectStatus "U5D1.C38" )
				)
				( pin "DDR0_DQ(35)"
					( objectStatus "U5D1.E38" )
				)
				( pin "DDR0_DQ(36)"
					( objectStatus "U5D1.E42" )
				)
				( pin "DDR0_DQ(37)"
					( objectStatus "U5D1.F41" )
				)
				( pin "DDR0_DQ(38)"
					( objectStatus "U5D1.B39" )
				)
				( pin "DDR0_DQ(39)"
					( objectStatus "U5D1.F39" )
				)
				( pin "DDR0_DQ(3)"
					( objectStatus "U5D1.AE84" )
				)
				( pin "DDR0_DQ(40)"
					( objectStatus "U5D1.K37" )
				)
				( pin "DDR0_DQ(41)"
					( objectStatus "U5D1.P37" )
				)
				( pin "DDR0_DQ(42)"
					( objectStatus "U5D1.L34" )
				)
				( pin "DDR0_DQ(43)"
					( objectStatus "U5D1.N34" )
				)
				( pin "DDR0_DQ(44)"
					( objectStatus "U5D1.L38" )
				)
				( pin "DDR0_DQ(45)"
					( objectStatus "U5D1.N38" )
				)
				( pin "DDR0_DQ(46)"
					( objectStatus "U5D1.K35" )
				)
				( pin "DDR0_DQ(47)"
					( objectStatus "U5D1.P35" )
				)
				( pin "DDR0_DQ(48)"
					( objectStatus "U5D1.K31" )
				)
				( pin "DDR0_DQ(49)"
					( objectStatus "U5D1.P31" )
				)
				( pin "DDR0_DQ(4)"
					( objectStatus "U5D1.AR86" )
				)
				( pin "DDR0_DQ(50)"
					( objectStatus "U5D1.L28" )
				)
				( pin "DDR0_DQ(51)"
					( objectStatus "U5D1.N28" )
				)
				( pin "DDR0_DQ(52)"
					( objectStatus "U5D1.L32" )
				)
				( pin "DDR0_DQ(53)"
					( objectStatus "U5D1.N32" )
				)
				( pin "DDR0_DQ(54)"
					( objectStatus "U5D1.K29" )
				)
				( pin "DDR0_DQ(55)"
					( objectStatus "U5D1.P29" )
				)
				( pin "DDR0_DQ(56)"
					( objectStatus "U5D1.K25" )
				)
				( pin "DDR0_DQ(57)"
					( objectStatus "U5D1.P25" )
				)
				( pin "DDR0_DQ(58)"
					( objectStatus "U5D1.P23" )
				)
				( pin "DDR0_DQ(59)"
					( objectStatus "U5D1.T23" )
				)
				( pin "DDR0_DQ(5)"
					( objectStatus "U5D1.AR84" )
				)
				( pin "DDR0_DQ(60)"
					( objectStatus "U5D1.L26" )
				)
				( pin "DDR0_DQ(61)"
					( objectStatus "U5D1.N26" )
				)
				( pin "DDR0_DQ(62)"
					( objectStatus "U5D1.H23" )
				)
				( pin "DDR0_DQ(63)"
					( objectStatus "U5D1.K23" )
				)
				( pin "DDR0_DQ(6)"
					( objectStatus "U5D1.AG86" )
				)
				( pin "DDR0_DQ(7)"
					( objectStatus "U5D1.AG84" )
				)
				( pin "DDR0_DQ(8)"
					( objectStatus "U5D1.W86" )
				)
				( pin "DDR0_DQ(9)"
					( objectStatus "U5D1.W84" )
				)
				( pin "DDR0_DQS_DN(0)"
					( objectStatus "U5D1.AJ84" )
				)
				( pin "DDR0_DQS_DN(10)"
					( objectStatus "U5D1.U84" )
				)
				( pin "DDR0_DQS_DN(11)"
					( objectStatus "U5D1.U82" )
				)
				( pin "DDR0_DQS_DN(12)"
					( objectStatus "U5D1.K75" )
				)
				( pin "DDR0_DQS_DN(13)"
					( objectStatus "U5D1.A40" )
				)
				( pin "DDR0_DQS_DN(14)"
					( objectStatus "U5D1.J36" )
				)
				( pin "DDR0_DQS_DN(15)"
					( objectStatus "U5D1.J30" )
				)
				( pin "DDR0_DQS_DN(16)"
					( objectStatus "U5D1.J24" )
				)
				( pin "DDR0_DQS_DN(17)"
					( objectStatus "U5D1.AB67" )
				)
				( pin "DDR0_DQS_DN(1)"
					( objectStatus "U5D1.R84" )
				)
				( pin "DDR0_DQS_DN(2)"
					( objectStatus "U5D1.P79" )
				)
				( pin "DDR0_DQS_DN(3)"
					( objectStatus "U5D1.T75" )
				)
				( pin "DDR0_DQS_DN(4)"
					( objectStatus "U5D1.G40" )
				)
				( pin "DDR0_DQS_DN(5)"
					( objectStatus "U5D1.R36" )
				)
				( pin "DDR0_DQS_DN(6)"
					( objectStatus "U5D1.R30" )
				)
				( pin "DDR0_DQS_DN(7)"
					( objectStatus "U5D1.N24" )
				)
				( pin "DDR0_DQS_DN(8)"
					( objectStatus "U5D1.AH67" )
				)
				( pin "DDR0_DQS_DN(9)"
					( objectStatus "U5D1.AL84" )
				)
				( pin "DDR0_DQS_DP(0)"
					( objectStatus "U5D1.AH85" )
				)
				( pin "DDR0_DQS_DP(10)"
					( objectStatus "U5D1.V85" )
				)
				( pin "DDR0_DQS_DP(11)"
					( objectStatus "U5D1.T81" )
				)
				( pin "DDR0_DQS_DP(12)"
					( objectStatus "U5D1.M75" )
				)
				( pin "DDR0_DQS_DP(13)"
					( objectStatus "U5D1.C40" )
				)
				( pin "DDR0_DQS_DP(14)"
					( objectStatus "U5D1.L36" )
				)
				( pin "DDR0_DQS_DP(15)"
					( objectStatus "U5D1.L30" )
				)
				( pin "DDR0_DQS_DP(16)"
					( objectStatus "U5D1.L24" )
				)
				( pin "DDR0_DQS_DP(17)"
					( objectStatus "U5D1.AD67" )
				)
				( pin "DDR0_DQS_DP(1)"
					( objectStatus "U5D1.P85" )
				)
				( pin "DDR0_DQS_DP(2)"
					( objectStatus "U5D1.R80" )
				)
				( pin "DDR0_DQS_DP(3)"
					( objectStatus "U5D1.P75" )
				)
				( pin "DDR0_DQS_DP(4)"
					( objectStatus "U5D1.E40" )
				)
				( pin "DDR0_DQS_DP(5)"
					( objectStatus "U5D1.N36" )
				)
				( pin "DDR0_DQS_DP(6)"
					( objectStatus "U5D1.N30" )
				)
				( pin "DDR0_DQS_DP(7)"
					( objectStatus "U5D1.R24" )
				)
				( pin "DDR0_DQS_DP(8)"
					( objectStatus "U5D1.AF67" )
				)
				( pin "DDR0_DQS_DP(9)"
					( objectStatus "U5D1.AM85" )
				)
				( pin "DDR0_ECC(0)"
					( objectStatus "U5D1.AC68" )
				)
				( pin "DDR0_ECC(1)"
					( objectStatus "U5D1.AG68" )
				)
				( pin "DDR0_ECC(2)"
					( objectStatus "U5D1.AD65" )
				)
				( pin "DDR0_ECC(3)"
					( objectStatus "U5D1.AF65" )
				)
				( pin "DDR0_ECC(4)"
					( objectStatus "U5D1.AD69" )
				)
				( pin "DDR0_ECC(5)"
					( objectStatus "U5D1.AF69" )
				)
				( pin "DDR0_ECC(6)"
					( objectStatus "U5D1.AC66" )
				)
				( pin "DDR0_ECC(7)"
					( objectStatus "U5D1.AG66" )
				)
				( pin "DDR0_MA(0)"
					( objectStatus "U5D1.F53" )
				)
				( pin "DDR0_MA(10)"
					( objectStatus "U5D1.J54" )
				)
				( pin "DDR0_MA(11)"
					( objectStatus "U5D1.G62" )
				)
				( pin "DDR0_MA(12)"
					( objectStatus "U5D1.J64" )
				)
				( pin "DDR0_MA(13)"
					( objectStatus "U5D1.J48" )
				)
				( pin "DDR0_MA(14)"
					( objectStatus "U5D1.F51" )
				)
				( pin "DDR0_MA(15)"
					( objectStatus "U5D1.K49" )
				)
				( pin "DDR0_MA(16)"
					( objectStatus "U5D1.D51" )
				)
				( pin "DDR0_MA(17)"
					( objectStatus "U5D1.K47" )
				)
				( pin "DDR0_MA(1)"
					( objectStatus "U5D1.F57" )
				)
				( pin "DDR0_MA(2)"
					( objectStatus "U5D1.D57" )
				)
				( pin "DDR0_MA(3)"
					( objectStatus "U5D1.C58" )
				)
				( pin "DDR0_MA(4)"
					( objectStatus "U5D1.G58" )
				)
				( pin "DDR0_MA(5)"
					( objectStatus "U5D1.F59" )
				)
				( pin "DDR0_MA(6)"
					( objectStatus "U5D1.D59" )
				)
				( pin "DDR0_MA(7)"
					( objectStatus "U5D1.G60" )
				)
				( pin "DDR0_MA(8)"
					( objectStatus "U5D1.C60" )
				)
				( pin "DDR0_MA(9)"
					( objectStatus "U5D1.F61" )
				)
				( pin "DDR0_ODT(0)"
					( objectStatus "U5D1.C50" )
				)
				( pin "DDR0_ODT(1)"
					( objectStatus "U5D1.C48" )
				)
				( pin "DDR0_ODT(2)"
					( objectStatus "U5D1.G50" )
				)
				( pin "DDR0_ODT(3)"
					( objectStatus "U5D1.G48" )
				)
				( pin "DDR0_PAR"
					( objectStatus "U5D1.D53" )
				)
			)
			( gate "@baseboard_fab2_lib.baseboard_fab2(sch_1):page24_i172"
				( objectStatus "F98" )
				( pin "DDR1_ACT_N"
					( objectStatus "U5D1.T63" )
				)
				( pin "DDR1_BA(0)"
					( objectStatus "U5D1.T53" )
				)
				( pin "DDR1_BA(1)"
					( objectStatus "U5D1.K55" )
				)
				( pin "DDR1_BG(0)"
					( objectStatus "U5D1.M61" )
				)
				( pin "DDR1_BG(1)"
					( objectStatus "U5D1.N60" )
				)
				( pin "DDR1_CID(2)"
					( objectStatus "U5D1.M47" )
				)
				( pin "DDR1_CKE(0)"
					( objectStatus "U5D1.N62" )
				)
				( pin "DDR1_CKE(1)"
					( objectStatus "U5D1.R64" )
				)
				( pin "DDR1_CKE(2)"
					( objectStatus "U5D1.K63" )
				)
				( pin "DDR1_CKE(3)"
					( objectStatus "U5D1.L64" )
				)
				( pin "DDR1_CS_N(0)"
					( objectStatus "U5D1.K51" )
				)
				( pin "DDR1_CS_N(1)"
					( objectStatus "U5D1.R50" )
				)
				( pin "DDR1_CS_N(2)"
					( objectStatus "U5D1.N46" )
				)
				( pin "DDR1_CS_N(3)"
					( objectStatus "U5D1.V47" )
				)
				( pin "DDR1_CS_N(4)"
					( objectStatus "U5D1.J50" )
				)
				( pin "DDR1_CS_N(5)"
					( objectStatus "U5D1.T49" )
				)
				( pin "DDR1_CS_N(6)"
					( objectStatus "U5D1.M45" )
				)
				( pin "DDR1_CS_N(7)"
					( objectStatus "U5D1.R46" )
				)
				( pin "DDR1_DQ(0)"
					( objectStatus "U5D1.AV81" )
				)
				( pin "DDR1_DQ(10)"
					( objectStatus "U5D1.AC82" )
				)
				( pin "DDR1_DQ(11)"
					( objectStatus "U5D1.AB81" )
				)
				( pin "DDR1_DQ(12)"
					( objectStatus "U5D1.AJ80" )
				)
				( pin "DDR1_DQ(13)"
					( objectStatus "U5D1.AH79" )
				)
				( pin "DDR1_DQ(14)"
					( objectStatus "U5D1.AE82" )
				)
				( pin "DDR1_DQ(15)"
					( objectStatus "U5D1.AC80" )
				)
				( pin "DDR1_DQ(16)"
					( objectStatus "U5D1.E80" )
				)
				( pin "DDR1_DQ(17)"
					( objectStatus "U5D1.J80" )
				)
				( pin "DDR1_DQ(18)"
					( objectStatus "U5D1.F77" )
				)
				( pin "DDR1_DQ(19)"
					( objectStatus "U5D1.H77" )
				)
				( pin "DDR1_DQ(1)"
					( objectStatus "U5D1.AT79" )
				)
				( pin "DDR1_DQ(20)"
					( objectStatus "U5D1.F81" )
				)
				( pin "DDR1_DQ(21)"
					( objectStatus "U5D1.H81" )
				)
				( pin "DDR1_DQ(22)"
					( objectStatus "U5D1.E78" )
				)
				( pin "DDR1_DQ(23)"
					( objectStatus "U5D1.J78" )
				)
				( pin "DDR1_DQ(24)"
					( objectStatus "U5D1.D75" )
				)
				( pin "DDR1_DQ(25)"
					( objectStatus "U5D1.C74" )
				)
				( pin "DDR1_DQ(26)"
					( objectStatus "U5D1.D71" )
				)
				( pin "DDR1_DQ(27)"
					( objectStatus "U5D1.F71" )
				)
				( pin "DDR1_DQ(28)"
					( objectStatus "U5D1.F75" )
				)
				( pin "DDR1_DQ(29)"
					( objectStatus "U5D1.G74" )
				)
				( pin "DDR1_DQ(2)"
					( objectStatus "U5D1.AN82" )
				)
				( pin "DDR1_DQ(30)"
					( objectStatus "U5D1.C72" )
				)
				( pin "DDR1_DQ(31)"
					( objectStatus "U5D1.G72" )
				)
				( pin "DDR1_DQ(32)"
					( objectStatus "U5D1.K43" )
				)
				( pin "DDR1_DQ(33)"
					( objectStatus "U5D1.H43" )
				)
				( pin "DDR1_DQ(34)"
					( objectStatus "U5D1.L40" )
				)
				( pin "DDR1_DQ(35)"
					( objectStatus "U5D1.N40" )
				)
				( pin "DDR1_DQ(36)"
					( objectStatus "U5D1.P43" )
				)
				( pin "DDR1_DQ(37)"
					( objectStatus "U5D1.T43" )
				)
				( pin "DDR1_DQ(38)"
					( objectStatus "U5D1.K41" )
				)
				( pin "DDR1_DQ(39)"
					( objectStatus "U5D1.P41" )
				)
				( pin "DDR1_DQ(3)"
					( objectStatus "U5D1.AM81" )
				)
				( pin "DDR1_DQ(40)"
					( objectStatus "U5D1.C36" )
				)
				( pin "DDR1_DQ(41)"
					( objectStatus "U5D1.B35" )
				)
				( pin "DDR1_DQ(42)"
					( objectStatus "U5D1.C32" )
				)
				( pin "DDR1_DQ(43)"
					( objectStatus "U5D1.E32" )
				)
				( pin "DDR1_DQ(44)"
					( objectStatus "U5D1.E36" )
				)
				( pin "DDR1_DQ(45)"
					( objectStatus "U5D1.F35" )
				)
				( pin "DDR1_DQ(46)"
					( objectStatus "U5D1.B33" )
				)
				( pin "DDR1_DQ(47)"
					( objectStatus "U5D1.F33" )
				)
				( pin "DDR1_DQ(48)"
					( objectStatus "U5D1.C30" )
				)
				( pin "DDR1_DQ(49)"
					( objectStatus "U5D1.B29" )
				)
				( pin "DDR1_DQ(4)"
					( objectStatus "U5D1.AW80" )
				)
				( pin "DDR1_DQ(50)"
					( objectStatus "U5D1.C26" )
				)
				( pin "DDR1_DQ(51)"
					( objectStatus "U5D1.E26" )
				)
				( pin "DDR1_DQ(52)"
					( objectStatus "U5D1.E30" )
				)
				( pin "DDR1_DQ(53)"
					( objectStatus "U5D1.F29" )
				)
				( pin "DDR1_DQ(54)"
					( objectStatus "U5D1.B27" )
				)
				( pin "DDR1_DQ(55)"
					( objectStatus "U5D1.F27" )
				)
				( pin "DDR1_DQ(56)"
					( objectStatus "U5D1.U28" )
				)
				( pin "DDR1_DQ(57)"
					( objectStatus "U5D1.AA28" )
				)
				( pin "DDR1_DQ(58)"
					( objectStatus "U5D1.V25" )
				)
				( pin "DDR1_DQ(59)"
					( objectStatus "U5D1.Y25" )
				)
				( pin "DDR1_DQ(5)"
					( objectStatus "U5D1.AV79" )
				)
				( pin "DDR1_DQ(60)"
					( objectStatus "U5D1.V29" )
				)
				( pin "DDR1_DQ(61)"
					( objectStatus "U5D1.Y29" )
				)
				( pin "DDR1_DQ(62)"
					( objectStatus "U5D1.U26" )
				)
				( pin "DDR1_DQ(63)"
					( objectStatus "U5D1.AA26" )
				)
				( pin "DDR1_DQ(6)"
					( objectStatus "U5D1.AR82" )
				)
				( pin "DDR1_DQ(7)"
					( objectStatus "U5D1.AN80" )
				)
				( pin "DDR1_DQ(8)"
					( objectStatus "U5D1.AH81" )
				)
				( pin "DDR1_DQ(9)"
					( objectStatus "U5D1.AF79" )
				)
				( pin "DDR1_DQS_DN(0)"
					( objectStatus "U5D1.AP79" )
				)
				( pin "DDR1_DQS_DN(10)"
					( objectStatus "U5D1.AG82" )
				)
				( pin "DDR1_DQS_DN(11)"
					( objectStatus "U5D1.D79" )
				)
				( pin "DDR1_DQS_DN(12)"
					( objectStatus "U5D1.B73" )
				)
				( pin "DDR1_DQS_DN(13)"
					( objectStatus "U5D1.J42" )
				)
				( pin "DDR1_DQS_DN(14)"
					( objectStatus "U5D1.A34" )
				)
				( pin "DDR1_DQS_DN(15)"
					( objectStatus "U5D1.A28" )
				)
				( pin "DDR1_DQS_DN(16)"
					( objectStatus "U5D1.T27" )
				)
				( pin "DDR1_DQS_DN(17)"
					( objectStatus "U5D1.G68" )
				)
				( pin "DDR1_DQS_DN(1)"
					( objectStatus "U5D1.AD79" )
				)
				( pin "DDR1_DQS_DN(2)"
					( objectStatus "U5D1.K79" )
				)
				( pin "DDR1_DQS_DN(3)"
					( objectStatus "U5D1.H73" )
				)
				( pin "DDR1_DQS_DN(4)"
					( objectStatus "U5D1.N42" )
				)
				( pin "DDR1_DQS_DN(5)"
					( objectStatus "U5D1.G34" )
				)
				( pin "DDR1_DQS_DN(6)"
					( objectStatus "U5D1.G28" )
				)
				( pin "DDR1_DQS_DN(7)"
					( objectStatus "U5D1.AB27" )
				)
				( pin "DDR1_DQS_DN(8)"
					( objectStatus "U5D1.N68" )
				)
				( pin "DDR1_DQS_DN(9)"
					( objectStatus "U5D1.AU82" )
				)
				( pin "DDR1_DQS_DP(0)"
					( objectStatus "U5D1.AR80" )
				)
				( pin "DDR1_DQS_DP(10)"
					( objectStatus "U5D1.AF81" )
				)
				( pin "DDR1_DQS_DP(11)"
					( objectStatus "U5D1.F79" )
				)
				( pin "DDR1_DQS_DP(12)"
					( objectStatus "U5D1.D73" )
				)
				( pin "DDR1_DQS_DP(13)"
					( objectStatus "U5D1.L42" )
				)
				( pin "DDR1_DQS_DP(14)"
					( objectStatus "U5D1.C34" )
				)
				( pin "DDR1_DQS_DP(15)"
					( objectStatus "U5D1.C28" )
				)
				( pin "DDR1_DQS_DP(16)"
					( objectStatus "U5D1.V27" )
				)
				( pin "DDR1_DQS_DP(17)"
					( objectStatus "U5D1.J68" )
				)
				( pin "DDR1_DQS_DP(1)"
					( objectStatus "U5D1.AE80" )
				)
				( pin "DDR1_DQS_DP(2)"
					( objectStatus "U5D1.H79" )
				)
				( pin "DDR1_DQS_DP(3)"
					( objectStatus "U5D1.F73" )
				)
				( pin "DDR1_DQS_DP(4)"
					( objectStatus "U5D1.R42" )
				)
				( pin "DDR1_DQS_DP(5)"
					( objectStatus "U5D1.E34" )
				)
				( pin "DDR1_DQS_DP(6)"
					( objectStatus "U5D1.E28" )
				)
				( pin "DDR1_DQS_DP(7)"
					( objectStatus "U5D1.Y27" )
				)
				( pin "DDR1_DQS_DP(8)"
					( objectStatus "U5D1.L68" )
				)
				( pin "DDR1_DQS_DP(9)"
					( objectStatus "U5D1.AT81" )
				)
				( pin "DDR1_ECC(0)"
					( objectStatus "U5D1.J70" )
				)
				( pin "DDR1_ECC(1)"
					( objectStatus "U5D1.H69" )
				)
				( pin "DDR1_ECC(2)"
					( objectStatus "U5D1.J66" )
				)
				( pin "DDR1_ECC(3)"
					( objectStatus "U5D1.L66" )
				)
				( pin "DDR1_ECC(4)"
					( objectStatus "U5D1.L70" )
				)
				( pin "DDR1_ECC(5)"
					( objectStatus "U5D1.M69" )
				)
				( pin "DDR1_ECC(6)"
					( objectStatus "U5D1.H67" )
				)
				( pin "DDR1_ECC(7)"
					( objectStatus "U5D1.M67" )
				)
				( pin "DDR1_MA(0)"
					( objectStatus "U5D1.J52" )
				)
				( pin "DDR1_MA(10)"
					( objectStatus "U5D1.M55" )
				)
				( pin "DDR1_MA(11)"
					( objectStatus "U5D1.R60" )
				)
				( pin "DDR1_MA(12)"
					( objectStatus "U5D1.T61" )
				)
				( pin "DDR1_MA(13)"
					( objectStatus "U5D1.M51" )
				)
				( pin "DDR1_MA(14)"
					( objectStatus "U5D1.T51" )
				)
				( pin "DDR1_MA(15)"
					( objectStatus "U5D1.N52" )
				)
				( pin "DDR1_MA(16)"
					( objectStatus "U5D1.R52" )
				)
				( pin "DDR1_MA(17)"
					( objectStatus "U5D1.N48" )
				)
				( pin "DDR1_MA(1)"
					( objectStatus "U5D1.J58" )
				)
				( pin "DDR1_MA(2)"
					( objectStatus "U5D1.K57" )
				)
				( pin "DDR1_MA(3)"
					( objectStatus "U5D1.N58" )
				)
				( pin "DDR1_MA(4)"
					( objectStatus "U5D1.M59" )
				)
				( pin "DDR1_MA(5)"
					( objectStatus "U5D1.R58" )
				)
				( pin "DDR1_MA(6)"
					( objectStatus "U5D1.T59" )
				)
				( pin "DDR1_MA(7)"
					( objectStatus "U5D1.V61" )
				)
				( pin "DDR1_MA(8)"
					( objectStatus "U5D1.W60" )
				)
				( pin "DDR1_MA(9)"
					( objectStatus "U5D1.K59" )
				)
				( pin "DDR1_ODT(0)"
					( objectStatus "U5D1.N50" )
				)
				( pin "DDR1_ODT(1)"
					( objectStatus "U5D1.R48" )
				)
				( pin "DDR1_ODT(2)"
					( objectStatus "U5D1.M49" )
				)
				( pin "DDR1_ODT(3)"
					( objectStatus "U5D1.T47" )
				)
				( pin "DDR1_PAR"
					( objectStatus "U5D1.K53" )
				)
			)
			( gate "@baseboard_fab2_lib.baseboard_fab2(sch_1):page25_i172"
				( objectStatus "F97" )
				( pin "DDR2_ACT_N"
					( objectStatus "U5D1.AB61" )
				)
				( pin "DDR2_BA(0)"
					( objectStatus "U5D1.W52" )
				)
				( pin "DDR2_BA(1)"
					( objectStatus "U5D1.AE56" )
				)
				( pin "DDR2_BG(0)"
					( objectStatus "U5D1.AA60" )
				)
				( pin "DDR2_BG(1)"
					( objectStatus "U5D1.AE62" )
				)
				( pin "DDR2_CID(2)"
					( objectStatus "U5D1.AB45" )
				)
				( pin "DDR2_CKE(0)"
					( objectStatus "U5D1.AA62" )
				)
				( pin "DDR2_CKE(1)"
					( objectStatus "U5D1.AD63" )
				)
				( pin "DDR2_CKE(2)"
					( objectStatus "U5D1.V63" )
				)
				( pin "DDR2_CKE(3)"
					( objectStatus "U5D1.AB63" )
				)
				( pin "DDR2_CS_N(0)"
					( objectStatus "U5D1.V51" )
				)
				( pin "DDR2_CS_N(1)"
					( objectStatus "U5D1.AB49" )
				)
				( pin "DDR2_CS_N(2)"
					( objectStatus "U5D1.W46" )
				)
				( pin "DDR2_CS_N(3)"
					( objectStatus "U5D1.AA46" )
				)
				( pin "DDR2_CS_N(4)"
					( objectStatus "U5D1.AB51" )
				)
				( pin "DDR2_CS_N(5)"
					( objectStatus "U5D1.W48" )
				)
				( pin "DDR2_CS_N(6)"
					( objectStatus "U5D1.T45" )
				)
				( pin "DDR2_CS_N(7)"
					( objectStatus "U5D1.V45" )
				)
				( pin "DDR2_DQ(0)"
					( objectStatus "U5D1.AR76" )
				)
				( pin "DDR2_DQ(10)"
					( objectStatus "U5D1.Y77" )
				)
				( pin "DDR2_DQ(11)"
					( objectStatus "U5D1.W76" )
				)
				( pin "DDR2_DQ(12)"
					( objectStatus "U5D1.AF75" )
				)
				( pin "DDR2_DQ(13)"
					( objectStatus "U5D1.AE74" )
				)
				( pin "DDR2_DQ(14)"
					( objectStatus "U5D1.AB77" )
				)
				( pin "DDR2_DQ(15)"
					( objectStatus "U5D1.Y75" )
				)
				( pin "DDR2_DQ(16)"
					( objectStatus "U5D1.W72" )
				)
				( pin "DDR2_DQ(17)"
					( objectStatus "U5D1.AA70" )
				)
				( pin "DDR2_DQ(18)"
					( objectStatus "U5D1.R70" )
				)
				( pin "DDR2_DQ(19)"
					( objectStatus "U5D1.T69" )
				)
				( pin "DDR2_DQ(1)"
					( objectStatus "U5D1.AN74" )
				)
				( pin "DDR2_DQ(20)"
					( objectStatus "U5D1.AA72" )
				)
				( pin "DDR2_DQ(21)"
					( objectStatus "U5D1.AB71" )
				)
				( pin "DDR2_DQ(22)"
					( objectStatus "U5D1.T71" )
				)
				( pin "DDR2_DQ(23)"
					( objectStatus "U5D1.V69" )
				)
				( pin "DDR2_DQ(24)"
					( objectStatus "U5D1.AM67" )
				)
				( pin "DDR2_DQ(25)"
					( objectStatus "U5D1.AT67" )
				)
				( pin "DDR2_DQ(26)"
					( objectStatus "U5D1.AN64" )
				)
				( pin "DDR2_DQ(27)"
					( objectStatus "U5D1.AR64" )
				)
				( pin "DDR2_DQ(28)"
					( objectStatus "U5D1.AN68" )
				)
				( pin "DDR2_DQ(29)"
					( objectStatus "U5D1.AR68" )
				)
				( pin "DDR2_DQ(2)"
					( objectStatus "U5D1.AK77" )
				)
				( pin "DDR2_DQ(30)"
					( objectStatus "U5D1.AM65" )
				)
				( pin "DDR2_DQ(31)"
					( objectStatus "U5D1.AT65" )
				)
				( pin "DDR2_DQ(32)"
					( objectStatus "U5D1.U40" )
				)
				( pin "DDR2_DQ(33)"
					( objectStatus "U5D1.AA40" )
				)
				( pin "DDR2_DQ(34)"
					( objectStatus "U5D1.V37" )
				)
				( pin "DDR2_DQ(35)"
					( objectStatus "U5D1.Y37" )
				)
				( pin "DDR2_DQ(36)"
					( objectStatus "U5D1.V41" )
				)
				( pin "DDR2_DQ(37)"
					( objectStatus "U5D1.Y41" )
				)
				( pin "DDR2_DQ(38)"
					( objectStatus "U5D1.U38" )
				)
				( pin "DDR2_DQ(39)"
					( objectStatus "U5D1.AA38" )
				)
				( pin "DDR2_DQ(3)"
					( objectStatus "U5D1.AJ76" )
				)
				( pin "DDR2_DQ(40)"
					( objectStatus "U5D1.U34" )
				)
				( pin "DDR2_DQ(41)"
					( objectStatus "U5D1.AA34" )
				)
				( pin "DDR2_DQ(42)"
					( objectStatus "U5D1.V31" )
				)
				( pin "DDR2_DQ(43)"
					( objectStatus "U5D1.Y31" )
				)
				( pin "DDR2_DQ(44)"
					( objectStatus "U5D1.V35" )
				)
				( pin "DDR2_DQ(45)"
					( objectStatus "U5D1.Y35" )
				)
				( pin "DDR2_DQ(46)"
					( objectStatus "U5D1.U32" )
				)
				( pin "DDR2_DQ(47)"
					( objectStatus "U5D1.AA32" )
				)
				( pin "DDR2_DQ(48)"
					( objectStatus "U5D1.AD31" )
				)
				( pin "DDR2_DQ(49)"
					( objectStatus "U5D1.AH31" )
				)
				( pin "DDR2_DQ(4)"
					( objectStatus "U5D1.AT75" )
				)
				( pin "DDR2_DQ(50)"
					( objectStatus "U5D1.AE28" )
				)
				( pin "DDR2_DQ(51)"
					( objectStatus "U5D1.AG28" )
				)
				( pin "DDR2_DQ(52)"
					( objectStatus "U5D1.AE32" )
				)
				( pin "DDR2_DQ(53)"
					( objectStatus "U5D1.AG32" )
				)
				( pin "DDR2_DQ(54)"
					( objectStatus "U5D1.AD29" )
				)
				( pin "DDR2_DQ(55)"
					( objectStatus "U5D1.AH29" )
				)
				( pin "DDR2_DQ(56)"
					( objectStatus "U5D1.AD25" )
				)
				( pin "DDR2_DQ(57)"
					( objectStatus "U5D1.AH25" )
				)
				( pin "DDR2_DQ(58)"
					( objectStatus "U5D1.AE22" )
				)
				( pin "DDR2_DQ(59)"
					( objectStatus "U5D1.AG22" )
				)
				( pin "DDR2_DQ(5)"
					( objectStatus "U5D1.AR74" )
				)
				( pin "DDR2_DQ(60)"
					( objectStatus "U5D1.AE26" )
				)
				( pin "DDR2_DQ(61)"
					( objectStatus "U5D1.AG26" )
				)
				( pin "DDR2_DQ(62)"
					( objectStatus "U5D1.AD23" )
				)
				( pin "DDR2_DQ(63)"
					( objectStatus "U5D1.AH23" )
				)
				( pin "DDR2_DQ(6)"
					( objectStatus "U5D1.AM77" )
				)
				( pin "DDR2_DQ(7)"
					( objectStatus "U5D1.AK75" )
				)
				( pin "DDR2_DQ(8)"
					( objectStatus "U5D1.AE76" )
				)
				( pin "DDR2_DQ(9)"
					( objectStatus "U5D1.AC74" )
				)
				( pin "DDR2_DQS_DN(0)"
					( objectStatus "U5D1.AL74" )
				)
				( pin "DDR2_DQS_DN(10)"
					( objectStatus "U5D1.AD77" )
				)
				( pin "DDR2_DQS_DN(11)"
					( objectStatus "U5D1.U72" )
				)
				( pin "DDR2_DQS_DN(12)"
					( objectStatus "U5D1.AL66" )
				)
				( pin "DDR2_DQS_DN(13)"
					( objectStatus "U5D1.T39" )
				)
				( pin "DDR2_DQS_DN(14)"
					( objectStatus "U5D1.T33" )
				)
				( pin "DDR2_DQS_DN(15)"
					( objectStatus "U5D1.AC30" )
				)
				( pin "DDR2_DQS_DN(16)"
					( objectStatus "U5D1.AC24" )
				)
				( pin "DDR2_DQS_DN(17)"
					( objectStatus "U5D1.AT71" )
				)
				( pin "DDR2_DQS_DN(1)"
					( objectStatus "U5D1.AA74" )
				)
				( pin "DDR2_DQS_DN(2)"
					( objectStatus "U5D1.Y69" )
				)
				( pin "DDR2_DQS_DN(3)"
					( objectStatus "U5D1.AU66" )
				)
				( pin "DDR2_DQS_DN(4)"
					( objectStatus "U5D1.AB39" )
				)
				( pin "DDR2_DQS_DN(5)"
					( objectStatus "U5D1.AB33" )
				)
				( pin "DDR2_DQS_DN(6)"
					( objectStatus "U5D1.AJ30" )
				)
				( pin "DDR2_DQS_DN(7)"
					( objectStatus "U5D1.AJ24" )
				)
				( pin "DDR2_DQS_DN(8)"
					( objectStatus "U5D1.BB71" )
				)
				( pin "DDR2_DQS_DN(9)"
					( objectStatus "U5D1.AP77" )
				)
				( pin "DDR2_DQS_DP(0)"
					( objectStatus "U5D1.AM75" )
				)
				( pin "DDR2_DQS_DP(10)"
					( objectStatus "U5D1.AC76" )
				)
				( pin "DDR2_DQS_DP(11)"
					( objectStatus "U5D1.V71" )
				)
				( pin "DDR2_DQS_DP(12)"
					( objectStatus "U5D1.AN66" )
				)
				( pin "DDR2_DQS_DP(13)"
					( objectStatus "U5D1.V39" )
				)
				( pin "DDR2_DQS_DP(14)"
					( objectStatus "U5D1.V33" )
				)
				( pin "DDR2_DQS_DP(15)"
					( objectStatus "U5D1.AE30" )
				)
				( pin "DDR2_DQS_DP(16)"
					( objectStatus "U5D1.AE24" )
				)
				( pin "DDR2_DQS_DP(17)"
					( objectStatus "U5D1.AV71" )
				)
				( pin "DDR2_DQS_DP(1)"
					( objectStatus "U5D1.AB75" )
				)
				( pin "DDR2_DQS_DP(2)"
					( objectStatus "U5D1.W70" )
				)
				( pin "DDR2_DQS_DP(3)"
					( objectStatus "U5D1.AR66" )
				)
				( pin "DDR2_DQS_DP(4)"
					( objectStatus "U5D1.Y39" )
				)
				( pin "DDR2_DQS_DP(5)"
					( objectStatus "U5D1.Y33" )
				)
				( pin "DDR2_DQS_DP(6)"
					( objectStatus "U5D1.AG30" )
				)
				( pin "DDR2_DQS_DP(7)"
					( objectStatus "U5D1.AG24" )
				)
				( pin "DDR2_DQS_DP(8)"
					( objectStatus "U5D1.AY71" )
				)
				( pin "DDR2_DQS_DP(9)"
					( objectStatus "U5D1.AN76" )
				)
				( pin "DDR2_ECC(0)"
					( objectStatus "U5D1.AU72" )
				)
				( pin "DDR2_ECC(1)"
					( objectStatus "U5D1.BA72" )
				)
				( pin "DDR2_ECC(2)"
					( objectStatus "U5D1.AV69" )
				)
				( pin "DDR2_ECC(3)"
					( objectStatus "U5D1.AY69" )
				)
				( pin "DDR2_ECC(4)"
					( objectStatus "U5D1.AV73" )
				)
				( pin "DDR2_ECC(5)"
					( objectStatus "U5D1.AY73" )
				)
				( pin "DDR2_ECC(6)"
					( objectStatus "U5D1.AU70" )
				)
				( pin "DDR2_ECC(7)"
					( objectStatus "U5D1.BA70" )
				)
				( pin "DDR2_MA(0)"
					( objectStatus "U5D1.AB53" )
				)
				( pin "DDR2_MA(10)"
					( objectStatus "U5D1.AD55" )
				)
				( pin "DDR2_MA(11)"
					( objectStatus "U5D1.AG60" )
				)
				( pin "DDR2_MA(12)"
					( objectStatus "U5D1.AG62" )
				)
				( pin "DDR2_MA(13)"
					( objectStatus "U5D1.AD53" )
				)
				( pin "DDR2_MA(14)"
					( objectStatus "U5D1.W50" )
				)
				( pin "DDR2_MA(15)"
					( objectStatus "U5D1.AE54" )
				)
				( pin "DDR2_MA(16)"
					( objectStatus "U5D1.AA52" )
				)
				( pin "DDR2_MA(17)"
					( objectStatus "U5D1.AC46" )
				)
				( pin "DDR2_MA(1)"
					( objectStatus "U5D1.AE58" )
				)
				( pin "DDR2_MA(2)"
					( objectStatus "U5D1.AD57" )
				)
				( pin "DDR2_MA(3)"
					( objectStatus "U5D1.W58" )
				)
				( pin "DDR2_MA(4)"
					( objectStatus "U5D1.AA58" )
				)
				( pin "DDR2_MA(5)"
					( objectStatus "U5D1.V59" )
				)
				( pin "DDR2_MA(6)"
					( objectStatus "U5D1.AB59" )
				)
				( pin "DDR2_MA(7)"
					( objectStatus "U5D1.AE60" )
				)
				( pin "DDR2_MA(8)"
					( objectStatus "U5D1.AD59" )
				)
				( pin "DDR2_MA(9)"
					( objectStatus "U5D1.AG58" )
				)
				( pin "DDR2_ODT(0)"
					( objectStatus "U5D1.AA50" )
				)
				( pin "DDR2_ODT(1)"
					( objectStatus "U5D1.AA48" )
				)
				( pin "DDR2_ODT(2)"
					( objectStatus "U5D1.V49" )
				)
				( pin "DDR2_ODT(3)"
					( objectStatus "U5D1.AB47" )
				)
				( pin "DDR2_PAR"
					( objectStatus "U5D1.V53" )
				)
			)
			( gate "@baseboard_fab2_lib.baseboard_fab2(sch_1):page26_i172"
				( objectStatus "F96" )
				( pin "DDR3_ACT_N"
					( objectStatus "U5D1.DW60" )
				)
				( pin "DDR3_BA(0)"
					( objectStatus "U5D1.EE52" )
				)
				( pin "DDR3_BA(1)"
					( objectStatus "U5D1.EA54" )
				)
				( pin "DDR3_BG(0)"
					( objectStatus "U5D1.ED61" )
				)
				( pin "DDR3_BG(1)"
					( objectStatus "U5D1.DW62" )
				)
				( pin "DDR3_CID(2)"
					( objectStatus "U5D1.DV47" )
				)
				( pin "DDR3_CKE(0)"
					( objectStatus "U5D1.EE62" )
				)
				( pin "DDR3_CKE(1)"
					( objectStatus "U5D1.EF63" )
				)
				( pin "DDR3_CKE(2)"
					( objectStatus "U5D1.EA62" )
				)
				( pin "DDR3_CKE(3)"
					( objectStatus "U5D1.EB63" )
				)
				( pin "DDR3_CS_N(0)"
					( objectStatus "U5D1.EF51" )
				)
				( pin "DDR3_CS_N(1)"
					( objectStatus "U5D1.ED49" )
				)
				( pin "DDR3_CS_N(2)"
					( objectStatus "U5D1.ED47" )
				)
				( pin "DDR3_CS_N(3)"
					( objectStatus "U5D1.EB47" )
				)
				( pin "DDR3_CS_N(4)"
					( objectStatus "U5D1.EB51" )
				)
				( pin "DDR3_CS_N(5)"
					( objectStatus "U5D1.EB49" )
				)
				( pin "DDR3_CS_N(6)"
					( objectStatus "U5D1.DV45" )
				)
				( pin "DDR3_CS_N(7)"
					( objectStatus "U5D1.EB45" )
				)
				( pin "DDR3_DQ(0)"
					( objectStatus "U5D1.CN84" )
				)
				( pin "DDR3_DQ(10)"
					( objectStatus "U5D1.DV83" )
				)
				( pin "DDR3_DQ(11)"
					( objectStatus "U5D1.DY83" )
				)
				( pin "DDR3_DQ(12)"
					( objectStatus "U5D1.DD85" )
				)
				( pin "DDR3_DQ(13)"
					( objectStatus "U5D1.DE84" )
				)
				( pin "DDR3_DQ(14)"
					( objectStatus "U5D1.DR84" )
				)
				( pin "DDR3_DQ(15)"
					( objectStatus "U5D1.DV85" )
				)
				( pin "DDR3_DQ(16)"
					( objectStatus "U5D1.DM79" )
				)
				( pin "DDR3_DQ(17)"
					( objectStatus "U5D1.DK81" )
				)
				( pin "DDR3_DQ(18)"
					( objectStatus "U5D1.DT81" )
				)
				( pin "DDR3_DQ(19)"
					( objectStatus "U5D1.DR82" )
				)
				( pin "DDR3_DQ(1)"
					( objectStatus "U5D1.CN86" )
				)
				( pin "DDR3_DQ(20)"
					( objectStatus "U5D1.DK79" )
				)
				( pin "DDR3_DQ(21)"
					( objectStatus "U5D1.DJ80" )
				)
				( pin "DDR3_DQ(22)"
					( objectStatus "U5D1.DR80" )
				)
				( pin "DDR3_DQ(23)"
					( objectStatus "U5D1.DN82" )
				)
				( pin "DDR3_DQ(24)"
					( objectStatus "U5D1.DN76" )
				)
				( pin "DDR3_DQ(25)"
					( objectStatus "U5D1.DU76" )
				)
				( pin "DDR3_DQ(26)"
					( objectStatus "U5D1.DP73" )
				)
				( pin "DDR3_DQ(27)"
					( objectStatus "U5D1.DT73" )
				)
				( pin "DDR3_DQ(28)"
					( objectStatus "U5D1.DP77" )
				)
				( pin "DDR3_DQ(29)"
					( objectStatus "U5D1.DT77" )
				)
				( pin "DDR3_DQ(2)"
					( objectStatus "U5D1.DA86" )
				)
				( pin "DDR3_DQ(30)"
					( objectStatus "U5D1.DN74" )
				)
				( pin "DDR3_DQ(31)"
					( objectStatus "U5D1.DU74" )
				)
				( pin "DDR3_DQ(32)"
					( objectStatus "U5D1.EC40" )
				)
				( pin "DDR3_DQ(33)"
					( objectStatus "U5D1.ED39" )
				)
				( pin "DDR3_DQ(34)"
					( objectStatus "U5D1.EA36" )
				)
				( pin "DDR3_DQ(35)"
					( objectStatus "U5D1.EC36" )
				)
				( pin "DDR3_DQ(36)"
					( objectStatus "U5D1.DY39" )
				)
				( pin "DDR3_DQ(37)"
					( objectStatus "U5D1.EA40" )
				)
				( pin "DDR3_DQ(38)"
					( objectStatus "U5D1.DY37" )
				)
				( pin "DDR3_DQ(39)"
					( objectStatus "U5D1.ED37" )
				)
				( pin "DDR3_DQ(3)"
					( objectStatus "U5D1.DA84" )
				)
				( pin "DDR3_DQ(40)"
					( objectStatus "U5D1.DN36" )
				)
				( pin "DDR3_DQ(41)"
					( objectStatus "U5D1.DU36" )
				)
				( pin "DDR3_DQ(42)"
					( objectStatus "U5D1.DP33" )
				)
				( pin "DDR3_DQ(43)"
					( objectStatus "U5D1.DT33" )
				)
				( pin "DDR3_DQ(44)"
					( objectStatus "U5D1.DP37" )
				)
				( pin "DDR3_DQ(45)"
					( objectStatus "U5D1.DT37" )
				)
				( pin "DDR3_DQ(46)"
					( objectStatus "U5D1.DN34" )
				)
				( pin "DDR3_DQ(47)"
					( objectStatus "U5D1.DU34" )
				)
				( pin "DDR3_DQ(48)"
					( objectStatus "U5D1.DN30" )
				)
				( pin "DDR3_DQ(49)"
					( objectStatus "U5D1.DU30" )
				)
				( pin "DDR3_DQ(4)"
					( objectStatus "U5D1.CL84" )
				)
				( pin "DDR3_DQ(50)"
					( objectStatus "U5D1.DP27" )
				)
				( pin "DDR3_DQ(51)"
					( objectStatus "U5D1.DT27" )
				)
				( pin "DDR3_DQ(52)"
					( objectStatus "U5D1.DP31" )
				)
				( pin "DDR3_DQ(53)"
					( objectStatus "U5D1.DT31" )
				)
				( pin "DDR3_DQ(54)"
					( objectStatus "U5D1.DN28" )
				)
				( pin "DDR3_DQ(55)"
					( objectStatus "U5D1.DU28" )
				)
				( pin "DDR3_DQ(56)"
					( objectStatus "U5D1.DN24" )
				)
				( pin "DDR3_DQ(57)"
					( objectStatus "U5D1.DU24" )
				)
				( pin "DDR3_DQ(58)"
					( objectStatus "U5D1.DY21" )
				)
				( pin "DDR3_DQ(59)"
					( objectStatus "U5D1.EB21" )
				)
				( pin "DDR3_DQ(5)"
					( objectStatus "U5D1.CL86" )
				)
				( pin "DDR3_DQ(60)"
					( objectStatus "U5D1.DP25" )
				)
				( pin "DDR3_DQ(61)"
					( objectStatus "U5D1.DT25" )
				)
				( pin "DDR3_DQ(62)"
					( objectStatus "U5D1.EC22" )
				)
				( pin "DDR3_DQ(63)"
					( objectStatus "U5D1.DW22" )
				)
				( pin "DDR3_DQ(6)"
					( objectStatus "U5D1.CW86" )
				)
				( pin "DDR3_DQ(7)"
					( objectStatus "U5D1.CW84" )
				)
				( pin "DDR3_DQ(8)"
					( objectStatus "U5D1.DG84" )
				)
				( pin "DDR3_DQ(9)"
					( objectStatus "U5D1.DH85" )
				)
				( pin "DDR3_DQS_DN(0)"
					( objectStatus "U5D1.CU84" )
				)
				( pin "DDR3_DQS_DN(10)"
					( objectStatus "U5D1.DM85" )
				)
				( pin "DDR3_DQS_DN(11)"
					( objectStatus "U5D1.DN80" )
				)
				( pin "DDR3_DQS_DN(12)"
					( objectStatus "U5D1.DP75" )
				)
				( pin "DDR3_DQS_DN(13)"
					( objectStatus "U5D1.EA38" )
				)
				( pin "DDR3_DQS_DN(14)"
					( objectStatus "U5D1.DP35" )
				)
				( pin "DDR3_DQS_DN(15)"
					( objectStatus "U5D1.DM29" )
				)
				( pin "DDR3_DQS_DN(16)"
					( objectStatus "U5D1.DM23" )
				)
				( pin "DDR3_DQS_DN(17)"
					( objectStatus "U5D1.DB67" )
				)
				( pin "DDR3_DQS_DN(1)"
					( objectStatus "U5D1.DN84" )
				)
				( pin "DDR3_DQS_DN(2)"
					( objectStatus "U5D1.DL82" )
				)
				( pin "DDR3_DQS_DN(3)"
					( objectStatus "U5D1.DV75" )
				)
				( pin "DDR3_DQS_DN(4)"
					( objectStatus "U5D1.EE38" )
				)
				( pin "DDR3_DQS_DN(5)"
					( objectStatus "U5D1.DV35" )
				)
				( pin "DDR3_DQS_DN(6)"
					( objectStatus "U5D1.DV29" )
				)
				( pin "DDR3_DQS_DN(7)"
					( objectStatus "U5D1.DV23" )
				)
				( pin "DDR3_DQS_DN(8)"
					( objectStatus "U5D1.DF67" )
				)
				( pin "DDR3_DQS_DN(9)"
					( objectStatus "U5D1.CR84" )
				)
				( pin "DDR3_DQS_DP(0)"
					( objectStatus "U5D1.CV85" )
				)
				( pin "DDR3_DQS_DP(10)"
					( objectStatus "U5D1.DL84" )
				)
				( pin "DDR3_DQS_DP(11)"
					( objectStatus "U5D1.DP79" )
				)
				( pin "DDR3_DQS_DP(12)"
					( objectStatus "U5D1.DM75" )
				)
				( pin "DDR3_DQS_DP(13)"
					( objectStatus "U5D1.DW38" )
				)
				( pin "DDR3_DQS_DP(14)"
					( objectStatus "U5D1.DM35" )
				)
				( pin "DDR3_DQS_DP(15)"
					( objectStatus "U5D1.DP29" )
				)
				( pin "DDR3_DQS_DP(16)"
					( objectStatus "U5D1.DP23" )
				)
				( pin "DDR3_DQS_DP(17)"
					( objectStatus "U5D1.CY67" )
				)
				( pin "DDR3_DQS_DP(1)"
					( objectStatus "U5D1.DP85" )
				)
				( pin "DDR3_DQS_DP(2)"
					( objectStatus "U5D1.DM81" )
				)
				( pin "DDR3_DQS_DP(3)"
					( objectStatus "U5D1.DT75" )
				)
				( pin "DDR3_DQS_DP(4)"
					( objectStatus "U5D1.EC38" )
				)
				( pin "DDR3_DQS_DP(5)"
					( objectStatus "U5D1.DT35" )
				)
				( pin "DDR3_DQS_DP(6)"
					( objectStatus "U5D1.DT29" )
				)
				( pin "DDR3_DQS_DP(7)"
					( objectStatus "U5D1.DT23" )
				)
				( pin "DDR3_DQS_DP(8)"
					( objectStatus "U5D1.DD67" )
				)
				( pin "DDR3_DQS_DP(9)"
					( objectStatus "U5D1.CP85" )
				)
				( pin "DDR3_ECC(0)"
					( objectStatus "U5D1.DA68" )
				)
				( pin "DDR3_ECC(1)"
					( objectStatus "U5D1.DE68" )
				)
				( pin "DDR3_ECC(2)"
					( objectStatus "U5D1.DB65" )
				)
				( pin "DDR3_ECC(3)"
					( objectStatus "U5D1.DD65" )
				)
				( pin "DDR3_ECC(4)"
					( objectStatus "U5D1.DB69" )
				)
				( pin "DDR3_ECC(5)"
					( objectStatus "U5D1.DD69" )
				)
				( pin "DDR3_ECC(6)"
					( objectStatus "U5D1.DA66" )
				)
				( pin "DDR3_ECC(7)"
					( objectStatus "U5D1.DE66" )
				)
				( pin "DDR3_MA(0)"
					( objectStatus "U5D1.EB53" )
				)
				( pin "DDR3_MA(10)"
					( objectStatus "U5D1.DW54" )
				)
				( pin "DDR3_MA(11)"
					( objectStatus "U5D1.EB61" )
				)
				( pin "DDR3_MA(12)"
					( objectStatus "U5D1.DT63" )
				)
				( pin "DDR3_MA(13)"
					( objectStatus "U5D1.DW48" )
				)
				( pin "DDR3_MA(14)"
					( objectStatus "U5D1.ED51" )
				)
				( pin "DDR3_MA(15)"
					( objectStatus "U5D1.DV49" )
				)
				( pin "DDR3_MA(16)"
					( objectStatus "U5D1.EA52" )
				)
				( pin "DDR3_MA(17)"
					( objectStatus "U5D1.EA46" )
				)
				( pin "DDR3_MA(1)"
					( objectStatus "U5D1.ED57" )
				)
				( pin "DDR3_MA(2)"
					( objectStatus "U5D1.EE58" )
				)
				( pin "DDR3_MA(3)"
					( objectStatus "U5D1.EB57" )
				)
				( pin "DDR3_MA(4)"
					( objectStatus "U5D1.ED59" )
				)
				( pin "DDR3_MA(5)"
					( objectStatus "U5D1.EA58" )
				)
				( pin "DDR3_MA(6)"
					( objectStatus "U5D1.EE60" )
				)
				( pin "DDR3_MA(7)"
					( objectStatus "U5D1.EA60" )
				)
				( pin "DDR3_MA(8)"
					( objectStatus "U5D1.EB59" )
				)
				( pin "DDR3_MA(9)"
					( objectStatus "U5D1.EF61" )
				)
				( pin "DDR3_ODT(0)"
					( objectStatus "U5D1.EE50" )
				)
				( pin "DDR3_ODT(1)"
					( objectStatus "U5D1.EE48" )
				)
				( pin "DDR3_ODT(2)"
					( objectStatus "U5D1.EA50" )
				)
				( pin "DDR3_ODT(3)"
					( objectStatus "U5D1.EA48" )
				)
				( pin "DDR3_PAR"
					( objectStatus "U5D1.ED53" )
				)
			)
			( gate "@baseboard_fab2_lib.baseboard_fab2(sch_1):page27_i172"
				( objectStatus "F95" )
				( pin "DDR4_ACT_N"
					( objectStatus "U5D1.DR62" )
				)
				( pin "DDR4_BA(0)"
					( objectStatus "U5D1.DM53" )
				)
				( pin "DDR4_BA(1)"
					( objectStatus "U5D1.DV55" )
				)
				( pin "DDR4_BG(0)"
					( objectStatus "U5D1.DJ62" )
				)
				( pin "DDR4_BG(1)"
					( objectStatus "U5D1.DM61" )
				)
				( pin "DDR4_CID(2)"
					( objectStatus "U5D1.DT47" )
				)
				( pin "DDR4_CKE(0)"
					( objectStatus "U5D1.DM63" )
				)
				( pin "DDR4_CKE(1)"
					( objectStatus "U5D1.DN64" )
				)
				( pin "DDR4_CKE(2)"
					( objectStatus "U5D1.DL64" )
				)
				( pin "DDR4_CKE(3)"
					( objectStatus "U5D1.DR64" )
				)
				( pin "DDR4_CS_N(0)"
					( objectStatus "U5D1.DV51" )
				)
				( pin "DDR4_CS_N(1)"
					( objectStatus "U5D1.DN50" )
				)
				( pin "DDR4_CS_N(2)"
					( objectStatus "U5D1.DR46" )
				)
				( pin "DDR4_CS_N(3)"
					( objectStatus "U5D1.DK47" )
				)
				( pin "DDR4_CS_N(4)"
					( objectStatus "U5D1.DW50" )
				)
				( pin "DDR4_CS_N(5)"
					( objectStatus "U5D1.DM49" )
				)
				( pin "DDR4_CS_N(6)"
					( objectStatus "U5D1.DT45" )
				)
				( pin "DDR4_CS_N(7)"
					( objectStatus "U5D1.DN46" )
				)
				( pin "DDR4_DQ(0)"
					( objectStatus "U5D1.CM79" )
				)
				( pin "DDR4_DQ(10)"
					( objectStatus "U5D1.DE80" )
				)
				( pin "DDR4_DQ(11)"
					( objectStatus "U5D1.DF81" )
				)
				( pin "DDR4_DQ(12)"
					( objectStatus "U5D1.CY79" )
				)
				( pin "DDR4_DQ(13)"
					( objectStatus "U5D1.CW80" )
				)
				( pin "DDR4_DQ(14)"
					( objectStatus "U5D1.DC82" )
				)
				( pin "DDR4_DQ(15)"
					( objectStatus "U5D1.DE82" )
				)
				( pin "DDR4_DQ(16)"
					( objectStatus "U5D1.DW80" )
				)
				( pin "DDR4_DQ(17)"
					( objectStatus "U5D1.EC80" )
				)
				( pin "DDR4_DQ(18)"
					( objectStatus "U5D1.DY77" )
				)
				( pin "DDR4_DQ(19)"
					( objectStatus "U5D1.EB77" )
				)
				( pin "DDR4_DQ(1)"
					( objectStatus "U5D1.CK81" )
				)
				( pin "DDR4_DQ(20)"
					( objectStatus "U5D1.DY81" )
				)
				( pin "DDR4_DQ(21)"
					( objectStatus "U5D1.EB81" )
				)
				( pin "DDR4_DQ(22)"
					( objectStatus "U5D1.DW78" )
				)
				( pin "DDR4_DQ(23)"
					( objectStatus "U5D1.EC78" )
				)
				( pin "DDR4_DQ(24)"
					( objectStatus "U5D1.ED75" )
				)
				( pin "DDR4_DQ(25)"
					( objectStatus "U5D1.EE74" )
				)
				( pin "DDR4_DQ(26)"
					( objectStatus "U5D1.EB71" )
				)
				( pin "DDR4_DQ(27)"
					( objectStatus "U5D1.ED71" )
				)
				( pin "DDR4_DQ(28)"
					( objectStatus "U5D1.EA74" )
				)
				( pin "DDR4_DQ(29)"
					( objectStatus "U5D1.EB75" )
				)
				( pin "DDR4_DQ(2)"
					( objectStatus "U5D1.CT81" )
				)
				( pin "DDR4_DQ(30)"
					( objectStatus "U5D1.EA72" )
				)
				( pin "DDR4_DQ(31)"
					( objectStatus "U5D1.EE72" )
				)
				( pin "DDR4_DQ(32)"
					( objectStatus "U5D1.DU42" )
				)
				( pin "DDR4_DQ(33)"
					( objectStatus "U5D1.DW42" )
				)
				( pin "DDR4_DQ(34)"
					( objectStatus "U5D1.DP39" )
				)
				( pin "DDR4_DQ(35)"
					( objectStatus "U5D1.DT39" )
				)
				( pin "DDR4_DQ(36)"
					( objectStatus "U5D1.DL42" )
				)
				( pin "DDR4_DQ(37)"
					( objectStatus "U5D1.DN42" )
				)
				( pin "DDR4_DQ(38)"
					( objectStatus "U5D1.DN40" )
				)
				( pin "DDR4_DQ(39)"
					( objectStatus "U5D1.DU40" )
				)
				( pin "DDR4_DQ(3)"
					( objectStatus "U5D1.CR82" )
				)
				( pin "DDR4_DQ(40)"
					( objectStatus "U5D1.EC34" )
				)
				( pin "DDR4_DQ(41)"
					( objectStatus "U5D1.ED33" )
				)
				( pin "DDR4_DQ(42)"
					( objectStatus "U5D1.EA30" )
				)
				( pin "DDR4_DQ(43)"
					( objectStatus "U5D1.EC30" )
				)
				( pin "DDR4_DQ(44)"
					( objectStatus "U5D1.DY33" )
				)
				( pin "DDR4_DQ(45)"
					( objectStatus "U5D1.EA34" )
				)
				( pin "DDR4_DQ(46)"
					( objectStatus "U5D1.DY31" )
				)
				( pin "DDR4_DQ(47)"
					( objectStatus "U5D1.ED31" )
				)
				( pin "DDR4_DQ(48)"
					( objectStatus "U5D1.EC28" )
				)
				( pin "DDR4_DQ(49)"
					( objectStatus "U5D1.ED27" )
				)
				( pin "DDR4_DQ(4)"
					( objectStatus "U5D1.CK79" )
				)
				( pin "DDR4_DQ(50)"
					( objectStatus "U5D1.EA24" )
				)
				( pin "DDR4_DQ(51)"
					( objectStatus "U5D1.EC24" )
				)
				( pin "DDR4_DQ(52)"
					( objectStatus "U5D1.DY27" )
				)
				( pin "DDR4_DQ(53)"
					( objectStatus "U5D1.EA28" )
				)
				( pin "DDR4_DQ(54)"
					( objectStatus "U5D1.DY25" )
				)
				( pin "DDR4_DQ(55)"
					( objectStatus "U5D1.ED25" )
				)
				( pin "DDR4_DQ(56)"
					( objectStatus "U5D1.DF27" )
				)
				( pin "DDR4_DQ(57)"
					( objectStatus "U5D1.DK27" )
				)
				( pin "DDR4_DQ(58)"
					( objectStatus "U5D1.DD25" )
				)
				( pin "DDR4_DQ(59)"
					( objectStatus "U5D1.DJ24" )
				)
				( pin "DDR4_DQ(5)"
					( objectStatus "U5D1.CJ80" )
				)
				( pin "DDR4_DQ(60)"
					( objectStatus "U5D1.DG28" )
				)
				( pin "DDR4_DQ(61)"
					( objectStatus "U5D1.DJ28" )
				)
				( pin "DDR4_DQ(62)"
					( objectStatus "U5D1.DF25" )
				)
				( pin "DDR4_DQ(63)"
					( objectStatus "U5D1.DK25" )
				)
				( pin "DDR4_DQ(6)"
					( objectStatus "U5D1.CR80" )
				)
				( pin "DDR4_DQ(7)"
					( objectStatus "U5D1.CN82" )
				)
				( pin "DDR4_DQ(8)"
					( objectStatus "U5D1.DB79" )
				)
				( pin "DDR4_DQ(9)"
					( objectStatus "U5D1.CY81" )
				)
				( pin "DDR4_DQS_DN(0)"
					( objectStatus "U5D1.CL82" )
				)
				( pin "DDR4_DQS_DN(10)"
					( objectStatus "U5D1.DC80" )
				)
				( pin "DDR4_DQS_DN(11)"
					( objectStatus "U5D1.DY79" )
				)
				( pin "DDR4_DQS_DN(12)"
					( objectStatus "U5D1.EB73" )
				)
				( pin "DDR4_DQS_DN(13)"
					( objectStatus "U5D1.DP41" )
				)
				( pin "DDR4_DQS_DN(14)"
					( objectStatus "U5D1.EA32" )
				)
				( pin "DDR4_DQS_DN(15)"
					( objectStatus "U5D1.EA26" )
				)
				( pin "DDR4_DQS_DN(16)"
					( objectStatus "U5D1.DG26" )
				)
				( pin "DDR4_DQS_DN(17)"
					( objectStatus "U5D1.DV67" )
				)
				( pin "DDR4_DQS_DN(1)"
					( objectStatus "U5D1.DA82" )
				)
				( pin "DDR4_DQS_DN(2)"
					( objectStatus "U5D1.ED79" )
				)
				( pin "DDR4_DQS_DN(3)"
					( objectStatus "U5D1.EF73" )
				)
				( pin "DDR4_DQS_DN(4)"
					( objectStatus "U5D1.DV41" )
				)
				( pin "DDR4_DQS_DN(5)"
					( objectStatus "U5D1.EE32" )
				)
				( pin "DDR4_DQS_DN(6)"
					( objectStatus "U5D1.EE26" )
				)
				( pin "DDR4_DQS_DN(7)"
					( objectStatus "U5D1.DL26" )
				)
				( pin "DDR4_DQS_DN(8)"
					( objectStatus "U5D1.EB67" )
				)
				( pin "DDR4_DQS_DN(9)"
					( objectStatus "U5D1.CN80" )
				)
				( pin "DDR4_DQS_DP(0)"
					( objectStatus "U5D1.CM81" )
				)
				( pin "DDR4_DQS_DP(10)"
					( objectStatus "U5D1.DD79" )
				)
				( pin "DDR4_DQS_DP(11)"
					( objectStatus "U5D1.DV79" )
				)
				( pin "DDR4_DQS_DP(12)"
					( objectStatus "U5D1.DY73" )
				)
				( pin "DDR4_DQS_DP(13)"
					( objectStatus "U5D1.DM41" )
				)
				( pin "DDR4_DQS_DP(14)"
					( objectStatus "U5D1.DW32" )
				)
				( pin "DDR4_DQS_DP(15)"
					( objectStatus "U5D1.DW26" )
				)
				( pin "DDR4_DQS_DP(16)"
					( objectStatus "U5D1.DE26" )
				)
				( pin "DDR4_DQS_DP(17)"
					( objectStatus "U5D1.DT67" )
				)
				( pin "DDR4_DQS_DP(1)"
					( objectStatus "U5D1.DB81" )
				)
				( pin "DDR4_DQS_DP(2)"
					( objectStatus "U5D1.EB79" )
				)
				( pin "DDR4_DQS_DP(3)"
					( objectStatus "U5D1.ED73" )
				)
				( pin "DDR4_DQS_DP(4)"
					( objectStatus "U5D1.DT41" )
				)
				( pin "DDR4_DQS_DP(5)"
					( objectStatus "U5D1.EC32" )
				)
				( pin "DDR4_DQS_DP(6)"
					( objectStatus "U5D1.EC26" )
				)
				( pin "DDR4_DQS_DP(7)"
					( objectStatus "U5D1.DJ26" )
				)
				( pin "DDR4_DQS_DP(8)"
					( objectStatus "U5D1.DY67" )
				)
				( pin "DDR4_DQS_DP(9)"
					( objectStatus "U5D1.CP79" )
				)
				( pin "DDR4_ECC(0)"
					( objectStatus "U5D1.DY69" )
				)
				( pin "DDR4_ECC(1)"
					( objectStatus "U5D1.EA68" )
				)
				( pin "DDR4_ECC(2)"
					( objectStatus "U5D1.DV65" )
				)
				( pin "DDR4_ECC(3)"
					( objectStatus "U5D1.DY65" )
				)
				( pin "DDR4_ECC(4)"
					( objectStatus "U5D1.DU68" )
				)
				( pin "DDR4_ECC(5)"
					( objectStatus "U5D1.DV69" )
				)
				( pin "DDR4_ECC(6)"
					( objectStatus "U5D1.DU66" )
				)
				( pin "DDR4_ECC(7)"
					( objectStatus "U5D1.EA66" )
				)
				( pin "DDR4_MA(0)"
					( objectStatus "U5D1.DW52" )
				)
				( pin "DDR4_MA(10)"
					( objectStatus "U5D1.DT55" )
				)
				( pin "DDR4_MA(11)"
					( objectStatus "U5D1.DR60" )
				)
				( pin "DDR4_MA(12)"
					( objectStatus "U5D1.DN60" )
				)
				( pin "DDR4_MA(13)"
					( objectStatus "U5D1.DT51" )
				)
				( pin "DDR4_MA(14)"
					( objectStatus "U5D1.DM51" )
				)
				( pin "DDR4_MA(15)"
					( objectStatus "U5D1.DR52" )
				)
				( pin "DDR4_MA(16)"
					( objectStatus "U5D1.DN52" )
				)
				( pin "DDR4_MA(17)"
					( objectStatus "U5D1.DR48" )
				)
				( pin "DDR4_MA(1)"
					( objectStatus "U5D1.DW58" )
				)
				( pin "DDR4_MA(2)"
					( objectStatus "U5D1.DV57" )
				)
				( pin "DDR4_MA(3)"
					( objectStatus "U5D1.DR58" )
				)
				( pin "DDR4_MA(4)"
					( objectStatus "U5D1.DT59" )
				)
				( pin "DDR4_MA(5)"
					( objectStatus "U5D1.DN58" )
				)
				( pin "DDR4_MA(6)"
					( objectStatus "U5D1.DM59" )
				)
				( pin "DDR4_MA(7)"
					( objectStatus "U5D1.DK61" )
				)
				( pin "DDR4_MA(8)"
					( objectStatus "U5D1.DJ60" )
				)
				( pin "DDR4_MA(9)"
					( objectStatus "U5D1.DV59" )
				)
				( pin "DDR4_ODT(0)"
					( objectStatus "U5D1.DR50" )
				)
				( pin "DDR4_ODT(1)"
					( objectStatus "U5D1.DN48" )
				)
				( pin "DDR4_ODT(2)"
					( objectStatus "U5D1.DT49" )
				)
				( pin "DDR4_ODT(3)"
					( objectStatus "U5D1.DM47" )
				)
				( pin "DDR4_PAR"
					( objectStatus "U5D1.DV53" )
				)
			)
			( gate "@baseboard_fab2_lib.baseboard_fab2(sch_1):page28_i172"
				( objectStatus "F94" )
				( pin "DDR5_ACT_N"
					( objectStatus "U5D1.DC62" )
				)
				( pin "DDR5_BA(0)"
					( objectStatus "U5D1.DJ52" )
				)
				( pin "DDR5_BA(1)"
					( objectStatus "U5D1.DC56" )
				)
				( pin "DDR5_BG(0)"
					( objectStatus "U5D1.DA62" )
				)
				( pin "DDR5_BG(1)"
					( objectStatus "U5D1.DF61" )
				)
				( pin "DDR5_CID(2)"
					( objectStatus "U5D1.DF45" )
				)
				( pin "DDR5_CKE(0)"
					( objectStatus "U5D1.DG62" )
				)
				( pin "DDR5_CKE(1)"
					( objectStatus "U5D1.DD63" )
				)
				( pin "DDR5_CKE(2)"
					( objectStatus "U5D1.DK63" )
				)
				( pin "DDR5_CKE(3)"
					( objectStatus "U5D1.DF63" )
				)
				( pin "DDR5_CS_N(0)"
					( objectStatus "U5D1.DK51" )
				)
				( pin "DDR5_CS_N(1)"
					( objectStatus "U5D1.DF49" )
				)
				( pin "DDR5_CS_N(2)"
					( objectStatus "U5D1.DJ46" )
				)
				( pin "DDR5_CS_N(3)"
					( objectStatus "U5D1.DG46" )
				)
				( pin "DDR5_CS_N(4)"
					( objectStatus "U5D1.DF51" )
				)
				( pin "DDR5_CS_N(5)"
					( objectStatus "U5D1.DJ48" )
				)
				( pin "DDR5_CS_N(6)"
					( objectStatus "U5D1.DM45" )
				)
				( pin "DDR5_CS_N(7)"
					( objectStatus "U5D1.DK45" )
				)
				( pin "DDR5_DQ(0)"
					( objectStatus "U5D1.CR74" )
				)
				( pin "DDR5_DQ(10)"
					( objectStatus "U5D1.DH75" )
				)
				( pin "DDR5_DQ(11)"
					( objectStatus "U5D1.DJ76" )
				)
				( pin "DDR5_DQ(12)"
					( objectStatus "U5D1.DC74" )
				)
				( pin "DDR5_DQ(13)"
					( objectStatus "U5D1.DB75" )
				)
				( pin "DDR5_DQ(14)"
					( objectStatus "U5D1.DF77" )
				)
				( pin "DDR5_DQ(15)"
					( objectStatus "U5D1.DH77" )
				)
				( pin "DDR5_DQ(16)"
					( objectStatus "U5D1.DG70" )
				)
				( pin "DDR5_DQ(17)"
					( objectStatus "U5D1.DJ72" )
				)
				( pin "DDR5_DQ(18)"
					( objectStatus "U5D1.DM69" )
				)
				( pin "DDR5_DQ(19)"
					( objectStatus "U5D1.DN70" )
				)
				( pin "DDR5_DQ(1)"
					( objectStatus "U5D1.CN76" )
				)
				( pin "DDR5_DQ(20)"
					( objectStatus "U5D1.DF71" )
				)
				( pin "DDR5_DQ(21)"
					( objectStatus "U5D1.DG72" )
				)
				( pin "DDR5_DQ(22)"
					( objectStatus "U5D1.DK69" )
				)
				( pin "DDR5_DQ(23)"
					( objectStatus "U5D1.DM71" )
				)
				( pin "DDR5_DQ(24)"
					( objectStatus "U5D1.CN66" )
				)
				( pin "DDR5_DQ(25)"
					( objectStatus "U5D1.CU66" )
				)
				( pin "DDR5_DQ(26)"
					( objectStatus "U5D1.CP63" )
				)
				( pin "DDR5_DQ(27)"
					( objectStatus "U5D1.CT63" )
				)
				( pin "DDR5_DQ(28)"
					( objectStatus "U5D1.CP67" )
				)
				( pin "DDR5_DQ(29)"
					( objectStatus "U5D1.CT67" )
				)
				( pin "DDR5_DQ(2)"
					( objectStatus "U5D1.CW76" )
				)
				( pin "DDR5_DQ(30)"
					( objectStatus "U5D1.CN64" )
				)
				( pin "DDR5_DQ(31)"
					( objectStatus "U5D1.CU64" )
				)
				( pin "DDR5_DQ(32)"
					( objectStatus "U5D1.DD41" )
				)
				( pin "DDR5_DQ(33)"
					( objectStatus "U5D1.DG42" )
				)
				( pin "DDR5_DQ(34)"
					( objectStatus "U5D1.DE38" )
				)
				( pin "DDR5_DQ(35)"
					( objectStatus "U5D1.DG38" )
				)
				( pin "DDR5_DQ(36)"
					( objectStatus "U5D1.DA42" )
				)
				( pin "DDR5_DQ(37)"
					( objectStatus "U5D1.DE42" )
				)
				( pin "DDR5_DQ(38)"
					( objectStatus "U5D1.DD39" )
				)
				( pin "DDR5_DQ(39)"
					( objectStatus "U5D1.DH39" )
				)
				( pin "DDR5_DQ(3)"
					( objectStatus "U5D1.CV77" )
				)
				( pin "DDR5_DQ(40)"
					( objectStatus "U5D1.DF33" )
				)
				( pin "DDR5_DQ(41)"
					( objectStatus "U5D1.DK33" )
				)
				( pin "DDR5_DQ(42)"
					( objectStatus "U5D1.DG30" )
				)
				( pin "DDR5_DQ(43)"
					( objectStatus "U5D1.DJ30" )
				)
				( pin "DDR5_DQ(44)"
					( objectStatus "U5D1.DG34" )
				)
				( pin "DDR5_DQ(45)"
					( objectStatus "U5D1.DJ34" )
				)
				( pin "DDR5_DQ(46)"
					( objectStatus "U5D1.DF31" )
				)
				( pin "DDR5_DQ(47)"
					( objectStatus "U5D1.DK31" )
				)
				( pin "DDR5_DQ(48)"
					( objectStatus "U5D1.CW36" )
				)
				( pin "DDR5_DQ(49)"
					( objectStatus "U5D1.DC36" )
				)
				( pin "DDR5_DQ(4)"
					( objectStatus "U5D1.CN74" )
				)
				( pin "DDR5_DQ(50)"
					( objectStatus "U5D1.CY33" )
				)
				( pin "DDR5_DQ(51)"
					( objectStatus "U5D1.DB33" )
				)
				( pin "DDR5_DQ(52)"
					( objectStatus "U5D1.CY37" )
				)
				( pin "DDR5_DQ(53)"
					( objectStatus "U5D1.DB37" )
				)
				( pin "DDR5_DQ(54)"
					( objectStatus "U5D1.CW34" )
				)
				( pin "DDR5_DQ(55)"
					( objectStatus "U5D1.DC34" )
				)
				( pin "DDR5_DQ(56)"
					( objectStatus "U5D1.CW30" )
				)
				( pin "DDR5_DQ(57)"
					( objectStatus "U5D1.DC30" )
				)
				( pin "DDR5_DQ(58)"
					( objectStatus "U5D1.CY27" )
				)
				( pin "DDR5_DQ(59)"
					( objectStatus "U5D1.DB27" )
				)
				( pin "DDR5_DQ(5)"
					( objectStatus "U5D1.CM75" )
				)
				( pin "DDR5_DQ(60)"
					( objectStatus "U5D1.CY31" )
				)
				( pin "DDR5_DQ(61)"
					( objectStatus "U5D1.DB31" )
				)
				( pin "DDR5_DQ(62)"
					( objectStatus "U5D1.CW28" )
				)
				( pin "DDR5_DQ(63)"
					( objectStatus "U5D1.DC28" )
				)
				( pin "DDR5_DQ(6)"
					( objectStatus "U5D1.CV75" )
				)
				( pin "DDR5_DQ(7)"
					( objectStatus "U5D1.CT77" )
				)
				( pin "DDR5_DQ(8)"
					( objectStatus "U5D1.DE74" )
				)
				( pin "DDR5_DQ(9)"
					( objectStatus "U5D1.DC76" )
				)
				( pin "DDR5_DQS_DN(0)"
					( objectStatus "U5D1.CP77" )
				)
				( pin "DDR5_DQS_DN(10)"
					( objectStatus "U5D1.DF75" )
				)
				( pin "DDR5_DQS_DN(11)"
					( objectStatus "U5D1.DJ70" )
				)
				( pin "DDR5_DQS_DN(12)"
					( objectStatus "U5D1.CP65" )
				)
				( pin "DDR5_DQS_DN(13)"
					( objectStatus "U5D1.DE40" )
				)
				( pin "DDR5_DQS_DN(14)"
					( objectStatus "U5D1.DG32" )
				)
				( pin "DDR5_DQS_DN(15)"
					( objectStatus "U5D1.CY35" )
				)
				( pin "DDR5_DQS_DN(16)"
					( objectStatus "U5D1.CY29" )
				)
				( pin "DDR5_DQS_DN(17)"
					( objectStatus "U5D1.CJ70" )
				)
				( pin "DDR5_DQS_DN(1)"
					( objectStatus "U5D1.DD77" )
				)
				( pin "DDR5_DQS_DN(2)"
					( objectStatus "U5D1.DL72" )
				)
				( pin "DDR5_DQS_DN(3)"
					( objectStatus "U5D1.CV65" )
				)
				( pin "DDR5_DQS_DN(4)"
					( objectStatus "U5D1.DG40" )
				)
				( pin "DDR5_DQS_DN(5)"
					( objectStatus "U5D1.DL32" )
				)
				( pin "DDR5_DQS_DN(6)"
					( objectStatus "U5D1.DD35" )
				)
				( pin "DDR5_DQS_DN(7)"
					( objectStatus "U5D1.DD29" )
				)
				( pin "DDR5_DQS_DN(8)"
					( objectStatus "U5D1.CN70" )
				)
				( pin "DDR5_DQS_DN(9)"
					( objectStatus "U5D1.CT75" )
				)
				( pin "DDR5_DQS_DP(0)"
					( objectStatus "U5D1.CR76" )
				)
				( pin "DDR5_DQS_DP(10)"
					( objectStatus "U5D1.DG74" )
				)
				( pin "DDR5_DQS_DP(11)"
					( objectStatus "U5D1.DH69" )
				)
				( pin "DDR5_DQS_DP(12)"
					( objectStatus "U5D1.CM65" )
				)
				( pin "DDR5_DQS_DP(13)"
					( objectStatus "U5D1.DC40" )
				)
				( pin "DDR5_DQS_DP(14)"
					( objectStatus "U5D1.DE32" )
				)
				( pin "DDR5_DQS_DP(15)"
					( objectStatus "U5D1.CV35" )
				)
				( pin "DDR5_DQS_DP(16)"
					( objectStatus "U5D1.CV29" )
				)
				( pin "DDR5_DQS_DP(17)"
					( objectStatus "U5D1.CG70" )
				)
				( pin "DDR5_DQS_DP(1)"
					( objectStatus "U5D1.DE76" )
				)
				( pin "DDR5_DQS_DP(2)"
					( objectStatus "U5D1.DK71" )
				)
				( pin "DDR5_DQS_DP(3)"
					( objectStatus "U5D1.CT65" )
				)
				( pin "DDR5_DQS_DP(4)"
					( objectStatus "U5D1.DJ40" )
				)
				( pin "DDR5_DQS_DP(5)"
					( objectStatus "U5D1.DJ32" )
				)
				( pin "DDR5_DQS_DP(6)"
					( objectStatus "U5D1.DB35" )
				)
				( pin "DDR5_DQS_DP(7)"
					( objectStatus "U5D1.DB29" )
				)
				( pin "DDR5_DQS_DP(8)"
					( objectStatus "U5D1.CL70" )
				)
				( pin "DDR5_DQS_DP(9)"
					( objectStatus "U5D1.CU74" )
				)
				( pin "DDR5_ECC(0)"
					( objectStatus "U5D1.CH71" )
				)
				( pin "DDR5_ECC(1)"
					( objectStatus "U5D1.CM71" )
				)
				( pin "DDR5_ECC(2)"
					( objectStatus "U5D1.CJ68" )
				)
				( pin "DDR5_ECC(3)"
					( objectStatus "U5D1.CL68" )
				)
				( pin "DDR5_ECC(4)"
					( objectStatus "U5D1.CJ72" )
				)
				( pin "DDR5_ECC(5)"
					( objectStatus "U5D1.CL72" )
				)
				( pin "DDR5_ECC(6)"
					( objectStatus "U5D1.CH69" )
				)
				( pin "DDR5_ECC(7)"
					( objectStatus "U5D1.CM69" )
				)
				( pin "DDR5_MA(0)"
					( objectStatus "U5D1.DF53" )
				)
				( pin "DDR5_MA(10)"
					( objectStatus "U5D1.DD55" )
				)
				( pin "DDR5_MA(11)"
					( objectStatus "U5D1.DA60" )
				)
				( pin "DDR5_MA(12)"
					( objectStatus "U5D1.DG60" )
				)
				( pin "DDR5_MA(13)"
					( objectStatus "U5D1.DD53" )
				)
				( pin "DDR5_MA(14)"
					( objectStatus "U5D1.DJ50" )
				)
				( pin "DDR5_MA(15)"
					( objectStatus "U5D1.DC54" )
				)
				( pin "DDR5_MA(16)"
					( objectStatus "U5D1.DG52" )
				)
				( pin "DDR5_MA(17)"
					( objectStatus "U5D1.DE46" )
				)
				( pin "DDR5_MA(1)"
					( objectStatus "U5D1.DC58" )
				)
				( pin "DDR5_MA(2)"
					( objectStatus "U5D1.DD57" )
				)
				( pin "DDR5_MA(3)"
					( objectStatus "U5D1.DG58" )
				)
				( pin "DDR5_MA(4)"
					( objectStatus "U5D1.DJ58" )
				)
				( pin "DDR5_MA(5)"
					( objectStatus "U5D1.DF59" )
				)
				( pin "DDR5_MA(6)"
					( objectStatus "U5D1.DK59" )
				)
				( pin "DDR5_MA(7)"
					( objectStatus "U5D1.DC60" )
				)
				( pin "DDR5_MA(8)"
					( objectStatus "U5D1.DD59" )
				)
				( pin "DDR5_MA(9)"
					( objectStatus "U5D1.DA58" )
				)
				( pin "DDR5_ODT(0)"
					( objectStatus "U5D1.DG50" )
				)
				( pin "DDR5_ODT(1)"
					( objectStatus "U5D1.DG48" )
				)
				( pin "DDR5_ODT(2)"
					( objectStatus "U5D1.DK49" )
				)
				( pin "DDR5_ODT(3)"
					( objectStatus "U5D1.DF47" )
				)
				( pin "DDR5_PAR"
					( objectStatus "U5D1.DK53" )
				)
			)
			( gate "@baseboard_fab2_lib.baseboard_fab2(sch_1):page29_i61"
				( objectStatus "F93" )
				( pin "CD_PE_REFCLK_DN"
					( objectStatus "U5D1.BU24" )
				)
				( pin "CD_PE_REFCLK_DP"
					( objectStatus "U5D1.BW24" )
				)
				( pin "DMI_RX_DN(0)"
					( objectStatus "U5D1.CK9" )
				)
				( pin "DMI_RX_DN(1)"
					( objectStatus "U5D1.CM11" )
				)
				( pin "DMI_RX_DN(2)"
					( objectStatus "U5D1.CR12" )
				)
				( pin "DMI_RX_DN(3)"
					( objectStatus "U5D1.CT11" )
				)
				( pin "DMI_RX_DP(0)"
					( objectStatus "U5D1.CL10" )
				)
				( pin "DMI_RX_DP(1)"
					( objectStatus "U5D1.CN10" )
				)
				( pin "DMI_RX_DP(2)"
					( objectStatus "U5D1.CP11" )
				)
				( pin "DMI_RX_DP(3)"
					( objectStatus "U5D1.CV11" )
				)
				( pin "DMI_TX_DN(0)"
					( objectStatus "U5D1.CG4" )
				)
				( pin "DMI_TX_DN(1)"
					( objectStatus "U5D1.CJ4" )
				)
				( pin "DMI_TX_DN(2)"
					( objectStatus "U5D1.CN4" )
				)
				( pin "DMI_TX_DN(3)"
					( objectStatus "U5D1.CP5" )
				)
				( pin "DMI_TX_DP(0)"
					( objectStatus "U5D1.CH5" )
				)
				( pin "DMI_TX_DP(1)"
					( objectStatus "U5D1.CL4" )
				)
				( pin "DMI_TX_DP(2)"
					( objectStatus "U5D1.CM3" )
				)
				( pin "DMI_TX_DP(3)"
					( objectStatus "U5D1.CR4" )
				)
			)
			( gate "@baseboard_fab2_lib.baseboard_fab2(sch_1):page30_i84"
				( objectStatus "F92" )
				( pin "PE1_RX_DN(0)"
					( objectStatus "U5D1.CW8" )
				)
				( pin "PE1_RX_DN(10)"
					( objectStatus "U5D1.DT11" )
				)
				( pin "PE1_RX_DN(11)"
					( objectStatus "U5D1.DT13" )
				)
				( pin "PE1_RX_DN(12)"
					( objectStatus "U5D1.DV13" )
				)
				( pin "PE1_RX_DN(13)"
					( objectStatus "U5D1.DW14" )
				)
				( pin "PE1_RX_DN(14)"
					( objectStatus "U5D1.DY15" )
				)
				( pin "PE1_RX_DN(15)"
					( objectStatus "U5D1.DU16" )
				)
				( pin "PE1_RX_DN(1)"
					( objectStatus "U5D1.DA8" )
				)
				( pin "PE1_RX_DN(2)"
					( objectStatus "U5D1.DC8" )
				)
				( pin "PE1_RX_DN(3)"
					( objectStatus "U5D1.DC10" )
				)
				( pin "PE1_RX_DN(4)"
					( objectStatus "U5D1.DE10" )
				)
				( pin "PE1_RX_DN(5)"
					( objectStatus "U5D1.DH9" )
				)
				( pin "PE1_RX_DN(6)"
					( objectStatus "U5D1.DK9" )
				)
				( pin "PE1_RX_DN(7)"
					( objectStatus "U5D1.DM9" )
				)
				( pin "PE1_RX_DN(8)"
					( objectStatus "U5D1.DM11" )
				)
				( pin "PE1_RX_DN(9)"
					( objectStatus "U5D1.DP11" )
				)
				( pin "PE1_RX_DP(0)"
					( objectStatus "U5D1.CU8" )
				)
				( pin "PE1_RX_DP(10)"
					( objectStatus "U5D1.DR12" )
				)
				( pin "PE1_RX_DP(11)"
					( objectStatus "U5D1.DP13" )
				)
				( pin "PE1_RX_DP(12)"
					( objectStatus "U5D1.DU12" )
				)
				( pin "PE1_RX_DP(13)"
					( objectStatus "U5D1.DY13" )
				)
				( pin "PE1_RX_DP(14)"
					( objectStatus "U5D1.DV15" )
				)
				( pin "PE1_RX_DP(15)"
					( objectStatus "U5D1.DT15" )
				)
				( pin "PE1_RX_DP(1)"
					( objectStatus "U5D1.CY7" )
				)
				( pin "PE1_RX_DP(2)"
					( objectStatus "U5D1.DB9" )
				)
				( pin "PE1_RX_DP(3)"
					( objectStatus "U5D1.DA10" )
				)
				( pin "PE1_RX_DP(4)"
					( objectStatus "U5D1.DD9" )
				)
				( pin "PE1_RX_DP(5)"
					( objectStatus "U5D1.DF9" )
				)
				( pin "PE1_RX_DP(6)"
					( objectStatus "U5D1.DJ8" )
				)
				( pin "PE1_RX_DP(7)"
					( objectStatus "U5D1.DL10" )
				)
				( pin "PE1_RX_DP(8)"
					( objectStatus "U5D1.DK11" )
				)
				( pin "PE1_RX_DP(9)"
					( objectStatus "U5D1.DN10" )
				)
				( pin "PE1_TX_DN(0)"
					( objectStatus "U5D1.DA2" )
				)
				( pin "PE1_TX_DN(10)"
					( objectStatus "U5D1.DW4" )
				)
				( pin "PE1_TX_DN(11)"
					( objectStatus "U5D1.DU6" )
				)
				( pin "PE1_TX_DN(12)"
					( objectStatus "U5D1.DV7" )
				)
				( pin "PE1_TX_DN(13)"
					( objectStatus "U5D1.DY7" )
				)
				( pin "PE1_TX_DN(14)"
					( objectStatus "U5D1.EA8" )
				)
				( pin "PE1_TX_DN(15)"
					( objectStatus "U5D1.ED9" )
				)
				( pin "PE1_TX_DN(1)"
					( objectStatus "U5D1.DC2" )
				)
				( pin "PE1_TX_DN(2)"
					( objectStatus "U5D1.DE2" )
				)
				( pin "PE1_TX_DN(3)"
					( objectStatus "U5D1.DE4" )
				)
				( pin "PE1_TX_DN(4)"
					( objectStatus "U5D1.DG4" )
				)
				( pin "PE1_TX_DN(5)"
					( objectStatus "U5D1.DK3" )
				)
				( pin "PE1_TX_DN(6)"
					( objectStatus "U5D1.DM3" )
				)
				( pin "PE1_TX_DN(7)"
					( objectStatus "U5D1.DN4" )
				)
				( pin "PE1_TX_DN(8)"
					( objectStatus "U5D1.DT5" )
				)
				( pin "PE1_TX_DN(9)"
					( objectStatus "U5D1.DV3" )
				)
				( pin "PE1_TX_DP(0)"
					( objectStatus "U5D1.CW2" )
				)
				( pin "PE1_TX_DP(10)"
					( objectStatus "U5D1.DU4" )
				)
				( pin "PE1_TX_DP(11)"
					( objectStatus "U5D1.DV5" )
				)
				( pin "PE1_TX_DP(12)"
					( objectStatus "U5D1.DT7" )
				)
				( pin "PE1_TX_DP(13)"
					( objectStatus "U5D1.DW6" )
				)
				( pin "PE1_TX_DP(14)"
					( objectStatus "U5D1.EB7" )
				)
				( pin "PE1_TX_DP(15)"
					( objectStatus "U5D1.EC8" )
				)
				( pin "PE1_TX_DP(1)"
					( objectStatus "U5D1.DB1" )
				)
				( pin "PE1_TX_DP(2)"
					( objectStatus "U5D1.DD3" )
				)
				( pin "PE1_TX_DP(3)"
					( objectStatus "U5D1.DC4" )
				)
				( pin "PE1_TX_DP(4)"
					( objectStatus "U5D1.DF3" )
				)
				( pin "PE1_TX_DP(5)"
					( objectStatus "U5D1.DH3" )
				)
				( pin "PE1_TX_DP(6)"
					( objectStatus "U5D1.DL2" )
				)
				( pin "PE1_TX_DP(7)"
					( objectStatus "U5D1.DP3" )
				)
				( pin "PE1_TX_DP(8)"
					( objectStatus "U5D1.DR4" )
				)
				( pin "PE1_TX_DP(9)"
					( objectStatus "U5D1.DU2" )
				)
			)
			( gate "@baseboard_fab2_lib.baseboard_fab2(sch_1):page31_i106"
				( objectStatus "F91" )
				( pin "PE2_RX_DN(0)"
					( objectStatus "U5D1.CT9" )
				)
				( pin "PE2_RX_DN(10)"
					( objectStatus "U5D1.BV7" )
				)
				( pin "PE2_RX_DN(11)"
					( objectStatus "U5D1.BT7" )
				)
				( pin "PE2_RX_DN(12)"
					( objectStatus "U5D1.BR8" )
				)
				( pin "PE2_RX_DN(13)"
					( objectStatus "U5D1.BN8" )
				)
				( pin "PE2_RX_DN(14)"
					( objectStatus "U5D1.BL8" )
				)
				( pin "PE2_RX_DN(15)"
					( objectStatus "U5D1.BK9" )
				)
				( pin "PE2_RX_DN(1)"
					( objectStatus "U5D1.CP9" )
				)
				( pin "PE2_RX_DN(2)"
					( objectStatus "U5D1.CP7" )
				)
				( pin "PE2_RX_DN(3)"
					( objectStatus "U5D1.CM7" )
				)
				( pin "PE2_RX_DN(4)"
					( objectStatus "U5D1.CK7" )
				)
				( pin "PE2_RX_DN(5)"
					( objectStatus "U5D1.CG8" )
				)
				( pin "PE2_RX_DN(6)"
					( objectStatus "U5D1.CE6" )
				)
				( pin "PE2_RX_DN(7)"
					( objectStatus "U5D1.CE8" )
				)
				( pin "PE2_RX_DN(8)"
					( objectStatus "U5D1.BY9" )
				)
				( pin "PE2_RX_DN(9)"
					( objectStatus "U5D1.BY7" )
				)
				( pin "PE2_RX_DP(0)"
					( objectStatus "U5D1.CR8" )
				)
				( pin "PE2_RX_DP(10)"
					( objectStatus "U5D1.BU6" )
				)
				( pin "PE2_RX_DP(11)"
					( objectStatus "U5D1.BP7" )
				)
				( pin "PE2_RX_DP(12)"
					( objectStatus "U5D1.BP9" )
				)
				( pin "PE2_RX_DP(13)"
					( objectStatus "U5D1.BM7" )
				)
				( pin "PE2_RX_DP(14)"
					( objectStatus "U5D1.BJ8" )
				)
				( pin "PE2_RX_DP(15)"
					( objectStatus "U5D1.BJ10" )
				)
				( pin "PE2_RX_DP(1)"
					( objectStatus "U5D1.CM9" )
				)
				( pin "PE2_RX_DP(2)"
					( objectStatus "U5D1.CN8" )
				)
				( pin "PE2_RX_DP(3)"
					( objectStatus "U5D1.CL6" )
				)
				( pin "PE2_RX_DP(4)"
					( objectStatus "U5D1.CH7" )
				)
				( pin "PE2_RX_DP(5)"
					( objectStatus "U5D1.CF7" )
				)
				( pin "PE2_RX_DP(6)"
					( objectStatus "U5D1.CD7" )
				)
				( pin "PE2_RX_DP(7)"
					( objectStatus "U5D1.CC8" )
				)
				( pin "PE2_RX_DP(8)"
					( objectStatus "U5D1.BV9" )
				)
				( pin "PE2_RX_DP(9)"
					( objectStatus "U5D1.BW8" )
				)
				( pin "PE2_TX_DN(0)"
					( objectStatus "U5D1.CY3" )
				)
				( pin "PE2_TX_DN(10)"
					( objectStatus "U5D1.CA4" )
				)
				( pin "PE2_TX_DN(11)"
					( objectStatus "U5D1.BW4" )
				)
				( pin "PE2_TX_DN(12)"
					( objectStatus "U5D1.BU4" )
				)
				( pin "PE2_TX_DN(13)"
					( objectStatus "U5D1.BP5" )
				)
				( pin "PE2_TX_DN(14)"
					( objectStatus "U5D1.BL4" )
				)
				( pin "PE2_TX_DN(15)"
					( objectStatus "U5D1.BM5" )
				)
				( pin "PE2_TX_DN(1)"
					( objectStatus "U5D1.CV3" )
				)
				( pin "PE2_TX_DN(2)"
					( objectStatus "U5D1.CT1" )
				)
				( pin "PE2_TX_DN(3)"
					( objectStatus "U5D1.CT3" )
				)
				( pin "PE2_TX_DN(4)"
					( objectStatus "U5D1.CM1" )
				)
				( pin "PE2_TX_DN(5)"
					( objectStatus "U5D1.CL2" )
				)
				( pin "PE2_TX_DN(6)"
					( objectStatus "U5D1.CG2" )
				)
				( pin "PE2_TX_DN(7)"
					( objectStatus "U5D1.CF3" )
				)
				( pin "PE2_TX_DN(8)"
					( objectStatus "U5D1.CC2" )
				)
				( pin "PE2_TX_DN(9)"
					( objectStatus "U5D1.CB3" )
				)
				( pin "PE2_TX_DP(0)"
					( objectStatus "U5D1.CW4" )
				)
				( pin "PE2_TX_DP(10)"
					( objectStatus "U5D1.BY5" )
				)
				( pin "PE2_TX_DP(11)"
					( objectStatus "U5D1.BV3" )
				)
				( pin "PE2_TX_DP(12)"
					( objectStatus "U5D1.BR4" )
				)
				( pin "PE2_TX_DP(13)"
					( objectStatus "U5D1.BN4" )
				)
				( pin "PE2_TX_DP(14)"
					( objectStatus "U5D1.BM3" )
				)
				( pin "PE2_TX_DP(15)"
					( objectStatus "U5D1.BK5" )
				)
				( pin "PE2_TX_DP(1)"
					( objectStatus "U5D1.CU2" )
				)
				( pin "PE2_TX_DP(2)"
					( objectStatus "U5D1.CR2" )
				)
				( pin "PE2_TX_DP(3)"
					( objectStatus "U5D1.CP3" )
				)
				( pin "PE2_TX_DP(4)"
					( objectStatus "U5D1.CK1" )
				)
				( pin "PE2_TX_DP(5)"
					( objectStatus "U5D1.CK3" )
				)
				( pin "PE2_TX_DP(6)"
					( objectStatus "U5D1.CE2" )
				)
				( pin "PE2_TX_DP(7)"
					( objectStatus "U5D1.CE4" )
				)
				( pin "PE2_TX_DP(8)"
					( objectStatus "U5D1.CD3" )
				)
				( pin "PE2_TX_DP(9)"
					( objectStatus "U5D1.BY3" )
				)
			)
			( gate "@baseboard_fab2_lib.baseboard_fab2(sch_1):page32_i89"
				( objectStatus "F90" )
				( pin "PE3_RX_DN(0)"
					( objectStatus "U5D1.EA18" )
				)
				( pin "PE3_RX_DN(10)"
					( objectStatus "U5D1.DG12" )
				)
				( pin "PE3_RX_DN(11)"
					( objectStatus "U5D1.DG10" )
				)
				( pin "PE3_RX_DN(12)"
					( objectStatus "U5D1.DD13" )
				)
				( pin "PE3_RX_DN(13)"
					( objectStatus "U5D1.DB11" )
				)
				( pin "PE3_RX_DN(14)"
					( objectStatus "U5D1.CY11" )
				)
				( pin "PE3_RX_DN(15)"
					( objectStatus "U5D1.CV9" )
				)
				( pin "PE3_RX_DN(1)"
					( objectStatus "U5D1.DW18" )
				)
				( pin "PE3_RX_DN(2)"
					( objectStatus "U5D1.DW16" )
				)
				( pin "PE3_RX_DN(3)"
					( objectStatus "U5D1.DT19" )
				)
				( pin "PE3_RX_DN(4)"
					( objectStatus "U5D1.DR16" )
				)
				( pin "PE3_RX_DN(5)"
					( objectStatus "U5D1.DR14" )
				)
				( pin "PE3_RX_DN(6)"
					( objectStatus "U5D1.DN14" )
				)
				( pin "PE3_RX_DN(7)"
					( objectStatus "U5D1.DL14" )
				)
				( pin "PE3_RX_DN(8)"
					( objectStatus "U5D1.DL12" )
				)
				( pin "PE3_RX_DN(9)"
					( objectStatus "U5D1.DJ12" )
				)
				( pin "PE3_RX_DP(0)"
					( objectStatus "U5D1.DY17" )
				)
				( pin "PE3_RX_DP(10)"
					( objectStatus "U5D1.DE12" )
				)
				( pin "PE3_RX_DP(11)"
					( objectStatus "U5D1.DF11" )
				)
				( pin "PE3_RX_DP(12)"
					( objectStatus "U5D1.DC12" )
				)
				( pin "PE3_RX_DP(13)"
					( objectStatus "U5D1.DA12" )
				)
				( pin "PE3_RX_DP(14)"
					( objectStatus "U5D1.CW10" )
				)
				( pin "PE3_RX_DP(15)"
					( objectStatus "U5D1.CU10" )
				)
				( pin "PE3_RX_DP(1)"
					( objectStatus "U5D1.DU18" )
				)
				( pin "PE3_RX_DP(2)"
					( objectStatus "U5D1.DV17" )
				)
				( pin "PE3_RX_DP(3)"
					( objectStatus "U5D1.DR18" )
				)
				( pin "PE3_RX_DP(4)"
					( objectStatus "U5D1.DN16" )
				)
				( pin "PE3_RX_DP(5)"
					( objectStatus "U5D1.DP15" )
				)
				( pin "PE3_RX_DP(6)"
					( objectStatus "U5D1.DM13" )
				)
				( pin "PE3_RX_DP(7)"
					( objectStatus "U5D1.DJ14" )
				)
				( pin "PE3_RX_DP(8)"
					( objectStatus "U5D1.DK13" )
				)
				( pin "PE3_RX_DP(9)"
					( objectStatus "U5D1.DH11" )
				)
				( pin "PE3_TX_DN(0)"
					( objectStatus "U5D1.EE14" )
				)
				( pin "PE3_TX_DN(10)"
					( objectStatus "U5D1.DL6" )
				)
				( pin "PE3_TX_DN(11)"
					( objectStatus "U5D1.DJ4" )
				)
				( pin "PE3_TX_DN(12)"
					( objectStatus "U5D1.DJ6" )
				)
				( pin "PE3_TX_DN(13)"
					( objectStatus "U5D1.DD5" )
				)
				( pin "PE3_TX_DN(14)"
					( objectStatus "U5D1.DB5" )
				)
				( pin "PE3_TX_DN(15)"
					( objectStatus "U5D1.CY5" )
				)
				( pin "PE3_TX_DN(1)"
					( objectStatus "U5D1.EE12" )
				)
				( pin "PE3_TX_DN(2)"
					( objectStatus "U5D1.EC12" )
				)
				( pin "PE3_TX_DN(3)"
					( objectStatus "U5D1.DY11" )
				)
				( pin "PE3_TX_DN(4)"
					( objectStatus "U5D1.EB9" )
				)
				( pin "PE3_TX_DN(5)"
					( objectStatus "U5D1.DW10" )
				)
				( pin "PE3_TX_DN(6)"
					( objectStatus "U5D1.DU8" )
				)
				( pin "PE3_TX_DN(7)"
					( objectStatus "U5D1.DR8" )
				)
				( pin "PE3_TX_DN(8)"
					( objectStatus "U5D1.DM7" )
				)
				( pin "PE3_TX_DN(9)"
					( objectStatus "U5D1.DP5" )
				)
				( pin "PE3_TX_DP(0)"
					( objectStatus "U5D1.EC14" )
				)
				( pin "PE3_TX_DP(10)"
					( objectStatus "U5D1.DK5" )
				)
				( pin "PE3_TX_DP(11)"
					( objectStatus "U5D1.DH5" )
				)
				( pin "PE3_TX_DP(12)"
					( objectStatus "U5D1.DG6" )
				)
				( pin "PE3_TX_DP(13)"
					( objectStatus "U5D1.DC6" )
				)
				( pin "PE3_TX_DP(14)"
					( objectStatus "U5D1.DA4" )
				)
				( pin "PE3_TX_DP(15)"
					( objectStatus "U5D1.CV5" )
				)
				( pin "PE3_TX_DP(1)"
					( objectStatus "U5D1.ED13" )
				)
				( pin "PE3_TX_DP(2)"
					( objectStatus "U5D1.EB11" )
				)
				( pin "PE3_TX_DP(3)"
					( objectStatus "U5D1.EA10" )
				)
				( pin "PE3_TX_DP(4)"
					( objectStatus "U5D1.DY9" )
				)
				( pin "PE3_TX_DP(5)"
					( objectStatus "U5D1.DV9" )
				)
				( pin "PE3_TX_DP(6)"
					( objectStatus "U5D1.DT9" )
				)
				( pin "PE3_TX_DP(7)"
					( objectStatus "U5D1.DP7" )
				)
				( pin "PE3_TX_DP(8)"
					( objectStatus "U5D1.DN6" )
				)
				( pin "PE3_TX_DP(9)"
					( objectStatus "U5D1.DM5" )
				)
			)
			( gate "@baseboard_fab2_lib.baseboard_fab2(sch_1):page33_i86"
				( objectStatus "F89" )
				( pin "UPI0_RX_DN(0)"
					( objectStatus "U5D1.AC10" )
				)
				( pin "UPI0_RX_DN(10)"
					( objectStatus "U5D1.AP7" )
				)
				( pin "UPI0_RX_DN(11)"
					( objectStatus "U5D1.AR8" )
				)
				( pin "UPI0_RX_DN(12)"
					( objectStatus "U5D1.AU10" )
				)
				( pin "UPI0_RX_DN(13)"
					( objectStatus "U5D1.BA8" )
				)
				( pin "UPI0_RX_DN(14)"
					( objectStatus "U5D1.BC6" )
				)
				( pin "UPI0_RX_DN(15)"
					( objectStatus "U5D1.BD7" )
				)
				( pin "UPI0_RX_DN(16)"
					( objectStatus "U5D1.AW8" )
				)
				( pin "UPI0_RX_DN(17)"
					( objectStatus "U5D1.AY9" )
				)
				( pin "UPI0_RX_DN(18)"
					( objectStatus "U5D1.BD9" )
				)
				( pin "UPI0_RX_DN(19)"
					( objectStatus "U5D1.BB11" )
				)
				( pin "UPI0_RX_DN(1)"
					( objectStatus "U5D1.AA8" )
				)
				( pin "UPI0_RX_DN(2)"
					( objectStatus "U5D1.AB7" )
				)
				( pin "UPI0_RX_DN(3)"
					( objectStatus "U5D1.AD5" )
				)
				( pin "UPI0_RX_DN(4)"
					( objectStatus "U5D1.AE6" )
				)
				( pin "UPI0_RX_DN(5)"
					( objectStatus "U5D1.AG8" )
				)
				( pin "UPI0_RX_DN(6)"
					( objectStatus "U5D1.AJ6" )
				)
				( pin "UPI0_RX_DN(7)"
					( objectStatus "U5D1.AL6" )
				)
				( pin "UPI0_RX_DN(8)"
					( objectStatus "U5D1.AK7" )
				)
				( pin "UPI0_RX_DN(9)"
					( objectStatus "U5D1.AM9" )
				)
				( pin "UPI0_RX_DP(0)"
					( objectStatus "U5D1.AB9" )
				)
				( pin "UPI0_RX_DP(10)"
					( objectStatus "U5D1.AN8" )
				)
				( pin "UPI0_RX_DP(11)"
					( objectStatus "U5D1.AU8" )
				)
				( pin "UPI0_RX_DP(12)"
					( objectStatus "U5D1.AT9" )
				)
				( pin "UPI0_RX_DP(13)"
					( objectStatus "U5D1.AY7" )
				)
				( pin "UPI0_RX_DP(14)"
					( objectStatus "U5D1.BB7" )
				)
				( pin "UPI0_RX_DP(15)"
					( objectStatus "U5D1.BF7" )
				)
				( pin "UPI0_RX_DP(16)"
					( objectStatus "U5D1.AV9" )
				)
				( pin "UPI0_RX_DP(17)"
					( objectStatus "U5D1.BB9" )
				)
				( pin "UPI0_RX_DP(18)"
					( objectStatus "U5D1.BC10" )
				)
				( pin "UPI0_RX_DP(19)"
					( objectStatus "U5D1.BA10" )
				)
				( pin "UPI0_RX_DP(1)"
					( objectStatus "U5D1.AC8" )
				)
				( pin "UPI0_RX_DP(2)"
					( objectStatus "U5D1.AA6" )
				)
				( pin "UPI0_RX_DP(3)"
					( objectStatus "U5D1.AC6" )
				)
				( pin "UPI0_RX_DP(4)"
					( objectStatus "U5D1.AG6" )
				)
				( pin "UPI0_RX_DP(5)"
					( objectStatus "U5D1.AF7" )
				)
				( pin "UPI0_RX_DP(6)"
					( objectStatus "U5D1.AH7" )
				)
				( pin "UPI0_RX_DP(7)"
					( objectStatus "U5D1.AK5" )
				)
				( pin "UPI0_RX_DP(8)"
					( objectStatus "U5D1.AM7" )
				)
				( pin "UPI0_RX_DP(9)"
					( objectStatus "U5D1.AL8" )
				)
				( pin "UPI0_TX_DN(0)"
					( objectStatus "U5D1.N2" )
				)
				( pin "UPI0_TX_DN(10)"
					( objectStatus "U5D1.AM3" )
				)
				( pin "UPI0_TX_DN(11)"
					( objectStatus "U5D1.AN4" )
				)
				( pin "UPI0_TX_DN(12)"
					( objectStatus "U5D1.AT1" )
				)
				( pin "UPI0_TX_DN(13)"
					( objectStatus "U5D1.AT3" )
				)
				( pin "UPI0_TX_DN(14)"
					( objectStatus "U5D1.AU4" )
				)
				( pin "UPI0_TX_DN(15)"
					( objectStatus "U5D1.AV5" )
				)
				( pin "UPI0_TX_DN(16)"
					( objectStatus "U5D1.BA4" )
				)
				( pin "UPI0_TX_DN(17)"
					( objectStatus "U5D1.BB3" )
				)
				( pin "UPI0_TX_DN(18)"
					( objectStatus "U5D1.BF3" )
				)
				( pin "UPI0_TX_DN(19)"
					( objectStatus "U5D1.BG4" )
				)
				( pin "UPI0_TX_DN(1)"
					( objectStatus "U5D1.P1" )
				)
				( pin "UPI0_TX_DN(2)"
					( objectStatus "U5D1.V3" )
				)
				( pin "UPI0_TX_DN(3)"
					( objectStatus "U5D1.Y1" )
				)
				( pin "UPI0_TX_DN(4)"
					( objectStatus "U5D1.AB3" )
				)
				( pin "UPI0_TX_DN(5)"
					( objectStatus "U5D1.AC2" )
				)
				( pin "UPI0_TX_DN(6)"
					( objectStatus "U5D1.AG4" )
				)
				( pin "UPI0_TX_DN(7)"
					( objectStatus "U5D1.AE2" )
				)
				( pin "UPI0_TX_DN(8)"
					( objectStatus "U5D1.AH3" )
				)
				( pin "UPI0_TX_DN(9)"
					( objectStatus "U5D1.AL2" )
				)
				( pin "UPI0_TX_DP(0)"
					( objectStatus "U5D1.M1" )
				)
				( pin "UPI0_TX_DP(10)"
					( objectStatus "U5D1.AK3" )
				)
				( pin "UPI0_TX_DP(11)"
					( objectStatus "U5D1.AP3" )
				)
				( pin "UPI0_TX_DP(12)"
					( objectStatus "U5D1.AP1" )
				)
				( pin "UPI0_TX_DP(13)"
					( objectStatus "U5D1.AR2" )
				)
				( pin "UPI0_TX_DP(14)"
					( objectStatus "U5D1.AR4" )
				)
				( pin "UPI0_TX_DP(15)"
					( objectStatus "U5D1.AW4" )
				)
				( pin "UPI0_TX_DP(16)"
					( objectStatus "U5D1.AY3" )
				)
				( pin "UPI0_TX_DP(17)"
					( objectStatus "U5D1.BC2" )
				)
				( pin "UPI0_TX_DP(18)"
					( objectStatus "U5D1.BD3" )
				)
				( pin "UPI0_TX_DP(19)"
					( objectStatus "U5D1.BH3" )
				)
				( pin "UPI0_TX_DP(1)"
					( objectStatus "U5D1.T1" )
				)
				( pin "UPI0_TX_DP(2)"
					( objectStatus "U5D1.Y3" )
				)
				( pin "UPI0_TX_DP(3)"
					( objectStatus "U5D1.W2" )
				)
				( pin "UPI0_TX_DP(4)"
					( objectStatus "U5D1.AA2" )
				)
				( pin "UPI0_TX_DP(5)"
					( objectStatus "U5D1.AD1" )
				)
				( pin "UPI0_TX_DP(6)"
					( objectStatus "U5D1.AF3" )
				)
				( pin "UPI0_TX_DP(7)"
					( objectStatus "U5D1.AG2" )
				)
				( pin "UPI0_TX_DP(8)"
					( objectStatus "U5D1.AJ2" )
				)
				( pin "UPI0_TX_DP(9)"
					( objectStatus "U5D1.AK1" )
				)
			)
			( gate "@baseboard_fab2_lib.baseboard_fab2(sch_1):page34_i86"
				( objectStatus "F88" )
				( pin "UPI1_RX_DN(0)"
					( objectStatus "U5D1.T5" )
				)
				( pin "UPI1_RX_DN(10)"
					( objectStatus "U5D1.R16" )
				)
				( pin "UPI1_RX_DN(11)"
					( objectStatus "U5D1.P17" )
				)
				( pin "UPI1_RX_DN(12)"
					( objectStatus "U5D1.U16" )
				)
				( pin "UPI1_RX_DN(13)"
					( objectStatus "U5D1.W18" )
				)
				( pin "UPI1_RX_DN(14)"
					( objectStatus "U5D1.R20" )
				)
				( pin "UPI1_RX_DN(15)"
					( objectStatus "U5D1.U18" )
				)
				( pin "UPI1_RX_DN(16)"
					( objectStatus "U5D1.P21" )
				)
				( pin "UPI1_RX_DN(17)"
					( objectStatus "U5D1.V19" )
				)
				( pin "UPI1_RX_DN(18)"
					( objectStatus "U5D1.Y21" )
				)
				( pin "UPI1_RX_DN(19)"
					( objectStatus "U5D1.AB19" )
				)
				( pin "UPI1_RX_DN(1)"
					( objectStatus "U5D1.P7" )
				)
				( pin "UPI1_RX_DN(2)"
					( objectStatus "U5D1.V7" )
				)
				( pin "UPI1_RX_DN(3)"
					( objectStatus "U5D1.T9" )
				)
				( pin "UPI1_RX_DN(4)"
					( objectStatus "U5D1.P9" )
				)
				( pin "UPI1_RX_DN(5)"
					( objectStatus "U5D1.R10" )
				)
				( pin "UPI1_RX_DN(6)"
					( objectStatus "U5D1.U12" )
				)
				( pin "UPI1_RX_DN(7)"
					( objectStatus "U5D1.L12" )
				)
				( pin "UPI1_RX_DN(8)"
					( objectStatus "U5D1.N14" )
				)
				( pin "UPI1_RX_DN(9)"
					( objectStatus "U5D1.R12" )
				)
				( pin "UPI1_RX_DP(0)"
					( objectStatus "U5D1.R6" )
				)
				( pin "UPI1_RX_DP(10)"
					( objectStatus "U5D1.T15" )
				)
				( pin "UPI1_RX_DP(11)"
					( objectStatus "U5D1.N16" )
				)
				( pin "UPI1_RX_DP(12)"
					( objectStatus "U5D1.W16" )
				)
				( pin "UPI1_RX_DP(13)"
					( objectStatus "U5D1.V17" )
				)
				( pin "UPI1_RX_DP(14)"
					( objectStatus "U5D1.P19" )
				)
				( pin "UPI1_RX_DP(15)"
					( objectStatus "U5D1.T19" )
				)
				( pin "UPI1_RX_DP(16)"
					( objectStatus "U5D1.T21" )
				)
				( pin "UPI1_RX_DP(17)"
					( objectStatus "U5D1.Y19" )
				)
				( pin "UPI1_RX_DP(18)"
					( objectStatus "U5D1.W20" )
				)
				( pin "UPI1_RX_DP(19)"
					( objectStatus "U5D1.AA20" )
				)
				( pin "UPI1_RX_DP(1)"
					( objectStatus "U5D1.T7" )
				)
				( pin "UPI1_RX_DP(2)"
					( objectStatus "U5D1.U8" )
				)
				( pin "UPI1_RX_DP(3)"
					( objectStatus "U5D1.R8" )
				)
				( pin "UPI1_RX_DP(4)"
					( objectStatus "U5D1.N10" )
				)
				( pin "UPI1_RX_DP(5)"
					( objectStatus "U5D1.U10" )
				)
				( pin "UPI1_RX_DP(6)"
					( objectStatus "U5D1.T11" )
				)
				( pin "UPI1_RX_DP(7)"
					( objectStatus "U5D1.N12" )
				)
				( pin "UPI1_RX_DP(8)"
					( objectStatus "U5D1.M13" )
				)
				( pin "UPI1_RX_DP(9)"
					( objectStatus "U5D1.P13" )
				)
				( pin "UPI1_TX_DN(0)"
					( objectStatus "U5D1.M3" )
				)
				( pin "UPI1_TX_DN(10)"
					( objectStatus "U5D1.E12" )
				)
				( pin "UPI1_TX_DN(11)"
					( objectStatus "U5D1.G14" )
				)
				( pin "UPI1_TX_DN(12)"
					( objectStatus "U5D1.D15" )
				)
				( pin "UPI1_TX_DN(13)"
					( objectStatus "U5D1.F15" )
				)
				( pin "UPI1_TX_DN(14)"
					( objectStatus "U5D1.H17" )
				)
				( pin "UPI1_TX_DN(15)"
					( objectStatus "U5D1.K19" )
				)
				( pin "UPI1_TX_DN(16)"
					( objectStatus "U5D1.G18" )
				)
				( pin "UPI1_TX_DN(17)"
					( objectStatus "U5D1.J20" )
				)
				( pin "UPI1_TX_DN(18)"
					( objectStatus "U5D1.F21" )
				)
				( pin "UPI1_TX_DN(19)"
					( objectStatus "U5D1.H21" )
				)
				( pin "UPI1_TX_DN(1)"
					( objectStatus "U5D1.L4" )
				)
				( pin "UPI1_TX_DN(2)"
					( objectStatus "U5D1.K5" )
				)
				( pin "UPI1_TX_DN(3)"
					( objectStatus "U5D1.J6" )
				)
				( pin "UPI1_TX_DN(4)"
					( objectStatus "U5D1.G6" )
				)
				( pin "UPI1_TX_DN(5)"
					( objectStatus "U5D1.H7" )
				)
				( pin "UPI1_TX_DN(6)"
					( objectStatus "U5D1.K9" )
				)
				( pin "UPI1_TX_DN(7)"
					( objectStatus "U5D1.D9" )
				)
				( pin "UPI1_TX_DN(8)"
					( objectStatus "U5D1.F11" )
				)
				( pin "UPI1_TX_DN(9)"
					( objectStatus "U5D1.G10" )
				)
				( pin "UPI1_TX_DP(0)"
					( objectStatus "U5D1.P3" )
				)
				( pin "UPI1_TX_DP(10)"
					( objectStatus "U5D1.G12" )
				)
				( pin "UPI1_TX_DP(11)"
					( objectStatus "U5D1.F13" )
				)
				( pin "UPI1_TX_DP(12)"
					( objectStatus "U5D1.E14" )
				)
				( pin "UPI1_TX_DP(13)"
					( objectStatus "U5D1.H15" )
				)
				( pin "UPI1_TX_DP(14)"
					( objectStatus "U5D1.G16" )
				)
				( pin "UPI1_TX_DP(15)"
					( objectStatus "U5D1.L18" )
				)
				( pin "UPI1_TX_DP(16)"
					( objectStatus "U5D1.J18" )
				)
				( pin "UPI1_TX_DP(17)"
					( objectStatus "U5D1.H19" )
				)
				( pin "UPI1_TX_DP(18)"
					( objectStatus "U5D1.G20" )
				)
				( pin "UPI1_TX_DP(19)"
					( objectStatus "U5D1.K21" )
				)
				( pin "UPI1_TX_DP(1)"
					( objectStatus "U5D1.K3" )
				)
				( pin "UPI1_TX_DP(2)"
					( objectStatus "U5D1.M5" )
				)
				( pin "UPI1_TX_DP(3)"
					( objectStatus "U5D1.H5" )
				)
				( pin "UPI1_TX_DP(4)"
					( objectStatus "U5D1.F7" )
				)
				( pin "UPI1_TX_DP(5)"
					( objectStatus "U5D1.K7" )
				)
				( pin "UPI1_TX_DP(6)"
					( objectStatus "U5D1.J8" )
				)
				( pin "UPI1_TX_DP(7)"
					( objectStatus "U5D1.F9" )
				)
				( pin "UPI1_TX_DP(8)"
					( objectStatus "U5D1.E10" )
				)
				( pin "UPI1_TX_DP(9)"
					( objectStatus "U5D1.H9" )
				)
			)
			( gate "@baseboard_fab2_lib.baseboard_fab2(sch_1):page35_i3"
				( objectStatus "F87" )
			)
			( gate "@baseboard_fab2_lib.baseboard_fab2(sch_1):page36_i15"
				( objectStatus "F86" )
				( pin "RSVD(153)"
					( objectStatus "U5D1.BD25" )
				)
				( pin "RSVD(165)"
					( objectStatus "U5D1.BB25" )
				)
			)
			( gate "@baseboard_fab2_lib.baseboard_fab2(sch_1):page36_i16"
				( objectStatus "F85" )
			)
			( gate "@baseboard_fab2_lib.baseboard_fab2(sch_1):page37_i310"
				( objectStatus "F84" )
			)
			( gate "@baseboard_fab2_lib.baseboard_fab2(sch_1):page37_i311"
				( objectStatus "F83" )
			)
			( gate "@baseboard_fab2_lib.baseboard_fab2(sch_1):page38_i33"
				( objectStatus "F82" )
			)
			( gate "@baseboard_fab2_lib.baseboard_fab2(sch_1):page38_i34"
				( objectStatus "F81" )
			)
			( gate "@baseboard_fab2_lib.baseboard_fab2(sch_1):page39_i127"
				( objectStatus "F80" )
			)
			( gate "@baseboard_fab2_lib.baseboard_fab2(sch_1):page40_i20"
				( objectStatus "F79" )
			)
			( gate "@baseboard_fab2_lib.baseboard_fab2(sch_1):page40_i21"
				( objectStatus "F78" )
			)
			( gate "@baseboard_fab2_lib.baseboard_fab2(sch_1):page40_i22"
				( objectStatus "F77" )
			)
			( gate "@baseboard_fab2_lib.baseboard_fab2(sch_1):page40_i23"
				( objectStatus "F76" )
			)
			( gate "@baseboard_fab2_lib.baseboard_fab2(sch_1):page41_i283"
				( objectStatus "F75" )
			)
			( gate "@baseboard_fab2_lib.baseboard_fab2(sch_1):page41_i284"
				( objectStatus "F74" )
			)
			( gate "@baseboard_fab2_lib.baseboard_fab2(sch_1):page41_i285"
				( objectStatus "F73" )
			)
			( gate "@baseboard_fab2_lib.baseboard_fab2(sch_1):page41_i286"
				( objectStatus "F72" )
			)
			( gate "@baseboard_fab2_lib.baseboard_fab2(sch_1):page55_i172"
				( objectStatus "F131" )
				( pin "BCLK0_DN"
					( objectStatus "U2D1.AU24" )
				)
				( pin "BCLK0_DP"
					( objectStatus "U2D1.AW24" )
				)
				( pin "BCLK1_DN"
					( objectStatus "U2D1.CR26" )
				)
				( pin "BCLK1_DP"
					( objectStatus "U2D1.CP27" )
				)
				( pin "BCLK2_DN"
					( objectStatus "U2D1.CT25" )
				)
				( pin "BCLK2_DP"
					( objectStatus "U2D1.CU26" )
				)
				( pin "BPM_N(0)"
					( objectStatus "U2D1.AJ10" )
				)
				( pin "BPM_N(1)"
					( objectStatus "U2D1.AH11" )
				)
				( pin "BPM_N(6)"
					( objectStatus "U2D1.AE12" )
				)
				( pin "BPM_N(7)"
					( objectStatus "U2D1.AC12" )
				)
				( pin "CATERR_N"
					( objectStatus "U2D1.AL14" )
				)
				( pin "DDR012_SPDSCL"
					( objectStatus "U2D1.AJ18" )
				)
				( pin "DDR012_SPDSDA"
					( objectStatus "U2D1.AF17" )
				)
				( pin "DDR345_SPDSCL"
					( objectStatus "U2D1.AE18" )
				)
				( pin "MSMI_N"
					( objectStatus "U2D1.AN20" )
				)
				( pin "PMSYNC"
					( objectStatus "U2D1.AR14" )
				)
				( pin "PM_FAST_WAKE_N"
					( objectStatus "U2D1.AF15" )
				)
				( pin "PRDY_N"
					( objectStatus "U2D1.AG16" )
				)
				( pin "PREQ_N"
					( objectStatus "U2D1.AR12" )
				)
				( pin "SVIDALERT_N(0)"
					( objectStatus "U2D1.DE44" )
				)
				( pin "SVIDALERT_N(1)"
					( objectStatus "U2D1.DL44" )
				)
				( pin "SVIDCLK(0)"
					( objectStatus "U2D1.DC44" )
				)
				( pin "SVIDCLK(1)"
					( objectStatus "U2D1.DG44" )
				)
				( pin "SVIDDATA(0)"
					( objectStatus "U2D1.DB45" )
				)
				( pin "SVIDDATA(1)"
					( objectStatus "U2D1.DJ44" )
				)
				( pin "TCK"
					( objectStatus "U2D1.AA14" )
				)
				( pin "TDI"
					( objectStatus "U2D1.AC14" )
				)
				( pin "TDO"
					( objectStatus "U2D1.AE14" )
				)
				( pin "TMS"
					( objectStatus "U2D1.W14" )
				)
				( pin "TRST_N"
					( objectStatus "U2D1.Y13" )
				)
			)
			( gate "@baseboard_fab2_lib.baseboard_fab2(sch_1):page56_i169"
				( objectStatus "F130" )
				( pin "RSVD(195)"
					( objectStatus "U2D1.AP27" )
				)
				( pin "RSVD(206)"
					( objectStatus "U2D1.AM27" )
				)
			)
			( gate "@baseboard_fab2_lib.baseboard_fab2(sch_1):page57_i172"
				( objectStatus "F129" )
				( pin "DDR0_ACT_N"
					( objectStatus "U2D1.J60" )
				)
				( pin "DDR0_BA(0)"
					( objectStatus "U2D1.C52" )
				)
				( pin "DDR0_BA(1)"
					( objectStatus "U2D1.G54" )
				)
				( pin "DDR0_BG(0)"
					( objectStatus "U2D1.D61" )
				)
				( pin "DDR0_BG(1)"
					( objectStatus "U2D1.F63" )
				)
				( pin "DDR0_CID(2)"
					( objectStatus "U2D1.G46" )
				)
				( pin "DDR0_CKE(0)"
					( objectStatus "U2D1.C62" )
				)
				( pin "DDR0_CKE(1)"
					( objectStatus "U2D1.C64" )
				)
				( pin "DDR0_CKE(2)"
					( objectStatus "U2D1.B63" )
				)
				( pin "DDR0_CKE(3)"
					( objectStatus "U2D1.D63" )
				)
				( pin "DDR0_CS_N(0)"
					( objectStatus "U2D1.G52" )
				)
				( pin "DDR0_CS_N(1)"
					( objectStatus "U2D1.F49" )
				)
				( pin "DDR0_CS_N(2)"
					( objectStatus "U2D1.D47" )
				)
				( pin "DDR0_CS_N(3)"
					( objectStatus "U2D1.F47" )
				)
				( pin "DDR0_CS_N(4)"
					( objectStatus "U2D1.B51" )
				)
				( pin "DDR0_CS_N(5)"
					( objectStatus "U2D1.D49" )
				)
				( pin "DDR0_CS_N(6)"
					( objectStatus "U2D1.F45" )
				)
				( pin "DDR0_CS_N(7)"
					( objectStatus "U2D1.K45" )
				)
				( pin "DDR0_DQ(0)"
					( objectStatus "U2D1.AN86" )
				)
				( pin "DDR0_DQ(10)"
					( objectStatus "U2D1.L86" )
				)
				( pin "DDR0_DQ(11)"
					( objectStatus "U2D1.L84" )
				)
				( pin "DDR0_DQ(12)"
					( objectStatus "U2D1.AA86" )
				)
				( pin "DDR0_DQ(13)"
					( objectStatus "U2D1.AA84" )
				)
				( pin "DDR0_DQ(14)"
					( objectStatus "U2D1.N86" )
				)
				( pin "DDR0_DQ(15)"
					( objectStatus "U2D1.N84" )
				)
				( pin "DDR0_DQ(16)"
					( objectStatus "U2D1.V81" )
				)
				( pin "DDR0_DQ(17)"
					( objectStatus "U2D1.T79" )
				)
				( pin "DDR0_DQ(18)"
					( objectStatus "U2D1.N82" )
				)
				( pin "DDR0_DQ(19)"
					( objectStatus "U2D1.M81" )
				)
				( pin "DDR0_DQ(1)"
					( objectStatus "U2D1.AN84" )
				)
				( pin "DDR0_DQ(20)"
					( objectStatus "U2D1.W80" )
				)
				( pin "DDR0_DQ(21)"
					( objectStatus "U2D1.V79" )
				)
				( pin "DDR0_DQ(22)"
					( objectStatus "U2D1.R82" )
				)
				( pin "DDR0_DQ(23)"
					( objectStatus "U2D1.N80" )
				)
				( pin "DDR0_DQ(24)"
					( objectStatus "U2D1.L76" )
				)
				( pin "DDR0_DQ(25)"
					( objectStatus "U2D1.R76" )
				)
				( pin "DDR0_DQ(26)"
					( objectStatus "U2D1.M73" )
				)
				( pin "DDR0_DQ(27)"
					( objectStatus "U2D1.P73" )
				)
				( pin "DDR0_DQ(28)"
					( objectStatus "U2D1.M77" )
				)
				( pin "DDR0_DQ(29)"
					( objectStatus "U2D1.P77" )
				)
				( pin "DDR0_DQ(2)"
					( objectStatus "U2D1.AE86" )
				)
				( pin "DDR0_DQ(30)"
					( objectStatus "U2D1.L74" )
				)
				( pin "DDR0_DQ(31)"
					( objectStatus "U2D1.R74" )
				)
				( pin "DDR0_DQ(32)"
					( objectStatus "U2D1.C42" )
				)
				( pin "DDR0_DQ(33)"
					( objectStatus "U2D1.B41" )
				)
				( pin "DDR0_DQ(34)"
					( objectStatus "U2D1.C38" )
				)
				( pin "DDR0_DQ(35)"
					( objectStatus "U2D1.E38" )
				)
				( pin "DDR0_DQ(36)"
					( objectStatus "U2D1.E42" )
				)
				( pin "DDR0_DQ(37)"
					( objectStatus "U2D1.F41" )
				)
				( pin "DDR0_DQ(38)"
					( objectStatus "U2D1.B39" )
				)
				( pin "DDR0_DQ(39)"
					( objectStatus "U2D1.F39" )
				)
				( pin "DDR0_DQ(3)"
					( objectStatus "U2D1.AE84" )
				)
				( pin "DDR0_DQ(40)"
					( objectStatus "U2D1.K37" )
				)
				( pin "DDR0_DQ(41)"
					( objectStatus "U2D1.P37" )
				)
				( pin "DDR0_DQ(42)"
					( objectStatus "U2D1.L34" )
				)
				( pin "DDR0_DQ(43)"
					( objectStatus "U2D1.N34" )
				)
				( pin "DDR0_DQ(44)"
					( objectStatus "U2D1.L38" )
				)
				( pin "DDR0_DQ(45)"
					( objectStatus "U2D1.N38" )
				)
				( pin "DDR0_DQ(46)"
					( objectStatus "U2D1.K35" )
				)
				( pin "DDR0_DQ(47)"
					( objectStatus "U2D1.P35" )
				)
				( pin "DDR0_DQ(48)"
					( objectStatus "U2D1.K31" )
				)
				( pin "DDR0_DQ(49)"
					( objectStatus "U2D1.P31" )
				)
				( pin "DDR0_DQ(4)"
					( objectStatus "U2D1.AR86" )
				)
				( pin "DDR0_DQ(50)"
					( objectStatus "U2D1.L28" )
				)
				( pin "DDR0_DQ(51)"
					( objectStatus "U2D1.N28" )
				)
				( pin "DDR0_DQ(52)"
					( objectStatus "U2D1.L32" )
				)
				( pin "DDR0_DQ(53)"
					( objectStatus "U2D1.N32" )
				)
				( pin "DDR0_DQ(54)"
					( objectStatus "U2D1.K29" )
				)
				( pin "DDR0_DQ(55)"
					( objectStatus "U2D1.P29" )
				)
				( pin "DDR0_DQ(56)"
					( objectStatus "U2D1.K25" )
				)
				( pin "DDR0_DQ(57)"
					( objectStatus "U2D1.P25" )
				)
				( pin "DDR0_DQ(58)"
					( objectStatus "U2D1.P23" )
				)
				( pin "DDR0_DQ(59)"
					( objectStatus "U2D1.T23" )
				)
				( pin "DDR0_DQ(5)"
					( objectStatus "U2D1.AR84" )
				)
				( pin "DDR0_DQ(60)"
					( objectStatus "U2D1.L26" )
				)
				( pin "DDR0_DQ(61)"
					( objectStatus "U2D1.N26" )
				)
				( pin "DDR0_DQ(62)"
					( objectStatus "U2D1.H23" )
				)
				( pin "DDR0_DQ(63)"
					( objectStatus "U2D1.K23" )
				)
				( pin "DDR0_DQ(6)"
					( objectStatus "U2D1.AG86" )
				)
				( pin "DDR0_DQ(7)"
					( objectStatus "U2D1.AG84" )
				)
				( pin "DDR0_DQ(8)"
					( objectStatus "U2D1.W86" )
				)
				( pin "DDR0_DQ(9)"
					( objectStatus "U2D1.W84" )
				)
				( pin "DDR0_DQS_DN(0)"
					( objectStatus "U2D1.AJ84" )
				)
				( pin "DDR0_DQS_DN(10)"
					( objectStatus "U2D1.U84" )
				)
				( pin "DDR0_DQS_DN(11)"
					( objectStatus "U2D1.U82" )
				)
				( pin "DDR0_DQS_DN(12)"
					( objectStatus "U2D1.K75" )
				)
				( pin "DDR0_DQS_DN(13)"
					( objectStatus "U2D1.A40" )
				)
				( pin "DDR0_DQS_DN(14)"
					( objectStatus "U2D1.J36" )
				)
				( pin "DDR0_DQS_DN(15)"
					( objectStatus "U2D1.J30" )
				)
				( pin "DDR0_DQS_DN(16)"
					( objectStatus "U2D1.J24" )
				)
				( pin "DDR0_DQS_DN(17)"
					( objectStatus "U2D1.AB67" )
				)
				( pin "DDR0_DQS_DN(1)"
					( objectStatus "U2D1.R84" )
				)
				( pin "DDR0_DQS_DN(2)"
					( objectStatus "U2D1.P79" )
				)
				( pin "DDR0_DQS_DN(3)"
					( objectStatus "U2D1.T75" )
				)
				( pin "DDR0_DQS_DN(4)"
					( objectStatus "U2D1.G40" )
				)
				( pin "DDR0_DQS_DN(5)"
					( objectStatus "U2D1.R36" )
				)
				( pin "DDR0_DQS_DN(6)"
					( objectStatus "U2D1.R30" )
				)
				( pin "DDR0_DQS_DN(7)"
					( objectStatus "U2D1.N24" )
				)
				( pin "DDR0_DQS_DN(8)"
					( objectStatus "U2D1.AH67" )
				)
				( pin "DDR0_DQS_DN(9)"
					( objectStatus "U2D1.AL84" )
				)
				( pin "DDR0_DQS_DP(0)"
					( objectStatus "U2D1.AH85" )
				)
				( pin "DDR0_DQS_DP(10)"
					( objectStatus "U2D1.V85" )
				)
				( pin "DDR0_DQS_DP(11)"
					( objectStatus "U2D1.T81" )
				)
				( pin "DDR0_DQS_DP(12)"
					( objectStatus "U2D1.M75" )
				)
				( pin "DDR0_DQS_DP(13)"
					( objectStatus "U2D1.C40" )
				)
				( pin "DDR0_DQS_DP(14)"
					( objectStatus "U2D1.L36" )
				)
				( pin "DDR0_DQS_DP(15)"
					( objectStatus "U2D1.L30" )
				)
				( pin "DDR0_DQS_DP(16)"
					( objectStatus "U2D1.L24" )
				)
				( pin "DDR0_DQS_DP(17)"
					( objectStatus "U2D1.AD67" )
				)
				( pin "DDR0_DQS_DP(1)"
					( objectStatus "U2D1.P85" )
				)
				( pin "DDR0_DQS_DP(2)"
					( objectStatus "U2D1.R80" )
				)
				( pin "DDR0_DQS_DP(3)"
					( objectStatus "U2D1.P75" )
				)
				( pin "DDR0_DQS_DP(4)"
					( objectStatus "U2D1.E40" )
				)
				( pin "DDR0_DQS_DP(5)"
					( objectStatus "U2D1.N36" )
				)
				( pin "DDR0_DQS_DP(6)"
					( objectStatus "U2D1.N30" )
				)
				( pin "DDR0_DQS_DP(7)"
					( objectStatus "U2D1.R24" )
				)
				( pin "DDR0_DQS_DP(8)"
					( objectStatus "U2D1.AF67" )
				)
				( pin "DDR0_DQS_DP(9)"
					( objectStatus "U2D1.AM85" )
				)
				( pin "DDR0_ECC(0)"
					( objectStatus "U2D1.AC68" )
				)
				( pin "DDR0_ECC(1)"
					( objectStatus "U2D1.AG68" )
				)
				( pin "DDR0_ECC(2)"
					( objectStatus "U2D1.AD65" )
				)
				( pin "DDR0_ECC(3)"
					( objectStatus "U2D1.AF65" )
				)
				( pin "DDR0_ECC(4)"
					( objectStatus "U2D1.AD69" )
				)
				( pin "DDR0_ECC(5)"
					( objectStatus "U2D1.AF69" )
				)
				( pin "DDR0_ECC(6)"
					( objectStatus "U2D1.AC66" )
				)
				( pin "DDR0_ECC(7)"
					( objectStatus "U2D1.AG66" )
				)
				( pin "DDR0_MA(0)"
					( objectStatus "U2D1.F53" )
				)
				( pin "DDR0_MA(10)"
					( objectStatus "U2D1.J54" )
				)
				( pin "DDR0_MA(11)"
					( objectStatus "U2D1.G62" )
				)
				( pin "DDR0_MA(12)"
					( objectStatus "U2D1.J64" )
				)
				( pin "DDR0_MA(13)"
					( objectStatus "U2D1.J48" )
				)
				( pin "DDR0_MA(14)"
					( objectStatus "U2D1.F51" )
				)
				( pin "DDR0_MA(15)"
					( objectStatus "U2D1.K49" )
				)
				( pin "DDR0_MA(16)"
					( objectStatus "U2D1.D51" )
				)
				( pin "DDR0_MA(17)"
					( objectStatus "U2D1.K47" )
				)
				( pin "DDR0_MA(1)"
					( objectStatus "U2D1.F57" )
				)
				( pin "DDR0_MA(2)"
					( objectStatus "U2D1.D57" )
				)
				( pin "DDR0_MA(3)"
					( objectStatus "U2D1.C58" )
				)
				( pin "DDR0_MA(4)"
					( objectStatus "U2D1.G58" )
				)
				( pin "DDR0_MA(5)"
					( objectStatus "U2D1.F59" )
				)
				( pin "DDR0_MA(6)"
					( objectStatus "U2D1.D59" )
				)
				( pin "DDR0_MA(7)"
					( objectStatus "U2D1.G60" )
				)
				( pin "DDR0_MA(8)"
					( objectStatus "U2D1.C60" )
				)
				( pin "DDR0_MA(9)"
					( objectStatus "U2D1.F61" )
				)
				( pin "DDR0_ODT(0)"
					( objectStatus "U2D1.C50" )
				)
				( pin "DDR0_ODT(1)"
					( objectStatus "U2D1.C48" )
				)
				( pin "DDR0_ODT(2)"
					( objectStatus "U2D1.G50" )
				)
				( pin "DDR0_ODT(3)"
					( objectStatus "U2D1.G48" )
				)
				( pin "DDR0_PAR"
					( objectStatus "U2D1.D53" )
				)
			)
			( gate "@baseboard_fab2_lib.baseboard_fab2(sch_1):page58_i172"
				( objectStatus "F128" )
				( pin "DDR1_ACT_N"
					( objectStatus "U2D1.T63" )
				)
				( pin "DDR1_BA(0)"
					( objectStatus "U2D1.T53" )
				)
				( pin "DDR1_BA(1)"
					( objectStatus "U2D1.K55" )
				)
				( pin "DDR1_BG(0)"
					( objectStatus "U2D1.M61" )
				)
				( pin "DDR1_BG(1)"
					( objectStatus "U2D1.N60" )
				)
				( pin "DDR1_CID(2)"
					( objectStatus "U2D1.M47" )
				)
				( pin "DDR1_CKE(0)"
					( objectStatus "U2D1.N62" )
				)
				( pin "DDR1_CKE(1)"
					( objectStatus "U2D1.R64" )
				)
				( pin "DDR1_CKE(2)"
					( objectStatus "U2D1.K63" )
				)
				( pin "DDR1_CKE(3)"
					( objectStatus "U2D1.L64" )
				)
				( pin "DDR1_CS_N(0)"
					( objectStatus "U2D1.K51" )
				)
				( pin "DDR1_CS_N(1)"
					( objectStatus "U2D1.R50" )
				)
				( pin "DDR1_CS_N(2)"
					( objectStatus "U2D1.N46" )
				)
				( pin "DDR1_CS_N(3)"
					( objectStatus "U2D1.V47" )
				)
				( pin "DDR1_CS_N(4)"
					( objectStatus "U2D1.J50" )
				)
				( pin "DDR1_CS_N(5)"
					( objectStatus "U2D1.T49" )
				)
				( pin "DDR1_CS_N(6)"
					( objectStatus "U2D1.M45" )
				)
				( pin "DDR1_CS_N(7)"
					( objectStatus "U2D1.R46" )
				)
				( pin "DDR1_DQ(0)"
					( objectStatus "U2D1.AV81" )
				)
				( pin "DDR1_DQ(10)"
					( objectStatus "U2D1.AC82" )
				)
				( pin "DDR1_DQ(11)"
					( objectStatus "U2D1.AB81" )
				)
				( pin "DDR1_DQ(12)"
					( objectStatus "U2D1.AJ80" )
				)
				( pin "DDR1_DQ(13)"
					( objectStatus "U2D1.AH79" )
				)
				( pin "DDR1_DQ(14)"
					( objectStatus "U2D1.AE82" )
				)
				( pin "DDR1_DQ(15)"
					( objectStatus "U2D1.AC80" )
				)
				( pin "DDR1_DQ(16)"
					( objectStatus "U2D1.E80" )
				)
				( pin "DDR1_DQ(17)"
					( objectStatus "U2D1.J80" )
				)
				( pin "DDR1_DQ(18)"
					( objectStatus "U2D1.F77" )
				)
				( pin "DDR1_DQ(19)"
					( objectStatus "U2D1.H77" )
				)
				( pin "DDR1_DQ(1)"
					( objectStatus "U2D1.AT79" )
				)
				( pin "DDR1_DQ(20)"
					( objectStatus "U2D1.F81" )
				)
				( pin "DDR1_DQ(21)"
					( objectStatus "U2D1.H81" )
				)
				( pin "DDR1_DQ(22)"
					( objectStatus "U2D1.E78" )
				)
				( pin "DDR1_DQ(23)"
					( objectStatus "U2D1.J78" )
				)
				( pin "DDR1_DQ(24)"
					( objectStatus "U2D1.D75" )
				)
				( pin "DDR1_DQ(25)"
					( objectStatus "U2D1.C74" )
				)
				( pin "DDR1_DQ(26)"
					( objectStatus "U2D1.D71" )
				)
				( pin "DDR1_DQ(27)"
					( objectStatus "U2D1.F71" )
				)
				( pin "DDR1_DQ(28)"
					( objectStatus "U2D1.F75" )
				)
				( pin "DDR1_DQ(29)"
					( objectStatus "U2D1.G74" )
				)
				( pin "DDR1_DQ(2)"
					( objectStatus "U2D1.AN82" )
				)
				( pin "DDR1_DQ(30)"
					( objectStatus "U2D1.C72" )
				)
				( pin "DDR1_DQ(31)"
					( objectStatus "U2D1.G72" )
				)
				( pin "DDR1_DQ(32)"
					( objectStatus "U2D1.K43" )
				)
				( pin "DDR1_DQ(33)"
					( objectStatus "U2D1.H43" )
				)
				( pin "DDR1_DQ(34)"
					( objectStatus "U2D1.L40" )
				)
				( pin "DDR1_DQ(35)"
					( objectStatus "U2D1.N40" )
				)
				( pin "DDR1_DQ(36)"
					( objectStatus "U2D1.P43" )
				)
				( pin "DDR1_DQ(37)"
					( objectStatus "U2D1.T43" )
				)
				( pin "DDR1_DQ(38)"
					( objectStatus "U2D1.K41" )
				)
				( pin "DDR1_DQ(39)"
					( objectStatus "U2D1.P41" )
				)
				( pin "DDR1_DQ(3)"
					( objectStatus "U2D1.AM81" )
				)
				( pin "DDR1_DQ(40)"
					( objectStatus "U2D1.C36" )
				)
				( pin "DDR1_DQ(41)"
					( objectStatus "U2D1.B35" )
				)
				( pin "DDR1_DQ(42)"
					( objectStatus "U2D1.C32" )
				)
				( pin "DDR1_DQ(43)"
					( objectStatus "U2D1.E32" )
				)
				( pin "DDR1_DQ(44)"
					( objectStatus "U2D1.E36" )
				)
				( pin "DDR1_DQ(45)"
					( objectStatus "U2D1.F35" )
				)
				( pin "DDR1_DQ(46)"
					( objectStatus "U2D1.B33" )
				)
				( pin "DDR1_DQ(47)"
					( objectStatus "U2D1.F33" )
				)
				( pin "DDR1_DQ(48)"
					( objectStatus "U2D1.C30" )
				)
				( pin "DDR1_DQ(49)"
					( objectStatus "U2D1.B29" )
				)
				( pin "DDR1_DQ(4)"
					( objectStatus "U2D1.AW80" )
				)
				( pin "DDR1_DQ(50)"
					( objectStatus "U2D1.C26" )
				)
				( pin "DDR1_DQ(51)"
					( objectStatus "U2D1.E26" )
				)
				( pin "DDR1_DQ(52)"
					( objectStatus "U2D1.E30" )
				)
				( pin "DDR1_DQ(53)"
					( objectStatus "U2D1.F29" )
				)
				( pin "DDR1_DQ(54)"
					( objectStatus "U2D1.B27" )
				)
				( pin "DDR1_DQ(55)"
					( objectStatus "U2D1.F27" )
				)
				( pin "DDR1_DQ(56)"
					( objectStatus "U2D1.U28" )
				)
				( pin "DDR1_DQ(57)"
					( objectStatus "U2D1.AA28" )
				)
				( pin "DDR1_DQ(58)"
					( objectStatus "U2D1.V25" )
				)
				( pin "DDR1_DQ(59)"
					( objectStatus "U2D1.Y25" )
				)
				( pin "DDR1_DQ(5)"
					( objectStatus "U2D1.AV79" )
				)
				( pin "DDR1_DQ(60)"
					( objectStatus "U2D1.V29" )
				)
				( pin "DDR1_DQ(61)"
					( objectStatus "U2D1.Y29" )
				)
				( pin "DDR1_DQ(62)"
					( objectStatus "U2D1.U26" )
				)
				( pin "DDR1_DQ(63)"
					( objectStatus "U2D1.AA26" )
				)
				( pin "DDR1_DQ(6)"
					( objectStatus "U2D1.AR82" )
				)
				( pin "DDR1_DQ(7)"
					( objectStatus "U2D1.AN80" )
				)
				( pin "DDR1_DQ(8)"
					( objectStatus "U2D1.AH81" )
				)
				( pin "DDR1_DQ(9)"
					( objectStatus "U2D1.AF79" )
				)
				( pin "DDR1_DQS_DN(0)"
					( objectStatus "U2D1.AP79" )
				)
				( pin "DDR1_DQS_DN(10)"
					( objectStatus "U2D1.AG82" )
				)
				( pin "DDR1_DQS_DN(11)"
					( objectStatus "U2D1.D79" )
				)
				( pin "DDR1_DQS_DN(12)"
					( objectStatus "U2D1.B73" )
				)
				( pin "DDR1_DQS_DN(13)"
					( objectStatus "U2D1.J42" )
				)
				( pin "DDR1_DQS_DN(14)"
					( objectStatus "U2D1.A34" )
				)
				( pin "DDR1_DQS_DN(15)"
					( objectStatus "U2D1.A28" )
				)
				( pin "DDR1_DQS_DN(16)"
					( objectStatus "U2D1.T27" )
				)
				( pin "DDR1_DQS_DN(17)"
					( objectStatus "U2D1.G68" )
				)
				( pin "DDR1_DQS_DN(1)"
					( objectStatus "U2D1.AD79" )
				)
				( pin "DDR1_DQS_DN(2)"
					( objectStatus "U2D1.K79" )
				)
				( pin "DDR1_DQS_DN(3)"
					( objectStatus "U2D1.H73" )
				)
				( pin "DDR1_DQS_DN(4)"
					( objectStatus "U2D1.N42" )
				)
				( pin "DDR1_DQS_DN(5)"
					( objectStatus "U2D1.G34" )
				)
				( pin "DDR1_DQS_DN(6)"
					( objectStatus "U2D1.G28" )
				)
				( pin "DDR1_DQS_DN(7)"
					( objectStatus "U2D1.AB27" )
				)
				( pin "DDR1_DQS_DN(8)"
					( objectStatus "U2D1.N68" )
				)
				( pin "DDR1_DQS_DN(9)"
					( objectStatus "U2D1.AU82" )
				)
				( pin "DDR1_DQS_DP(0)"
					( objectStatus "U2D1.AR80" )
				)
				( pin "DDR1_DQS_DP(10)"
					( objectStatus "U2D1.AF81" )
				)
				( pin "DDR1_DQS_DP(11)"
					( objectStatus "U2D1.F79" )
				)
				( pin "DDR1_DQS_DP(12)"
					( objectStatus "U2D1.D73" )
				)
				( pin "DDR1_DQS_DP(13)"
					( objectStatus "U2D1.L42" )
				)
				( pin "DDR1_DQS_DP(14)"
					( objectStatus "U2D1.C34" )
				)
				( pin "DDR1_DQS_DP(15)"
					( objectStatus "U2D1.C28" )
				)
				( pin "DDR1_DQS_DP(16)"
					( objectStatus "U2D1.V27" )
				)
				( pin "DDR1_DQS_DP(17)"
					( objectStatus "U2D1.J68" )
				)
				( pin "DDR1_DQS_DP(1)"
					( objectStatus "U2D1.AE80" )
				)
				( pin "DDR1_DQS_DP(2)"
					( objectStatus "U2D1.H79" )
				)
				( pin "DDR1_DQS_DP(3)"
					( objectStatus "U2D1.F73" )
				)
				( pin "DDR1_DQS_DP(4)"
					( objectStatus "U2D1.R42" )
				)
				( pin "DDR1_DQS_DP(5)"
					( objectStatus "U2D1.E34" )
				)
				( pin "DDR1_DQS_DP(6)"
					( objectStatus "U2D1.E28" )
				)
				( pin "DDR1_DQS_DP(7)"
					( objectStatus "U2D1.Y27" )
				)
				( pin "DDR1_DQS_DP(8)"
					( objectStatus "U2D1.L68" )
				)
				( pin "DDR1_DQS_DP(9)"
					( objectStatus "U2D1.AT81" )
				)
				( pin "DDR1_ECC(0)"
					( objectStatus "U2D1.J70" )
				)
				( pin "DDR1_ECC(1)"
					( objectStatus "U2D1.H69" )
				)
				( pin "DDR1_ECC(2)"
					( objectStatus "U2D1.J66" )
				)
				( pin "DDR1_ECC(3)"
					( objectStatus "U2D1.L66" )
				)
				( pin "DDR1_ECC(4)"
					( objectStatus "U2D1.L70" )
				)
				( pin "DDR1_ECC(5)"
					( objectStatus "U2D1.M69" )
				)
				( pin "DDR1_ECC(6)"
					( objectStatus "U2D1.H67" )
				)
				( pin "DDR1_ECC(7)"
					( objectStatus "U2D1.M67" )
				)
				( pin "DDR1_MA(0)"
					( objectStatus "U2D1.J52" )
				)
				( pin "DDR1_MA(10)"
					( objectStatus "U2D1.M55" )
				)
				( pin "DDR1_MA(11)"
					( objectStatus "U2D1.R60" )
				)
				( pin "DDR1_MA(12)"
					( objectStatus "U2D1.T61" )
				)
				( pin "DDR1_MA(13)"
					( objectStatus "U2D1.M51" )
				)
				( pin "DDR1_MA(14)"
					( objectStatus "U2D1.T51" )
				)
				( pin "DDR1_MA(15)"
					( objectStatus "U2D1.N52" )
				)
				( pin "DDR1_MA(16)"
					( objectStatus "U2D1.R52" )
				)
				( pin "DDR1_MA(17)"
					( objectStatus "U2D1.N48" )
				)
				( pin "DDR1_MA(1)"
					( objectStatus "U2D1.J58" )
				)
				( pin "DDR1_MA(2)"
					( objectStatus "U2D1.K57" )
				)
				( pin "DDR1_MA(3)"
					( objectStatus "U2D1.N58" )
				)
				( pin "DDR1_MA(4)"
					( objectStatus "U2D1.M59" )
				)
				( pin "DDR1_MA(5)"
					( objectStatus "U2D1.R58" )
				)
				( pin "DDR1_MA(6)"
					( objectStatus "U2D1.T59" )
				)
				( pin "DDR1_MA(7)"
					( objectStatus "U2D1.V61" )
				)
				( pin "DDR1_MA(8)"
					( objectStatus "U2D1.W60" )
				)
				( pin "DDR1_MA(9)"
					( objectStatus "U2D1.K59" )
				)
				( pin "DDR1_ODT(0)"
					( objectStatus "U2D1.N50" )
				)
				( pin "DDR1_ODT(1)"
					( objectStatus "U2D1.R48" )
				)
				( pin "DDR1_ODT(2)"
					( objectStatus "U2D1.M49" )
				)
				( pin "DDR1_ODT(3)"
					( objectStatus "U2D1.T47" )
				)
				( pin "DDR1_PAR"
					( objectStatus "U2D1.K53" )
				)
			)
			( gate "@baseboard_fab2_lib.baseboard_fab2(sch_1):page59_i172"
				( objectStatus "F127" )
				( pin "DDR2_ACT_N"
					( objectStatus "U2D1.AB61" )
				)
				( pin "DDR2_BA(0)"
					( objectStatus "U2D1.W52" )
				)
				( pin "DDR2_BA(1)"
					( objectStatus "U2D1.AE56" )
				)
				( pin "DDR2_BG(0)"
					( objectStatus "U2D1.AA60" )
				)
				( pin "DDR2_BG(1)"
					( objectStatus "U2D1.AE62" )
				)
				( pin "DDR2_CID(2)"
					( objectStatus "U2D1.AB45" )
				)
				( pin "DDR2_CKE(0)"
					( objectStatus "U2D1.AA62" )
				)
				( pin "DDR2_CKE(1)"
					( objectStatus "U2D1.AD63" )
				)
				( pin "DDR2_CKE(2)"
					( objectStatus "U2D1.V63" )
				)
				( pin "DDR2_CKE(3)"
					( objectStatus "U2D1.AB63" )
				)
				( pin "DDR2_CS_N(0)"
					( objectStatus "U2D1.V51" )
				)
				( pin "DDR2_CS_N(1)"
					( objectStatus "U2D1.AB49" )
				)
				( pin "DDR2_CS_N(2)"
					( objectStatus "U2D1.W46" )
				)
				( pin "DDR2_CS_N(3)"
					( objectStatus "U2D1.AA46" )
				)
				( pin "DDR2_CS_N(4)"
					( objectStatus "U2D1.AB51" )
				)
				( pin "DDR2_CS_N(5)"
					( objectStatus "U2D1.W48" )
				)
				( pin "DDR2_CS_N(6)"
					( objectStatus "U2D1.T45" )
				)
				( pin "DDR2_CS_N(7)"
					( objectStatus "U2D1.V45" )
				)
				( pin "DDR2_DQ(0)"
					( objectStatus "U2D1.AR76" )
				)
				( pin "DDR2_DQ(10)"
					( objectStatus "U2D1.Y77" )
				)
				( pin "DDR2_DQ(11)"
					( objectStatus "U2D1.W76" )
				)
				( pin "DDR2_DQ(12)"
					( objectStatus "U2D1.AF75" )
				)
				( pin "DDR2_DQ(13)"
					( objectStatus "U2D1.AE74" )
				)
				( pin "DDR2_DQ(14)"
					( objectStatus "U2D1.AB77" )
				)
				( pin "DDR2_DQ(15)"
					( objectStatus "U2D1.Y75" )
				)
				( pin "DDR2_DQ(16)"
					( objectStatus "U2D1.W72" )
				)
				( pin "DDR2_DQ(17)"
					( objectStatus "U2D1.AA70" )
				)
				( pin "DDR2_DQ(18)"
					( objectStatus "U2D1.R70" )
				)
				( pin "DDR2_DQ(19)"
					( objectStatus "U2D1.T69" )
				)
				( pin "DDR2_DQ(1)"
					( objectStatus "U2D1.AN74" )
				)
				( pin "DDR2_DQ(20)"
					( objectStatus "U2D1.AA72" )
				)
				( pin "DDR2_DQ(21)"
					( objectStatus "U2D1.AB71" )
				)
				( pin "DDR2_DQ(22)"
					( objectStatus "U2D1.T71" )
				)
				( pin "DDR2_DQ(23)"
					( objectStatus "U2D1.V69" )
				)
				( pin "DDR2_DQ(24)"
					( objectStatus "U2D1.AM67" )
				)
				( pin "DDR2_DQ(25)"
					( objectStatus "U2D1.AT67" )
				)
				( pin "DDR2_DQ(26)"
					( objectStatus "U2D1.AN64" )
				)
				( pin "DDR2_DQ(27)"
					( objectStatus "U2D1.AR64" )
				)
				( pin "DDR2_DQ(28)"
					( objectStatus "U2D1.AN68" )
				)
				( pin "DDR2_DQ(29)"
					( objectStatus "U2D1.AR68" )
				)
				( pin "DDR2_DQ(2)"
					( objectStatus "U2D1.AK77" )
				)
				( pin "DDR2_DQ(30)"
					( objectStatus "U2D1.AM65" )
				)
				( pin "DDR2_DQ(31)"
					( objectStatus "U2D1.AT65" )
				)
				( pin "DDR2_DQ(32)"
					( objectStatus "U2D1.U40" )
				)
				( pin "DDR2_DQ(33)"
					( objectStatus "U2D1.AA40" )
				)
				( pin "DDR2_DQ(34)"
					( objectStatus "U2D1.V37" )
				)
				( pin "DDR2_DQ(35)"
					( objectStatus "U2D1.Y37" )
				)
				( pin "DDR2_DQ(36)"
					( objectStatus "U2D1.V41" )
				)
				( pin "DDR2_DQ(37)"
					( objectStatus "U2D1.Y41" )
				)
				( pin "DDR2_DQ(38)"
					( objectStatus "U2D1.U38" )
				)
				( pin "DDR2_DQ(39)"
					( objectStatus "U2D1.AA38" )
				)
				( pin "DDR2_DQ(3)"
					( objectStatus "U2D1.AJ76" )
				)
				( pin "DDR2_DQ(40)"
					( objectStatus "U2D1.U34" )
				)
				( pin "DDR2_DQ(41)"
					( objectStatus "U2D1.AA34" )
				)
				( pin "DDR2_DQ(42)"
					( objectStatus "U2D1.V31" )
				)
				( pin "DDR2_DQ(43)"
					( objectStatus "U2D1.Y31" )
				)
				( pin "DDR2_DQ(44)"
					( objectStatus "U2D1.V35" )
				)
				( pin "DDR2_DQ(45)"
					( objectStatus "U2D1.Y35" )
				)
				( pin "DDR2_DQ(46)"
					( objectStatus "U2D1.U32" )
				)
				( pin "DDR2_DQ(47)"
					( objectStatus "U2D1.AA32" )
				)
				( pin "DDR2_DQ(48)"
					( objectStatus "U2D1.AD31" )
				)
				( pin "DDR2_DQ(49)"
					( objectStatus "U2D1.AH31" )
				)
				( pin "DDR2_DQ(4)"
					( objectStatus "U2D1.AT75" )
				)
				( pin "DDR2_DQ(50)"
					( objectStatus "U2D1.AE28" )
				)
				( pin "DDR2_DQ(51)"
					( objectStatus "U2D1.AG28" )
				)
				( pin "DDR2_DQ(52)"
					( objectStatus "U2D1.AE32" )
				)
				( pin "DDR2_DQ(53)"
					( objectStatus "U2D1.AG32" )
				)
				( pin "DDR2_DQ(54)"
					( objectStatus "U2D1.AD29" )
				)
				( pin "DDR2_DQ(55)"
					( objectStatus "U2D1.AH29" )
				)
				( pin "DDR2_DQ(56)"
					( objectStatus "U2D1.AD25" )
				)
				( pin "DDR2_DQ(57)"
					( objectStatus "U2D1.AH25" )
				)
				( pin "DDR2_DQ(58)"
					( objectStatus "U2D1.AE22" )
				)
				( pin "DDR2_DQ(59)"
					( objectStatus "U2D1.AG22" )
				)
				( pin "DDR2_DQ(5)"
					( objectStatus "U2D1.AR74" )
				)
				( pin "DDR2_DQ(60)"
					( objectStatus "U2D1.AE26" )
				)
				( pin "DDR2_DQ(61)"
					( objectStatus "U2D1.AG26" )
				)
				( pin "DDR2_DQ(62)"
					( objectStatus "U2D1.AD23" )
				)
				( pin "DDR2_DQ(63)"
					( objectStatus "U2D1.AH23" )
				)
				( pin "DDR2_DQ(6)"
					( objectStatus "U2D1.AM77" )
				)
				( pin "DDR2_DQ(7)"
					( objectStatus "U2D1.AK75" )
				)
				( pin "DDR2_DQ(8)"
					( objectStatus "U2D1.AE76" )
				)
				( pin "DDR2_DQ(9)"
					( objectStatus "U2D1.AC74" )
				)
				( pin "DDR2_DQS_DN(0)"
					( objectStatus "U2D1.AL74" )
				)
				( pin "DDR2_DQS_DN(10)"
					( objectStatus "U2D1.AD77" )
				)
				( pin "DDR2_DQS_DN(11)"
					( objectStatus "U2D1.U72" )
				)
				( pin "DDR2_DQS_DN(12)"
					( objectStatus "U2D1.AL66" )
				)
				( pin "DDR2_DQS_DN(13)"
					( objectStatus "U2D1.T39" )
				)
				( pin "DDR2_DQS_DN(14)"
					( objectStatus "U2D1.T33" )
				)
				( pin "DDR2_DQS_DN(15)"
					( objectStatus "U2D1.AC30" )
				)
				( pin "DDR2_DQS_DN(16)"
					( objectStatus "U2D1.AC24" )
				)
				( pin "DDR2_DQS_DN(17)"
					( objectStatus "U2D1.AT71" )
				)
				( pin "DDR2_DQS_DN(1)"
					( objectStatus "U2D1.AA74" )
				)
				( pin "DDR2_DQS_DN(2)"
					( objectStatus "U2D1.Y69" )
				)
				( pin "DDR2_DQS_DN(3)"
					( objectStatus "U2D1.AU66" )
				)
				( pin "DDR2_DQS_DN(4)"
					( objectStatus "U2D1.AB39" )
				)
				( pin "DDR2_DQS_DN(5)"
					( objectStatus "U2D1.AB33" )
				)
				( pin "DDR2_DQS_DN(6)"
					( objectStatus "U2D1.AJ30" )
				)
				( pin "DDR2_DQS_DN(7)"
					( objectStatus "U2D1.AJ24" )
				)
				( pin "DDR2_DQS_DN(8)"
					( objectStatus "U2D1.BB71" )
				)
				( pin "DDR2_DQS_DN(9)"
					( objectStatus "U2D1.AP77" )
				)
				( pin "DDR2_DQS_DP(0)"
					( objectStatus "U2D1.AM75" )
				)
				( pin "DDR2_DQS_DP(10)"
					( objectStatus "U2D1.AC76" )
				)
				( pin "DDR2_DQS_DP(11)"
					( objectStatus "U2D1.V71" )
				)
				( pin "DDR2_DQS_DP(12)"
					( objectStatus "U2D1.AN66" )
				)
				( pin "DDR2_DQS_DP(13)"
					( objectStatus "U2D1.V39" )
				)
				( pin "DDR2_DQS_DP(14)"
					( objectStatus "U2D1.V33" )
				)
				( pin "DDR2_DQS_DP(15)"
					( objectStatus "U2D1.AE30" )
				)
				( pin "DDR2_DQS_DP(16)"
					( objectStatus "U2D1.AE24" )
				)
				( pin "DDR2_DQS_DP(17)"
					( objectStatus "U2D1.AV71" )
				)
				( pin "DDR2_DQS_DP(1)"
					( objectStatus "U2D1.AB75" )
				)
				( pin "DDR2_DQS_DP(2)"
					( objectStatus "U2D1.W70" )
				)
				( pin "DDR2_DQS_DP(3)"
					( objectStatus "U2D1.AR66" )
				)
				( pin "DDR2_DQS_DP(4)"
					( objectStatus "U2D1.Y39" )
				)
				( pin "DDR2_DQS_DP(5)"
					( objectStatus "U2D1.Y33" )
				)
				( pin "DDR2_DQS_DP(6)"
					( objectStatus "U2D1.AG30" )
				)
				( pin "DDR2_DQS_DP(7)"
					( objectStatus "U2D1.AG24" )
				)
				( pin "DDR2_DQS_DP(8)"
					( objectStatus "U2D1.AY71" )
				)
				( pin "DDR2_DQS_DP(9)"
					( objectStatus "U2D1.AN76" )
				)
				( pin "DDR2_ECC(0)"
					( objectStatus "U2D1.AU72" )
				)
				( pin "DDR2_ECC(1)"
					( objectStatus "U2D1.BA72" )
				)
				( pin "DDR2_ECC(2)"
					( objectStatus "U2D1.AV69" )
				)
				( pin "DDR2_ECC(3)"
					( objectStatus "U2D1.AY69" )
				)
				( pin "DDR2_ECC(4)"
					( objectStatus "U2D1.AV73" )
				)
				( pin "DDR2_ECC(5)"
					( objectStatus "U2D1.AY73" )
				)
				( pin "DDR2_ECC(6)"
					( objectStatus "U2D1.AU70" )
				)
				( pin "DDR2_ECC(7)"
					( objectStatus "U2D1.BA70" )
				)
				( pin "DDR2_MA(0)"
					( objectStatus "U2D1.AB53" )
				)
				( pin "DDR2_MA(10)"
					( objectStatus "U2D1.AD55" )
				)
				( pin "DDR2_MA(11)"
					( objectStatus "U2D1.AG60" )
				)
				( pin "DDR2_MA(12)"
					( objectStatus "U2D1.AG62" )
				)
				( pin "DDR2_MA(13)"
					( objectStatus "U2D1.AD53" )
				)
				( pin "DDR2_MA(14)"
					( objectStatus "U2D1.W50" )
				)
				( pin "DDR2_MA(15)"
					( objectStatus "U2D1.AE54" )
				)
				( pin "DDR2_MA(16)"
					( objectStatus "U2D1.AA52" )
				)
				( pin "DDR2_MA(17)"
					( objectStatus "U2D1.AC46" )
				)
				( pin "DDR2_MA(1)"
					( objectStatus "U2D1.AE58" )
				)
				( pin "DDR2_MA(2)"
					( objectStatus "U2D1.AD57" )
				)
				( pin "DDR2_MA(3)"
					( objectStatus "U2D1.W58" )
				)
				( pin "DDR2_MA(4)"
					( objectStatus "U2D1.AA58" )
				)
				( pin "DDR2_MA(5)"
					( objectStatus "U2D1.V59" )
				)
				( pin "DDR2_MA(6)"
					( objectStatus "U2D1.AB59" )
				)
				( pin "DDR2_MA(7)"
					( objectStatus "U2D1.AE60" )
				)
				( pin "DDR2_MA(8)"
					( objectStatus "U2D1.AD59" )
				)
				( pin "DDR2_MA(9)"
					( objectStatus "U2D1.AG58" )
				)
				( pin "DDR2_ODT(0)"
					( objectStatus "U2D1.AA50" )
				)
				( pin "DDR2_ODT(1)"
					( objectStatus "U2D1.AA48" )
				)
				( pin "DDR2_ODT(2)"
					( objectStatus "U2D1.V49" )
				)
				( pin "DDR2_ODT(3)"
					( objectStatus "U2D1.AB47" )
				)
				( pin "DDR2_PAR"
					( objectStatus "U2D1.V53" )
				)
			)
			( gate "@baseboard_fab2_lib.baseboard_fab2(sch_1):page60_i172"
				( objectStatus "F126" )
				( pin "DDR3_ACT_N"
					( objectStatus "U2D1.DW60" )
				)
				( pin "DDR3_BA(0)"
					( objectStatus "U2D1.EE52" )
				)
				( pin "DDR3_BA(1)"
					( objectStatus "U2D1.EA54" )
				)
				( pin "DDR3_BG(0)"
					( objectStatus "U2D1.ED61" )
				)
				( pin "DDR3_BG(1)"
					( objectStatus "U2D1.DW62" )
				)
				( pin "DDR3_CID(2)"
					( objectStatus "U2D1.DV47" )
				)
				( pin "DDR3_CKE(0)"
					( objectStatus "U2D1.EE62" )
				)
				( pin "DDR3_CKE(1)"
					( objectStatus "U2D1.EF63" )
				)
				( pin "DDR3_CKE(2)"
					( objectStatus "U2D1.EA62" )
				)
				( pin "DDR3_CKE(3)"
					( objectStatus "U2D1.EB63" )
				)
				( pin "DDR3_CS_N(0)"
					( objectStatus "U2D1.EF51" )
				)
				( pin "DDR3_CS_N(1)"
					( objectStatus "U2D1.ED49" )
				)
				( pin "DDR3_CS_N(2)"
					( objectStatus "U2D1.ED47" )
				)
				( pin "DDR3_CS_N(3)"
					( objectStatus "U2D1.EB47" )
				)
				( pin "DDR3_CS_N(4)"
					( objectStatus "U2D1.EB51" )
				)
				( pin "DDR3_CS_N(5)"
					( objectStatus "U2D1.EB49" )
				)
				( pin "DDR3_CS_N(6)"
					( objectStatus "U2D1.DV45" )
				)
				( pin "DDR3_CS_N(7)"
					( objectStatus "U2D1.EB45" )
				)
				( pin "DDR3_DQ(0)"
					( objectStatus "U2D1.CN84" )
				)
				( pin "DDR3_DQ(10)"
					( objectStatus "U2D1.DV83" )
				)
				( pin "DDR3_DQ(11)"
					( objectStatus "U2D1.DY83" )
				)
				( pin "DDR3_DQ(12)"
					( objectStatus "U2D1.DD85" )
				)
				( pin "DDR3_DQ(13)"
					( objectStatus "U2D1.DE84" )
				)
				( pin "DDR3_DQ(14)"
					( objectStatus "U2D1.DR84" )
				)
				( pin "DDR3_DQ(15)"
					( objectStatus "U2D1.DV85" )
				)
				( pin "DDR3_DQ(16)"
					( objectStatus "U2D1.DM79" )
				)
				( pin "DDR3_DQ(17)"
					( objectStatus "U2D1.DK81" )
				)
				( pin "DDR3_DQ(18)"
					( objectStatus "U2D1.DT81" )
				)
				( pin "DDR3_DQ(19)"
					( objectStatus "U2D1.DR82" )
				)
				( pin "DDR3_DQ(1)"
					( objectStatus "U2D1.CN86" )
				)
				( pin "DDR3_DQ(20)"
					( objectStatus "U2D1.DK79" )
				)
				( pin "DDR3_DQ(21)"
					( objectStatus "U2D1.DJ80" )
				)
				( pin "DDR3_DQ(22)"
					( objectStatus "U2D1.DR80" )
				)
				( pin "DDR3_DQ(23)"
					( objectStatus "U2D1.DN82" )
				)
				( pin "DDR3_DQ(24)"
					( objectStatus "U2D1.DN76" )
				)
				( pin "DDR3_DQ(25)"
					( objectStatus "U2D1.DU76" )
				)
				( pin "DDR3_DQ(26)"
					( objectStatus "U2D1.DP73" )
				)
				( pin "DDR3_DQ(27)"
					( objectStatus "U2D1.DT73" )
				)
				( pin "DDR3_DQ(28)"
					( objectStatus "U2D1.DP77" )
				)
				( pin "DDR3_DQ(29)"
					( objectStatus "U2D1.DT77" )
				)
				( pin "DDR3_DQ(2)"
					( objectStatus "U2D1.DA86" )
				)
				( pin "DDR3_DQ(30)"
					( objectStatus "U2D1.DN74" )
				)
				( pin "DDR3_DQ(31)"
					( objectStatus "U2D1.DU74" )
				)
				( pin "DDR3_DQ(32)"
					( objectStatus "U2D1.EC40" )
				)
				( pin "DDR3_DQ(33)"
					( objectStatus "U2D1.ED39" )
				)
				( pin "DDR3_DQ(34)"
					( objectStatus "U2D1.EA36" )
				)
				( pin "DDR3_DQ(35)"
					( objectStatus "U2D1.EC36" )
				)
				( pin "DDR3_DQ(36)"
					( objectStatus "U2D1.DY39" )
				)
				( pin "DDR3_DQ(37)"
					( objectStatus "U2D1.EA40" )
				)
				( pin "DDR3_DQ(38)"
					( objectStatus "U2D1.DY37" )
				)
				( pin "DDR3_DQ(39)"
					( objectStatus "U2D1.ED37" )
				)
				( pin "DDR3_DQ(3)"
					( objectStatus "U2D1.DA84" )
				)
				( pin "DDR3_DQ(40)"
					( objectStatus "U2D1.DN36" )
				)
				( pin "DDR3_DQ(41)"
					( objectStatus "U2D1.DU36" )
				)
				( pin "DDR3_DQ(42)"
					( objectStatus "U2D1.DP33" )
				)
				( pin "DDR3_DQ(43)"
					( objectStatus "U2D1.DT33" )
				)
				( pin "DDR3_DQ(44)"
					( objectStatus "U2D1.DP37" )
				)
				( pin "DDR3_DQ(45)"
					( objectStatus "U2D1.DT37" )
				)
				( pin "DDR3_DQ(46)"
					( objectStatus "U2D1.DN34" )
				)
				( pin "DDR3_DQ(47)"
					( objectStatus "U2D1.DU34" )
				)
				( pin "DDR3_DQ(48)"
					( objectStatus "U2D1.DN30" )
				)
				( pin "DDR3_DQ(49)"
					( objectStatus "U2D1.DU30" )
				)
				( pin "DDR3_DQ(4)"
					( objectStatus "U2D1.CL84" )
				)
				( pin "DDR3_DQ(50)"
					( objectStatus "U2D1.DP27" )
				)
				( pin "DDR3_DQ(51)"
					( objectStatus "U2D1.DT27" )
				)
				( pin "DDR3_DQ(52)"
					( objectStatus "U2D1.DP31" )
				)
				( pin "DDR3_DQ(53)"
					( objectStatus "U2D1.DT31" )
				)
				( pin "DDR3_DQ(54)"
					( objectStatus "U2D1.DN28" )
				)
				( pin "DDR3_DQ(55)"
					( objectStatus "U2D1.DU28" )
				)
				( pin "DDR3_DQ(56)"
					( objectStatus "U2D1.DN24" )
				)
				( pin "DDR3_DQ(57)"
					( objectStatus "U2D1.DU24" )
				)
				( pin "DDR3_DQ(58)"
					( objectStatus "U2D1.DY21" )
				)
				( pin "DDR3_DQ(59)"
					( objectStatus "U2D1.EB21" )
				)
				( pin "DDR3_DQ(5)"
					( objectStatus "U2D1.CL86" )
				)
				( pin "DDR3_DQ(60)"
					( objectStatus "U2D1.DP25" )
				)
				( pin "DDR3_DQ(61)"
					( objectStatus "U2D1.DT25" )
				)
				( pin "DDR3_DQ(62)"
					( objectStatus "U2D1.EC22" )
				)
				( pin "DDR3_DQ(63)"
					( objectStatus "U2D1.DW22" )
				)
				( pin "DDR3_DQ(6)"
					( objectStatus "U2D1.CW86" )
				)
				( pin "DDR3_DQ(7)"
					( objectStatus "U2D1.CW84" )
				)
				( pin "DDR3_DQ(8)"
					( objectStatus "U2D1.DG84" )
				)
				( pin "DDR3_DQ(9)"
					( objectStatus "U2D1.DH85" )
				)
				( pin "DDR3_DQS_DN(0)"
					( objectStatus "U2D1.CU84" )
				)
				( pin "DDR3_DQS_DN(10)"
					( objectStatus "U2D1.DM85" )
				)
				( pin "DDR3_DQS_DN(11)"
					( objectStatus "U2D1.DN80" )
				)
				( pin "DDR3_DQS_DN(12)"
					( objectStatus "U2D1.DP75" )
				)
				( pin "DDR3_DQS_DN(13)"
					( objectStatus "U2D1.EA38" )
				)
				( pin "DDR3_DQS_DN(14)"
					( objectStatus "U2D1.DP35" )
				)
				( pin "DDR3_DQS_DN(15)"
					( objectStatus "U2D1.DM29" )
				)
				( pin "DDR3_DQS_DN(16)"
					( objectStatus "U2D1.DM23" )
				)
				( pin "DDR3_DQS_DN(17)"
					( objectStatus "U2D1.DB67" )
				)
				( pin "DDR3_DQS_DN(1)"
					( objectStatus "U2D1.DN84" )
				)
				( pin "DDR3_DQS_DN(2)"
					( objectStatus "U2D1.DL82" )
				)
				( pin "DDR3_DQS_DN(3)"
					( objectStatus "U2D1.DV75" )
				)
				( pin "DDR3_DQS_DN(4)"
					( objectStatus "U2D1.EE38" )
				)
				( pin "DDR3_DQS_DN(5)"
					( objectStatus "U2D1.DV35" )
				)
				( pin "DDR3_DQS_DN(6)"
					( objectStatus "U2D1.DV29" )
				)
				( pin "DDR3_DQS_DN(7)"
					( objectStatus "U2D1.DV23" )
				)
				( pin "DDR3_DQS_DN(8)"
					( objectStatus "U2D1.DF67" )
				)
				( pin "DDR3_DQS_DN(9)"
					( objectStatus "U2D1.CR84" )
				)
				( pin "DDR3_DQS_DP(0)"
					( objectStatus "U2D1.CV85" )
				)
				( pin "DDR3_DQS_DP(10)"
					( objectStatus "U2D1.DL84" )
				)
				( pin "DDR3_DQS_DP(11)"
					( objectStatus "U2D1.DP79" )
				)
				( pin "DDR3_DQS_DP(12)"
					( objectStatus "U2D1.DM75" )
				)
				( pin "DDR3_DQS_DP(13)"
					( objectStatus "U2D1.DW38" )
				)
				( pin "DDR3_DQS_DP(14)"
					( objectStatus "U2D1.DM35" )
				)
				( pin "DDR3_DQS_DP(15)"
					( objectStatus "U2D1.DP29" )
				)
				( pin "DDR3_DQS_DP(16)"
					( objectStatus "U2D1.DP23" )
				)
				( pin "DDR3_DQS_DP(17)"
					( objectStatus "U2D1.CY67" )
				)
				( pin "DDR3_DQS_DP(1)"
					( objectStatus "U2D1.DP85" )
				)
				( pin "DDR3_DQS_DP(2)"
					( objectStatus "U2D1.DM81" )
				)
				( pin "DDR3_DQS_DP(3)"
					( objectStatus "U2D1.DT75" )
				)
				( pin "DDR3_DQS_DP(4)"
					( objectStatus "U2D1.EC38" )
				)
				( pin "DDR3_DQS_DP(5)"
					( objectStatus "U2D1.DT35" )
				)
				( pin "DDR3_DQS_DP(6)"
					( objectStatus "U2D1.DT29" )
				)
				( pin "DDR3_DQS_DP(7)"
					( objectStatus "U2D1.DT23" )
				)
				( pin "DDR3_DQS_DP(8)"
					( objectStatus "U2D1.DD67" )
				)
				( pin "DDR3_DQS_DP(9)"
					( objectStatus "U2D1.CP85" )
				)
				( pin "DDR3_ECC(0)"
					( objectStatus "U2D1.DA68" )
				)
				( pin "DDR3_ECC(1)"
					( objectStatus "U2D1.DE68" )
				)
				( pin "DDR3_ECC(2)"
					( objectStatus "U2D1.DB65" )
				)
				( pin "DDR3_ECC(3)"
					( objectStatus "U2D1.DD65" )
				)
				( pin "DDR3_ECC(4)"
					( objectStatus "U2D1.DB69" )
				)
				( pin "DDR3_ECC(5)"
					( objectStatus "U2D1.DD69" )
				)
				( pin "DDR3_ECC(6)"
					( objectStatus "U2D1.DA66" )
				)
				( pin "DDR3_ECC(7)"
					( objectStatus "U2D1.DE66" )
				)
				( pin "DDR3_MA(0)"
					( objectStatus "U2D1.EB53" )
				)
				( pin "DDR3_MA(10)"
					( objectStatus "U2D1.DW54" )
				)
				( pin "DDR3_MA(11)"
					( objectStatus "U2D1.EB61" )
				)
				( pin "DDR3_MA(12)"
					( objectStatus "U2D1.DT63" )
				)
				( pin "DDR3_MA(13)"
					( objectStatus "U2D1.DW48" )
				)
				( pin "DDR3_MA(14)"
					( objectStatus "U2D1.ED51" )
				)
				( pin "DDR3_MA(15)"
					( objectStatus "U2D1.DV49" )
				)
				( pin "DDR3_MA(16)"
					( objectStatus "U2D1.EA52" )
				)
				( pin "DDR3_MA(17)"
					( objectStatus "U2D1.EA46" )
				)
				( pin "DDR3_MA(1)"
					( objectStatus "U2D1.ED57" )
				)
				( pin "DDR3_MA(2)"
					( objectStatus "U2D1.EE58" )
				)
				( pin "DDR3_MA(3)"
					( objectStatus "U2D1.EB57" )
				)
				( pin "DDR3_MA(4)"
					( objectStatus "U2D1.ED59" )
				)
				( pin "DDR3_MA(5)"
					( objectStatus "U2D1.EA58" )
				)
				( pin "DDR3_MA(6)"
					( objectStatus "U2D1.EE60" )
				)
				( pin "DDR3_MA(7)"
					( objectStatus "U2D1.EA60" )
				)
				( pin "DDR3_MA(8)"
					( objectStatus "U2D1.EB59" )
				)
				( pin "DDR3_MA(9)"
					( objectStatus "U2D1.EF61" )
				)
				( pin "DDR3_ODT(0)"
					( objectStatus "U2D1.EE50" )
				)
				( pin "DDR3_ODT(1)"
					( objectStatus "U2D1.EE48" )
				)
				( pin "DDR3_ODT(2)"
					( objectStatus "U2D1.EA50" )
				)
				( pin "DDR3_ODT(3)"
					( objectStatus "U2D1.EA48" )
				)
				( pin "DDR3_PAR"
					( objectStatus "U2D1.ED53" )
				)
			)
			( gate "@baseboard_fab2_lib.baseboard_fab2(sch_1):page61_i172"
				( objectStatus "F125" )
				( pin "DDR4_ACT_N"
					( objectStatus "U2D1.DR62" )
				)
				( pin "DDR4_BA(0)"
					( objectStatus "U2D1.DM53" )
				)
				( pin "DDR4_BA(1)"
					( objectStatus "U2D1.DV55" )
				)
				( pin "DDR4_BG(0)"
					( objectStatus "U2D1.DJ62" )
				)
				( pin "DDR4_BG(1)"
					( objectStatus "U2D1.DM61" )
				)
				( pin "DDR4_CID(2)"
					( objectStatus "U2D1.DT47" )
				)
				( pin "DDR4_CKE(0)"
					( objectStatus "U2D1.DM63" )
				)
				( pin "DDR4_CKE(1)"
					( objectStatus "U2D1.DN64" )
				)
				( pin "DDR4_CKE(2)"
					( objectStatus "U2D1.DL64" )
				)
				( pin "DDR4_CKE(3)"
					( objectStatus "U2D1.DR64" )
				)
				( pin "DDR4_CS_N(0)"
					( objectStatus "U2D1.DV51" )
				)
				( pin "DDR4_CS_N(1)"
					( objectStatus "U2D1.DN50" )
				)
				( pin "DDR4_CS_N(2)"
					( objectStatus "U2D1.DR46" )
				)
				( pin "DDR4_CS_N(3)"
					( objectStatus "U2D1.DK47" )
				)
				( pin "DDR4_CS_N(4)"
					( objectStatus "U2D1.DW50" )
				)
				( pin "DDR4_CS_N(5)"
					( objectStatus "U2D1.DM49" )
				)
				( pin "DDR4_CS_N(6)"
					( objectStatus "U2D1.DT45" )
				)
				( pin "DDR4_CS_N(7)"
					( objectStatus "U2D1.DN46" )
				)
				( pin "DDR4_DQ(0)"
					( objectStatus "U2D1.CM79" )
				)
				( pin "DDR4_DQ(10)"
					( objectStatus "U2D1.DE80" )
				)
				( pin "DDR4_DQ(11)"
					( objectStatus "U2D1.DF81" )
				)
				( pin "DDR4_DQ(12)"
					( objectStatus "U2D1.CY79" )
				)
				( pin "DDR4_DQ(13)"
					( objectStatus "U2D1.CW80" )
				)
				( pin "DDR4_DQ(14)"
					( objectStatus "U2D1.DC82" )
				)
				( pin "DDR4_DQ(15)"
					( objectStatus "U2D1.DE82" )
				)
				( pin "DDR4_DQ(16)"
					( objectStatus "U2D1.DW80" )
				)
				( pin "DDR4_DQ(17)"
					( objectStatus "U2D1.EC80" )
				)
				( pin "DDR4_DQ(18)"
					( objectStatus "U2D1.DY77" )
				)
				( pin "DDR4_DQ(19)"
					( objectStatus "U2D1.EB77" )
				)
				( pin "DDR4_DQ(1)"
					( objectStatus "U2D1.CK81" )
				)
				( pin "DDR4_DQ(20)"
					( objectStatus "U2D1.DY81" )
				)
				( pin "DDR4_DQ(21)"
					( objectStatus "U2D1.EB81" )
				)
				( pin "DDR4_DQ(22)"
					( objectStatus "U2D1.DW78" )
				)
				( pin "DDR4_DQ(23)"
					( objectStatus "U2D1.EC78" )
				)
				( pin "DDR4_DQ(24)"
					( objectStatus "U2D1.ED75" )
				)
				( pin "DDR4_DQ(25)"
					( objectStatus "U2D1.EE74" )
				)
				( pin "DDR4_DQ(26)"
					( objectStatus "U2D1.EB71" )
				)
				( pin "DDR4_DQ(27)"
					( objectStatus "U2D1.ED71" )
				)
				( pin "DDR4_DQ(28)"
					( objectStatus "U2D1.EA74" )
				)
				( pin "DDR4_DQ(29)"
					( objectStatus "U2D1.EB75" )
				)
				( pin "DDR4_DQ(2)"
					( objectStatus "U2D1.CT81" )
				)
				( pin "DDR4_DQ(30)"
					( objectStatus "U2D1.EA72" )
				)
				( pin "DDR4_DQ(31)"
					( objectStatus "U2D1.EE72" )
				)
				( pin "DDR4_DQ(32)"
					( objectStatus "U2D1.DU42" )
				)
				( pin "DDR4_DQ(33)"
					( objectStatus "U2D1.DW42" )
				)
				( pin "DDR4_DQ(34)"
					( objectStatus "U2D1.DP39" )
				)
				( pin "DDR4_DQ(35)"
					( objectStatus "U2D1.DT39" )
				)
				( pin "DDR4_DQ(36)"
					( objectStatus "U2D1.DL42" )
				)
				( pin "DDR4_DQ(37)"
					( objectStatus "U2D1.DN42" )
				)
				( pin "DDR4_DQ(38)"
					( objectStatus "U2D1.DN40" )
				)
				( pin "DDR4_DQ(39)"
					( objectStatus "U2D1.DU40" )
				)
				( pin "DDR4_DQ(3)"
					( objectStatus "U2D1.CR82" )
				)
				( pin "DDR4_DQ(40)"
					( objectStatus "U2D1.EC34" )
				)
				( pin "DDR4_DQ(41)"
					( objectStatus "U2D1.ED33" )
				)
				( pin "DDR4_DQ(42)"
					( objectStatus "U2D1.EA30" )
				)
				( pin "DDR4_DQ(43)"
					( objectStatus "U2D1.EC30" )
				)
				( pin "DDR4_DQ(44)"
					( objectStatus "U2D1.DY33" )
				)
				( pin "DDR4_DQ(45)"
					( objectStatus "U2D1.EA34" )
				)
				( pin "DDR4_DQ(46)"
					( objectStatus "U2D1.DY31" )
				)
				( pin "DDR4_DQ(47)"
					( objectStatus "U2D1.ED31" )
				)
				( pin "DDR4_DQ(48)"
					( objectStatus "U2D1.EC28" )
				)
				( pin "DDR4_DQ(49)"
					( objectStatus "U2D1.ED27" )
				)
				( pin "DDR4_DQ(4)"
					( objectStatus "U2D1.CK79" )
				)
				( pin "DDR4_DQ(50)"
					( objectStatus "U2D1.EA24" )
				)
				( pin "DDR4_DQ(51)"
					( objectStatus "U2D1.EC24" )
				)
				( pin "DDR4_DQ(52)"
					( objectStatus "U2D1.DY27" )
				)
				( pin "DDR4_DQ(53)"
					( objectStatus "U2D1.EA28" )
				)
				( pin "DDR4_DQ(54)"
					( objectStatus "U2D1.DY25" )
				)
				( pin "DDR4_DQ(55)"
					( objectStatus "U2D1.ED25" )
				)
				( pin "DDR4_DQ(56)"
					( objectStatus "U2D1.DF27" )
				)
				( pin "DDR4_DQ(57)"
					( objectStatus "U2D1.DK27" )
				)
				( pin "DDR4_DQ(58)"
					( objectStatus "U2D1.DD25" )
				)
				( pin "DDR4_DQ(59)"
					( objectStatus "U2D1.DJ24" )
				)
				( pin "DDR4_DQ(5)"
					( objectStatus "U2D1.CJ80" )
				)
				( pin "DDR4_DQ(60)"
					( objectStatus "U2D1.DG28" )
				)
				( pin "DDR4_DQ(61)"
					( objectStatus "U2D1.DJ28" )
				)
				( pin "DDR4_DQ(62)"
					( objectStatus "U2D1.DF25" )
				)
				( pin "DDR4_DQ(63)"
					( objectStatus "U2D1.DK25" )
				)
				( pin "DDR4_DQ(6)"
					( objectStatus "U2D1.CR80" )
				)
				( pin "DDR4_DQ(7)"
					( objectStatus "U2D1.CN82" )
				)
				( pin "DDR4_DQ(8)"
					( objectStatus "U2D1.DB79" )
				)
				( pin "DDR4_DQ(9)"
					( objectStatus "U2D1.CY81" )
				)
				( pin "DDR4_DQS_DN(0)"
					( objectStatus "U2D1.CL82" )
				)
				( pin "DDR4_DQS_DN(10)"
					( objectStatus "U2D1.DC80" )
				)
				( pin "DDR4_DQS_DN(11)"
					( objectStatus "U2D1.DY79" )
				)
				( pin "DDR4_DQS_DN(12)"
					( objectStatus "U2D1.EB73" )
				)
				( pin "DDR4_DQS_DN(13)"
					( objectStatus "U2D1.DP41" )
				)
				( pin "DDR4_DQS_DN(14)"
					( objectStatus "U2D1.EA32" )
				)
				( pin "DDR4_DQS_DN(15)"
					( objectStatus "U2D1.EA26" )
				)
				( pin "DDR4_DQS_DN(16)"
					( objectStatus "U2D1.DG26" )
				)
				( pin "DDR4_DQS_DN(17)"
					( objectStatus "U2D1.DV67" )
				)
				( pin "DDR4_DQS_DN(1)"
					( objectStatus "U2D1.DA82" )
				)
				( pin "DDR4_DQS_DN(2)"
					( objectStatus "U2D1.ED79" )
				)
				( pin "DDR4_DQS_DN(3)"
					( objectStatus "U2D1.EF73" )
				)
				( pin "DDR4_DQS_DN(4)"
					( objectStatus "U2D1.DV41" )
				)
				( pin "DDR4_DQS_DN(5)"
					( objectStatus "U2D1.EE32" )
				)
				( pin "DDR4_DQS_DN(6)"
					( objectStatus "U2D1.EE26" )
				)
				( pin "DDR4_DQS_DN(7)"
					( objectStatus "U2D1.DL26" )
				)
				( pin "DDR4_DQS_DN(8)"
					( objectStatus "U2D1.EB67" )
				)
				( pin "DDR4_DQS_DN(9)"
					( objectStatus "U2D1.CN80" )
				)
				( pin "DDR4_DQS_DP(0)"
					( objectStatus "U2D1.CM81" )
				)
				( pin "DDR4_DQS_DP(10)"
					( objectStatus "U2D1.DD79" )
				)
				( pin "DDR4_DQS_DP(11)"
					( objectStatus "U2D1.DV79" )
				)
				( pin "DDR4_DQS_DP(12)"
					( objectStatus "U2D1.DY73" )
				)
				( pin "DDR4_DQS_DP(13)"
					( objectStatus "U2D1.DM41" )
				)
				( pin "DDR4_DQS_DP(14)"
					( objectStatus "U2D1.DW32" )
				)
				( pin "DDR4_DQS_DP(15)"
					( objectStatus "U2D1.DW26" )
				)
				( pin "DDR4_DQS_DP(16)"
					( objectStatus "U2D1.DE26" )
				)
				( pin "DDR4_DQS_DP(17)"
					( objectStatus "U2D1.DT67" )
				)
				( pin "DDR4_DQS_DP(1)"
					( objectStatus "U2D1.DB81" )
				)
				( pin "DDR4_DQS_DP(2)"
					( objectStatus "U2D1.EB79" )
				)
				( pin "DDR4_DQS_DP(3)"
					( objectStatus "U2D1.ED73" )
				)
				( pin "DDR4_DQS_DP(4)"
					( objectStatus "U2D1.DT41" )
				)
				( pin "DDR4_DQS_DP(5)"
					( objectStatus "U2D1.EC32" )
				)
				( pin "DDR4_DQS_DP(6)"
					( objectStatus "U2D1.EC26" )
				)
				( pin "DDR4_DQS_DP(7)"
					( objectStatus "U2D1.DJ26" )
				)
				( pin "DDR4_DQS_DP(8)"
					( objectStatus "U2D1.DY67" )
				)
				( pin "DDR4_DQS_DP(9)"
					( objectStatus "U2D1.CP79" )
				)
				( pin "DDR4_ECC(0)"
					( objectStatus "U2D1.DY69" )
				)
				( pin "DDR4_ECC(1)"
					( objectStatus "U2D1.EA68" )
				)
				( pin "DDR4_ECC(2)"
					( objectStatus "U2D1.DV65" )
				)
				( pin "DDR4_ECC(3)"
					( objectStatus "U2D1.DY65" )
				)
				( pin "DDR4_ECC(4)"
					( objectStatus "U2D1.DU68" )
				)
				( pin "DDR4_ECC(5)"
					( objectStatus "U2D1.DV69" )
				)
				( pin "DDR4_ECC(6)"
					( objectStatus "U2D1.DU66" )
				)
				( pin "DDR4_ECC(7)"
					( objectStatus "U2D1.EA66" )
				)
				( pin "DDR4_MA(0)"
					( objectStatus "U2D1.DW52" )
				)
				( pin "DDR4_MA(10)"
					( objectStatus "U2D1.DT55" )
				)
				( pin "DDR4_MA(11)"
					( objectStatus "U2D1.DR60" )
				)
				( pin "DDR4_MA(12)"
					( objectStatus "U2D1.DN60" )
				)
				( pin "DDR4_MA(13)"
					( objectStatus "U2D1.DT51" )
				)
				( pin "DDR4_MA(14)"
					( objectStatus "U2D1.DM51" )
				)
				( pin "DDR4_MA(15)"
					( objectStatus "U2D1.DR52" )
				)
				( pin "DDR4_MA(16)"
					( objectStatus "U2D1.DN52" )
				)
				( pin "DDR4_MA(17)"
					( objectStatus "U2D1.DR48" )
				)
				( pin "DDR4_MA(1)"
					( objectStatus "U2D1.DW58" )
				)
				( pin "DDR4_MA(2)"
					( objectStatus "U2D1.DV57" )
				)
				( pin "DDR4_MA(3)"
					( objectStatus "U2D1.DR58" )
				)
				( pin "DDR4_MA(4)"
					( objectStatus "U2D1.DT59" )
				)
				( pin "DDR4_MA(5)"
					( objectStatus "U2D1.DN58" )
				)
				( pin "DDR4_MA(6)"
					( objectStatus "U2D1.DM59" )
				)
				( pin "DDR4_MA(7)"
					( objectStatus "U2D1.DK61" )
				)
				( pin "DDR4_MA(8)"
					( objectStatus "U2D1.DJ60" )
				)
				( pin "DDR4_MA(9)"
					( objectStatus "U2D1.DV59" )
				)
				( pin "DDR4_ODT(0)"
					( objectStatus "U2D1.DR50" )
				)
				( pin "DDR4_ODT(1)"
					( objectStatus "U2D1.DN48" )
				)
				( pin "DDR4_ODT(2)"
					( objectStatus "U2D1.DT49" )
				)
				( pin "DDR4_ODT(3)"
					( objectStatus "U2D1.DM47" )
				)
				( pin "DDR4_PAR"
					( objectStatus "U2D1.DV53" )
				)
			)
			( gate "@baseboard_fab2_lib.baseboard_fab2(sch_1):page62_i172"
				( objectStatus "F124" )
				( pin "DDR5_ACT_N"
					( objectStatus "U2D1.DC62" )
				)
				( pin "DDR5_BA(0)"
					( objectStatus "U2D1.DJ52" )
				)
				( pin "DDR5_BA(1)"
					( objectStatus "U2D1.DC56" )
				)
				( pin "DDR5_BG(0)"
					( objectStatus "U2D1.DA62" )
				)
				( pin "DDR5_BG(1)"
					( objectStatus "U2D1.DF61" )
				)
				( pin "DDR5_CID(2)"
					( objectStatus "U2D1.DF45" )
				)
				( pin "DDR5_CKE(0)"
					( objectStatus "U2D1.DG62" )
				)
				( pin "DDR5_CKE(1)"
					( objectStatus "U2D1.DD63" )
				)
				( pin "DDR5_CKE(2)"
					( objectStatus "U2D1.DK63" )
				)
				( pin "DDR5_CKE(3)"
					( objectStatus "U2D1.DF63" )
				)
				( pin "DDR5_CS_N(0)"
					( objectStatus "U2D1.DK51" )
				)
				( pin "DDR5_CS_N(1)"
					( objectStatus "U2D1.DF49" )
				)
				( pin "DDR5_CS_N(2)"
					( objectStatus "U2D1.DJ46" )
				)
				( pin "DDR5_CS_N(3)"
					( objectStatus "U2D1.DG46" )
				)
				( pin "DDR5_CS_N(4)"
					( objectStatus "U2D1.DF51" )
				)
				( pin "DDR5_CS_N(5)"
					( objectStatus "U2D1.DJ48" )
				)
				( pin "DDR5_CS_N(6)"
					( objectStatus "U2D1.DM45" )
				)
				( pin "DDR5_CS_N(7)"
					( objectStatus "U2D1.DK45" )
				)
				( pin "DDR5_DQ(0)"
					( objectStatus "U2D1.CR74" )
				)
				( pin "DDR5_DQ(10)"
					( objectStatus "U2D1.DH75" )
				)
				( pin "DDR5_DQ(11)"
					( objectStatus "U2D1.DJ76" )
				)
				( pin "DDR5_DQ(12)"
					( objectStatus "U2D1.DC74" )
				)
				( pin "DDR5_DQ(13)"
					( objectStatus "U2D1.DB75" )
				)
				( pin "DDR5_DQ(14)"
					( objectStatus "U2D1.DF77" )
				)
				( pin "DDR5_DQ(15)"
					( objectStatus "U2D1.DH77" )
				)
				( pin "DDR5_DQ(16)"
					( objectStatus "U2D1.DG70" )
				)
				( pin "DDR5_DQ(17)"
					( objectStatus "U2D1.DJ72" )
				)
				( pin "DDR5_DQ(18)"
					( objectStatus "U2D1.DM69" )
				)
				( pin "DDR5_DQ(19)"
					( objectStatus "U2D1.DN70" )
				)
				( pin "DDR5_DQ(1)"
					( objectStatus "U2D1.CN76" )
				)
				( pin "DDR5_DQ(20)"
					( objectStatus "U2D1.DF71" )
				)
				( pin "DDR5_DQ(21)"
					( objectStatus "U2D1.DG72" )
				)
				( pin "DDR5_DQ(22)"
					( objectStatus "U2D1.DK69" )
				)
				( pin "DDR5_DQ(23)"
					( objectStatus "U2D1.DM71" )
				)
				( pin "DDR5_DQ(24)"
					( objectStatus "U2D1.CN66" )
				)
				( pin "DDR5_DQ(25)"
					( objectStatus "U2D1.CU66" )
				)
				( pin "DDR5_DQ(26)"
					( objectStatus "U2D1.CP63" )
				)
				( pin "DDR5_DQ(27)"
					( objectStatus "U2D1.CT63" )
				)
				( pin "DDR5_DQ(28)"
					( objectStatus "U2D1.CP67" )
				)
				( pin "DDR5_DQ(29)"
					( objectStatus "U2D1.CT67" )
				)
				( pin "DDR5_DQ(2)"
					( objectStatus "U2D1.CW76" )
				)
				( pin "DDR5_DQ(30)"
					( objectStatus "U2D1.CN64" )
				)
				( pin "DDR5_DQ(31)"
					( objectStatus "U2D1.CU64" )
				)
				( pin "DDR5_DQ(32)"
					( objectStatus "U2D1.DD41" )
				)
				( pin "DDR5_DQ(33)"
					( objectStatus "U2D1.DG42" )
				)
				( pin "DDR5_DQ(34)"
					( objectStatus "U2D1.DE38" )
				)
				( pin "DDR5_DQ(35)"
					( objectStatus "U2D1.DG38" )
				)
				( pin "DDR5_DQ(36)"
					( objectStatus "U2D1.DA42" )
				)
				( pin "DDR5_DQ(37)"
					( objectStatus "U2D1.DE42" )
				)
				( pin "DDR5_DQ(38)"
					( objectStatus "U2D1.DD39" )
				)
				( pin "DDR5_DQ(39)"
					( objectStatus "U2D1.DH39" )
				)
				( pin "DDR5_DQ(3)"
					( objectStatus "U2D1.CV77" )
				)
				( pin "DDR5_DQ(40)"
					( objectStatus "U2D1.DF33" )
				)
				( pin "DDR5_DQ(41)"
					( objectStatus "U2D1.DK33" )
				)
				( pin "DDR5_DQ(42)"
					( objectStatus "U2D1.DG30" )
				)
				( pin "DDR5_DQ(43)"
					( objectStatus "U2D1.DJ30" )
				)
				( pin "DDR5_DQ(44)"
					( objectStatus "U2D1.DG34" )
				)
				( pin "DDR5_DQ(45)"
					( objectStatus "U2D1.DJ34" )
				)
				( pin "DDR5_DQ(46)"
					( objectStatus "U2D1.DF31" )
				)
				( pin "DDR5_DQ(47)"
					( objectStatus "U2D1.DK31" )
				)
				( pin "DDR5_DQ(48)"
					( objectStatus "U2D1.CW36" )
				)
				( pin "DDR5_DQ(49)"
					( objectStatus "U2D1.DC36" )
				)
				( pin "DDR5_DQ(4)"
					( objectStatus "U2D1.CN74" )
				)
				( pin "DDR5_DQ(50)"
					( objectStatus "U2D1.CY33" )
				)
				( pin "DDR5_DQ(51)"
					( objectStatus "U2D1.DB33" )
				)
				( pin "DDR5_DQ(52)"
					( objectStatus "U2D1.CY37" )
				)
				( pin "DDR5_DQ(53)"
					( objectStatus "U2D1.DB37" )
				)
				( pin "DDR5_DQ(54)"
					( objectStatus "U2D1.CW34" )
				)
				( pin "DDR5_DQ(55)"
					( objectStatus "U2D1.DC34" )
				)
				( pin "DDR5_DQ(56)"
					( objectStatus "U2D1.CW30" )
				)
				( pin "DDR5_DQ(57)"
					( objectStatus "U2D1.DC30" )
				)
				( pin "DDR5_DQ(58)"
					( objectStatus "U2D1.CY27" )
				)
				( pin "DDR5_DQ(59)"
					( objectStatus "U2D1.DB27" )
				)
				( pin "DDR5_DQ(5)"
					( objectStatus "U2D1.CM75" )
				)
				( pin "DDR5_DQ(60)"
					( objectStatus "U2D1.CY31" )
				)
				( pin "DDR5_DQ(61)"
					( objectStatus "U2D1.DB31" )
				)
				( pin "DDR5_DQ(62)"
					( objectStatus "U2D1.CW28" )
				)
				( pin "DDR5_DQ(63)"
					( objectStatus "U2D1.DC28" )
				)
				( pin "DDR5_DQ(6)"
					( objectStatus "U2D1.CV75" )
				)
				( pin "DDR5_DQ(7)"
					( objectStatus "U2D1.CT77" )
				)
				( pin "DDR5_DQ(8)"
					( objectStatus "U2D1.DE74" )
				)
				( pin "DDR5_DQ(9)"
					( objectStatus "U2D1.DC76" )
				)
				( pin "DDR5_DQS_DN(0)"
					( objectStatus "U2D1.CP77" )
				)
				( pin "DDR5_DQS_DN(10)"
					( objectStatus "U2D1.DF75" )
				)
				( pin "DDR5_DQS_DN(11)"
					( objectStatus "U2D1.DJ70" )
				)
				( pin "DDR5_DQS_DN(12)"
					( objectStatus "U2D1.CP65" )
				)
				( pin "DDR5_DQS_DN(13)"
					( objectStatus "U2D1.DE40" )
				)
				( pin "DDR5_DQS_DN(14)"
					( objectStatus "U2D1.DG32" )
				)
				( pin "DDR5_DQS_DN(15)"
					( objectStatus "U2D1.CY35" )
				)
				( pin "DDR5_DQS_DN(16)"
					( objectStatus "U2D1.CY29" )
				)
				( pin "DDR5_DQS_DN(17)"
					( objectStatus "U2D1.CJ70" )
				)
				( pin "DDR5_DQS_DN(1)"
					( objectStatus "U2D1.DD77" )
				)
				( pin "DDR5_DQS_DN(2)"
					( objectStatus "U2D1.DL72" )
				)
				( pin "DDR5_DQS_DN(3)"
					( objectStatus "U2D1.CV65" )
				)
				( pin "DDR5_DQS_DN(4)"
					( objectStatus "U2D1.DG40" )
				)
				( pin "DDR5_DQS_DN(5)"
					( objectStatus "U2D1.DL32" )
				)
				( pin "DDR5_DQS_DN(6)"
					( objectStatus "U2D1.DD35" )
				)
				( pin "DDR5_DQS_DN(7)"
					( objectStatus "U2D1.DD29" )
				)
				( pin "DDR5_DQS_DN(8)"
					( objectStatus "U2D1.CN70" )
				)
				( pin "DDR5_DQS_DN(9)"
					( objectStatus "U2D1.CT75" )
				)
				( pin "DDR5_DQS_DP(0)"
					( objectStatus "U2D1.CR76" )
				)
				( pin "DDR5_DQS_DP(10)"
					( objectStatus "U2D1.DG74" )
				)
				( pin "DDR5_DQS_DP(11)"
					( objectStatus "U2D1.DH69" )
				)
				( pin "DDR5_DQS_DP(12)"
					( objectStatus "U2D1.CM65" )
				)
				( pin "DDR5_DQS_DP(13)"
					( objectStatus "U2D1.DC40" )
				)
				( pin "DDR5_DQS_DP(14)"
					( objectStatus "U2D1.DE32" )
				)
				( pin "DDR5_DQS_DP(15)"
					( objectStatus "U2D1.CV35" )
				)
				( pin "DDR5_DQS_DP(16)"
					( objectStatus "U2D1.CV29" )
				)
				( pin "DDR5_DQS_DP(17)"
					( objectStatus "U2D1.CG70" )
				)
				( pin "DDR5_DQS_DP(1)"
					( objectStatus "U2D1.DE76" )
				)
				( pin "DDR5_DQS_DP(2)"
					( objectStatus "U2D1.DK71" )
				)
				( pin "DDR5_DQS_DP(3)"
					( objectStatus "U2D1.CT65" )
				)
				( pin "DDR5_DQS_DP(4)"
					( objectStatus "U2D1.DJ40" )
				)
				( pin "DDR5_DQS_DP(5)"
					( objectStatus "U2D1.DJ32" )
				)
				( pin "DDR5_DQS_DP(6)"
					( objectStatus "U2D1.DB35" )
				)
				( pin "DDR5_DQS_DP(7)"
					( objectStatus "U2D1.DB29" )
				)
				( pin "DDR5_DQS_DP(8)"
					( objectStatus "U2D1.CL70" )
				)
				( pin "DDR5_DQS_DP(9)"
					( objectStatus "U2D1.CU74" )
				)
				( pin "DDR5_ECC(0)"
					( objectStatus "U2D1.CH71" )
				)
				( pin "DDR5_ECC(1)"
					( objectStatus "U2D1.CM71" )
				)
				( pin "DDR5_ECC(2)"
					( objectStatus "U2D1.CJ68" )
				)
				( pin "DDR5_ECC(3)"
					( objectStatus "U2D1.CL68" )
				)
				( pin "DDR5_ECC(4)"
					( objectStatus "U2D1.CJ72" )
				)
				( pin "DDR5_ECC(5)"
					( objectStatus "U2D1.CL72" )
				)
				( pin "DDR5_ECC(6)"
					( objectStatus "U2D1.CH69" )
				)
				( pin "DDR5_ECC(7)"
					( objectStatus "U2D1.CM69" )
				)
				( pin "DDR5_MA(0)"
					( objectStatus "U2D1.DF53" )
				)
				( pin "DDR5_MA(10)"
					( objectStatus "U2D1.DD55" )
				)
				( pin "DDR5_MA(11)"
					( objectStatus "U2D1.DA60" )
				)
				( pin "DDR5_MA(12)"
					( objectStatus "U2D1.DG60" )
				)
				( pin "DDR5_MA(13)"
					( objectStatus "U2D1.DD53" )
				)
				( pin "DDR5_MA(14)"
					( objectStatus "U2D1.DJ50" )
				)
				( pin "DDR5_MA(15)"
					( objectStatus "U2D1.DC54" )
				)
				( pin "DDR5_MA(16)"
					( objectStatus "U2D1.DG52" )
				)
				( pin "DDR5_MA(17)"
					( objectStatus "U2D1.DE46" )
				)
				( pin "DDR5_MA(1)"
					( objectStatus "U2D1.DC58" )
				)
				( pin "DDR5_MA(2)"
					( objectStatus "U2D1.DD57" )
				)
				( pin "DDR5_MA(3)"
					( objectStatus "U2D1.DG58" )
				)
				( pin "DDR5_MA(4)"
					( objectStatus "U2D1.DJ58" )
				)
				( pin "DDR5_MA(5)"
					( objectStatus "U2D1.DF59" )
				)
				( pin "DDR5_MA(6)"
					( objectStatus "U2D1.DK59" )
				)
				( pin "DDR5_MA(7)"
					( objectStatus "U2D1.DC60" )
				)
				( pin "DDR5_MA(8)"
					( objectStatus "U2D1.DD59" )
				)
				( pin "DDR5_MA(9)"
					( objectStatus "U2D1.DA58" )
				)
				( pin "DDR5_ODT(0)"
					( objectStatus "U2D1.DG50" )
				)
				( pin "DDR5_ODT(1)"
					( objectStatus "U2D1.DG48" )
				)
				( pin "DDR5_ODT(2)"
					( objectStatus "U2D1.DK49" )
				)
				( pin "DDR5_ODT(3)"
					( objectStatus "U2D1.DF47" )
				)
				( pin "DDR5_PAR"
					( objectStatus "U2D1.DK53" )
				)
			)
			( gate "@baseboard_fab2_lib.baseboard_fab2(sch_1):page63_i23"
				( objectStatus "F123" )
				( pin "CD_PE_REFCLK_DN"
					( objectStatus "U2D1.BU24" )
				)
				( pin "CD_PE_REFCLK_DP"
					( objectStatus "U2D1.BW24" )
				)
			)
			( gate "@baseboard_fab2_lib.baseboard_fab2(sch_1):page64_i68"
				( objectStatus "F122" )
			)
			( gate "@baseboard_fab2_lib.baseboard_fab2(sch_1):page65_i68"
				( objectStatus "F121" )
			)
			( gate "@baseboard_fab2_lib.baseboard_fab2(sch_1):page66_i84"
				( objectStatus "F120" )
				( pin "PE3_RX_DN(0)"
					( objectStatus "U2D1.EA18" )
				)
				( pin "PE3_RX_DN(10)"
					( objectStatus "U2D1.DG12" )
				)
				( pin "PE3_RX_DN(11)"
					( objectStatus "U2D1.DG10" )
				)
				( pin "PE3_RX_DN(12)"
					( objectStatus "U2D1.DD13" )
				)
				( pin "PE3_RX_DN(13)"
					( objectStatus "U2D1.DB11" )
				)
				( pin "PE3_RX_DN(14)"
					( objectStatus "U2D1.CY11" )
				)
				( pin "PE3_RX_DN(15)"
					( objectStatus "U2D1.CV9" )
				)
				( pin "PE3_RX_DN(1)"
					( objectStatus "U2D1.DW18" )
				)
				( pin "PE3_RX_DN(2)"
					( objectStatus "U2D1.DW16" )
				)
				( pin "PE3_RX_DN(3)"
					( objectStatus "U2D1.DT19" )
				)
				( pin "PE3_RX_DN(4)"
					( objectStatus "U2D1.DR16" )
				)
				( pin "PE3_RX_DN(5)"
					( objectStatus "U2D1.DR14" )
				)
				( pin "PE3_RX_DN(6)"
					( objectStatus "U2D1.DN14" )
				)
				( pin "PE3_RX_DN(7)"
					( objectStatus "U2D1.DL14" )
				)
				( pin "PE3_RX_DN(8)"
					( objectStatus "U2D1.DL12" )
				)
				( pin "PE3_RX_DN(9)"
					( objectStatus "U2D1.DJ12" )
				)
				( pin "PE3_RX_DP(0)"
					( objectStatus "U2D1.DY17" )
				)
				( pin "PE3_RX_DP(10)"
					( objectStatus "U2D1.DE12" )
				)
				( pin "PE3_RX_DP(11)"
					( objectStatus "U2D1.DF11" )
				)
				( pin "PE3_RX_DP(12)"
					( objectStatus "U2D1.DC12" )
				)
				( pin "PE3_RX_DP(13)"
					( objectStatus "U2D1.DA12" )
				)
				( pin "PE3_RX_DP(14)"
					( objectStatus "U2D1.CW10" )
				)
				( pin "PE3_RX_DP(15)"
					( objectStatus "U2D1.CU10" )
				)
				( pin "PE3_RX_DP(1)"
					( objectStatus "U2D1.DU18" )
				)
				( pin "PE3_RX_DP(2)"
					( objectStatus "U2D1.DV17" )
				)
				( pin "PE3_RX_DP(3)"
					( objectStatus "U2D1.DR18" )
				)
				( pin "PE3_RX_DP(4)"
					( objectStatus "U2D1.DN16" )
				)
				( pin "PE3_RX_DP(5)"
					( objectStatus "U2D1.DP15" )
				)
				( pin "PE3_RX_DP(6)"
					( objectStatus "U2D1.DM13" )
				)
				( pin "PE3_RX_DP(7)"
					( objectStatus "U2D1.DJ14" )
				)
				( pin "PE3_RX_DP(8)"
					( objectStatus "U2D1.DK13" )
				)
				( pin "PE3_RX_DP(9)"
					( objectStatus "U2D1.DH11" )
				)
				( pin "PE3_TX_DN(0)"
					( objectStatus "U2D1.EE14" )
				)
				( pin "PE3_TX_DN(10)"
					( objectStatus "U2D1.DL6" )
				)
				( pin "PE3_TX_DN(11)"
					( objectStatus "U2D1.DJ4" )
				)
				( pin "PE3_TX_DN(12)"
					( objectStatus "U2D1.DJ6" )
				)
				( pin "PE3_TX_DN(13)"
					( objectStatus "U2D1.DD5" )
				)
				( pin "PE3_TX_DN(14)"
					( objectStatus "U2D1.DB5" )
				)
				( pin "PE3_TX_DN(15)"
					( objectStatus "U2D1.CY5" )
				)
				( pin "PE3_TX_DN(1)"
					( objectStatus "U2D1.EE12" )
				)
				( pin "PE3_TX_DN(2)"
					( objectStatus "U2D1.EC12" )
				)
				( pin "PE3_TX_DN(3)"
					( objectStatus "U2D1.DY11" )
				)
				( pin "PE3_TX_DN(4)"
					( objectStatus "U2D1.EB9" )
				)
				( pin "PE3_TX_DN(5)"
					( objectStatus "U2D1.DW10" )
				)
				( pin "PE3_TX_DN(6)"
					( objectStatus "U2D1.DU8" )
				)
				( pin "PE3_TX_DN(7)"
					( objectStatus "U2D1.DR8" )
				)
				( pin "PE3_TX_DN(8)"
					( objectStatus "U2D1.DM7" )
				)
				( pin "PE3_TX_DN(9)"
					( objectStatus "U2D1.DP5" )
				)
				( pin "PE3_TX_DP(0)"
					( objectStatus "U2D1.EC14" )
				)
				( pin "PE3_TX_DP(10)"
					( objectStatus "U2D1.DK5" )
				)
				( pin "PE3_TX_DP(11)"
					( objectStatus "U2D1.DH5" )
				)
				( pin "PE3_TX_DP(12)"
					( objectStatus "U2D1.DG6" )
				)
				( pin "PE3_TX_DP(13)"
					( objectStatus "U2D1.DC6" )
				)
				( pin "PE3_TX_DP(14)"
					( objectStatus "U2D1.DA4" )
				)
				( pin "PE3_TX_DP(15)"
					( objectStatus "U2D1.CV5" )
				)
				( pin "PE3_TX_DP(1)"
					( objectStatus "U2D1.ED13" )
				)
				( pin "PE3_TX_DP(2)"
					( objectStatus "U2D1.EB11" )
				)
				( pin "PE3_TX_DP(3)"
					( objectStatus "U2D1.EA10" )
				)
				( pin "PE3_TX_DP(4)"
					( objectStatus "U2D1.DY9" )
				)
				( pin "PE3_TX_DP(5)"
					( objectStatus "U2D1.DV9" )
				)
				( pin "PE3_TX_DP(6)"
					( objectStatus "U2D1.DT9" )
				)
				( pin "PE3_TX_DP(7)"
					( objectStatus "U2D1.DP7" )
				)
				( pin "PE3_TX_DP(8)"
					( objectStatus "U2D1.DN6" )
				)
				( pin "PE3_TX_DP(9)"
					( objectStatus "U2D1.DM5" )
				)
			)
			( gate "@baseboard_fab2_lib.baseboard_fab2(sch_1):page67_i132"
				( objectStatus "F119" )
				( pin "UPI0_RX_DN(0)"
					( objectStatus "U2D1.AC10" )
				)
				( pin "UPI0_RX_DN(10)"
					( objectStatus "U2D1.AP7" )
				)
				( pin "UPI0_RX_DN(11)"
					( objectStatus "U2D1.AR8" )
				)
				( pin "UPI0_RX_DN(12)"
					( objectStatus "U2D1.AU10" )
				)
				( pin "UPI0_RX_DN(13)"
					( objectStatus "U2D1.BA8" )
				)
				( pin "UPI0_RX_DN(14)"
					( objectStatus "U2D1.BC6" )
				)
				( pin "UPI0_RX_DN(15)"
					( objectStatus "U2D1.BD7" )
				)
				( pin "UPI0_RX_DN(16)"
					( objectStatus "U2D1.AW8" )
				)
				( pin "UPI0_RX_DN(17)"
					( objectStatus "U2D1.AY9" )
				)
				( pin "UPI0_RX_DN(18)"
					( objectStatus "U2D1.BD9" )
				)
				( pin "UPI0_RX_DN(19)"
					( objectStatus "U2D1.BB11" )
				)
				( pin "UPI0_RX_DN(1)"
					( objectStatus "U2D1.AA8" )
				)
				( pin "UPI0_RX_DN(2)"
					( objectStatus "U2D1.AB7" )
				)
				( pin "UPI0_RX_DN(3)"
					( objectStatus "U2D1.AD5" )
				)
				( pin "UPI0_RX_DN(4)"
					( objectStatus "U2D1.AE6" )
				)
				( pin "UPI0_RX_DN(5)"
					( objectStatus "U2D1.AG8" )
				)
				( pin "UPI0_RX_DN(6)"
					( objectStatus "U2D1.AJ6" )
				)
				( pin "UPI0_RX_DN(7)"
					( objectStatus "U2D1.AL6" )
				)
				( pin "UPI0_RX_DN(8)"
					( objectStatus "U2D1.AK7" )
				)
				( pin "UPI0_RX_DN(9)"
					( objectStatus "U2D1.AM9" )
				)
				( pin "UPI0_RX_DP(0)"
					( objectStatus "U2D1.AB9" )
				)
				( pin "UPI0_RX_DP(10)"
					( objectStatus "U2D1.AN8" )
				)
				( pin "UPI0_RX_DP(11)"
					( objectStatus "U2D1.AU8" )
				)
				( pin "UPI0_RX_DP(12)"
					( objectStatus "U2D1.AT9" )
				)
				( pin "UPI0_RX_DP(13)"
					( objectStatus "U2D1.AY7" )
				)
				( pin "UPI0_RX_DP(14)"
					( objectStatus "U2D1.BB7" )
				)
				( pin "UPI0_RX_DP(15)"
					( objectStatus "U2D1.BF7" )
				)
				( pin "UPI0_RX_DP(16)"
					( objectStatus "U2D1.AV9" )
				)
				( pin "UPI0_RX_DP(17)"
					( objectStatus "U2D1.BB9" )
				)
				( pin "UPI0_RX_DP(18)"
					( objectStatus "U2D1.BC10" )
				)
				( pin "UPI0_RX_DP(19)"
					( objectStatus "U2D1.BA10" )
				)
				( pin "UPI0_RX_DP(1)"
					( objectStatus "U2D1.AC8" )
				)
				( pin "UPI0_RX_DP(2)"
					( objectStatus "U2D1.AA6" )
				)
				( pin "UPI0_RX_DP(3)"
					( objectStatus "U2D1.AC6" )
				)
				( pin "UPI0_RX_DP(4)"
					( objectStatus "U2D1.AG6" )
				)
				( pin "UPI0_RX_DP(5)"
					( objectStatus "U2D1.AF7" )
				)
				( pin "UPI0_RX_DP(6)"
					( objectStatus "U2D1.AH7" )
				)
				( pin "UPI0_RX_DP(7)"
					( objectStatus "U2D1.AK5" )
				)
				( pin "UPI0_RX_DP(8)"
					( objectStatus "U2D1.AM7" )
				)
				( pin "UPI0_RX_DP(9)"
					( objectStatus "U2D1.AL8" )
				)
				( pin "UPI0_TX_DN(0)"
					( objectStatus "U2D1.N2" )
				)
				( pin "UPI0_TX_DN(10)"
					( objectStatus "U2D1.AM3" )
				)
				( pin "UPI0_TX_DN(11)"
					( objectStatus "U2D1.AN4" )
				)
				( pin "UPI0_TX_DN(12)"
					( objectStatus "U2D1.AT1" )
				)
				( pin "UPI0_TX_DN(13)"
					( objectStatus "U2D1.AT3" )
				)
				( pin "UPI0_TX_DN(14)"
					( objectStatus "U2D1.AU4" )
				)
				( pin "UPI0_TX_DN(15)"
					( objectStatus "U2D1.AV5" )
				)
				( pin "UPI0_TX_DN(16)"
					( objectStatus "U2D1.BA4" )
				)
				( pin "UPI0_TX_DN(17)"
					( objectStatus "U2D1.BB3" )
				)
				( pin "UPI0_TX_DN(18)"
					( objectStatus "U2D1.BF3" )
				)
				( pin "UPI0_TX_DN(19)"
					( objectStatus "U2D1.BG4" )
				)
				( pin "UPI0_TX_DN(1)"
					( objectStatus "U2D1.P1" )
				)
				( pin "UPI0_TX_DN(2)"
					( objectStatus "U2D1.V3" )
				)
				( pin "UPI0_TX_DN(3)"
					( objectStatus "U2D1.Y1" )
				)
				( pin "UPI0_TX_DN(4)"
					( objectStatus "U2D1.AB3" )
				)
				( pin "UPI0_TX_DN(5)"
					( objectStatus "U2D1.AC2" )
				)
				( pin "UPI0_TX_DN(6)"
					( objectStatus "U2D1.AG4" )
				)
				( pin "UPI0_TX_DN(7)"
					( objectStatus "U2D1.AE2" )
				)
				( pin "UPI0_TX_DN(8)"
					( objectStatus "U2D1.AH3" )
				)
				( pin "UPI0_TX_DN(9)"
					( objectStatus "U2D1.AL2" )
				)
				( pin "UPI0_TX_DP(0)"
					( objectStatus "U2D1.M1" )
				)
				( pin "UPI0_TX_DP(10)"
					( objectStatus "U2D1.AK3" )
				)
				( pin "UPI0_TX_DP(11)"
					( objectStatus "U2D1.AP3" )
				)
				( pin "UPI0_TX_DP(12)"
					( objectStatus "U2D1.AP1" )
				)
				( pin "UPI0_TX_DP(13)"
					( objectStatus "U2D1.AR2" )
				)
				( pin "UPI0_TX_DP(14)"
					( objectStatus "U2D1.AR4" )
				)
				( pin "UPI0_TX_DP(15)"
					( objectStatus "U2D1.AW4" )
				)
				( pin "UPI0_TX_DP(16)"
					( objectStatus "U2D1.AY3" )
				)
				( pin "UPI0_TX_DP(17)"
					( objectStatus "U2D1.BC2" )
				)
				( pin "UPI0_TX_DP(18)"
					( objectStatus "U2D1.BD3" )
				)
				( pin "UPI0_TX_DP(19)"
					( objectStatus "U2D1.BH3" )
				)
				( pin "UPI0_TX_DP(1)"
					( objectStatus "U2D1.T1" )
				)
				( pin "UPI0_TX_DP(2)"
					( objectStatus "U2D1.Y3" )
				)
				( pin "UPI0_TX_DP(3)"
					( objectStatus "U2D1.W2" )
				)
				( pin "UPI0_TX_DP(4)"
					( objectStatus "U2D1.AA2" )
				)
				( pin "UPI0_TX_DP(5)"
					( objectStatus "U2D1.AD1" )
				)
				( pin "UPI0_TX_DP(6)"
					( objectStatus "U2D1.AF3" )
				)
				( pin "UPI0_TX_DP(7)"
					( objectStatus "U2D1.AG2" )
				)
				( pin "UPI0_TX_DP(8)"
					( objectStatus "U2D1.AJ2" )
				)
				( pin "UPI0_TX_DP(9)"
					( objectStatus "U2D1.AK1" )
				)
			)
			( gate "@baseboard_fab2_lib.baseboard_fab2(sch_1):page68_i125"
				( objectStatus "F118" )
				( pin "UPI1_RX_DN(0)"
					( objectStatus "U2D1.T5" )
				)
				( pin "UPI1_RX_DN(10)"
					( objectStatus "U2D1.R16" )
				)
				( pin "UPI1_RX_DN(11)"
					( objectStatus "U2D1.P17" )
				)
				( pin "UPI1_RX_DN(12)"
					( objectStatus "U2D1.U16" )
				)
				( pin "UPI1_RX_DN(13)"
					( objectStatus "U2D1.W18" )
				)
				( pin "UPI1_RX_DN(14)"
					( objectStatus "U2D1.R20" )
				)
				( pin "UPI1_RX_DN(15)"
					( objectStatus "U2D1.U18" )
				)
				( pin "UPI1_RX_DN(16)"
					( objectStatus "U2D1.P21" )
				)
				( pin "UPI1_RX_DN(17)"
					( objectStatus "U2D1.V19" )
				)
				( pin "UPI1_RX_DN(18)"
					( objectStatus "U2D1.Y21" )
				)
				( pin "UPI1_RX_DN(19)"
					( objectStatus "U2D1.AB19" )
				)
				( pin "UPI1_RX_DN(1)"
					( objectStatus "U2D1.P7" )
				)
				( pin "UPI1_RX_DN(2)"
					( objectStatus "U2D1.V7" )
				)
				( pin "UPI1_RX_DN(3)"
					( objectStatus "U2D1.T9" )
				)
				( pin "UPI1_RX_DN(4)"
					( objectStatus "U2D1.P9" )
				)
				( pin "UPI1_RX_DN(5)"
					( objectStatus "U2D1.R10" )
				)
				( pin "UPI1_RX_DN(6)"
					( objectStatus "U2D1.U12" )
				)
				( pin "UPI1_RX_DN(7)"
					( objectStatus "U2D1.L12" )
				)
				( pin "UPI1_RX_DN(8)"
					( objectStatus "U2D1.N14" )
				)
				( pin "UPI1_RX_DN(9)"
					( objectStatus "U2D1.R12" )
				)
				( pin "UPI1_RX_DP(0)"
					( objectStatus "U2D1.R6" )
				)
				( pin "UPI1_RX_DP(10)"
					( objectStatus "U2D1.T15" )
				)
				( pin "UPI1_RX_DP(11)"
					( objectStatus "U2D1.N16" )
				)
				( pin "UPI1_RX_DP(12)"
					( objectStatus "U2D1.W16" )
				)
				( pin "UPI1_RX_DP(13)"
					( objectStatus "U2D1.V17" )
				)
				( pin "UPI1_RX_DP(14)"
					( objectStatus "U2D1.P19" )
				)
				( pin "UPI1_RX_DP(15)"
					( objectStatus "U2D1.T19" )
				)
				( pin "UPI1_RX_DP(16)"
					( objectStatus "U2D1.T21" )
				)
				( pin "UPI1_RX_DP(17)"
					( objectStatus "U2D1.Y19" )
				)
				( pin "UPI1_RX_DP(18)"
					( objectStatus "U2D1.W20" )
				)
				( pin "UPI1_RX_DP(19)"
					( objectStatus "U2D1.AA20" )
				)
				( pin "UPI1_RX_DP(1)"
					( objectStatus "U2D1.T7" )
				)
				( pin "UPI1_RX_DP(2)"
					( objectStatus "U2D1.U8" )
				)
				( pin "UPI1_RX_DP(3)"
					( objectStatus "U2D1.R8" )
				)
				( pin "UPI1_RX_DP(4)"
					( objectStatus "U2D1.N10" )
				)
				( pin "UPI1_RX_DP(5)"
					( objectStatus "U2D1.U10" )
				)
				( pin "UPI1_RX_DP(6)"
					( objectStatus "U2D1.T11" )
				)
				( pin "UPI1_RX_DP(7)"
					( objectStatus "U2D1.N12" )
				)
				( pin "UPI1_RX_DP(8)"
					( objectStatus "U2D1.M13" )
				)
				( pin "UPI1_RX_DP(9)"
					( objectStatus "U2D1.P13" )
				)
				( pin "UPI1_TX_DN(0)"
					( objectStatus "U2D1.M3" )
				)
				( pin "UPI1_TX_DN(10)"
					( objectStatus "U2D1.E12" )
				)
				( pin "UPI1_TX_DN(11)"
					( objectStatus "U2D1.G14" )
				)
				( pin "UPI1_TX_DN(12)"
					( objectStatus "U2D1.D15" )
				)
				( pin "UPI1_TX_DN(13)"
					( objectStatus "U2D1.F15" )
				)
				( pin "UPI1_TX_DN(14)"
					( objectStatus "U2D1.H17" )
				)
				( pin "UPI1_TX_DN(15)"
					( objectStatus "U2D1.K19" )
				)
				( pin "UPI1_TX_DN(16)"
					( objectStatus "U2D1.G18" )
				)
				( pin "UPI1_TX_DN(17)"
					( objectStatus "U2D1.J20" )
				)
				( pin "UPI1_TX_DN(18)"
					( objectStatus "U2D1.F21" )
				)
				( pin "UPI1_TX_DN(19)"
					( objectStatus "U2D1.H21" )
				)
				( pin "UPI1_TX_DN(1)"
					( objectStatus "U2D1.L4" )
				)
				( pin "UPI1_TX_DN(2)"
					( objectStatus "U2D1.K5" )
				)
				( pin "UPI1_TX_DN(3)"
					( objectStatus "U2D1.J6" )
				)
				( pin "UPI1_TX_DN(4)"
					( objectStatus "U2D1.G6" )
				)
				( pin "UPI1_TX_DN(5)"
					( objectStatus "U2D1.H7" )
				)
				( pin "UPI1_TX_DN(6)"
					( objectStatus "U2D1.K9" )
				)
				( pin "UPI1_TX_DN(7)"
					( objectStatus "U2D1.D9" )
				)
				( pin "UPI1_TX_DN(8)"
					( objectStatus "U2D1.F11" )
				)
				( pin "UPI1_TX_DN(9)"
					( objectStatus "U2D1.G10" )
				)
				( pin "UPI1_TX_DP(0)"
					( objectStatus "U2D1.P3" )
				)
				( pin "UPI1_TX_DP(10)"
					( objectStatus "U2D1.G12" )
				)
				( pin "UPI1_TX_DP(11)"
					( objectStatus "U2D1.F13" )
				)
				( pin "UPI1_TX_DP(12)"
					( objectStatus "U2D1.E14" )
				)
				( pin "UPI1_TX_DP(13)"
					( objectStatus "U2D1.H15" )
				)
				( pin "UPI1_TX_DP(14)"
					( objectStatus "U2D1.G16" )
				)
				( pin "UPI1_TX_DP(15)"
					( objectStatus "U2D1.L18" )
				)
				( pin "UPI1_TX_DP(16)"
					( objectStatus "U2D1.J18" )
				)
				( pin "UPI1_TX_DP(17)"
					( objectStatus "U2D1.H19" )
				)
				( pin "UPI1_TX_DP(18)"
					( objectStatus "U2D1.G20" )
				)
				( pin "UPI1_TX_DP(19)"
					( objectStatus "U2D1.K21" )
				)
				( pin "UPI1_TX_DP(1)"
					( objectStatus "U2D1.K3" )
				)
				( pin "UPI1_TX_DP(2)"
					( objectStatus "U2D1.M5" )
				)
				( pin "UPI1_TX_DP(3)"
					( objectStatus "U2D1.H5" )
				)
				( pin "UPI1_TX_DP(4)"
					( objectStatus "U2D1.F7" )
				)
				( pin "UPI1_TX_DP(5)"
					( objectStatus "U2D1.K7" )
				)
				( pin "UPI1_TX_DP(6)"
					( objectStatus "U2D1.J8" )
				)
				( pin "UPI1_TX_DP(7)"
					( objectStatus "U2D1.F9" )
				)
				( pin "UPI1_TX_DP(8)"
					( objectStatus "U2D1.E10" )
				)
				( pin "UPI1_TX_DP(9)"
					( objectStatus "U2D1.H9" )
				)
			)
			( gate "@baseboard_fab2_lib.baseboard_fab2(sch_1):page69_i1"
				( objectStatus "F117" )
			)
			( gate "@baseboard_fab2_lib.baseboard_fab2(sch_1):page70_i9"
				( objectStatus "F116" )
				( pin "RSVD(153)"
					( objectStatus "U2D1.BD25" )
				)
				( pin "RSVD(165)"
					( objectStatus "U2D1.BB25" )
				)
			)
			( gate "@baseboard_fab2_lib.baseboard_fab2(sch_1):page70_i10"
				( objectStatus "F115" )
			)
			( gate "@baseboard_fab2_lib.baseboard_fab2(sch_1):page71_i50"
				( objectStatus "F114" )
			)
			( gate "@baseboard_fab2_lib.baseboard_fab2(sch_1):page71_i51"
				( objectStatus "F113" )
			)
			( gate "@baseboard_fab2_lib.baseboard_fab2(sch_1):page72_i32"
				( objectStatus "F112" )
			)
			( gate "@baseboard_fab2_lib.baseboard_fab2(sch_1):page72_i33"
				( objectStatus "F111" )
			)
			( gate "@baseboard_fab2_lib.baseboard_fab2(sch_1):page73_i107"
				( objectStatus "F110" )
			)
			( gate "@baseboard_fab2_lib.baseboard_fab2(sch_1):page74_i20"
				( objectStatus "F109" )
			)
			( gate "@baseboard_fab2_lib.baseboard_fab2(sch_1):page74_i21"
				( objectStatus "F108" )
			)
			( gate "@baseboard_fab2_lib.baseboard_fab2(sch_1):page74_i22"
				( objectStatus "F107" )
			)
			( gate "@baseboard_fab2_lib.baseboard_fab2(sch_1):page74_i23"
				( objectStatus "F106" )
			)
			( gate "@baseboard_fab2_lib.baseboard_fab2(sch_1):page75_i17"
				( objectStatus "F105" )
			)
			( gate "@baseboard_fab2_lib.baseboard_fab2(sch_1):page75_i18"
				( objectStatus "F104" )
			)
			( gate "@baseboard_fab2_lib.baseboard_fab2(sch_1):page75_i19"
				( objectStatus "F103" )
			)
			( gate "@baseboard_fab2_lib.baseboard_fab2(sch_1):page75_i20"
				( objectStatus "F102" )
			)
			( gate "@baseboard_fab2_lib.baseboard_fab2(sch_1):page198_i1"
				( objectStatus "F71" )
			)
			( gate "@baseboard_fab2_lib.baseboard_fab2(sch_1):page198_i19"
				( objectStatus "F70" )
			)
			( gate "@baseboard_fab2_lib.baseboard_fab2(sch_1):page198_i13"
				( objectStatus "F69" )
			)
			( gate "@baseboard_fab2_lib.baseboard_fab2(sch_1):page198_i69"
				( objectStatus "F68" )
			)
			( gate "@baseboard_fab2_lib.baseboard_fab2(sch_1):page139_i109"
				( objectStatus "F2232" )
			)
			( gate "@baseboard_fab2_lib.baseboard_fab2(sch_1):page196_i74"
				( objectStatus "F282" )
			)
			( gate "@baseboard_fab2_lib.baseboard_fab2(sch_1):page199_i84"
				( objectStatus "F283" )
			)
			( gate "@baseboard_fab2_lib.baseboard_fab2(sch_1):page212_i25"
				( objectStatus "F2083" )
			)
			( gate "@baseboard_fab2_lib.baseboard_fab2(sch_1):page214_i67"
				( objectStatus "F2084" )
			)
			( gate "@baseboard_fab2_lib.baseboard_fab2(sch_1):page188_i41"
				( objectStatus "F2285" )
			)
			( gate "@baseboard_fab2_lib.baseboard_fab2(sch_1):page240_i137"
				( objectStatus "F2283" )
			)
			( gate "@baseboard_fab2_lib.baseboard_fab2(sch_1):page241_i39"
				( objectStatus "F2284" )
			)
			( gate "@baseboard_fab2_lib.baseboard_fab2(sch_1):page172_i53"
				( objectStatus "F2243" )
				( pin "IO2"
					( objectStatus "J2L1.2" )
				)
				( pin "IO3"
					( objectStatus "J2L1.3" )
				)
				( pin "IO4"
					( objectStatus "J2L1.4" )
				)
			)
			( gate "@baseboard_fab2_lib.baseboard_fab2(sch_1):page43_i1"
				( objectStatus "F148" )
				( pin "A0"
					( objectStatus "J4G1.79" )
				)
				( pin "A1"
					( objectStatus "J4G1.72" )
				)
				( pin "A10"
					( objectStatus "J4G1.225" )
				)
				( pin "A11"
					( objectStatus "J4G1.210" )
				)
				( pin "A12"
					( objectStatus "J4G1.65" )
				)
				( pin "A13"
					( objectStatus "J4G1.232" )
				)
				( pin "A14_WE_N"
					( objectStatus "J4G1.228" )
				)
				( pin "A15_CAS_N"
					( objectStatus "J4G1.86" )
				)
				( pin "A16_RAS_N"
					( objectStatus "J4G1.82" )
				)
				( pin "A17"
					( objectStatus "J4G1.234" )
				)
				( pin "A2"
					( objectStatus "J4G1.216" )
				)
				( pin "A3"
					( objectStatus "J4G1.71" )
				)
				( pin "A4"
					( objectStatus "J4G1.214" )
				)
				( pin "A5"
					( objectStatus "J4G1.213" )
				)
				( pin "A6"
					( objectStatus "J4G1.69" )
				)
				( pin "A7"
					( objectStatus "J4G1.211" )
				)
				( pin "A8"
					( objectStatus "J4G1.68" )
				)
				( pin "A9"
					( objectStatus "J4G1.66" )
				)
				( pin "ACT_N"
					( objectStatus "J4G1.62" )
				)
				( pin "BA(0)"
					( objectStatus "J4G1.81" )
				)
				( pin "BA(1)"
					( objectStatus "J4G1.224" )
				)
				( pin "BG(0)"
					( objectStatus "J4G1.63" )
				)
				( pin "BG(1)"
					( objectStatus "J4G1.207" )
				)
				( pin "C(2)"
					( objectStatus "J4G1.235" )
				)
				( pin "CB(0)"
					( objectStatus "J4G1.49" )
				)
				( pin "CB(1)"
					( objectStatus "J4G1.194" )
				)
				( pin "CB(2)"
					( objectStatus "J4G1.56" )
				)
				( pin "CB(3)"
					( objectStatus "J4G1.201" )
				)
				( pin "CB(4)"
					( objectStatus "J4G1.47" )
				)
				( pin "CB(5)"
					( objectStatus "J4G1.192" )
				)
				( pin "CB(6)"
					( objectStatus "J4G1.54" )
				)
				( pin "CB(7)"
					( objectStatus "J4G1.199" )
				)
				( pin "CKE(0)"
					( objectStatus "J4G1.60" )
				)
				( pin "CKE(1)"
					( objectStatus "J4G1.203" )
				)
				( pin "DQ(0)"
					( objectStatus "J4G1.5" )
				)
				( pin "DQ(10)"
					( objectStatus "J4G1.23" )
				)
				( pin "DQ(11)"
					( objectStatus "J4G1.168" )
				)
				( pin "DQ(12)"
					( objectStatus "J4G1.14" )
				)
				( pin "DQ(13)"
					( objectStatus "J4G1.159" )
				)
				( pin "DQ(14)"
					( objectStatus "J4G1.21" )
				)
				( pin "DQ(15)"
					( objectStatus "J4G1.166" )
				)
				( pin "DQ(16)"
					( objectStatus "J4G1.27" )
				)
				( pin "DQ(17)"
					( objectStatus "J4G1.172" )
				)
				( pin "DQ(18)"
					( objectStatus "J4G1.34" )
				)
				( pin "DQ(19)"
					( objectStatus "J4G1.179" )
				)
				( pin "DQ(1)"
					( objectStatus "J4G1.150" )
				)
				( pin "DQ(20)"
					( objectStatus "J4G1.25" )
				)
				( pin "DQ(21)"
					( objectStatus "J4G1.170" )
				)
				( pin "DQ(22)"
					( objectStatus "J4G1.32" )
				)
				( pin "DQ(23)"
					( objectStatus "J4G1.177" )
				)
				( pin "DQ(24)"
					( objectStatus "J4G1.38" )
				)
				( pin "DQ(25)"
					( objectStatus "J4G1.183" )
				)
				( pin "DQ(26)"
					( objectStatus "J4G1.45" )
				)
				( pin "DQ(27)"
					( objectStatus "J4G1.190" )
				)
				( pin "DQ(28)"
					( objectStatus "J4G1.36" )
				)
				( pin "DQ(29)"
					( objectStatus "J4G1.181" )
				)
				( pin "DQ(2)"
					( objectStatus "J4G1.12" )
				)
				( pin "DQ(30)"
					( objectStatus "J4G1.43" )
				)
				( pin "DQ(31)"
					( objectStatus "J4G1.188" )
				)
				( pin "DQ(32)"
					( objectStatus "J4G1.97" )
				)
				( pin "DQ(33)"
					( objectStatus "J4G1.242" )
				)
				( pin "DQ(34)"
					( objectStatus "J4G1.104" )
				)
				( pin "DQ(35)"
					( objectStatus "J4G1.249" )
				)
				( pin "DQ(36)"
					( objectStatus "J4G1.95" )
				)
				( pin "DQ(37)"
					( objectStatus "J4G1.240" )
				)
				( pin "DQ(38)"
					( objectStatus "J4G1.102" )
				)
				( pin "DQ(39)"
					( objectStatus "J4G1.247" )
				)
				( pin "DQ(3)"
					( objectStatus "J4G1.157" )
				)
				( pin "DQ(40)"
					( objectStatus "J4G1.108" )
				)
				( pin "DQ(41)"
					( objectStatus "J4G1.253" )
				)
				( pin "DQ(42)"
					( objectStatus "J4G1.115" )
				)
				( pin "DQ(43)"
					( objectStatus "J4G1.260" )
				)
				( pin "DQ(44)"
					( objectStatus "J4G1.106" )
				)
				( pin "DQ(45)"
					( objectStatus "J4G1.251" )
				)
				( pin "DQ(46)"
					( objectStatus "J4G1.113" )
				)
				( pin "DQ(47)"
					( objectStatus "J4G1.258" )
				)
				( pin "DQ(48)"
					( objectStatus "J4G1.119" )
				)
				( pin "DQ(49)"
					( objectStatus "J4G1.264" )
				)
				( pin "DQ(4)"
					( objectStatus "J4G1.3" )
				)
				( pin "DQ(50)"
					( objectStatus "J4G1.126" )
				)
				( pin "DQ(51)"
					( objectStatus "J4G1.271" )
				)
				( pin "DQ(52)"
					( objectStatus "J4G1.117" )
				)
				( pin "DQ(53)"
					( objectStatus "J4G1.262" )
				)
				( pin "DQ(54)"
					( objectStatus "J4G1.124" )
				)
				( pin "DQ(55)"
					( objectStatus "J4G1.269" )
				)
				( pin "DQ(56)"
					( objectStatus "J4G1.130" )
				)
				( pin "DQ(57)"
					( objectStatus "J4G1.275" )
				)
				( pin "DQ(58)"
					( objectStatus "J4G1.137" )
				)
				( pin "DQ(59)"
					( objectStatus "J4G1.282" )
				)
				( pin "DQ(5)"
					( objectStatus "J4G1.148" )
				)
				( pin "DQ(60)"
					( objectStatus "J4G1.128" )
				)
				( pin "DQ(61)"
					( objectStatus "J4G1.273" )
				)
				( pin "DQ(62)"
					( objectStatus "J4G1.135" )
				)
				( pin "DQ(63)"
					( objectStatus "J4G1.280" )
				)
				( pin "DQ(6)"
					( objectStatus "J4G1.10" )
				)
				( pin "DQ(7)"
					( objectStatus "J4G1.155" )
				)
				( pin "DQ(8)"
					( objectStatus "J4G1.16" )
				)
				( pin "DQ(9)"
					( objectStatus "J4G1.161" )
				)
				( pin "ODT(0)"
					( objectStatus "J4G1.87" )
				)
				( pin "ODT(1)"
					( objectStatus "J4G1.91" )
				)
				( pin "PAR"
					( objectStatus "J4G1.222" )
				)
				( pin "S0_N"
					( objectStatus "J4G1.84" )
				)
				( pin "S1_N"
					( objectStatus "J4G1.89" )
				)
				( pin "S2_N_C(0)"
					( objectStatus "J4G1.93" )
				)
				( pin "S3_N_C(1)"
					( objectStatus "J4G1.237" )
				)
			)
			( gate "@baseboard_fab2_lib.baseboard_fab2(sch_1):page43_i2"
				( objectStatus "F147" )
				( pin "DQS0N"
					( objectStatus "J4G1.152" )
				)
				( pin "DQS0P"
					( objectStatus "J4G1.153" )
				)
				( pin "DQS10N"
					( objectStatus "J4G1.19" )
				)
				( pin "DQS10P"
					( objectStatus "J4G1.18" )
				)
				( pin "DQS11N"
					( objectStatus "J4G1.30" )
				)
				( pin "DQS11P"
					( objectStatus "J4G1.29" )
				)
				( pin "DQS12N"
					( objectStatus "J4G1.41" )
				)
				( pin "DQS12P"
					( objectStatus "J4G1.40" )
				)
				( pin "DQS13N"
					( objectStatus "J4G1.100" )
				)
				( pin "DQS13P"
					( objectStatus "J4G1.99" )
				)
				( pin "DQS14N"
					( objectStatus "J4G1.111" )
				)
				( pin "DQS14P"
					( objectStatus "J4G1.110" )
				)
				( pin "DQS15N"
					( objectStatus "J4G1.122" )
				)
				( pin "DQS15P"
					( objectStatus "J4G1.121" )
				)
				( pin "DQS16N"
					( objectStatus "J4G1.133" )
				)
				( pin "DQS16P"
					( objectStatus "J4G1.132" )
				)
				( pin "DQS17N"
					( objectStatus "J4G1.52" )
				)
				( pin "DQS17P"
					( objectStatus "J4G1.51" )
				)
				( pin "DQS1N"
					( objectStatus "J4G1.163" )
				)
				( pin "DQS1P"
					( objectStatus "J4G1.164" )
				)
				( pin "DQS2N"
					( objectStatus "J4G1.174" )
				)
				( pin "DQS2P"
					( objectStatus "J4G1.175" )
				)
				( pin "DQS3N"
					( objectStatus "J4G1.185" )
				)
				( pin "DQS3P"
					( objectStatus "J4G1.186" )
				)
				( pin "DQS4N"
					( objectStatus "J4G1.244" )
				)
				( pin "DQS4P"
					( objectStatus "J4G1.245" )
				)
				( pin "DQS5N"
					( objectStatus "J4G1.255" )
				)
				( pin "DQS5P"
					( objectStatus "J4G1.256" )
				)
				( pin "DQS6N"
					( objectStatus "J4G1.266" )
				)
				( pin "DQS6P"
					( objectStatus "J4G1.267" )
				)
				( pin "DQS7N"
					( objectStatus "J4G1.277" )
				)
				( pin "DQS7P"
					( objectStatus "J4G1.278" )
				)
				( pin "DQS8N"
					( objectStatus "J4G1.196" )
				)
				( pin "DQS8P"
					( objectStatus "J4G1.197" )
				)
				( pin "DQS9N"
					( objectStatus "J4G1.8" )
				)
				( pin "DQS9P"
					( objectStatus "J4G1.7" )
				)
			)
			( gate "@baseboard_fab2_lib.baseboard_fab2(sch_1):page43_i259"
				( objectStatus "F146" )
			)
			( gate "@baseboard_fab2_lib.baseboard_fab2(sch_1):page43_i260"
				( objectStatus "F145" )
			)
			( gate "@baseboard_fab2_lib.baseboard_fab2(sch_1):page45_i111"
				( objectStatus "F144" )
				( pin "A0"
					( objectStatus "J4G2.79" )
				)
				( pin "A1"
					( objectStatus "J4G2.72" )
				)
				( pin "A10"
					( objectStatus "J4G2.225" )
				)
				( pin "A11"
					( objectStatus "J4G2.210" )
				)
				( pin "A12"
					( objectStatus "J4G2.65" )
				)
				( pin "A13"
					( objectStatus "J4G2.232" )
				)
				( pin "A14_WE_N"
					( objectStatus "J4G2.228" )
				)
				( pin "A15_CAS_N"
					( objectStatus "J4G2.86" )
				)
				( pin "A16_RAS_N"
					( objectStatus "J4G2.82" )
				)
				( pin "A17"
					( objectStatus "J4G2.234" )
				)
				( pin "A2"
					( objectStatus "J4G2.216" )
				)
				( pin "A3"
					( objectStatus "J4G2.71" )
				)
				( pin "A4"
					( objectStatus "J4G2.214" )
				)
				( pin "A5"
					( objectStatus "J4G2.213" )
				)
				( pin "A6"
					( objectStatus "J4G2.69" )
				)
				( pin "A7"
					( objectStatus "J4G2.211" )
				)
				( pin "A8"
					( objectStatus "J4G2.68" )
				)
				( pin "A9"
					( objectStatus "J4G2.66" )
				)
				( pin "ACT_N"
					( objectStatus "J4G2.62" )
				)
				( pin "BA(0)"
					( objectStatus "J4G2.81" )
				)
				( pin "BA(1)"
					( objectStatus "J4G2.224" )
				)
				( pin "BG(0)"
					( objectStatus "J4G2.63" )
				)
				( pin "BG(1)"
					( objectStatus "J4G2.207" )
				)
				( pin "C(2)"
					( objectStatus "J4G2.235" )
				)
				( pin "CB(0)"
					( objectStatus "J4G2.49" )
				)
				( pin "CB(1)"
					( objectStatus "J4G2.194" )
				)
				( pin "CB(2)"
					( objectStatus "J4G2.56" )
				)
				( pin "CB(3)"
					( objectStatus "J4G2.201" )
				)
				( pin "CB(4)"
					( objectStatus "J4G2.47" )
				)
				( pin "CB(5)"
					( objectStatus "J4G2.192" )
				)
				( pin "CB(6)"
					( objectStatus "J4G2.54" )
				)
				( pin "CB(7)"
					( objectStatus "J4G2.199" )
				)
				( pin "CKE(0)"
					( objectStatus "J4G2.60" )
				)
				( pin "CKE(1)"
					( objectStatus "J4G2.203" )
				)
				( pin "DQ(0)"
					( objectStatus "J4G2.5" )
				)
				( pin "DQ(10)"
					( objectStatus "J4G2.23" )
				)
				( pin "DQ(11)"
					( objectStatus "J4G2.168" )
				)
				( pin "DQ(12)"
					( objectStatus "J4G2.14" )
				)
				( pin "DQ(13)"
					( objectStatus "J4G2.159" )
				)
				( pin "DQ(14)"
					( objectStatus "J4G2.21" )
				)
				( pin "DQ(15)"
					( objectStatus "J4G2.166" )
				)
				( pin "DQ(16)"
					( objectStatus "J4G2.27" )
				)
				( pin "DQ(17)"
					( objectStatus "J4G2.172" )
				)
				( pin "DQ(18)"
					( objectStatus "J4G2.34" )
				)
				( pin "DQ(19)"
					( objectStatus "J4G2.179" )
				)
				( pin "DQ(1)"
					( objectStatus "J4G2.150" )
				)
				( pin "DQ(20)"
					( objectStatus "J4G2.25" )
				)
				( pin "DQ(21)"
					( objectStatus "J4G2.170" )
				)
				( pin "DQ(22)"
					( objectStatus "J4G2.32" )
				)
				( pin "DQ(23)"
					( objectStatus "J4G2.177" )
				)
				( pin "DQ(24)"
					( objectStatus "J4G2.38" )
				)
				( pin "DQ(25)"
					( objectStatus "J4G2.183" )
				)
				( pin "DQ(26)"
					( objectStatus "J4G2.45" )
				)
				( pin "DQ(27)"
					( objectStatus "J4G2.190" )
				)
				( pin "DQ(28)"
					( objectStatus "J4G2.36" )
				)
				( pin "DQ(29)"
					( objectStatus "J4G2.181" )
				)
				( pin "DQ(2)"
					( objectStatus "J4G2.12" )
				)
				( pin "DQ(30)"
					( objectStatus "J4G2.43" )
				)
				( pin "DQ(31)"
					( objectStatus "J4G2.188" )
				)
				( pin "DQ(32)"
					( objectStatus "J4G2.97" )
				)
				( pin "DQ(33)"
					( objectStatus "J4G2.242" )
				)
				( pin "DQ(34)"
					( objectStatus "J4G2.104" )
				)
				( pin "DQ(35)"
					( objectStatus "J4G2.249" )
				)
				( pin "DQ(36)"
					( objectStatus "J4G2.95" )
				)
				( pin "DQ(37)"
					( objectStatus "J4G2.240" )
				)
				( pin "DQ(38)"
					( objectStatus "J4G2.102" )
				)
				( pin "DQ(39)"
					( objectStatus "J4G2.247" )
				)
				( pin "DQ(3)"
					( objectStatus "J4G2.157" )
				)
				( pin "DQ(40)"
					( objectStatus "J4G2.108" )
				)
				( pin "DQ(41)"
					( objectStatus "J4G2.253" )
				)
				( pin "DQ(42)"
					( objectStatus "J4G2.115" )
				)
				( pin "DQ(43)"
					( objectStatus "J4G2.260" )
				)
				( pin "DQ(44)"
					( objectStatus "J4G2.106" )
				)
				( pin "DQ(45)"
					( objectStatus "J4G2.251" )
				)
				( pin "DQ(46)"
					( objectStatus "J4G2.113" )
				)
				( pin "DQ(47)"
					( objectStatus "J4G2.258" )
				)
				( pin "DQ(48)"
					( objectStatus "J4G2.119" )
				)
				( pin "DQ(49)"
					( objectStatus "J4G2.264" )
				)
				( pin "DQ(4)"
					( objectStatus "J4G2.3" )
				)
				( pin "DQ(50)"
					( objectStatus "J4G2.126" )
				)
				( pin "DQ(51)"
					( objectStatus "J4G2.271" )
				)
				( pin "DQ(52)"
					( objectStatus "J4G2.117" )
				)
				( pin "DQ(53)"
					( objectStatus "J4G2.262" )
				)
				( pin "DQ(54)"
					( objectStatus "J4G2.124" )
				)
				( pin "DQ(55)"
					( objectStatus "J4G2.269" )
				)
				( pin "DQ(56)"
					( objectStatus "J4G2.130" )
				)
				( pin "DQ(57)"
					( objectStatus "J4G2.275" )
				)
				( pin "DQ(58)"
					( objectStatus "J4G2.137" )
				)
				( pin "DQ(59)"
					( objectStatus "J4G2.282" )
				)
				( pin "DQ(5)"
					( objectStatus "J4G2.148" )
				)
				( pin "DQ(60)"
					( objectStatus "J4G2.128" )
				)
				( pin "DQ(61)"
					( objectStatus "J4G2.273" )
				)
				( pin "DQ(62)"
					( objectStatus "J4G2.135" )
				)
				( pin "DQ(63)"
					( objectStatus "J4G2.280" )
				)
				( pin "DQ(6)"
					( objectStatus "J4G2.10" )
				)
				( pin "DQ(7)"
					( objectStatus "J4G2.155" )
				)
				( pin "DQ(8)"
					( objectStatus "J4G2.16" )
				)
				( pin "DQ(9)"
					( objectStatus "J4G2.161" )
				)
				( pin "ODT(0)"
					( objectStatus "J4G2.87" )
				)
				( pin "ODT(1)"
					( objectStatus "J4G2.91" )
				)
				( pin "PAR"
					( objectStatus "J4G2.222" )
				)
				( pin "S0_N"
					( objectStatus "J4G2.84" )
				)
				( pin "S1_N"
					( objectStatus "J4G2.89" )
				)
				( pin "S2_N_C(0)"
					( objectStatus "J4G2.93" )
				)
				( pin "S3_N_C(1)"
					( objectStatus "J4G2.237" )
				)
			)
			( gate "@baseboard_fab2_lib.baseboard_fab2(sch_1):page45_i61"
				( objectStatus "F143" )
				( pin "DQS0N"
					( objectStatus "J4G2.152" )
				)
				( pin "DQS0P"
					( objectStatus "J4G2.153" )
				)
				( pin "DQS10N"
					( objectStatus "J4G2.19" )
				)
				( pin "DQS10P"
					( objectStatus "J4G2.18" )
				)
				( pin "DQS11N"
					( objectStatus "J4G2.30" )
				)
				( pin "DQS11P"
					( objectStatus "J4G2.29" )
				)
				( pin "DQS12N"
					( objectStatus "J4G2.41" )
				)
				( pin "DQS12P"
					( objectStatus "J4G2.40" )
				)
				( pin "DQS13N"
					( objectStatus "J4G2.100" )
				)
				( pin "DQS13P"
					( objectStatus "J4G2.99" )
				)
				( pin "DQS14N"
					( objectStatus "J4G2.111" )
				)
				( pin "DQS14P"
					( objectStatus "J4G2.110" )
				)
				( pin "DQS15N"
					( objectStatus "J4G2.122" )
				)
				( pin "DQS15P"
					( objectStatus "J4G2.121" )
				)
				( pin "DQS16N"
					( objectStatus "J4G2.133" )
				)
				( pin "DQS16P"
					( objectStatus "J4G2.132" )
				)
				( pin "DQS17N"
					( objectStatus "J4G2.52" )
				)
				( pin "DQS17P"
					( objectStatus "J4G2.51" )
				)
				( pin "DQS1N"
					( objectStatus "J4G2.163" )
				)
				( pin "DQS1P"
					( objectStatus "J4G2.164" )
				)
				( pin "DQS2N"
					( objectStatus "J4G2.174" )
				)
				( pin "DQS2P"
					( objectStatus "J4G2.175" )
				)
				( pin "DQS3N"
					( objectStatus "J4G2.185" )
				)
				( pin "DQS3P"
					( objectStatus "J4G2.186" )
				)
				( pin "DQS4N"
					( objectStatus "J4G2.244" )
				)
				( pin "DQS4P"
					( objectStatus "J4G2.245" )
				)
				( pin "DQS5N"
					( objectStatus "J4G2.255" )
				)
				( pin "DQS5P"
					( objectStatus "J4G2.256" )
				)
				( pin "DQS6N"
					( objectStatus "J4G2.266" )
				)
				( pin "DQS6P"
					( objectStatus "J4G2.267" )
				)
				( pin "DQS7N"
					( objectStatus "J4G2.277" )
				)
				( pin "DQS7P"
					( objectStatus "J4G2.278" )
				)
				( pin "DQS8N"
					( objectStatus "J4G2.196" )
				)
				( pin "DQS8P"
					( objectStatus "J4G2.197" )
				)
				( pin "DQS9N"
					( objectStatus "J4G2.8" )
				)
				( pin "DQS9P"
					( objectStatus "J4G2.7" )
				)
			)
			( gate "@baseboard_fab2_lib.baseboard_fab2(sch_1):page45_i43"
				( objectStatus "F142" )
			)
			( gate "@baseboard_fab2_lib.baseboard_fab2(sch_1):page45_i169"
				( objectStatus "F141" )
			)
			( gate "@baseboard_fab2_lib.baseboard_fab2(sch_1):page47_i111"
				( objectStatus "F140" )
				( pin "A0"
					( objectStatus "J4G3.79" )
				)
				( pin "A1"
					( objectStatus "J4G3.72" )
				)
				( pin "A10"
					( objectStatus "J4G3.225" )
				)
				( pin "A11"
					( objectStatus "J4G3.210" )
				)
				( pin "A12"
					( objectStatus "J4G3.65" )
				)
				( pin "A13"
					( objectStatus "J4G3.232" )
				)
				( pin "A14_WE_N"
					( objectStatus "J4G3.228" )
				)
				( pin "A15_CAS_N"
					( objectStatus "J4G3.86" )
				)
				( pin "A16_RAS_N"
					( objectStatus "J4G3.82" )
				)
				( pin "A17"
					( objectStatus "J4G3.234" )
				)
				( pin "A2"
					( objectStatus "J4G3.216" )
				)
				( pin "A3"
					( objectStatus "J4G3.71" )
				)
				( pin "A4"
					( objectStatus "J4G3.214" )
				)
				( pin "A5"
					( objectStatus "J4G3.213" )
				)
				( pin "A6"
					( objectStatus "J4G3.69" )
				)
				( pin "A7"
					( objectStatus "J4G3.211" )
				)
				( pin "A8"
					( objectStatus "J4G3.68" )
				)
				( pin "A9"
					( objectStatus "J4G3.66" )
				)
				( pin "ACT_N"
					( objectStatus "J4G3.62" )
				)
				( pin "BA(0)"
					( objectStatus "J4G3.81" )
				)
				( pin "BA(1)"
					( objectStatus "J4G3.224" )
				)
				( pin "BG(0)"
					( objectStatus "J4G3.63" )
				)
				( pin "BG(1)"
					( objectStatus "J4G3.207" )
				)
				( pin "C(2)"
					( objectStatus "J4G3.235" )
				)
				( pin "CB(0)"
					( objectStatus "J4G3.49" )
				)
				( pin "CB(1)"
					( objectStatus "J4G3.194" )
				)
				( pin "CB(2)"
					( objectStatus "J4G3.56" )
				)
				( pin "CB(3)"
					( objectStatus "J4G3.201" )
				)
				( pin "CB(4)"
					( objectStatus "J4G3.47" )
				)
				( pin "CB(5)"
					( objectStatus "J4G3.192" )
				)
				( pin "CB(6)"
					( objectStatus "J4G3.54" )
				)
				( pin "CB(7)"
					( objectStatus "J4G3.199" )
				)
				( pin "CKE(0)"
					( objectStatus "J4G3.60" )
				)
				( pin "CKE(1)"
					( objectStatus "J4G3.203" )
				)
				( pin "DQ(0)"
					( objectStatus "J4G3.5" )
				)
				( pin "DQ(10)"
					( objectStatus "J4G3.23" )
				)
				( pin "DQ(11)"
					( objectStatus "J4G3.168" )
				)
				( pin "DQ(12)"
					( objectStatus "J4G3.14" )
				)
				( pin "DQ(13)"
					( objectStatus "J4G3.159" )
				)
				( pin "DQ(14)"
					( objectStatus "J4G3.21" )
				)
				( pin "DQ(15)"
					( objectStatus "J4G3.166" )
				)
				( pin "DQ(16)"
					( objectStatus "J4G3.27" )
				)
				( pin "DQ(17)"
					( objectStatus "J4G3.172" )
				)
				( pin "DQ(18)"
					( objectStatus "J4G3.34" )
				)
				( pin "DQ(19)"
					( objectStatus "J4G3.179" )
				)
				( pin "DQ(1)"
					( objectStatus "J4G3.150" )
				)
				( pin "DQ(20)"
					( objectStatus "J4G3.25" )
				)
				( pin "DQ(21)"
					( objectStatus "J4G3.170" )
				)
				( pin "DQ(22)"
					( objectStatus "J4G3.32" )
				)
				( pin "DQ(23)"
					( objectStatus "J4G3.177" )
				)
				( pin "DQ(24)"
					( objectStatus "J4G3.38" )
				)
				( pin "DQ(25)"
					( objectStatus "J4G3.183" )
				)
				( pin "DQ(26)"
					( objectStatus "J4G3.45" )
				)
				( pin "DQ(27)"
					( objectStatus "J4G3.190" )
				)
				( pin "DQ(28)"
					( objectStatus "J4G3.36" )
				)
				( pin "DQ(29)"
					( objectStatus "J4G3.181" )
				)
				( pin "DQ(2)"
					( objectStatus "J4G3.12" )
				)
				( pin "DQ(30)"
					( objectStatus "J4G3.43" )
				)
				( pin "DQ(31)"
					( objectStatus "J4G3.188" )
				)
				( pin "DQ(32)"
					( objectStatus "J4G3.97" )
				)
				( pin "DQ(33)"
					( objectStatus "J4G3.242" )
				)
				( pin "DQ(34)"
					( objectStatus "J4G3.104" )
				)
				( pin "DQ(35)"
					( objectStatus "J4G3.249" )
				)
				( pin "DQ(36)"
					( objectStatus "J4G3.95" )
				)
				( pin "DQ(37)"
					( objectStatus "J4G3.240" )
				)
				( pin "DQ(38)"
					( objectStatus "J4G3.102" )
				)
				( pin "DQ(39)"
					( objectStatus "J4G3.247" )
				)
				( pin "DQ(3)"
					( objectStatus "J4G3.157" )
				)
				( pin "DQ(40)"
					( objectStatus "J4G3.108" )
				)
				( pin "DQ(41)"
					( objectStatus "J4G3.253" )
				)
				( pin "DQ(42)"
					( objectStatus "J4G3.115" )
				)
				( pin "DQ(43)"
					( objectStatus "J4G3.260" )
				)
				( pin "DQ(44)"
					( objectStatus "J4G3.106" )
				)
				( pin "DQ(45)"
					( objectStatus "J4G3.251" )
				)
				( pin "DQ(46)"
					( objectStatus "J4G3.113" )
				)
				( pin "DQ(47)"
					( objectStatus "J4G3.258" )
				)
				( pin "DQ(48)"
					( objectStatus "J4G3.119" )
				)
				( pin "DQ(49)"
					( objectStatus "J4G3.264" )
				)
				( pin "DQ(4)"
					( objectStatus "J4G3.3" )
				)
				( pin "DQ(50)"
					( objectStatus "J4G3.126" )
				)
				( pin "DQ(51)"
					( objectStatus "J4G3.271" )
				)
				( pin "DQ(52)"
					( objectStatus "J4G3.117" )
				)
				( pin "DQ(53)"
					( objectStatus "J4G3.262" )
				)
				( pin "DQ(54)"
					( objectStatus "J4G3.124" )
				)
				( pin "DQ(55)"
					( objectStatus "J4G3.269" )
				)
				( pin "DQ(56)"
					( objectStatus "J4G3.130" )
				)
				( pin "DQ(57)"
					( objectStatus "J4G3.275" )
				)
				( pin "DQ(58)"
					( objectStatus "J4G3.137" )
				)
				( pin "DQ(59)"
					( objectStatus "J4G3.282" )
				)
				( pin "DQ(5)"
					( objectStatus "J4G3.148" )
				)
				( pin "DQ(60)"
					( objectStatus "J4G3.128" )
				)
				( pin "DQ(61)"
					( objectStatus "J4G3.273" )
				)
				( pin "DQ(62)"
					( objectStatus "J4G3.135" )
				)
				( pin "DQ(63)"
					( objectStatus "J4G3.280" )
				)
				( pin "DQ(6)"
					( objectStatus "J4G3.10" )
				)
				( pin "DQ(7)"
					( objectStatus "J4G3.155" )
				)
				( pin "DQ(8)"
					( objectStatus "J4G3.16" )
				)
				( pin "DQ(9)"
					( objectStatus "J4G3.161" )
				)
				( pin "ODT(0)"
					( objectStatus "J4G3.87" )
				)
				( pin "ODT(1)"
					( objectStatus "J4G3.91" )
				)
				( pin "PAR"
					( objectStatus "J4G3.222" )
				)
				( pin "S0_N"
					( objectStatus "J4G3.84" )
				)
				( pin "S1_N"
					( objectStatus "J4G3.89" )
				)
				( pin "S2_N_C(0)"
					( objectStatus "J4G3.93" )
				)
				( pin "S3_N_C(1)"
					( objectStatus "J4G3.237" )
				)
				( pin "SCL"
					( objectStatus "J4G3.141" )
				)
				( pin "SDA"
					( objectStatus "J4G3.285" )
				)
			)
			( gate "@baseboard_fab2_lib.baseboard_fab2(sch_1):page47_i61"
				( objectStatus "F139" )
				( pin "DQS0N"
					( objectStatus "J4G3.152" )
				)
				( pin "DQS0P"
					( objectStatus "J4G3.153" )
				)
				( pin "DQS10N"
					( objectStatus "J4G3.19" )
				)
				( pin "DQS10P"
					( objectStatus "J4G3.18" )
				)
				( pin "DQS11N"
					( objectStatus "J4G3.30" )
				)
				( pin "DQS11P"
					( objectStatus "J4G3.29" )
				)
				( pin "DQS12N"
					( objectStatus "J4G3.41" )
				)
				( pin "DQS12P"
					( objectStatus "J4G3.40" )
				)
				( pin "DQS13N"
					( objectStatus "J4G3.100" )
				)
				( pin "DQS13P"
					( objectStatus "J4G3.99" )
				)
				( pin "DQS14N"
					( objectStatus "J4G3.111" )
				)
				( pin "DQS14P"
					( objectStatus "J4G3.110" )
				)
				( pin "DQS15N"
					( objectStatus "J4G3.122" )
				)
				( pin "DQS15P"
					( objectStatus "J4G3.121" )
				)
				( pin "DQS16N"
					( objectStatus "J4G3.133" )
				)
				( pin "DQS16P"
					( objectStatus "J4G3.132" )
				)
				( pin "DQS17N"
					( objectStatus "J4G3.52" )
				)
				( pin "DQS17P"
					( objectStatus "J4G3.51" )
				)
				( pin "DQS1N"
					( objectStatus "J4G3.163" )
				)
				( pin "DQS1P"
					( objectStatus "J4G3.164" )
				)
				( pin "DQS2N"
					( objectStatus "J4G3.174" )
				)
				( pin "DQS2P"
					( objectStatus "J4G3.175" )
				)
				( pin "DQS3N"
					( objectStatus "J4G3.185" )
				)
				( pin "DQS3P"
					( objectStatus "J4G3.186" )
				)
				( pin "DQS4N"
					( objectStatus "J4G3.244" )
				)
				( pin "DQS4P"
					( objectStatus "J4G3.245" )
				)
				( pin "DQS5N"
					( objectStatus "J4G3.255" )
				)
				( pin "DQS5P"
					( objectStatus "J4G3.256" )
				)
				( pin "DQS6N"
					( objectStatus "J4G3.266" )
				)
				( pin "DQS6P"
					( objectStatus "J4G3.267" )
				)
				( pin "DQS7N"
					( objectStatus "J4G3.277" )
				)
				( pin "DQS7P"
					( objectStatus "J4G3.278" )
				)
				( pin "DQS8N"
					( objectStatus "J4G3.196" )
				)
				( pin "DQS8P"
					( objectStatus "J4G3.197" )
				)
				( pin "DQS9N"
					( objectStatus "J4G3.8" )
				)
				( pin "DQS9P"
					( objectStatus "J4G3.7" )
				)
			)
			( gate "@baseboard_fab2_lib.baseboard_fab2(sch_1):page47_i43"
				( objectStatus "F138" )
			)
			( gate "@baseboard_fab2_lib.baseboard_fab2(sch_1):page47_i179"
				( objectStatus "F137" )
			)
			( gate "@baseboard_fab2_lib.baseboard_fab2(sch_1):page49_i111"
				( objectStatus "F152" )
				( pin "A0"
					( objectStatus "J4B1.79" )
				)
				( pin "A1"
					( objectStatus "J4B1.72" )
				)
				( pin "A10"
					( objectStatus "J4B1.225" )
				)
				( pin "A11"
					( objectStatus "J4B1.210" )
				)
				( pin "A12"
					( objectStatus "J4B1.65" )
				)
				( pin "A13"
					( objectStatus "J4B1.232" )
				)
				( pin "A14_WE_N"
					( objectStatus "J4B1.228" )
				)
				( pin "A15_CAS_N"
					( objectStatus "J4B1.86" )
				)
				( pin "A16_RAS_N"
					( objectStatus "J4B1.82" )
				)
				( pin "A17"
					( objectStatus "J4B1.234" )
				)
				( pin "A2"
					( objectStatus "J4B1.216" )
				)
				( pin "A3"
					( objectStatus "J4B1.71" )
				)
				( pin "A4"
					( objectStatus "J4B1.214" )
				)
				( pin "A5"
					( objectStatus "J4B1.213" )
				)
				( pin "A6"
					( objectStatus "J4B1.69" )
				)
				( pin "A7"
					( objectStatus "J4B1.211" )
				)
				( pin "A8"
					( objectStatus "J4B1.68" )
				)
				( pin "A9"
					( objectStatus "J4B1.66" )
				)
				( pin "ACT_N"
					( objectStatus "J4B1.62" )
				)
				( pin "BA(0)"
					( objectStatus "J4B1.81" )
				)
				( pin "BA(1)"
					( objectStatus "J4B1.224" )
				)
				( pin "BG(0)"
					( objectStatus "J4B1.63" )
				)
				( pin "BG(1)"
					( objectStatus "J4B1.207" )
				)
				( pin "C(2)"
					( objectStatus "J4B1.235" )
				)
				( pin "CB(0)"
					( objectStatus "J4B1.49" )
				)
				( pin "CB(1)"
					( objectStatus "J4B1.194" )
				)
				( pin "CB(2)"
					( objectStatus "J4B1.56" )
				)
				( pin "CB(3)"
					( objectStatus "J4B1.201" )
				)
				( pin "CB(4)"
					( objectStatus "J4B1.47" )
				)
				( pin "CB(5)"
					( objectStatus "J4B1.192" )
				)
				( pin "CB(6)"
					( objectStatus "J4B1.54" )
				)
				( pin "CB(7)"
					( objectStatus "J4B1.199" )
				)
				( pin "CKE(0)"
					( objectStatus "J4B1.60" )
				)
				( pin "CKE(1)"
					( objectStatus "J4B1.203" )
				)
				( pin "DQ(0)"
					( objectStatus "J4B1.5" )
				)
				( pin "DQ(10)"
					( objectStatus "J4B1.23" )
				)
				( pin "DQ(11)"
					( objectStatus "J4B1.168" )
				)
				( pin "DQ(12)"
					( objectStatus "J4B1.14" )
				)
				( pin "DQ(13)"
					( objectStatus "J4B1.159" )
				)
				( pin "DQ(14)"
					( objectStatus "J4B1.21" )
				)
				( pin "DQ(15)"
					( objectStatus "J4B1.166" )
				)
				( pin "DQ(16)"
					( objectStatus "J4B1.27" )
				)
				( pin "DQ(17)"
					( objectStatus "J4B1.172" )
				)
				( pin "DQ(18)"
					( objectStatus "J4B1.34" )
				)
				( pin "DQ(19)"
					( objectStatus "J4B1.179" )
				)
				( pin "DQ(1)"
					( objectStatus "J4B1.150" )
				)
				( pin "DQ(20)"
					( objectStatus "J4B1.25" )
				)
				( pin "DQ(21)"
					( objectStatus "J4B1.170" )
				)
				( pin "DQ(22)"
					( objectStatus "J4B1.32" )
				)
				( pin "DQ(23)"
					( objectStatus "J4B1.177" )
				)
				( pin "DQ(24)"
					( objectStatus "J4B1.38" )
				)
				( pin "DQ(25)"
					( objectStatus "J4B1.183" )
				)
				( pin "DQ(26)"
					( objectStatus "J4B1.45" )
				)
				( pin "DQ(27)"
					( objectStatus "J4B1.190" )
				)
				( pin "DQ(28)"
					( objectStatus "J4B1.36" )
				)
				( pin "DQ(29)"
					( objectStatus "J4B1.181" )
				)
				( pin "DQ(2)"
					( objectStatus "J4B1.12" )
				)
				( pin "DQ(30)"
					( objectStatus "J4B1.43" )
				)
				( pin "DQ(31)"
					( objectStatus "J4B1.188" )
				)
				( pin "DQ(32)"
					( objectStatus "J4B1.97" )
				)
				( pin "DQ(33)"
					( objectStatus "J4B1.242" )
				)
				( pin "DQ(34)"
					( objectStatus "J4B1.104" )
				)
				( pin "DQ(35)"
					( objectStatus "J4B1.249" )
				)
				( pin "DQ(36)"
					( objectStatus "J4B1.95" )
				)
				( pin "DQ(37)"
					( objectStatus "J4B1.240" )
				)
				( pin "DQ(38)"
					( objectStatus "J4B1.102" )
				)
				( pin "DQ(39)"
					( objectStatus "J4B1.247" )
				)
				( pin "DQ(3)"
					( objectStatus "J4B1.157" )
				)
				( pin "DQ(40)"
					( objectStatus "J4B1.108" )
				)
				( pin "DQ(41)"
					( objectStatus "J4B1.253" )
				)
				( pin "DQ(42)"
					( objectStatus "J4B1.115" )
				)
				( pin "DQ(43)"
					( objectStatus "J4B1.260" )
				)
				( pin "DQ(44)"
					( objectStatus "J4B1.106" )
				)
				( pin "DQ(45)"
					( objectStatus "J4B1.251" )
				)
				( pin "DQ(46)"
					( objectStatus "J4B1.113" )
				)
				( pin "DQ(47)"
					( objectStatus "J4B1.258" )
				)
				( pin "DQ(48)"
					( objectStatus "J4B1.119" )
				)
				( pin "DQ(49)"
					( objectStatus "J4B1.264" )
				)
				( pin "DQ(4)"
					( objectStatus "J4B1.3" )
				)
				( pin "DQ(50)"
					( objectStatus "J4B1.126" )
				)
				( pin "DQ(51)"
					( objectStatus "J4B1.271" )
				)
				( pin "DQ(52)"
					( objectStatus "J4B1.117" )
				)
				( pin "DQ(53)"
					( objectStatus "J4B1.262" )
				)
				( pin "DQ(54)"
					( objectStatus "J4B1.124" )
				)
				( pin "DQ(55)"
					( objectStatus "J4B1.269" )
				)
				( pin "DQ(56)"
					( objectStatus "J4B1.130" )
				)
				( pin "DQ(57)"
					( objectStatus "J4B1.275" )
				)
				( pin "DQ(58)"
					( objectStatus "J4B1.137" )
				)
				( pin "DQ(59)"
					( objectStatus "J4B1.282" )
				)
				( pin "DQ(5)"
					( objectStatus "J4B1.148" )
				)
				( pin "DQ(60)"
					( objectStatus "J4B1.128" )
				)
				( pin "DQ(61)"
					( objectStatus "J4B1.273" )
				)
				( pin "DQ(62)"
					( objectStatus "J4B1.135" )
				)
				( pin "DQ(63)"
					( objectStatus "J4B1.280" )
				)
				( pin "DQ(6)"
					( objectStatus "J4B1.10" )
				)
				( pin "DQ(7)"
					( objectStatus "J4B1.155" )
				)
				( pin "DQ(8)"
					( objectStatus "J4B1.16" )
				)
				( pin "DQ(9)"
					( objectStatus "J4B1.161" )
				)
				( pin "ODT(0)"
					( objectStatus "J4B1.87" )
				)
				( pin "ODT(1)"
					( objectStatus "J4B1.91" )
				)
				( pin "PAR"
					( objectStatus "J4B1.222" )
				)
				( pin "S0_N"
					( objectStatus "J4B1.84" )
				)
				( pin "S1_N"
					( objectStatus "J4B1.89" )
				)
				( pin "S2_N_C(0)"
					( objectStatus "J4B1.93" )
				)
				( pin "S3_N_C(1)"
					( objectStatus "J4B1.237" )
				)
			)
			( gate "@baseboard_fab2_lib.baseboard_fab2(sch_1):page49_i66"
				( objectStatus "F151" )
				( pin "DQS0N"
					( objectStatus "J4B1.152" )
				)
				( pin "DQS0P"
					( objectStatus "J4B1.153" )
				)
				( pin "DQS10N"
					( objectStatus "J4B1.19" )
				)
				( pin "DQS10P"
					( objectStatus "J4B1.18" )
				)
				( pin "DQS11N"
					( objectStatus "J4B1.30" )
				)
				( pin "DQS11P"
					( objectStatus "J4B1.29" )
				)
				( pin "DQS12N"
					( objectStatus "J4B1.41" )
				)
				( pin "DQS12P"
					( objectStatus "J4B1.40" )
				)
				( pin "DQS13N"
					( objectStatus "J4B1.100" )
				)
				( pin "DQS13P"
					( objectStatus "J4B1.99" )
				)
				( pin "DQS14N"
					( objectStatus "J4B1.111" )
				)
				( pin "DQS14P"
					( objectStatus "J4B1.110" )
				)
				( pin "DQS15N"
					( objectStatus "J4B1.122" )
				)
				( pin "DQS15P"
					( objectStatus "J4B1.121" )
				)
				( pin "DQS16N"
					( objectStatus "J4B1.133" )
				)
				( pin "DQS16P"
					( objectStatus "J4B1.132" )
				)
				( pin "DQS17N"
					( objectStatus "J4B1.52" )
				)
				( pin "DQS17P"
					( objectStatus "J4B1.51" )
				)
				( pin "DQS1N"
					( objectStatus "J4B1.163" )
				)
				( pin "DQS1P"
					( objectStatus "J4B1.164" )
				)
				( pin "DQS2N"
					( objectStatus "J4B1.174" )
				)
				( pin "DQS2P"
					( objectStatus "J4B1.175" )
				)
				( pin "DQS3N"
					( objectStatus "J4B1.185" )
				)
				( pin "DQS3P"
					( objectStatus "J4B1.186" )
				)
				( pin "DQS4N"
					( objectStatus "J4B1.244" )
				)
				( pin "DQS4P"
					( objectStatus "J4B1.245" )
				)
				( pin "DQS5N"
					( objectStatus "J4B1.255" )
				)
				( pin "DQS5P"
					( objectStatus "J4B1.256" )
				)
				( pin "DQS6N"
					( objectStatus "J4B1.266" )
				)
				( pin "DQS6P"
					( objectStatus "J4B1.267" )
				)
				( pin "DQS7N"
					( objectStatus "J4B1.277" )
				)
				( pin "DQS7P"
					( objectStatus "J4B1.278" )
				)
				( pin "DQS8N"
					( objectStatus "J4B1.196" )
				)
				( pin "DQS8P"
					( objectStatus "J4B1.197" )
				)
				( pin "DQS9N"
					( objectStatus "J4B1.8" )
				)
				( pin "DQS9P"
					( objectStatus "J4B1.7" )
				)
			)
			( gate "@baseboard_fab2_lib.baseboard_fab2(sch_1):page49_i43"
				( objectStatus "F150" )
			)
			( gate "@baseboard_fab2_lib.baseboard_fab2(sch_1):page49_i169"
				( objectStatus "F149" )
			)
			( gate "@baseboard_fab2_lib.baseboard_fab2(sch_1):page51_i111"
				( objectStatus "F156" )
				( pin "A0"
					( objectStatus "J4A2.79" )
				)
				( pin "A1"
					( objectStatus "J4A2.72" )
				)
				( pin "A10"
					( objectStatus "J4A2.225" )
				)
				( pin "A11"
					( objectStatus "J4A2.210" )
				)
				( pin "A12"
					( objectStatus "J4A2.65" )
				)
				( pin "A13"
					( objectStatus "J4A2.232" )
				)
				( pin "A14_WE_N"
					( objectStatus "J4A2.228" )
				)
				( pin "A15_CAS_N"
					( objectStatus "J4A2.86" )
				)
				( pin "A16_RAS_N"
					( objectStatus "J4A2.82" )
				)
				( pin "A17"
					( objectStatus "J4A2.234" )
				)
				( pin "A2"
					( objectStatus "J4A2.216" )
				)
				( pin "A3"
					( objectStatus "J4A2.71" )
				)
				( pin "A4"
					( objectStatus "J4A2.214" )
				)
				( pin "A5"
					( objectStatus "J4A2.213" )
				)
				( pin "A6"
					( objectStatus "J4A2.69" )
				)
				( pin "A7"
					( objectStatus "J4A2.211" )
				)
				( pin "A8"
					( objectStatus "J4A2.68" )
				)
				( pin "A9"
					( objectStatus "J4A2.66" )
				)
				( pin "ACT_N"
					( objectStatus "J4A2.62" )
				)
				( pin "BA(0)"
					( objectStatus "J4A2.81" )
				)
				( pin "BA(1)"
					( objectStatus "J4A2.224" )
				)
				( pin "BG(0)"
					( objectStatus "J4A2.63" )
				)
				( pin "BG(1)"
					( objectStatus "J4A2.207" )
				)
				( pin "C(2)"
					( objectStatus "J4A2.235" )
				)
				( pin "CB(0)"
					( objectStatus "J4A2.49" )
				)
				( pin "CB(1)"
					( objectStatus "J4A2.194" )
				)
				( pin "CB(2)"
					( objectStatus "J4A2.56" )
				)
				( pin "CB(3)"
					( objectStatus "J4A2.201" )
				)
				( pin "CB(4)"
					( objectStatus "J4A2.47" )
				)
				( pin "CB(5)"
					( objectStatus "J4A2.192" )
				)
				( pin "CB(6)"
					( objectStatus "J4A2.54" )
				)
				( pin "CB(7)"
					( objectStatus "J4A2.199" )
				)
				( pin "CKE(0)"
					( objectStatus "J4A2.60" )
				)
				( pin "CKE(1)"
					( objectStatus "J4A2.203" )
				)
				( pin "DQ(0)"
					( objectStatus "J4A2.5" )
				)
				( pin "DQ(10)"
					( objectStatus "J4A2.23" )
				)
				( pin "DQ(11)"
					( objectStatus "J4A2.168" )
				)
				( pin "DQ(12)"
					( objectStatus "J4A2.14" )
				)
				( pin "DQ(13)"
					( objectStatus "J4A2.159" )
				)
				( pin "DQ(14)"
					( objectStatus "J4A2.21" )
				)
				( pin "DQ(15)"
					( objectStatus "J4A2.166" )
				)
				( pin "DQ(16)"
					( objectStatus "J4A2.27" )
				)
				( pin "DQ(17)"
					( objectStatus "J4A2.172" )
				)
				( pin "DQ(18)"
					( objectStatus "J4A2.34" )
				)
				( pin "DQ(19)"
					( objectStatus "J4A2.179" )
				)
				( pin "DQ(1)"
					( objectStatus "J4A2.150" )
				)
				( pin "DQ(20)"
					( objectStatus "J4A2.25" )
				)
				( pin "DQ(21)"
					( objectStatus "J4A2.170" )
				)
				( pin "DQ(22)"
					( objectStatus "J4A2.32" )
				)
				( pin "DQ(23)"
					( objectStatus "J4A2.177" )
				)
				( pin "DQ(24)"
					( objectStatus "J4A2.38" )
				)
				( pin "DQ(25)"
					( objectStatus "J4A2.183" )
				)
				( pin "DQ(26)"
					( objectStatus "J4A2.45" )
				)
				( pin "DQ(27)"
					( objectStatus "J4A2.190" )
				)
				( pin "DQ(28)"
					( objectStatus "J4A2.36" )
				)
				( pin "DQ(29)"
					( objectStatus "J4A2.181" )
				)
				( pin "DQ(2)"
					( objectStatus "J4A2.12" )
				)
				( pin "DQ(30)"
					( objectStatus "J4A2.43" )
				)
				( pin "DQ(31)"
					( objectStatus "J4A2.188" )
				)
				( pin "DQ(32)"
					( objectStatus "J4A2.97" )
				)
				( pin "DQ(33)"
					( objectStatus "J4A2.242" )
				)
				( pin "DQ(34)"
					( objectStatus "J4A2.104" )
				)
				( pin "DQ(35)"
					( objectStatus "J4A2.249" )
				)
				( pin "DQ(36)"
					( objectStatus "J4A2.95" )
				)
				( pin "DQ(37)"
					( objectStatus "J4A2.240" )
				)
				( pin "DQ(38)"
					( objectStatus "J4A2.102" )
				)
				( pin "DQ(39)"
					( objectStatus "J4A2.247" )
				)
				( pin "DQ(3)"
					( objectStatus "J4A2.157" )
				)
				( pin "DQ(40)"
					( objectStatus "J4A2.108" )
				)
				( pin "DQ(41)"
					( objectStatus "J4A2.253" )
				)
				( pin "DQ(42)"
					( objectStatus "J4A2.115" )
				)
				( pin "DQ(43)"
					( objectStatus "J4A2.260" )
				)
				( pin "DQ(44)"
					( objectStatus "J4A2.106" )
				)
				( pin "DQ(45)"
					( objectStatus "J4A2.251" )
				)
				( pin "DQ(46)"
					( objectStatus "J4A2.113" )
				)
				( pin "DQ(47)"
					( objectStatus "J4A2.258" )
				)
				( pin "DQ(48)"
					( objectStatus "J4A2.119" )
				)
				( pin "DQ(49)"
					( objectStatus "J4A2.264" )
				)
				( pin "DQ(4)"
					( objectStatus "J4A2.3" )
				)
				( pin "DQ(50)"
					( objectStatus "J4A2.126" )
				)
				( pin "DQ(51)"
					( objectStatus "J4A2.271" )
				)
				( pin "DQ(52)"
					( objectStatus "J4A2.117" )
				)
				( pin "DQ(53)"
					( objectStatus "J4A2.262" )
				)
				( pin "DQ(54)"
					( objectStatus "J4A2.124" )
				)
				( pin "DQ(55)"
					( objectStatus "J4A2.269" )
				)
				( pin "DQ(56)"
					( objectStatus "J4A2.130" )
				)
				( pin "DQ(57)"
					( objectStatus "J4A2.275" )
				)
				( pin "DQ(58)"
					( objectStatus "J4A2.137" )
				)
				( pin "DQ(59)"
					( objectStatus "J4A2.282" )
				)
				( pin "DQ(5)"
					( objectStatus "J4A2.148" )
				)
				( pin "DQ(60)"
					( objectStatus "J4A2.128" )
				)
				( pin "DQ(61)"
					( objectStatus "J4A2.273" )
				)
				( pin "DQ(62)"
					( objectStatus "J4A2.135" )
				)
				( pin "DQ(63)"
					( objectStatus "J4A2.280" )
				)
				( pin "DQ(6)"
					( objectStatus "J4A2.10" )
				)
				( pin "DQ(7)"
					( objectStatus "J4A2.155" )
				)
				( pin "DQ(8)"
					( objectStatus "J4A2.16" )
				)
				( pin "DQ(9)"
					( objectStatus "J4A2.161" )
				)
				( pin "ODT(0)"
					( objectStatus "J4A2.87" )
				)
				( pin "ODT(1)"
					( objectStatus "J4A2.91" )
				)
				( pin "PAR"
					( objectStatus "J4A2.222" )
				)
				( pin "S0_N"
					( objectStatus "J4A2.84" )
				)
				( pin "S1_N"
					( objectStatus "J4A2.89" )
				)
				( pin "S2_N_C(0)"
					( objectStatus "J4A2.93" )
				)
				( pin "S3_N_C(1)"
					( objectStatus "J4A2.237" )
				)
			)
			( gate "@baseboard_fab2_lib.baseboard_fab2(sch_1):page51_i66"
				( objectStatus "F155" )
				( pin "DQS0N"
					( objectStatus "J4A2.152" )
				)
				( pin "DQS0P"
					( objectStatus "J4A2.153" )
				)
				( pin "DQS10N"
					( objectStatus "J4A2.19" )
				)
				( pin "DQS10P"
					( objectStatus "J4A2.18" )
				)
				( pin "DQS11N"
					( objectStatus "J4A2.30" )
				)
				( pin "DQS11P"
					( objectStatus "J4A2.29" )
				)
				( pin "DQS12N"
					( objectStatus "J4A2.41" )
				)
				( pin "DQS12P"
					( objectStatus "J4A2.40" )
				)
				( pin "DQS13N"
					( objectStatus "J4A2.100" )
				)
				( pin "DQS13P"
					( objectStatus "J4A2.99" )
				)
				( pin "DQS14N"
					( objectStatus "J4A2.111" )
				)
				( pin "DQS14P"
					( objectStatus "J4A2.110" )
				)
				( pin "DQS15N"
					( objectStatus "J4A2.122" )
				)
				( pin "DQS15P"
					( objectStatus "J4A2.121" )
				)
				( pin "DQS16N"
					( objectStatus "J4A2.133" )
				)
				( pin "DQS16P"
					( objectStatus "J4A2.132" )
				)
				( pin "DQS17N"
					( objectStatus "J4A2.52" )
				)
				( pin "DQS17P"
					( objectStatus "J4A2.51" )
				)
				( pin "DQS1N"
					( objectStatus "J4A2.163" )
				)
				( pin "DQS1P"
					( objectStatus "J4A2.164" )
				)
				( pin "DQS2N"
					( objectStatus "J4A2.174" )
				)
				( pin "DQS2P"
					( objectStatus "J4A2.175" )
				)
				( pin "DQS3N"
					( objectStatus "J4A2.185" )
				)
				( pin "DQS3P"
					( objectStatus "J4A2.186" )
				)
				( pin "DQS4N"
					( objectStatus "J4A2.244" )
				)
				( pin "DQS4P"
					( objectStatus "J4A2.245" )
				)
				( pin "DQS5N"
					( objectStatus "J4A2.255" )
				)
				( pin "DQS5P"
					( objectStatus "J4A2.256" )
				)
				( pin "DQS6N"
					( objectStatus "J4A2.266" )
				)
				( pin "DQS6P"
					( objectStatus "J4A2.267" )
				)
				( pin "DQS7N"
					( objectStatus "J4A2.277" )
				)
				( pin "DQS7P"
					( objectStatus "J4A2.278" )
				)
				( pin "DQS8N"
					( objectStatus "J4A2.196" )
				)
				( pin "DQS8P"
					( objectStatus "J4A2.197" )
				)
				( pin "DQS9N"
					( objectStatus "J4A2.8" )
				)
				( pin "DQS9P"
					( objectStatus "J4A2.7" )
				)
			)
			( gate "@baseboard_fab2_lib.baseboard_fab2(sch_1):page51_i43"
				( objectStatus "F154" )
			)
			( gate "@baseboard_fab2_lib.baseboard_fab2(sch_1):page51_i167"
				( objectStatus "F153" )
			)
			( gate "@baseboard_fab2_lib.baseboard_fab2(sch_1):page53_i111"
				( objectStatus "F160" )
				( pin "A0"
					( objectStatus "J4A1.79" )
				)
				( pin "A1"
					( objectStatus "J4A1.72" )
				)
				( pin "A10"
					( objectStatus "J4A1.225" )
				)
				( pin "A11"
					( objectStatus "J4A1.210" )
				)
				( pin "A12"
					( objectStatus "J4A1.65" )
				)
				( pin "A13"
					( objectStatus "J4A1.232" )
				)
				( pin "A14_WE_N"
					( objectStatus "J4A1.228" )
				)
				( pin "A15_CAS_N"
					( objectStatus "J4A1.86" )
				)
				( pin "A16_RAS_N"
					( objectStatus "J4A1.82" )
				)
				( pin "A17"
					( objectStatus "J4A1.234" )
				)
				( pin "A2"
					( objectStatus "J4A1.216" )
				)
				( pin "A3"
					( objectStatus "J4A1.71" )
				)
				( pin "A4"
					( objectStatus "J4A1.214" )
				)
				( pin "A5"
					( objectStatus "J4A1.213" )
				)
				( pin "A6"
					( objectStatus "J4A1.69" )
				)
				( pin "A7"
					( objectStatus "J4A1.211" )
				)
				( pin "A8"
					( objectStatus "J4A1.68" )
				)
				( pin "A9"
					( objectStatus "J4A1.66" )
				)
				( pin "ACT_N"
					( objectStatus "J4A1.62" )
				)
				( pin "BA(0)"
					( objectStatus "J4A1.81" )
				)
				( pin "BA(1)"
					( objectStatus "J4A1.224" )
				)
				( pin "BG(0)"
					( objectStatus "J4A1.63" )
				)
				( pin "BG(1)"
					( objectStatus "J4A1.207" )
				)
				( pin "C(2)"
					( objectStatus "J4A1.235" )
				)
				( pin "CB(0)"
					( objectStatus "J4A1.49" )
				)
				( pin "CB(1)"
					( objectStatus "J4A1.194" )
				)
				( pin "CB(2)"
					( objectStatus "J4A1.56" )
				)
				( pin "CB(3)"
					( objectStatus "J4A1.201" )
				)
				( pin "CB(4)"
					( objectStatus "J4A1.47" )
				)
				( pin "CB(5)"
					( objectStatus "J4A1.192" )
				)
				( pin "CB(6)"
					( objectStatus "J4A1.54" )
				)
				( pin "CB(7)"
					( objectStatus "J4A1.199" )
				)
				( pin "CKE(0)"
					( objectStatus "J4A1.60" )
				)
				( pin "CKE(1)"
					( objectStatus "J4A1.203" )
				)
				( pin "DQ(0)"
					( objectStatus "J4A1.5" )
				)
				( pin "DQ(10)"
					( objectStatus "J4A1.23" )
				)
				( pin "DQ(11)"
					( objectStatus "J4A1.168" )
				)
				( pin "DQ(12)"
					( objectStatus "J4A1.14" )
				)
				( pin "DQ(13)"
					( objectStatus "J4A1.159" )
				)
				( pin "DQ(14)"
					( objectStatus "J4A1.21" )
				)
				( pin "DQ(15)"
					( objectStatus "J4A1.166" )
				)
				( pin "DQ(16)"
					( objectStatus "J4A1.27" )
				)
				( pin "DQ(17)"
					( objectStatus "J4A1.172" )
				)
				( pin "DQ(18)"
					( objectStatus "J4A1.34" )
				)
				( pin "DQ(19)"
					( objectStatus "J4A1.179" )
				)
				( pin "DQ(1)"
					( objectStatus "J4A1.150" )
				)
				( pin "DQ(20)"
					( objectStatus "J4A1.25" )
				)
				( pin "DQ(21)"
					( objectStatus "J4A1.170" )
				)
				( pin "DQ(22)"
					( objectStatus "J4A1.32" )
				)
				( pin "DQ(23)"
					( objectStatus "J4A1.177" )
				)
				( pin "DQ(24)"
					( objectStatus "J4A1.38" )
				)
				( pin "DQ(25)"
					( objectStatus "J4A1.183" )
				)
				( pin "DQ(26)"
					( objectStatus "J4A1.45" )
				)
				( pin "DQ(27)"
					( objectStatus "J4A1.190" )
				)
				( pin "DQ(28)"
					( objectStatus "J4A1.36" )
				)
				( pin "DQ(29)"
					( objectStatus "J4A1.181" )
				)
				( pin "DQ(2)"
					( objectStatus "J4A1.12" )
				)
				( pin "DQ(30)"
					( objectStatus "J4A1.43" )
				)
				( pin "DQ(31)"
					( objectStatus "J4A1.188" )
				)
				( pin "DQ(32)"
					( objectStatus "J4A1.97" )
				)
				( pin "DQ(33)"
					( objectStatus "J4A1.242" )
				)
				( pin "DQ(34)"
					( objectStatus "J4A1.104" )
				)
				( pin "DQ(35)"
					( objectStatus "J4A1.249" )
				)
				( pin "DQ(36)"
					( objectStatus "J4A1.95" )
				)
				( pin "DQ(37)"
					( objectStatus "J4A1.240" )
				)
				( pin "DQ(38)"
					( objectStatus "J4A1.102" )
				)
				( pin "DQ(39)"
					( objectStatus "J4A1.247" )
				)
				( pin "DQ(3)"
					( objectStatus "J4A1.157" )
				)
				( pin "DQ(40)"
					( objectStatus "J4A1.108" )
				)
				( pin "DQ(41)"
					( objectStatus "J4A1.253" )
				)
				( pin "DQ(42)"
					( objectStatus "J4A1.115" )
				)
				( pin "DQ(43)"
					( objectStatus "J4A1.260" )
				)
				( pin "DQ(44)"
					( objectStatus "J4A1.106" )
				)
				( pin "DQ(45)"
					( objectStatus "J4A1.251" )
				)
				( pin "DQ(46)"
					( objectStatus "J4A1.113" )
				)
				( pin "DQ(47)"
					( objectStatus "J4A1.258" )
				)
				( pin "DQ(48)"
					( objectStatus "J4A1.119" )
				)
				( pin "DQ(49)"
					( objectStatus "J4A1.264" )
				)
				( pin "DQ(4)"
					( objectStatus "J4A1.3" )
				)
				( pin "DQ(50)"
					( objectStatus "J4A1.126" )
				)
				( pin "DQ(51)"
					( objectStatus "J4A1.271" )
				)
				( pin "DQ(52)"
					( objectStatus "J4A1.117" )
				)
				( pin "DQ(53)"
					( objectStatus "J4A1.262" )
				)
				( pin "DQ(54)"
					( objectStatus "J4A1.124" )
				)
				( pin "DQ(55)"
					( objectStatus "J4A1.269" )
				)
				( pin "DQ(56)"
					( objectStatus "J4A1.130" )
				)
				( pin "DQ(57)"
					( objectStatus "J4A1.275" )
				)
				( pin "DQ(58)"
					( objectStatus "J4A1.137" )
				)
				( pin "DQ(59)"
					( objectStatus "J4A1.282" )
				)
				( pin "DQ(5)"
					( objectStatus "J4A1.148" )
				)
				( pin "DQ(60)"
					( objectStatus "J4A1.128" )
				)
				( pin "DQ(61)"
					( objectStatus "J4A1.273" )
				)
				( pin "DQ(62)"
					( objectStatus "J4A1.135" )
				)
				( pin "DQ(63)"
					( objectStatus "J4A1.280" )
				)
				( pin "DQ(6)"
					( objectStatus "J4A1.10" )
				)
				( pin "DQ(7)"
					( objectStatus "J4A1.155" )
				)
				( pin "DQ(8)"
					( objectStatus "J4A1.16" )
				)
				( pin "DQ(9)"
					( objectStatus "J4A1.161" )
				)
				( pin "ODT(0)"
					( objectStatus "J4A1.87" )
				)
				( pin "ODT(1)"
					( objectStatus "J4A1.91" )
				)
				( pin "PAR"
					( objectStatus "J4A1.222" )
				)
				( pin "S0_N"
					( objectStatus "J4A1.84" )
				)
				( pin "S1_N"
					( objectStatus "J4A1.89" )
				)
				( pin "S2_N_C(0)"
					( objectStatus "J4A1.93" )
				)
				( pin "S3_N_C(1)"
					( objectStatus "J4A1.237" )
				)
				( pin "SCL"
					( objectStatus "J4A1.141" )
				)
				( pin "SDA"
					( objectStatus "J4A1.285" )
				)
			)
			( gate "@baseboard_fab2_lib.baseboard_fab2(sch_1):page53_i66"
				( objectStatus "F159" )
				( pin "DQS0N"
					( objectStatus "J4A1.152" )
				)
				( pin "DQS0P"
					( objectStatus "J4A1.153" )
				)
				( pin "DQS10N"
					( objectStatus "J4A1.19" )
				)
				( pin "DQS10P"
					( objectStatus "J4A1.18" )
				)
				( pin "DQS11N"
					( objectStatus "J4A1.30" )
				)
				( pin "DQS11P"
					( objectStatus "J4A1.29" )
				)
				( pin "DQS12N"
					( objectStatus "J4A1.41" )
				)
				( pin "DQS12P"
					( objectStatus "J4A1.40" )
				)
				( pin "DQS13N"
					( objectStatus "J4A1.100" )
				)
				( pin "DQS13P"
					( objectStatus "J4A1.99" )
				)
				( pin "DQS14N"
					( objectStatus "J4A1.111" )
				)
				( pin "DQS14P"
					( objectStatus "J4A1.110" )
				)
				( pin "DQS15N"
					( objectStatus "J4A1.122" )
				)
				( pin "DQS15P"
					( objectStatus "J4A1.121" )
				)
				( pin "DQS16N"
					( objectStatus "J4A1.133" )
				)
				( pin "DQS16P"
					( objectStatus "J4A1.132" )
				)
				( pin "DQS17N"
					( objectStatus "J4A1.52" )
				)
				( pin "DQS17P"
					( objectStatus "J4A1.51" )
				)
				( pin "DQS1N"
					( objectStatus "J4A1.163" )
				)
				( pin "DQS1P"
					( objectStatus "J4A1.164" )
				)
				( pin "DQS2N"
					( objectStatus "J4A1.174" )
				)
				( pin "DQS2P"
					( objectStatus "J4A1.175" )
				)
				( pin "DQS3N"
					( objectStatus "J4A1.185" )
				)
				( pin "DQS3P"
					( objectStatus "J4A1.186" )
				)
				( pin "DQS4N"
					( objectStatus "J4A1.244" )
				)
				( pin "DQS4P"
					( objectStatus "J4A1.245" )
				)
				( pin "DQS5N"
					( objectStatus "J4A1.255" )
				)
				( pin "DQS5P"
					( objectStatus "J4A1.256" )
				)
				( pin "DQS6N"
					( objectStatus "J4A1.266" )
				)
				( pin "DQS6P"
					( objectStatus "J4A1.267" )
				)
				( pin "DQS7N"
					( objectStatus "J4A1.277" )
				)
				( pin "DQS7P"
					( objectStatus "J4A1.278" )
				)
				( pin "DQS8N"
					( objectStatus "J4A1.196" )
				)
				( pin "DQS8P"
					( objectStatus "J4A1.197" )
				)
				( pin "DQS9N"
					( objectStatus "J4A1.8" )
				)
				( pin "DQS9P"
					( objectStatus "J4A1.7" )
				)
			)
			( gate "@baseboard_fab2_lib.baseboard_fab2(sch_1):page53_i43"
				( objectStatus "F158" )
			)
			( gate "@baseboard_fab2_lib.baseboard_fab2(sch_1):page53_i171"
				( objectStatus "F157" )
			)
			( gate "@baseboard_fab2_lib.baseboard_fab2(sch_1):page77_i111"
				( objectStatus "F172" )
				( pin "A0"
					( objectStatus "J1G1.79" )
				)
				( pin "A1"
					( objectStatus "J1G1.72" )
				)
				( pin "A10"
					( objectStatus "J1G1.225" )
				)
				( pin "A11"
					( objectStatus "J1G1.210" )
				)
				( pin "A12"
					( objectStatus "J1G1.65" )
				)
				( pin "A13"
					( objectStatus "J1G1.232" )
				)
				( pin "A14_WE_N"
					( objectStatus "J1G1.228" )
				)
				( pin "A15_CAS_N"
					( objectStatus "J1G1.86" )
				)
				( pin "A16_RAS_N"
					( objectStatus "J1G1.82" )
				)
				( pin "A17"
					( objectStatus "J1G1.234" )
				)
				( pin "A2"
					( objectStatus "J1G1.216" )
				)
				( pin "A3"
					( objectStatus "J1G1.71" )
				)
				( pin "A4"
					( objectStatus "J1G1.214" )
				)
				( pin "A5"
					( objectStatus "J1G1.213" )
				)
				( pin "A6"
					( objectStatus "J1G1.69" )
				)
				( pin "A7"
					( objectStatus "J1G1.211" )
				)
				( pin "A8"
					( objectStatus "J1G1.68" )
				)
				( pin "A9"
					( objectStatus "J1G1.66" )
				)
				( pin "ACT_N"
					( objectStatus "J1G1.62" )
				)
				( pin "BA(0)"
					( objectStatus "J1G1.81" )
				)
				( pin "BA(1)"
					( objectStatus "J1G1.224" )
				)
				( pin "BG(0)"
					( objectStatus "J1G1.63" )
				)
				( pin "BG(1)"
					( objectStatus "J1G1.207" )
				)
				( pin "C(2)"
					( objectStatus "J1G1.235" )
				)
				( pin "CB(0)"
					( objectStatus "J1G1.49" )
				)
				( pin "CB(1)"
					( objectStatus "J1G1.194" )
				)
				( pin "CB(2)"
					( objectStatus "J1G1.56" )
				)
				( pin "CB(3)"
					( objectStatus "J1G1.201" )
				)
				( pin "CB(4)"
					( objectStatus "J1G1.47" )
				)
				( pin "CB(5)"
					( objectStatus "J1G1.192" )
				)
				( pin "CB(6)"
					( objectStatus "J1G1.54" )
				)
				( pin "CB(7)"
					( objectStatus "J1G1.199" )
				)
				( pin "CKE(0)"
					( objectStatus "J1G1.60" )
				)
				( pin "CKE(1)"
					( objectStatus "J1G1.203" )
				)
				( pin "DQ(0)"
					( objectStatus "J1G1.5" )
				)
				( pin "DQ(10)"
					( objectStatus "J1G1.23" )
				)
				( pin "DQ(11)"
					( objectStatus "J1G1.168" )
				)
				( pin "DQ(12)"
					( objectStatus "J1G1.14" )
				)
				( pin "DQ(13)"
					( objectStatus "J1G1.159" )
				)
				( pin "DQ(14)"
					( objectStatus "J1G1.21" )
				)
				( pin "DQ(15)"
					( objectStatus "J1G1.166" )
				)
				( pin "DQ(16)"
					( objectStatus "J1G1.27" )
				)
				( pin "DQ(17)"
					( objectStatus "J1G1.172" )
				)
				( pin "DQ(18)"
					( objectStatus "J1G1.34" )
				)
				( pin "DQ(19)"
					( objectStatus "J1G1.179" )
				)
				( pin "DQ(1)"
					( objectStatus "J1G1.150" )
				)
				( pin "DQ(20)"
					( objectStatus "J1G1.25" )
				)
				( pin "DQ(21)"
					( objectStatus "J1G1.170" )
				)
				( pin "DQ(22)"
					( objectStatus "J1G1.32" )
				)
				( pin "DQ(23)"
					( objectStatus "J1G1.177" )
				)
				( pin "DQ(24)"
					( objectStatus "J1G1.38" )
				)
				( pin "DQ(25)"
					( objectStatus "J1G1.183" )
				)
				( pin "DQ(26)"
					( objectStatus "J1G1.45" )
				)
				( pin "DQ(27)"
					( objectStatus "J1G1.190" )
				)
				( pin "DQ(28)"
					( objectStatus "J1G1.36" )
				)
				( pin "DQ(29)"
					( objectStatus "J1G1.181" )
				)
				( pin "DQ(2)"
					( objectStatus "J1G1.12" )
				)
				( pin "DQ(30)"
					( objectStatus "J1G1.43" )
				)
				( pin "DQ(31)"
					( objectStatus "J1G1.188" )
				)
				( pin "DQ(32)"
					( objectStatus "J1G1.97" )
				)
				( pin "DQ(33)"
					( objectStatus "J1G1.242" )
				)
				( pin "DQ(34)"
					( objectStatus "J1G1.104" )
				)
				( pin "DQ(35)"
					( objectStatus "J1G1.249" )
				)
				( pin "DQ(36)"
					( objectStatus "J1G1.95" )
				)
				( pin "DQ(37)"
					( objectStatus "J1G1.240" )
				)
				( pin "DQ(38)"
					( objectStatus "J1G1.102" )
				)
				( pin "DQ(39)"
					( objectStatus "J1G1.247" )
				)
				( pin "DQ(3)"
					( objectStatus "J1G1.157" )
				)
				( pin "DQ(40)"
					( objectStatus "J1G1.108" )
				)
				( pin "DQ(41)"
					( objectStatus "J1G1.253" )
				)
				( pin "DQ(42)"
					( objectStatus "J1G1.115" )
				)
				( pin "DQ(43)"
					( objectStatus "J1G1.260" )
				)
				( pin "DQ(44)"
					( objectStatus "J1G1.106" )
				)
				( pin "DQ(45)"
					( objectStatus "J1G1.251" )
				)
				( pin "DQ(46)"
					( objectStatus "J1G1.113" )
				)
				( pin "DQ(47)"
					( objectStatus "J1G1.258" )
				)
				( pin "DQ(48)"
					( objectStatus "J1G1.119" )
				)
				( pin "DQ(49)"
					( objectStatus "J1G1.264" )
				)
				( pin "DQ(4)"
					( objectStatus "J1G1.3" )
				)
				( pin "DQ(50)"
					( objectStatus "J1G1.126" )
				)
				( pin "DQ(51)"
					( objectStatus "J1G1.271" )
				)
				( pin "DQ(52)"
					( objectStatus "J1G1.117" )
				)
				( pin "DQ(53)"
					( objectStatus "J1G1.262" )
				)
				( pin "DQ(54)"
					( objectStatus "J1G1.124" )
				)
				( pin "DQ(55)"
					( objectStatus "J1G1.269" )
				)
				( pin "DQ(56)"
					( objectStatus "J1G1.130" )
				)
				( pin "DQ(57)"
					( objectStatus "J1G1.275" )
				)
				( pin "DQ(58)"
					( objectStatus "J1G1.137" )
				)
				( pin "DQ(59)"
					( objectStatus "J1G1.282" )
				)
				( pin "DQ(5)"
					( objectStatus "J1G1.148" )
				)
				( pin "DQ(60)"
					( objectStatus "J1G1.128" )
				)
				( pin "DQ(61)"
					( objectStatus "J1G1.273" )
				)
				( pin "DQ(62)"
					( objectStatus "J1G1.135" )
				)
				( pin "DQ(63)"
					( objectStatus "J1G1.280" )
				)
				( pin "DQ(6)"
					( objectStatus "J1G1.10" )
				)
				( pin "DQ(7)"
					( objectStatus "J1G1.155" )
				)
				( pin "DQ(8)"
					( objectStatus "J1G1.16" )
				)
				( pin "DQ(9)"
					( objectStatus "J1G1.161" )
				)
				( pin "ODT(0)"
					( objectStatus "J1G1.87" )
				)
				( pin "ODT(1)"
					( objectStatus "J1G1.91" )
				)
				( pin "PAR"
					( objectStatus "J1G1.222" )
				)
				( pin "S0_N"
					( objectStatus "J1G1.84" )
				)
				( pin "S1_N"
					( objectStatus "J1G1.89" )
				)
				( pin "S2_N_C(0)"
					( objectStatus "J1G1.93" )
				)
				( pin "S3_N_C(1)"
					( objectStatus "J1G1.237" )
				)
			)
			( gate "@baseboard_fab2_lib.baseboard_fab2(sch_1):page77_i66"
				( objectStatus "F171" )
				( pin "DQS0N"
					( objectStatus "J1G1.152" )
				)
				( pin "DQS0P"
					( objectStatus "J1G1.153" )
				)
				( pin "DQS10N"
					( objectStatus "J1G1.19" )
				)
				( pin "DQS10P"
					( objectStatus "J1G1.18" )
				)
				( pin "DQS11N"
					( objectStatus "J1G1.30" )
				)
				( pin "DQS11P"
					( objectStatus "J1G1.29" )
				)
				( pin "DQS12N"
					( objectStatus "J1G1.41" )
				)
				( pin "DQS12P"
					( objectStatus "J1G1.40" )
				)
				( pin "DQS13N"
					( objectStatus "J1G1.100" )
				)
				( pin "DQS13P"
					( objectStatus "J1G1.99" )
				)
				( pin "DQS14N"
					( objectStatus "J1G1.111" )
				)
				( pin "DQS14P"
					( objectStatus "J1G1.110" )
				)
				( pin "DQS15N"
					( objectStatus "J1G1.122" )
				)
				( pin "DQS15P"
					( objectStatus "J1G1.121" )
				)
				( pin "DQS16N"
					( objectStatus "J1G1.133" )
				)
				( pin "DQS16P"
					( objectStatus "J1G1.132" )
				)
				( pin "DQS17N"
					( objectStatus "J1G1.52" )
				)
				( pin "DQS17P"
					( objectStatus "J1G1.51" )
				)
				( pin "DQS1N"
					( objectStatus "J1G1.163" )
				)
				( pin "DQS1P"
					( objectStatus "J1G1.164" )
				)
				( pin "DQS2N"
					( objectStatus "J1G1.174" )
				)
				( pin "DQS2P"
					( objectStatus "J1G1.175" )
				)
				( pin "DQS3N"
					( objectStatus "J1G1.185" )
				)
				( pin "DQS3P"
					( objectStatus "J1G1.186" )
				)
				( pin "DQS4N"
					( objectStatus "J1G1.244" )
				)
				( pin "DQS4P"
					( objectStatus "J1G1.245" )
				)
				( pin "DQS5N"
					( objectStatus "J1G1.255" )
				)
				( pin "DQS5P"
					( objectStatus "J1G1.256" )
				)
				( pin "DQS6N"
					( objectStatus "J1G1.266" )
				)
				( pin "DQS6P"
					( objectStatus "J1G1.267" )
				)
				( pin "DQS7N"
					( objectStatus "J1G1.277" )
				)
				( pin "DQS7P"
					( objectStatus "J1G1.278" )
				)
				( pin "DQS8N"
					( objectStatus "J1G1.196" )
				)
				( pin "DQS8P"
					( objectStatus "J1G1.197" )
				)
				( pin "DQS9N"
					( objectStatus "J1G1.8" )
				)
				( pin "DQS9P"
					( objectStatus "J1G1.7" )
				)
			)
			( gate "@baseboard_fab2_lib.baseboard_fab2(sch_1):page77_i43"
				( objectStatus "F170" )
			)
			( gate "@baseboard_fab2_lib.baseboard_fab2(sch_1):page77_i171"
				( objectStatus "F169" )
			)
			( gate "@baseboard_fab2_lib.baseboard_fab2(sch_1):page79_i111"
				( objectStatus "F168" )
				( pin "A0"
					( objectStatus "J1G2.79" )
				)
				( pin "A1"
					( objectStatus "J1G2.72" )
				)
				( pin "A10"
					( objectStatus "J1G2.225" )
				)
				( pin "A11"
					( objectStatus "J1G2.210" )
				)
				( pin "A12"
					( objectStatus "J1G2.65" )
				)
				( pin "A13"
					( objectStatus "J1G2.232" )
				)
				( pin "A14_WE_N"
					( objectStatus "J1G2.228" )
				)
				( pin "A15_CAS_N"
					( objectStatus "J1G2.86" )
				)
				( pin "A16_RAS_N"
					( objectStatus "J1G2.82" )
				)
				( pin "A17"
					( objectStatus "J1G2.234" )
				)
				( pin "A2"
					( objectStatus "J1G2.216" )
				)
				( pin "A3"
					( objectStatus "J1G2.71" )
				)
				( pin "A4"
					( objectStatus "J1G2.214" )
				)
				( pin "A5"
					( objectStatus "J1G2.213" )
				)
				( pin "A6"
					( objectStatus "J1G2.69" )
				)
				( pin "A7"
					( objectStatus "J1G2.211" )
				)
				( pin "A8"
					( objectStatus "J1G2.68" )
				)
				( pin "A9"
					( objectStatus "J1G2.66" )
				)
				( pin "ACT_N"
					( objectStatus "J1G2.62" )
				)
				( pin "BA(0)"
					( objectStatus "J1G2.81" )
				)
				( pin "BA(1)"
					( objectStatus "J1G2.224" )
				)
				( pin "BG(0)"
					( objectStatus "J1G2.63" )
				)
				( pin "BG(1)"
					( objectStatus "J1G2.207" )
				)
				( pin "C(2)"
					( objectStatus "J1G2.235" )
				)
				( pin "CB(0)"
					( objectStatus "J1G2.49" )
				)
				( pin "CB(1)"
					( objectStatus "J1G2.194" )
				)
				( pin "CB(2)"
					( objectStatus "J1G2.56" )
				)
				( pin "CB(3)"
					( objectStatus "J1G2.201" )
				)
				( pin "CB(4)"
					( objectStatus "J1G2.47" )
				)
				( pin "CB(5)"
					( objectStatus "J1G2.192" )
				)
				( pin "CB(6)"
					( objectStatus "J1G2.54" )
				)
				( pin "CB(7)"
					( objectStatus "J1G2.199" )
				)
				( pin "CKE(0)"
					( objectStatus "J1G2.60" )
				)
				( pin "CKE(1)"
					( objectStatus "J1G2.203" )
				)
				( pin "DQ(0)"
					( objectStatus "J1G2.5" )
				)
				( pin "DQ(10)"
					( objectStatus "J1G2.23" )
				)
				( pin "DQ(11)"
					( objectStatus "J1G2.168" )
				)
				( pin "DQ(12)"
					( objectStatus "J1G2.14" )
				)
				( pin "DQ(13)"
					( objectStatus "J1G2.159" )
				)
				( pin "DQ(14)"
					( objectStatus "J1G2.21" )
				)
				( pin "DQ(15)"
					( objectStatus "J1G2.166" )
				)
				( pin "DQ(16)"
					( objectStatus "J1G2.27" )
				)
				( pin "DQ(17)"
					( objectStatus "J1G2.172" )
				)
				( pin "DQ(18)"
					( objectStatus "J1G2.34" )
				)
				( pin "DQ(19)"
					( objectStatus "J1G2.179" )
				)
				( pin "DQ(1)"
					( objectStatus "J1G2.150" )
				)
				( pin "DQ(20)"
					( objectStatus "J1G2.25" )
				)
				( pin "DQ(21)"
					( objectStatus "J1G2.170" )
				)
				( pin "DQ(22)"
					( objectStatus "J1G2.32" )
				)
				( pin "DQ(23)"
					( objectStatus "J1G2.177" )
				)
				( pin "DQ(24)"
					( objectStatus "J1G2.38" )
				)
				( pin "DQ(25)"
					( objectStatus "J1G2.183" )
				)
				( pin "DQ(26)"
					( objectStatus "J1G2.45" )
				)
				( pin "DQ(27)"
					( objectStatus "J1G2.190" )
				)
				( pin "DQ(28)"
					( objectStatus "J1G2.36" )
				)
				( pin "DQ(29)"
					( objectStatus "J1G2.181" )
				)
				( pin "DQ(2)"
					( objectStatus "J1G2.12" )
				)
				( pin "DQ(30)"
					( objectStatus "J1G2.43" )
				)
				( pin "DQ(31)"
					( objectStatus "J1G2.188" )
				)
				( pin "DQ(32)"
					( objectStatus "J1G2.97" )
				)
				( pin "DQ(33)"
					( objectStatus "J1G2.242" )
				)
				( pin "DQ(34)"
					( objectStatus "J1G2.104" )
				)
				( pin "DQ(35)"
					( objectStatus "J1G2.249" )
				)
				( pin "DQ(36)"
					( objectStatus "J1G2.95" )
				)
				( pin "DQ(37)"
					( objectStatus "J1G2.240" )
				)
				( pin "DQ(38)"
					( objectStatus "J1G2.102" )
				)
				( pin "DQ(39)"
					( objectStatus "J1G2.247" )
				)
				( pin "DQ(3)"
					( objectStatus "J1G2.157" )
				)
				( pin "DQ(40)"
					( objectStatus "J1G2.108" )
				)
				( pin "DQ(41)"
					( objectStatus "J1G2.253" )
				)
				( pin "DQ(42)"
					( objectStatus "J1G2.115" )
				)
				( pin "DQ(43)"
					( objectStatus "J1G2.260" )
				)
				( pin "DQ(44)"
					( objectStatus "J1G2.106" )
				)
				( pin "DQ(45)"
					( objectStatus "J1G2.251" )
				)
				( pin "DQ(46)"
					( objectStatus "J1G2.113" )
				)
				( pin "DQ(47)"
					( objectStatus "J1G2.258" )
				)
				( pin "DQ(48)"
					( objectStatus "J1G2.119" )
				)
				( pin "DQ(49)"
					( objectStatus "J1G2.264" )
				)
				( pin "DQ(4)"
					( objectStatus "J1G2.3" )
				)
				( pin "DQ(50)"
					( objectStatus "J1G2.126" )
				)
				( pin "DQ(51)"
					( objectStatus "J1G2.271" )
				)
				( pin "DQ(52)"
					( objectStatus "J1G2.117" )
				)
				( pin "DQ(53)"
					( objectStatus "J1G2.262" )
				)
				( pin "DQ(54)"
					( objectStatus "J1G2.124" )
				)
				( pin "DQ(55)"
					( objectStatus "J1G2.269" )
				)
				( pin "DQ(56)"
					( objectStatus "J1G2.130" )
				)
				( pin "DQ(57)"
					( objectStatus "J1G2.275" )
				)
				( pin "DQ(58)"
					( objectStatus "J1G2.137" )
				)
				( pin "DQ(59)"
					( objectStatus "J1G2.282" )
				)
				( pin "DQ(5)"
					( objectStatus "J1G2.148" )
				)
				( pin "DQ(60)"
					( objectStatus "J1G2.128" )
				)
				( pin "DQ(61)"
					( objectStatus "J1G2.273" )
				)
				( pin "DQ(62)"
					( objectStatus "J1G2.135" )
				)
				( pin "DQ(63)"
					( objectStatus "J1G2.280" )
				)
				( pin "DQ(6)"
					( objectStatus "J1G2.10" )
				)
				( pin "DQ(7)"
					( objectStatus "J1G2.155" )
				)
				( pin "DQ(8)"
					( objectStatus "J1G2.16" )
				)
				( pin "DQ(9)"
					( objectStatus "J1G2.161" )
				)
				( pin "ODT(0)"
					( objectStatus "J1G2.87" )
				)
				( pin "ODT(1)"
					( objectStatus "J1G2.91" )
				)
				( pin "PAR"
					( objectStatus "J1G2.222" )
				)
				( pin "S0_N"
					( objectStatus "J1G2.84" )
				)
				( pin "S1_N"
					( objectStatus "J1G2.89" )
				)
				( pin "S2_N_C(0)"
					( objectStatus "J1G2.93" )
				)
				( pin "S3_N_C(1)"
					( objectStatus "J1G2.237" )
				)
			)
			( gate "@baseboard_fab2_lib.baseboard_fab2(sch_1):page79_i64"
				( objectStatus "F167" )
				( pin "DQS0N"
					( objectStatus "J1G2.152" )
				)
				( pin "DQS0P"
					( objectStatus "J1G2.153" )
				)
				( pin "DQS10N"
					( objectStatus "J1G2.19" )
				)
				( pin "DQS10P"
					( objectStatus "J1G2.18" )
				)
				( pin "DQS11N"
					( objectStatus "J1G2.30" )
				)
				( pin "DQS11P"
					( objectStatus "J1G2.29" )
				)
				( pin "DQS12N"
					( objectStatus "J1G2.41" )
				)
				( pin "DQS12P"
					( objectStatus "J1G2.40" )
				)
				( pin "DQS13N"
					( objectStatus "J1G2.100" )
				)
				( pin "DQS13P"
					( objectStatus "J1G2.99" )
				)
				( pin "DQS14N"
					( objectStatus "J1G2.111" )
				)
				( pin "DQS14P"
					( objectStatus "J1G2.110" )
				)
				( pin "DQS15N"
					( objectStatus "J1G2.122" )
				)
				( pin "DQS15P"
					( objectStatus "J1G2.121" )
				)
				( pin "DQS16N"
					( objectStatus "J1G2.133" )
				)
				( pin "DQS16P"
					( objectStatus "J1G2.132" )
				)
				( pin "DQS17N"
					( objectStatus "J1G2.52" )
				)
				( pin "DQS17P"
					( objectStatus "J1G2.51" )
				)
				( pin "DQS1N"
					( objectStatus "J1G2.163" )
				)
				( pin "DQS1P"
					( objectStatus "J1G2.164" )
				)
				( pin "DQS2N"
					( objectStatus "J1G2.174" )
				)
				( pin "DQS2P"
					( objectStatus "J1G2.175" )
				)
				( pin "DQS3N"
					( objectStatus "J1G2.185" )
				)
				( pin "DQS3P"
					( objectStatus "J1G2.186" )
				)
				( pin "DQS4N"
					( objectStatus "J1G2.244" )
				)
				( pin "DQS4P"
					( objectStatus "J1G2.245" )
				)
				( pin "DQS5N"
					( objectStatus "J1G2.255" )
				)
				( pin "DQS5P"
					( objectStatus "J1G2.256" )
				)
				( pin "DQS6N"
					( objectStatus "J1G2.266" )
				)
				( pin "DQS6P"
					( objectStatus "J1G2.267" )
				)
				( pin "DQS7N"
					( objectStatus "J1G2.277" )
				)
				( pin "DQS7P"
					( objectStatus "J1G2.278" )
				)
				( pin "DQS8N"
					( objectStatus "J1G2.196" )
				)
				( pin "DQS8P"
					( objectStatus "J1G2.197" )
				)
				( pin "DQS9N"
					( objectStatus "J1G2.8" )
				)
				( pin "DQS9P"
					( objectStatus "J1G2.7" )
				)
			)
			( gate "@baseboard_fab2_lib.baseboard_fab2(sch_1):page79_i43"
				( objectStatus "F166" )
			)
			( gate "@baseboard_fab2_lib.baseboard_fab2(sch_1):page79_i169"
				( objectStatus "F165" )
			)
			( gate "@baseboard_fab2_lib.baseboard_fab2(sch_1):page81_i186"
				( objectStatus "F164" )
				( pin "A0"
					( objectStatus "J1G3.79" )
				)
				( pin "A1"
					( objectStatus "J1G3.72" )
				)
				( pin "A10"
					( objectStatus "J1G3.225" )
				)
				( pin "A11"
					( objectStatus "J1G3.210" )
				)
				( pin "A12"
					( objectStatus "J1G3.65" )
				)
				( pin "A13"
					( objectStatus "J1G3.232" )
				)
				( pin "A14_WE_N"
					( objectStatus "J1G3.228" )
				)
				( pin "A15_CAS_N"
					( objectStatus "J1G3.86" )
				)
				( pin "A16_RAS_N"
					( objectStatus "J1G3.82" )
				)
				( pin "A17"
					( objectStatus "J1G3.234" )
				)
				( pin "A2"
					( objectStatus "J1G3.216" )
				)
				( pin "A3"
					( objectStatus "J1G3.71" )
				)
				( pin "A4"
					( objectStatus "J1G3.214" )
				)
				( pin "A5"
					( objectStatus "J1G3.213" )
				)
				( pin "A6"
					( objectStatus "J1G3.69" )
				)
				( pin "A7"
					( objectStatus "J1G3.211" )
				)
				( pin "A8"
					( objectStatus "J1G3.68" )
				)
				( pin "A9"
					( objectStatus "J1G3.66" )
				)
				( pin "ACT_N"
					( objectStatus "J1G3.62" )
				)
				( pin "BA(0)"
					( objectStatus "J1G3.81" )
				)
				( pin "BA(1)"
					( objectStatus "J1G3.224" )
				)
				( pin "BG(0)"
					( objectStatus "J1G3.63" )
				)
				( pin "BG(1)"
					( objectStatus "J1G3.207" )
				)
				( pin "C(2)"
					( objectStatus "J1G3.235" )
				)
				( pin "CB(0)"
					( objectStatus "J1G3.49" )
				)
				( pin "CB(1)"
					( objectStatus "J1G3.194" )
				)
				( pin "CB(2)"
					( objectStatus "J1G3.56" )
				)
				( pin "CB(3)"
					( objectStatus "J1G3.201" )
				)
				( pin "CB(4)"
					( objectStatus "J1G3.47" )
				)
				( pin "CB(5)"
					( objectStatus "J1G3.192" )
				)
				( pin "CB(6)"
					( objectStatus "J1G3.54" )
				)
				( pin "CB(7)"
					( objectStatus "J1G3.199" )
				)
				( pin "CKE(0)"
					( objectStatus "J1G3.60" )
				)
				( pin "CKE(1)"
					( objectStatus "J1G3.203" )
				)
				( pin "DQ(0)"
					( objectStatus "J1G3.5" )
				)
				( pin "DQ(10)"
					( objectStatus "J1G3.23" )
				)
				( pin "DQ(11)"
					( objectStatus "J1G3.168" )
				)
				( pin "DQ(12)"
					( objectStatus "J1G3.14" )
				)
				( pin "DQ(13)"
					( objectStatus "J1G3.159" )
				)
				( pin "DQ(14)"
					( objectStatus "J1G3.21" )
				)
				( pin "DQ(15)"
					( objectStatus "J1G3.166" )
				)
				( pin "DQ(16)"
					( objectStatus "J1G3.27" )
				)
				( pin "DQ(17)"
					( objectStatus "J1G3.172" )
				)
				( pin "DQ(18)"
					( objectStatus "J1G3.34" )
				)
				( pin "DQ(19)"
					( objectStatus "J1G3.179" )
				)
				( pin "DQ(1)"
					( objectStatus "J1G3.150" )
				)
				( pin "DQ(20)"
					( objectStatus "J1G3.25" )
				)
				( pin "DQ(21)"
					( objectStatus "J1G3.170" )
				)
				( pin "DQ(22)"
					( objectStatus "J1G3.32" )
				)
				( pin "DQ(23)"
					( objectStatus "J1G3.177" )
				)
				( pin "DQ(24)"
					( objectStatus "J1G3.38" )
				)
				( pin "DQ(25)"
					( objectStatus "J1G3.183" )
				)
				( pin "DQ(26)"
					( objectStatus "J1G3.45" )
				)
				( pin "DQ(27)"
					( objectStatus "J1G3.190" )
				)
				( pin "DQ(28)"
					( objectStatus "J1G3.36" )
				)
				( pin "DQ(29)"
					( objectStatus "J1G3.181" )
				)
				( pin "DQ(2)"
					( objectStatus "J1G3.12" )
				)
				( pin "DQ(30)"
					( objectStatus "J1G3.43" )
				)
				( pin "DQ(31)"
					( objectStatus "J1G3.188" )
				)
				( pin "DQ(32)"
					( objectStatus "J1G3.97" )
				)
				( pin "DQ(33)"
					( objectStatus "J1G3.242" )
				)
				( pin "DQ(34)"
					( objectStatus "J1G3.104" )
				)
				( pin "DQ(35)"
					( objectStatus "J1G3.249" )
				)
				( pin "DQ(36)"
					( objectStatus "J1G3.95" )
				)
				( pin "DQ(37)"
					( objectStatus "J1G3.240" )
				)
				( pin "DQ(38)"
					( objectStatus "J1G3.102" )
				)
				( pin "DQ(39)"
					( objectStatus "J1G3.247" )
				)
				( pin "DQ(3)"
					( objectStatus "J1G3.157" )
				)
				( pin "DQ(40)"
					( objectStatus "J1G3.108" )
				)
				( pin "DQ(41)"
					( objectStatus "J1G3.253" )
				)
				( pin "DQ(42)"
					( objectStatus "J1G3.115" )
				)
				( pin "DQ(43)"
					( objectStatus "J1G3.260" )
				)
				( pin "DQ(44)"
					( objectStatus "J1G3.106" )
				)
				( pin "DQ(45)"
					( objectStatus "J1G3.251" )
				)
				( pin "DQ(46)"
					( objectStatus "J1G3.113" )
				)
				( pin "DQ(47)"
					( objectStatus "J1G3.258" )
				)
				( pin "DQ(48)"
					( objectStatus "J1G3.119" )
				)
				( pin "DQ(49)"
					( objectStatus "J1G3.264" )
				)
				( pin "DQ(4)"
					( objectStatus "J1G3.3" )
				)
				( pin "DQ(50)"
					( objectStatus "J1G3.126" )
				)
				( pin "DQ(51)"
					( objectStatus "J1G3.271" )
				)
				( pin "DQ(52)"
					( objectStatus "J1G3.117" )
				)
				( pin "DQ(53)"
					( objectStatus "J1G3.262" )
				)
				( pin "DQ(54)"
					( objectStatus "J1G3.124" )
				)
				( pin "DQ(55)"
					( objectStatus "J1G3.269" )
				)
				( pin "DQ(56)"
					( objectStatus "J1G3.130" )
				)
				( pin "DQ(57)"
					( objectStatus "J1G3.275" )
				)
				( pin "DQ(58)"
					( objectStatus "J1G3.137" )
				)
				( pin "DQ(59)"
					( objectStatus "J1G3.282" )
				)
				( pin "DQ(5)"
					( objectStatus "J1G3.148" )
				)
				( pin "DQ(60)"
					( objectStatus "J1G3.128" )
				)
				( pin "DQ(61)"
					( objectStatus "J1G3.273" )
				)
				( pin "DQ(62)"
					( objectStatus "J1G3.135" )
				)
				( pin "DQ(63)"
					( objectStatus "J1G3.280" )
				)
				( pin "DQ(6)"
					( objectStatus "J1G3.10" )
				)
				( pin "DQ(7)"
					( objectStatus "J1G3.155" )
				)
				( pin "DQ(8)"
					( objectStatus "J1G3.16" )
				)
				( pin "DQ(9)"
					( objectStatus "J1G3.161" )
				)
				( pin "ODT(0)"
					( objectStatus "J1G3.87" )
				)
				( pin "ODT(1)"
					( objectStatus "J1G3.91" )
				)
				( pin "PAR"
					( objectStatus "J1G3.222" )
				)
				( pin "S0_N"
					( objectStatus "J1G3.84" )
				)
				( pin "S1_N"
					( objectStatus "J1G3.89" )
				)
				( pin "S2_N_C(0)"
					( objectStatus "J1G3.93" )
				)
				( pin "S3_N_C(1)"
					( objectStatus "J1G3.237" )
				)
			)
			( gate "@baseboard_fab2_lib.baseboard_fab2(sch_1):page81_i67"
				( objectStatus "F163" )
				( pin "DQS0N"
					( objectStatus "J1G3.152" )
				)
				( pin "DQS0P"
					( objectStatus "J1G3.153" )
				)
				( pin "DQS10N"
					( objectStatus "J1G3.19" )
				)
				( pin "DQS10P"
					( objectStatus "J1G3.18" )
				)
				( pin "DQS11N"
					( objectStatus "J1G3.30" )
				)
				( pin "DQS11P"
					( objectStatus "J1G3.29" )
				)
				( pin "DQS12N"
					( objectStatus "J1G3.41" )
				)
				( pin "DQS12P"
					( objectStatus "J1G3.40" )
				)
				( pin "DQS13N"
					( objectStatus "J1G3.100" )
				)
				( pin "DQS13P"
					( objectStatus "J1G3.99" )
				)
				( pin "DQS14N"
					( objectStatus "J1G3.111" )
				)
				( pin "DQS14P"
					( objectStatus "J1G3.110" )
				)
				( pin "DQS15N"
					( objectStatus "J1G3.122" )
				)
				( pin "DQS15P"
					( objectStatus "J1G3.121" )
				)
				( pin "DQS16N"
					( objectStatus "J1G3.133" )
				)
				( pin "DQS16P"
					( objectStatus "J1G3.132" )
				)
				( pin "DQS17N"
					( objectStatus "J1G3.52" )
				)
				( pin "DQS17P"
					( objectStatus "J1G3.51" )
				)
				( pin "DQS1N"
					( objectStatus "J1G3.163" )
				)
				( pin "DQS1P"
					( objectStatus "J1G3.164" )
				)
				( pin "DQS2N"
					( objectStatus "J1G3.174" )
				)
				( pin "DQS2P"
					( objectStatus "J1G3.175" )
				)
				( pin "DQS3N"
					( objectStatus "J1G3.185" )
				)
				( pin "DQS3P"
					( objectStatus "J1G3.186" )
				)
				( pin "DQS4N"
					( objectStatus "J1G3.244" )
				)
				( pin "DQS4P"
					( objectStatus "J1G3.245" )
				)
				( pin "DQS5N"
					( objectStatus "J1G3.255" )
				)
				( pin "DQS5P"
					( objectStatus "J1G3.256" )
				)
				( pin "DQS6N"
					( objectStatus "J1G3.266" )
				)
				( pin "DQS6P"
					( objectStatus "J1G3.267" )
				)
				( pin "DQS7N"
					( objectStatus "J1G3.277" )
				)
				( pin "DQS7P"
					( objectStatus "J1G3.278" )
				)
				( pin "DQS8N"
					( objectStatus "J1G3.196" )
				)
				( pin "DQS8P"
					( objectStatus "J1G3.197" )
				)
				( pin "DQS9N"
					( objectStatus "J1G3.8" )
				)
				( pin "DQS9P"
					( objectStatus "J1G3.7" )
				)
			)
			( gate "@baseboard_fab2_lib.baseboard_fab2(sch_1):page81_i185"
				( objectStatus "F162" )
			)
			( gate "@baseboard_fab2_lib.baseboard_fab2(sch_1):page81_i169"
				( objectStatus "F161" )
			)
			( gate "@baseboard_fab2_lib.baseboard_fab2(sch_1):page83_i111"
				( objectStatus "F176" )
				( pin "A0"
					( objectStatus "J1B1.79" )
				)
				( pin "A1"
					( objectStatus "J1B1.72" )
				)
				( pin "A10"
					( objectStatus "J1B1.225" )
				)
				( pin "A11"
					( objectStatus "J1B1.210" )
				)
				( pin "A12"
					( objectStatus "J1B1.65" )
				)
				( pin "A13"
					( objectStatus "J1B1.232" )
				)
				( pin "A14_WE_N"
					( objectStatus "J1B1.228" )
				)
				( pin "A15_CAS_N"
					( objectStatus "J1B1.86" )
				)
				( pin "A16_RAS_N"
					( objectStatus "J1B1.82" )
				)
				( pin "A17"
					( objectStatus "J1B1.234" )
				)
				( pin "A2"
					( objectStatus "J1B1.216" )
				)
				( pin "A3"
					( objectStatus "J1B1.71" )
				)
				( pin "A4"
					( objectStatus "J1B1.214" )
				)
				( pin "A5"
					( objectStatus "J1B1.213" )
				)
				( pin "A6"
					( objectStatus "J1B1.69" )
				)
				( pin "A7"
					( objectStatus "J1B1.211" )
				)
				( pin "A8"
					( objectStatus "J1B1.68" )
				)
				( pin "A9"
					( objectStatus "J1B1.66" )
				)
				( pin "ACT_N"
					( objectStatus "J1B1.62" )
				)
				( pin "BA(0)"
					( objectStatus "J1B1.81" )
				)
				( pin "BA(1)"
					( objectStatus "J1B1.224" )
				)
				( pin "BG(0)"
					( objectStatus "J1B1.63" )
				)
				( pin "BG(1)"
					( objectStatus "J1B1.207" )
				)
				( pin "C(2)"
					( objectStatus "J1B1.235" )
				)
				( pin "CB(0)"
					( objectStatus "J1B1.49" )
				)
				( pin "CB(1)"
					( objectStatus "J1B1.194" )
				)
				( pin "CB(2)"
					( objectStatus "J1B1.56" )
				)
				( pin "CB(3)"
					( objectStatus "J1B1.201" )
				)
				( pin "CB(4)"
					( objectStatus "J1B1.47" )
				)
				( pin "CB(5)"
					( objectStatus "J1B1.192" )
				)
				( pin "CB(6)"
					( objectStatus "J1B1.54" )
				)
				( pin "CB(7)"
					( objectStatus "J1B1.199" )
				)
				( pin "CKE(0)"
					( objectStatus "J1B1.60" )
				)
				( pin "CKE(1)"
					( objectStatus "J1B1.203" )
				)
				( pin "DQ(0)"
					( objectStatus "J1B1.5" )
				)
				( pin "DQ(10)"
					( objectStatus "J1B1.23" )
				)
				( pin "DQ(11)"
					( objectStatus "J1B1.168" )
				)
				( pin "DQ(12)"
					( objectStatus "J1B1.14" )
				)
				( pin "DQ(13)"
					( objectStatus "J1B1.159" )
				)
				( pin "DQ(14)"
					( objectStatus "J1B1.21" )
				)
				( pin "DQ(15)"
					( objectStatus "J1B1.166" )
				)
				( pin "DQ(16)"
					( objectStatus "J1B1.27" )
				)
				( pin "DQ(17)"
					( objectStatus "J1B1.172" )
				)
				( pin "DQ(18)"
					( objectStatus "J1B1.34" )
				)
				( pin "DQ(19)"
					( objectStatus "J1B1.179" )
				)
				( pin "DQ(1)"
					( objectStatus "J1B1.150" )
				)
				( pin "DQ(20)"
					( objectStatus "J1B1.25" )
				)
				( pin "DQ(21)"
					( objectStatus "J1B1.170" )
				)
				( pin "DQ(22)"
					( objectStatus "J1B1.32" )
				)
				( pin "DQ(23)"
					( objectStatus "J1B1.177" )
				)
				( pin "DQ(24)"
					( objectStatus "J1B1.38" )
				)
				( pin "DQ(25)"
					( objectStatus "J1B1.183" )
				)
				( pin "DQ(26)"
					( objectStatus "J1B1.45" )
				)
				( pin "DQ(27)"
					( objectStatus "J1B1.190" )
				)
				( pin "DQ(28)"
					( objectStatus "J1B1.36" )
				)
				( pin "DQ(29)"
					( objectStatus "J1B1.181" )
				)
				( pin "DQ(2)"
					( objectStatus "J1B1.12" )
				)
				( pin "DQ(30)"
					( objectStatus "J1B1.43" )
				)
				( pin "DQ(31)"
					( objectStatus "J1B1.188" )
				)
				( pin "DQ(32)"
					( objectStatus "J1B1.97" )
				)
				( pin "DQ(33)"
					( objectStatus "J1B1.242" )
				)
				( pin "DQ(34)"
					( objectStatus "J1B1.104" )
				)
				( pin "DQ(35)"
					( objectStatus "J1B1.249" )
				)
				( pin "DQ(36)"
					( objectStatus "J1B1.95" )
				)
				( pin "DQ(37)"
					( objectStatus "J1B1.240" )
				)
				( pin "DQ(38)"
					( objectStatus "J1B1.102" )
				)
				( pin "DQ(39)"
					( objectStatus "J1B1.247" )
				)
				( pin "DQ(3)"
					( objectStatus "J1B1.157" )
				)
				( pin "DQ(40)"
					( objectStatus "J1B1.108" )
				)
				( pin "DQ(41)"
					( objectStatus "J1B1.253" )
				)
				( pin "DQ(42)"
					( objectStatus "J1B1.115" )
				)
				( pin "DQ(43)"
					( objectStatus "J1B1.260" )
				)
				( pin "DQ(44)"
					( objectStatus "J1B1.106" )
				)
				( pin "DQ(45)"
					( objectStatus "J1B1.251" )
				)
				( pin "DQ(46)"
					( objectStatus "J1B1.113" )
				)
				( pin "DQ(47)"
					( objectStatus "J1B1.258" )
				)
				( pin "DQ(48)"
					( objectStatus "J1B1.119" )
				)
				( pin "DQ(49)"
					( objectStatus "J1B1.264" )
				)
				( pin "DQ(4)"
					( objectStatus "J1B1.3" )
				)
				( pin "DQ(50)"
					( objectStatus "J1B1.126" )
				)
				( pin "DQ(51)"
					( objectStatus "J1B1.271" )
				)
				( pin "DQ(52)"
					( objectStatus "J1B1.117" )
				)
				( pin "DQ(53)"
					( objectStatus "J1B1.262" )
				)
				( pin "DQ(54)"
					( objectStatus "J1B1.124" )
				)
				( pin "DQ(55)"
					( objectStatus "J1B1.269" )
				)
				( pin "DQ(56)"
					( objectStatus "J1B1.130" )
				)
				( pin "DQ(57)"
					( objectStatus "J1B1.275" )
				)
				( pin "DQ(58)"
					( objectStatus "J1B1.137" )
				)
				( pin "DQ(59)"
					( objectStatus "J1B1.282" )
				)
				( pin "DQ(5)"
					( objectStatus "J1B1.148" )
				)
				( pin "DQ(60)"
					( objectStatus "J1B1.128" )
				)
				( pin "DQ(61)"
					( objectStatus "J1B1.273" )
				)
				( pin "DQ(62)"
					( objectStatus "J1B1.135" )
				)
				( pin "DQ(63)"
					( objectStatus "J1B1.280" )
				)
				( pin "DQ(6)"
					( objectStatus "J1B1.10" )
				)
				( pin "DQ(7)"
					( objectStatus "J1B1.155" )
				)
				( pin "DQ(8)"
					( objectStatus "J1B1.16" )
				)
				( pin "DQ(9)"
					( objectStatus "J1B1.161" )
				)
				( pin "ODT(0)"
					( objectStatus "J1B1.87" )
				)
				( pin "ODT(1)"
					( objectStatus "J1B1.91" )
				)
				( pin "PAR"
					( objectStatus "J1B1.222" )
				)
				( pin "S0_N"
					( objectStatus "J1B1.84" )
				)
				( pin "S1_N"
					( objectStatus "J1B1.89" )
				)
				( pin "S2_N_C(0)"
					( objectStatus "J1B1.93" )
				)
				( pin "S3_N_C(1)"
					( objectStatus "J1B1.237" )
				)
			)
			( gate "@baseboard_fab2_lib.baseboard_fab2(sch_1):page83_i66"
				( objectStatus "F175" )
				( pin "DQS0N"
					( objectStatus "J1B1.152" )
				)
				( pin "DQS0P"
					( objectStatus "J1B1.153" )
				)
				( pin "DQS10N"
					( objectStatus "J1B1.19" )
				)
				( pin "DQS10P"
					( objectStatus "J1B1.18" )
				)
				( pin "DQS11N"
					( objectStatus "J1B1.30" )
				)
				( pin "DQS11P"
					( objectStatus "J1B1.29" )
				)
				( pin "DQS12N"
					( objectStatus "J1B1.41" )
				)
				( pin "DQS12P"
					( objectStatus "J1B1.40" )
				)
				( pin "DQS13N"
					( objectStatus "J1B1.100" )
				)
				( pin "DQS13P"
					( objectStatus "J1B1.99" )
				)
				( pin "DQS14N"
					( objectStatus "J1B1.111" )
				)
				( pin "DQS14P"
					( objectStatus "J1B1.110" )
				)
				( pin "DQS15N"
					( objectStatus "J1B1.122" )
				)
				( pin "DQS15P"
					( objectStatus "J1B1.121" )
				)
				( pin "DQS16N"
					( objectStatus "J1B1.133" )
				)
				( pin "DQS16P"
					( objectStatus "J1B1.132" )
				)
				( pin "DQS17N"
					( objectStatus "J1B1.52" )
				)
				( pin "DQS17P"
					( objectStatus "J1B1.51" )
				)
				( pin "DQS1N"
					( objectStatus "J1B1.163" )
				)
				( pin "DQS1P"
					( objectStatus "J1B1.164" )
				)
				( pin "DQS2N"
					( objectStatus "J1B1.174" )
				)
				( pin "DQS2P"
					( objectStatus "J1B1.175" )
				)
				( pin "DQS3N"
					( objectStatus "J1B1.185" )
				)
				( pin "DQS3P"
					( objectStatus "J1B1.186" )
				)
				( pin "DQS4N"
					( objectStatus "J1B1.244" )
				)
				( pin "DQS4P"
					( objectStatus "J1B1.245" )
				)
				( pin "DQS5N"
					( objectStatus "J1B1.255" )
				)
				( pin "DQS5P"
					( objectStatus "J1B1.256" )
				)
				( pin "DQS6N"
					( objectStatus "J1B1.266" )
				)
				( pin "DQS6P"
					( objectStatus "J1B1.267" )
				)
				( pin "DQS7N"
					( objectStatus "J1B1.277" )
				)
				( pin "DQS7P"
					( objectStatus "J1B1.278" )
				)
				( pin "DQS8N"
					( objectStatus "J1B1.196" )
				)
				( pin "DQS8P"
					( objectStatus "J1B1.197" )
				)
				( pin "DQS9N"
					( objectStatus "J1B1.8" )
				)
				( pin "DQS9P"
					( objectStatus "J1B1.7" )
				)
			)
			( gate "@baseboard_fab2_lib.baseboard_fab2(sch_1):page83_i43"
				( objectStatus "F174" )
			)
			( gate "@baseboard_fab2_lib.baseboard_fab2(sch_1):page83_i167"
				( objectStatus "F173" )
			)
			( gate "@baseboard_fab2_lib.baseboard_fab2(sch_1):page85_i111"
				( objectStatus "F180" )
				( pin "A0"
					( objectStatus "J1A2.79" )
				)
				( pin "A1"
					( objectStatus "J1A2.72" )
				)
				( pin "A10"
					( objectStatus "J1A2.225" )
				)
				( pin "A11"
					( objectStatus "J1A2.210" )
				)
				( pin "A12"
					( objectStatus "J1A2.65" )
				)
				( pin "A13"
					( objectStatus "J1A2.232" )
				)
				( pin "A14_WE_N"
					( objectStatus "J1A2.228" )
				)
				( pin "A15_CAS_N"
					( objectStatus "J1A2.86" )
				)
				( pin "A16_RAS_N"
					( objectStatus "J1A2.82" )
				)
				( pin "A17"
					( objectStatus "J1A2.234" )
				)
				( pin "A2"
					( objectStatus "J1A2.216" )
				)
				( pin "A3"
					( objectStatus "J1A2.71" )
				)
				( pin "A4"
					( objectStatus "J1A2.214" )
				)
				( pin "A5"
					( objectStatus "J1A2.213" )
				)
				( pin "A6"
					( objectStatus "J1A2.69" )
				)
				( pin "A7"
					( objectStatus "J1A2.211" )
				)
				( pin "A8"
					( objectStatus "J1A2.68" )
				)
				( pin "A9"
					( objectStatus "J1A2.66" )
				)
				( pin "ACT_N"
					( objectStatus "J1A2.62" )
				)
				( pin "BA(0)"
					( objectStatus "J1A2.81" )
				)
				( pin "BA(1)"
					( objectStatus "J1A2.224" )
				)
				( pin "BG(0)"
					( objectStatus "J1A2.63" )
				)
				( pin "BG(1)"
					( objectStatus "J1A2.207" )
				)
				( pin "C(2)"
					( objectStatus "J1A2.235" )
				)
				( pin "CB(0)"
					( objectStatus "J1A2.49" )
				)
				( pin "CB(1)"
					( objectStatus "J1A2.194" )
				)
				( pin "CB(2)"
					( objectStatus "J1A2.56" )
				)
				( pin "CB(3)"
					( objectStatus "J1A2.201" )
				)
				( pin "CB(4)"
					( objectStatus "J1A2.47" )
				)
				( pin "CB(5)"
					( objectStatus "J1A2.192" )
				)
				( pin "CB(6)"
					( objectStatus "J1A2.54" )
				)
				( pin "CB(7)"
					( objectStatus "J1A2.199" )
				)
				( pin "CKE(0)"
					( objectStatus "J1A2.60" )
				)
				( pin "CKE(1)"
					( objectStatus "J1A2.203" )
				)
				( pin "DQ(0)"
					( objectStatus "J1A2.5" )
				)
				( pin "DQ(10)"
					( objectStatus "J1A2.23" )
				)
				( pin "DQ(11)"
					( objectStatus "J1A2.168" )
				)
				( pin "DQ(12)"
					( objectStatus "J1A2.14" )
				)
				( pin "DQ(13)"
					( objectStatus "J1A2.159" )
				)
				( pin "DQ(14)"
					( objectStatus "J1A2.21" )
				)
				( pin "DQ(15)"
					( objectStatus "J1A2.166" )
				)
				( pin "DQ(16)"
					( objectStatus "J1A2.27" )
				)
				( pin "DQ(17)"
					( objectStatus "J1A2.172" )
				)
				( pin "DQ(18)"
					( objectStatus "J1A2.34" )
				)
				( pin "DQ(19)"
					( objectStatus "J1A2.179" )
				)
				( pin "DQ(1)"
					( objectStatus "J1A2.150" )
				)
				( pin "DQ(20)"
					( objectStatus "J1A2.25" )
				)
				( pin "DQ(21)"
					( objectStatus "J1A2.170" )
				)
				( pin "DQ(22)"
					( objectStatus "J1A2.32" )
				)
				( pin "DQ(23)"
					( objectStatus "J1A2.177" )
				)
				( pin "DQ(24)"
					( objectStatus "J1A2.38" )
				)
				( pin "DQ(25)"
					( objectStatus "J1A2.183" )
				)
				( pin "DQ(26)"
					( objectStatus "J1A2.45" )
				)
				( pin "DQ(27)"
					( objectStatus "J1A2.190" )
				)
				( pin "DQ(28)"
					( objectStatus "J1A2.36" )
				)
				( pin "DQ(29)"
					( objectStatus "J1A2.181" )
				)
				( pin "DQ(2)"
					( objectStatus "J1A2.12" )
				)
				( pin "DQ(30)"
					( objectStatus "J1A2.43" )
				)
				( pin "DQ(31)"
					( objectStatus "J1A2.188" )
				)
				( pin "DQ(32)"
					( objectStatus "J1A2.97" )
				)
				( pin "DQ(33)"
					( objectStatus "J1A2.242" )
				)
				( pin "DQ(34)"
					( objectStatus "J1A2.104" )
				)
				( pin "DQ(35)"
					( objectStatus "J1A2.249" )
				)
				( pin "DQ(36)"
					( objectStatus "J1A2.95" )
				)
				( pin "DQ(37)"
					( objectStatus "J1A2.240" )
				)
				( pin "DQ(38)"
					( objectStatus "J1A2.102" )
				)
				( pin "DQ(39)"
					( objectStatus "J1A2.247" )
				)
				( pin "DQ(3)"
					( objectStatus "J1A2.157" )
				)
				( pin "DQ(40)"
					( objectStatus "J1A2.108" )
				)
				( pin "DQ(41)"
					( objectStatus "J1A2.253" )
				)
				( pin "DQ(42)"
					( objectStatus "J1A2.115" )
				)
				( pin "DQ(43)"
					( objectStatus "J1A2.260" )
				)
				( pin "DQ(44)"
					( objectStatus "J1A2.106" )
				)
				( pin "DQ(45)"
					( objectStatus "J1A2.251" )
				)
				( pin "DQ(46)"
					( objectStatus "J1A2.113" )
				)
				( pin "DQ(47)"
					( objectStatus "J1A2.258" )
				)
				( pin "DQ(48)"
					( objectStatus "J1A2.119" )
				)
				( pin "DQ(49)"
					( objectStatus "J1A2.264" )
				)
				( pin "DQ(4)"
					( objectStatus "J1A2.3" )
				)
				( pin "DQ(50)"
					( objectStatus "J1A2.126" )
				)
				( pin "DQ(51)"
					( objectStatus "J1A2.271" )
				)
				( pin "DQ(52)"
					( objectStatus "J1A2.117" )
				)
				( pin "DQ(53)"
					( objectStatus "J1A2.262" )
				)
				( pin "DQ(54)"
					( objectStatus "J1A2.124" )
				)
				( pin "DQ(55)"
					( objectStatus "J1A2.269" )
				)
				( pin "DQ(56)"
					( objectStatus "J1A2.130" )
				)
				( pin "DQ(57)"
					( objectStatus "J1A2.275" )
				)
				( pin "DQ(58)"
					( objectStatus "J1A2.137" )
				)
				( pin "DQ(59)"
					( objectStatus "J1A2.282" )
				)
				( pin "DQ(5)"
					( objectStatus "J1A2.148" )
				)
				( pin "DQ(60)"
					( objectStatus "J1A2.128" )
				)
				( pin "DQ(61)"
					( objectStatus "J1A2.273" )
				)
				( pin "DQ(62)"
					( objectStatus "J1A2.135" )
				)
				( pin "DQ(63)"
					( objectStatus "J1A2.280" )
				)
				( pin "DQ(6)"
					( objectStatus "J1A2.10" )
				)
				( pin "DQ(7)"
					( objectStatus "J1A2.155" )
				)
				( pin "DQ(8)"
					( objectStatus "J1A2.16" )
				)
				( pin "DQ(9)"
					( objectStatus "J1A2.161" )
				)
				( pin "ODT(0)"
					( objectStatus "J1A2.87" )
				)
				( pin "ODT(1)"
					( objectStatus "J1A2.91" )
				)
				( pin "PAR"
					( objectStatus "J1A2.222" )
				)
				( pin "S0_N"
					( objectStatus "J1A2.84" )
				)
				( pin "S1_N"
					( objectStatus "J1A2.89" )
				)
				( pin "S2_N_C(0)"
					( objectStatus "J1A2.93" )
				)
				( pin "S3_N_C(1)"
					( objectStatus "J1A2.237" )
				)
			)
			( gate "@baseboard_fab2_lib.baseboard_fab2(sch_1):page85_i66"
				( objectStatus "F179" )
				( pin "DQS0N"
					( objectStatus "J1A2.152" )
				)
				( pin "DQS0P"
					( objectStatus "J1A2.153" )
				)
				( pin "DQS10N"
					( objectStatus "J1A2.19" )
				)
				( pin "DQS10P"
					( objectStatus "J1A2.18" )
				)
				( pin "DQS11N"
					( objectStatus "J1A2.30" )
				)
				( pin "DQS11P"
					( objectStatus "J1A2.29" )
				)
				( pin "DQS12N"
					( objectStatus "J1A2.41" )
				)
				( pin "DQS12P"
					( objectStatus "J1A2.40" )
				)
				( pin "DQS13N"
					( objectStatus "J1A2.100" )
				)
				( pin "DQS13P"
					( objectStatus "J1A2.99" )
				)
				( pin "DQS14N"
					( objectStatus "J1A2.111" )
				)
				( pin "DQS14P"
					( objectStatus "J1A2.110" )
				)
				( pin "DQS15N"
					( objectStatus "J1A2.122" )
				)
				( pin "DQS15P"
					( objectStatus "J1A2.121" )
				)
				( pin "DQS16N"
					( objectStatus "J1A2.133" )
				)
				( pin "DQS16P"
					( objectStatus "J1A2.132" )
				)
				( pin "DQS17N"
					( objectStatus "J1A2.52" )
				)
				( pin "DQS17P"
					( objectStatus "J1A2.51" )
				)
				( pin "DQS1N"
					( objectStatus "J1A2.163" )
				)
				( pin "DQS1P"
					( objectStatus "J1A2.164" )
				)
				( pin "DQS2N"
					( objectStatus "J1A2.174" )
				)
				( pin "DQS2P"
					( objectStatus "J1A2.175" )
				)
				( pin "DQS3N"
					( objectStatus "J1A2.185" )
				)
				( pin "DQS3P"
					( objectStatus "J1A2.186" )
				)
				( pin "DQS4N"
					( objectStatus "J1A2.244" )
				)
				( pin "DQS4P"
					( objectStatus "J1A2.245" )
				)
				( pin "DQS5N"
					( objectStatus "J1A2.255" )
				)
				( pin "DQS5P"
					( objectStatus "J1A2.256" )
				)
				( pin "DQS6N"
					( objectStatus "J1A2.266" )
				)
				( pin "DQS6P"
					( objectStatus "J1A2.267" )
				)
				( pin "DQS7N"
					( objectStatus "J1A2.277" )
				)
				( pin "DQS7P"
					( objectStatus "J1A2.278" )
				)
				( pin "DQS8N"
					( objectStatus "J1A2.196" )
				)
				( pin "DQS8P"
					( objectStatus "J1A2.197" )
				)
				( pin "DQS9N"
					( objectStatus "J1A2.8" )
				)
				( pin "DQS9P"
					( objectStatus "J1A2.7" )
				)
			)
			( gate "@baseboard_fab2_lib.baseboard_fab2(sch_1):page85_i43"
				( objectStatus "F178" )
			)
			( gate "@baseboard_fab2_lib.baseboard_fab2(sch_1):page85_i172"
				( objectStatus "F177" )
			)
			( gate "@baseboard_fab2_lib.baseboard_fab2(sch_1):page87_i186"
				( objectStatus "F184" )
				( pin "A0"
					( objectStatus "J1A1.79" )
				)
				( pin "A1"
					( objectStatus "J1A1.72" )
				)
				( pin "A10"
					( objectStatus "J1A1.225" )
				)
				( pin "A11"
					( objectStatus "J1A1.210" )
				)
				( pin "A12"
					( objectStatus "J1A1.65" )
				)
				( pin "A13"
					( objectStatus "J1A1.232" )
				)
				( pin "A14_WE_N"
					( objectStatus "J1A1.228" )
				)
				( pin "A15_CAS_N"
					( objectStatus "J1A1.86" )
				)
				( pin "A16_RAS_N"
					( objectStatus "J1A1.82" )
				)
				( pin "A17"
					( objectStatus "J1A1.234" )
				)
				( pin "A2"
					( objectStatus "J1A1.216" )
				)
				( pin "A3"
					( objectStatus "J1A1.71" )
				)
				( pin "A4"
					( objectStatus "J1A1.214" )
				)
				( pin "A5"
					( objectStatus "J1A1.213" )
				)
				( pin "A6"
					( objectStatus "J1A1.69" )
				)
				( pin "A7"
					( objectStatus "J1A1.211" )
				)
				( pin "A8"
					( objectStatus "J1A1.68" )
				)
				( pin "A9"
					( objectStatus "J1A1.66" )
				)
				( pin "ACT_N"
					( objectStatus "J1A1.62" )
				)
				( pin "BA(0)"
					( objectStatus "J1A1.81" )
				)
				( pin "BA(1)"
					( objectStatus "J1A1.224" )
				)
				( pin "BG(0)"
					( objectStatus "J1A1.63" )
				)
				( pin "BG(1)"
					( objectStatus "J1A1.207" )
				)
				( pin "C(2)"
					( objectStatus "J1A1.235" )
				)
				( pin "CB(0)"
					( objectStatus "J1A1.49" )
				)
				( pin "CB(1)"
					( objectStatus "J1A1.194" )
				)
				( pin "CB(2)"
					( objectStatus "J1A1.56" )
				)
				( pin "CB(3)"
					( objectStatus "J1A1.201" )
				)
				( pin "CB(4)"
					( objectStatus "J1A1.47" )
				)
				( pin "CB(5)"
					( objectStatus "J1A1.192" )
				)
				( pin "CB(6)"
					( objectStatus "J1A1.54" )
				)
				( pin "CB(7)"
					( objectStatus "J1A1.199" )
				)
				( pin "CKE(0)"
					( objectStatus "J1A1.60" )
				)
				( pin "CKE(1)"
					( objectStatus "J1A1.203" )
				)
				( pin "DQ(0)"
					( objectStatus "J1A1.5" )
				)
				( pin "DQ(10)"
					( objectStatus "J1A1.23" )
				)
				( pin "DQ(11)"
					( objectStatus "J1A1.168" )
				)
				( pin "DQ(12)"
					( objectStatus "J1A1.14" )
				)
				( pin "DQ(13)"
					( objectStatus "J1A1.159" )
				)
				( pin "DQ(14)"
					( objectStatus "J1A1.21" )
				)
				( pin "DQ(15)"
					( objectStatus "J1A1.166" )
				)
				( pin "DQ(16)"
					( objectStatus "J1A1.27" )
				)
				( pin "DQ(17)"
					( objectStatus "J1A1.172" )
				)
				( pin "DQ(18)"
					( objectStatus "J1A1.34" )
				)
				( pin "DQ(19)"
					( objectStatus "J1A1.179" )
				)
				( pin "DQ(1)"
					( objectStatus "J1A1.150" )
				)
				( pin "DQ(20)"
					( objectStatus "J1A1.25" )
				)
				( pin "DQ(21)"
					( objectStatus "J1A1.170" )
				)
				( pin "DQ(22)"
					( objectStatus "J1A1.32" )
				)
				( pin "DQ(23)"
					( objectStatus "J1A1.177" )
				)
				( pin "DQ(24)"
					( objectStatus "J1A1.38" )
				)
				( pin "DQ(25)"
					( objectStatus "J1A1.183" )
				)
				( pin "DQ(26)"
					( objectStatus "J1A1.45" )
				)
				( pin "DQ(27)"
					( objectStatus "J1A1.190" )
				)
				( pin "DQ(28)"
					( objectStatus "J1A1.36" )
				)
				( pin "DQ(29)"
					( objectStatus "J1A1.181" )
				)
				( pin "DQ(2)"
					( objectStatus "J1A1.12" )
				)
				( pin "DQ(30)"
					( objectStatus "J1A1.43" )
				)
				( pin "DQ(31)"
					( objectStatus "J1A1.188" )
				)
				( pin "DQ(32)"
					( objectStatus "J1A1.97" )
				)
				( pin "DQ(33)"
					( objectStatus "J1A1.242" )
				)
				( pin "DQ(34)"
					( objectStatus "J1A1.104" )
				)
				( pin "DQ(35)"
					( objectStatus "J1A1.249" )
				)
				( pin "DQ(36)"
					( objectStatus "J1A1.95" )
				)
				( pin "DQ(37)"
					( objectStatus "J1A1.240" )
				)
				( pin "DQ(38)"
					( objectStatus "J1A1.102" )
				)
				( pin "DQ(39)"
					( objectStatus "J1A1.247" )
				)
				( pin "DQ(3)"
					( objectStatus "J1A1.157" )
				)
				( pin "DQ(40)"
					( objectStatus "J1A1.108" )
				)
				( pin "DQ(41)"
					( objectStatus "J1A1.253" )
				)
				( pin "DQ(42)"
					( objectStatus "J1A1.115" )
				)
				( pin "DQ(43)"
					( objectStatus "J1A1.260" )
				)
				( pin "DQ(44)"
					( objectStatus "J1A1.106" )
				)
				( pin "DQ(45)"
					( objectStatus "J1A1.251" )
				)
				( pin "DQ(46)"
					( objectStatus "J1A1.113" )
				)
				( pin "DQ(47)"
					( objectStatus "J1A1.258" )
				)
				( pin "DQ(48)"
					( objectStatus "J1A1.119" )
				)
				( pin "DQ(49)"
					( objectStatus "J1A1.264" )
				)
				( pin "DQ(4)"
					( objectStatus "J1A1.3" )
				)
				( pin "DQ(50)"
					( objectStatus "J1A1.126" )
				)
				( pin "DQ(51)"
					( objectStatus "J1A1.271" )
				)
				( pin "DQ(52)"
					( objectStatus "J1A1.117" )
				)
				( pin "DQ(53)"
					( objectStatus "J1A1.262" )
				)
				( pin "DQ(54)"
					( objectStatus "J1A1.124" )
				)
				( pin "DQ(55)"
					( objectStatus "J1A1.269" )
				)
				( pin "DQ(56)"
					( objectStatus "J1A1.130" )
				)
				( pin "DQ(57)"
					( objectStatus "J1A1.275" )
				)
				( pin "DQ(58)"
					( objectStatus "J1A1.137" )
				)
				( pin "DQ(59)"
					( objectStatus "J1A1.282" )
				)
				( pin "DQ(5)"
					( objectStatus "J1A1.148" )
				)
				( pin "DQ(60)"
					( objectStatus "J1A1.128" )
				)
				( pin "DQ(61)"
					( objectStatus "J1A1.273" )
				)
				( pin "DQ(62)"
					( objectStatus "J1A1.135" )
				)
				( pin "DQ(63)"
					( objectStatus "J1A1.280" )
				)
				( pin "DQ(6)"
					( objectStatus "J1A1.10" )
				)
				( pin "DQ(7)"
					( objectStatus "J1A1.155" )
				)
				( pin "DQ(8)"
					( objectStatus "J1A1.16" )
				)
				( pin "DQ(9)"
					( objectStatus "J1A1.161" )
				)
				( pin "ODT(0)"
					( objectStatus "J1A1.87" )
				)
				( pin "ODT(1)"
					( objectStatus "J1A1.91" )
				)
				( pin "PAR"
					( objectStatus "J1A1.222" )
				)
				( pin "S0_N"
					( objectStatus "J1A1.84" )
				)
				( pin "S1_N"
					( objectStatus "J1A1.89" )
				)
				( pin "S2_N_C(0)"
					( objectStatus "J1A1.93" )
				)
				( pin "S3_N_C(1)"
					( objectStatus "J1A1.237" )
				)
				( pin "SCL"
					( objectStatus "J1A1.141" )
				)
				( pin "SDA"
					( objectStatus "J1A1.285" )
				)
			)
			( gate "@baseboard_fab2_lib.baseboard_fab2(sch_1):page87_i187"
				( objectStatus "F183" )
				( pin "DQS0N"
					( objectStatus "J1A1.152" )
				)
				( pin "DQS0P"
					( objectStatus "J1A1.153" )
				)
				( pin "DQS10N"
					( objectStatus "J1A1.19" )
				)
				( pin "DQS10P"
					( objectStatus "J1A1.18" )
				)
				( pin "DQS11N"
					( objectStatus "J1A1.30" )
				)
				( pin "DQS11P"
					( objectStatus "J1A1.29" )
				)
				( pin "DQS12N"
					( objectStatus "J1A1.41" )
				)
				( pin "DQS12P"
					( objectStatus "J1A1.40" )
				)
				( pin "DQS13N"
					( objectStatus "J1A1.100" )
				)
				( pin "DQS13P"
					( objectStatus "J1A1.99" )
				)
				( pin "DQS14N"
					( objectStatus "J1A1.111" )
				)
				( pin "DQS14P"
					( objectStatus "J1A1.110" )
				)
				( pin "DQS15N"
					( objectStatus "J1A1.122" )
				)
				( pin "DQS15P"
					( objectStatus "J1A1.121" )
				)
				( pin "DQS16N"
					( objectStatus "J1A1.133" )
				)
				( pin "DQS16P"
					( objectStatus "J1A1.132" )
				)
				( pin "DQS17N"
					( objectStatus "J1A1.52" )
				)
				( pin "DQS17P"
					( objectStatus "J1A1.51" )
				)
				( pin "DQS1N"
					( objectStatus "J1A1.163" )
				)
				( pin "DQS1P"
					( objectStatus "J1A1.164" )
				)
				( pin "DQS2N"
					( objectStatus "J1A1.174" )
				)
				( pin "DQS2P"
					( objectStatus "J1A1.175" )
				)
				( pin "DQS3N"
					( objectStatus "J1A1.185" )
				)
				( pin "DQS3P"
					( objectStatus "J1A1.186" )
				)
				( pin "DQS4N"
					( objectStatus "J1A1.244" )
				)
				( pin "DQS4P"
					( objectStatus "J1A1.245" )
				)
				( pin "DQS5N"
					( objectStatus "J1A1.255" )
				)
				( pin "DQS5P"
					( objectStatus "J1A1.256" )
				)
				( pin "DQS6N"
					( objectStatus "J1A1.266" )
				)
				( pin "DQS6P"
					( objectStatus "J1A1.267" )
				)
				( pin "DQS7N"
					( objectStatus "J1A1.277" )
				)
				( pin "DQS7P"
					( objectStatus "J1A1.278" )
				)
				( pin "DQS8N"
					( objectStatus "J1A1.196" )
				)
				( pin "DQS8P"
					( objectStatus "J1A1.197" )
				)
				( pin "DQS9N"
					( objectStatus "J1A1.8" )
				)
				( pin "DQS9P"
					( objectStatus "J1A1.7" )
				)
			)
			( gate "@baseboard_fab2_lib.baseboard_fab2(sch_1):page87_i185"
				( objectStatus "F182" )
			)
			( gate "@baseboard_fab2_lib.baseboard_fab2(sch_1):page87_i169"
				( objectStatus "F181" )
			)
			( gate "@baseboard_fab2_lib.baseboard_fab2(sch_1):page138_i159"
				( objectStatus "F912" )
			)
			( gate "@baseboard_fab2_lib.baseboard_fab2(sch_1):page138_i158"
				( objectStatus "F913" )
				( pin "A"
					( objectStatus "R2U8.1" )
				)
			)
			( gate "@baseboard_fab2_lib.baseboard_fab2(sch_1):page108_i320"
				( objectStatus "F911" )
				( pin "B"
					( objectStatus "R2U35.2" )
				)
			)
			( gate "@baseboard_fab2_lib.baseboard_fab2(sch_1):page108_i340"
				( objectStatus "F910" )
				( pin "B"
					( objectStatus "R2U36.2" )
				)
			)
			( gate "@baseboard_fab2_lib.baseboard_fab2(sch_1):page44_i13"
				( objectStatus "F220" )
				( pin "A0"
					( objectStatus "J6T1.79" )
				)
				( pin "A1"
					( objectStatus "J6T1.72" )
				)
				( pin "A10"
					( objectStatus "J6T1.225" )
				)
				( pin "A11"
					( objectStatus "J6T1.210" )
				)
				( pin "A12"
					( objectStatus "J6T1.65" )
				)
				( pin "A13"
					( objectStatus "J6T1.232" )
				)
				( pin "A14_WE_N"
					( objectStatus "J6T1.228" )
				)
				( pin "A15_CAS_N"
					( objectStatus "J6T1.86" )
				)
				( pin "A16_RAS_N"
					( objectStatus "J6T1.82" )
				)
				( pin "A17"
					( objectStatus "J6T1.234" )
				)
				( pin "A2"
					( objectStatus "J6T1.216" )
				)
				( pin "A3"
					( objectStatus "J6T1.71" )
				)
				( pin "A4"
					( objectStatus "J6T1.214" )
				)
				( pin "A5"
					( objectStatus "J6T1.213" )
				)
				( pin "A6"
					( objectStatus "J6T1.69" )
				)
				( pin "A7"
					( objectStatus "J6T1.211" )
				)
				( pin "A8"
					( objectStatus "J6T1.68" )
				)
				( pin "A9"
					( objectStatus "J6T1.66" )
				)
				( pin "ACT_N"
					( objectStatus "J6T1.62" )
				)
				( pin "BA(0)"
					( objectStatus "J6T1.81" )
				)
				( pin "BA(1)"
					( objectStatus "J6T1.224" )
				)
				( pin "BG(0)"
					( objectStatus "J6T1.63" )
				)
				( pin "BG(1)"
					( objectStatus "J6T1.207" )
				)
				( pin "C(2)"
					( objectStatus "J6T1.235" )
				)
				( pin "CB(0)"
					( objectStatus "J6T1.49" )
				)
				( pin "CB(1)"
					( objectStatus "J6T1.194" )
				)
				( pin "CB(2)"
					( objectStatus "J6T1.56" )
				)
				( pin "CB(3)"
					( objectStatus "J6T1.201" )
				)
				( pin "CB(4)"
					( objectStatus "J6T1.47" )
				)
				( pin "CB(5)"
					( objectStatus "J6T1.192" )
				)
				( pin "CB(6)"
					( objectStatus "J6T1.54" )
				)
				( pin "CB(7)"
					( objectStatus "J6T1.199" )
				)
				( pin "CKE(0)"
					( objectStatus "J6T1.60" )
				)
				( pin "CKE(1)"
					( objectStatus "J6T1.203" )
				)
				( pin "DQ(0)"
					( objectStatus "J6T1.5" )
				)
				( pin "DQ(10)"
					( objectStatus "J6T1.23" )
				)
				( pin "DQ(11)"
					( objectStatus "J6T1.168" )
				)
				( pin "DQ(12)"
					( objectStatus "J6T1.14" )
				)
				( pin "DQ(13)"
					( objectStatus "J6T1.159" )
				)
				( pin "DQ(14)"
					( objectStatus "J6T1.21" )
				)
				( pin "DQ(15)"
					( objectStatus "J6T1.166" )
				)
				( pin "DQ(16)"
					( objectStatus "J6T1.27" )
				)
				( pin "DQ(17)"
					( objectStatus "J6T1.172" )
				)
				( pin "DQ(18)"
					( objectStatus "J6T1.34" )
				)
				( pin "DQ(19)"
					( objectStatus "J6T1.179" )
				)
				( pin "DQ(1)"
					( objectStatus "J6T1.150" )
				)
				( pin "DQ(20)"
					( objectStatus "J6T1.25" )
				)
				( pin "DQ(21)"
					( objectStatus "J6T1.170" )
				)
				( pin "DQ(22)"
					( objectStatus "J6T1.32" )
				)
				( pin "DQ(23)"
					( objectStatus "J6T1.177" )
				)
				( pin "DQ(24)"
					( objectStatus "J6T1.38" )
				)
				( pin "DQ(25)"
					( objectStatus "J6T1.183" )
				)
				( pin "DQ(26)"
					( objectStatus "J6T1.45" )
				)
				( pin "DQ(27)"
					( objectStatus "J6T1.190" )
				)
				( pin "DQ(28)"
					( objectStatus "J6T1.36" )
				)
				( pin "DQ(29)"
					( objectStatus "J6T1.181" )
				)
				( pin "DQ(2)"
					( objectStatus "J6T1.12" )
				)
				( pin "DQ(30)"
					( objectStatus "J6T1.43" )
				)
				( pin "DQ(31)"
					( objectStatus "J6T1.188" )
				)
				( pin "DQ(32)"
					( objectStatus "J6T1.97" )
				)
				( pin "DQ(33)"
					( objectStatus "J6T1.242" )
				)
				( pin "DQ(34)"
					( objectStatus "J6T1.104" )
				)
				( pin "DQ(35)"
					( objectStatus "J6T1.249" )
				)
				( pin "DQ(36)"
					( objectStatus "J6T1.95" )
				)
				( pin "DQ(37)"
					( objectStatus "J6T1.240" )
				)
				( pin "DQ(38)"
					( objectStatus "J6T1.102" )
				)
				( pin "DQ(39)"
					( objectStatus "J6T1.247" )
				)
				( pin "DQ(3)"
					( objectStatus "J6T1.157" )
				)
				( pin "DQ(40)"
					( objectStatus "J6T1.108" )
				)
				( pin "DQ(41)"
					( objectStatus "J6T1.253" )
				)
				( pin "DQ(42)"
					( objectStatus "J6T1.115" )
				)
				( pin "DQ(43)"
					( objectStatus "J6T1.260" )
				)
				( pin "DQ(44)"
					( objectStatus "J6T1.106" )
				)
				( pin "DQ(45)"
					( objectStatus "J6T1.251" )
				)
				( pin "DQ(46)"
					( objectStatus "J6T1.113" )
				)
				( pin "DQ(47)"
					( objectStatus "J6T1.258" )
				)
				( pin "DQ(48)"
					( objectStatus "J6T1.119" )
				)
				( pin "DQ(49)"
					( objectStatus "J6T1.264" )
				)
				( pin "DQ(4)"
					( objectStatus "J6T1.3" )
				)
				( pin "DQ(50)"
					( objectStatus "J6T1.126" )
				)
				( pin "DQ(51)"
					( objectStatus "J6T1.271" )
				)
				( pin "DQ(52)"
					( objectStatus "J6T1.117" )
				)
				( pin "DQ(53)"
					( objectStatus "J6T1.262" )
				)
				( pin "DQ(54)"
					( objectStatus "J6T1.124" )
				)
				( pin "DQ(55)"
					( objectStatus "J6T1.269" )
				)
				( pin "DQ(56)"
					( objectStatus "J6T1.130" )
				)
				( pin "DQ(57)"
					( objectStatus "J6T1.275" )
				)
				( pin "DQ(58)"
					( objectStatus "J6T1.137" )
				)
				( pin "DQ(59)"
					( objectStatus "J6T1.282" )
				)
				( pin "DQ(5)"
					( objectStatus "J6T1.148" )
				)
				( pin "DQ(60)"
					( objectStatus "J6T1.128" )
				)
				( pin "DQ(61)"
					( objectStatus "J6T1.273" )
				)
				( pin "DQ(62)"
					( objectStatus "J6T1.135" )
				)
				( pin "DQ(63)"
					( objectStatus "J6T1.280" )
				)
				( pin "DQ(6)"
					( objectStatus "J6T1.10" )
				)
				( pin "DQ(7)"
					( objectStatus "J6T1.155" )
				)
				( pin "DQ(8)"
					( objectStatus "J6T1.16" )
				)
				( pin "DQ(9)"
					( objectStatus "J6T1.161" )
				)
				( pin "ODT(0)"
					( objectStatus "J6T1.87" )
				)
				( pin "ODT(1)"
					( objectStatus "J6T1.91" )
				)
				( pin "PAR"
					( objectStatus "J6T1.222" )
				)
				( pin "S0_N"
					( objectStatus "J6T1.84" )
				)
				( pin "S1_N"
					( objectStatus "J6T1.89" )
				)
				( pin "S2_N_C(0)"
					( objectStatus "J6T1.93" )
				)
				( pin "S3_N_C(1)"
					( objectStatus "J6T1.237" )
				)
			)
			( gate "@baseboard_fab2_lib.baseboard_fab2(sch_1):page44_i120"
				( objectStatus "F219" )
				( pin "DQS0N"
					( objectStatus "J6T1.152" )
				)
				( pin "DQS0P"
					( objectStatus "J6T1.153" )
				)
				( pin "DQS10N"
					( objectStatus "J6T1.19" )
				)
				( pin "DQS10P"
					( objectStatus "J6T1.18" )
				)
				( pin "DQS11N"
					( objectStatus "J6T1.30" )
				)
				( pin "DQS11P"
					( objectStatus "J6T1.29" )
				)
				( pin "DQS12N"
					( objectStatus "J6T1.41" )
				)
				( pin "DQS12P"
					( objectStatus "J6T1.40" )
				)
				( pin "DQS13N"
					( objectStatus "J6T1.100" )
				)
				( pin "DQS13P"
					( objectStatus "J6T1.99" )
				)
				( pin "DQS14N"
					( objectStatus "J6T1.111" )
				)
				( pin "DQS14P"
					( objectStatus "J6T1.110" )
				)
				( pin "DQS15N"
					( objectStatus "J6T1.122" )
				)
				( pin "DQS15P"
					( objectStatus "J6T1.121" )
				)
				( pin "DQS16N"
					( objectStatus "J6T1.133" )
				)
				( pin "DQS16P"
					( objectStatus "J6T1.132" )
				)
				( pin "DQS17N"
					( objectStatus "J6T1.52" )
				)
				( pin "DQS17P"
					( objectStatus "J6T1.51" )
				)
				( pin "DQS1N"
					( objectStatus "J6T1.163" )
				)
				( pin "DQS1P"
					( objectStatus "J6T1.164" )
				)
				( pin "DQS2N"
					( objectStatus "J6T1.174" )
				)
				( pin "DQS2P"
					( objectStatus "J6T1.175" )
				)
				( pin "DQS3N"
					( objectStatus "J6T1.185" )
				)
				( pin "DQS3P"
					( objectStatus "J6T1.186" )
				)
				( pin "DQS4N"
					( objectStatus "J6T1.244" )
				)
				( pin "DQS4P"
					( objectStatus "J6T1.245" )
				)
				( pin "DQS5N"
					( objectStatus "J6T1.255" )
				)
				( pin "DQS5P"
					( objectStatus "J6T1.256" )
				)
				( pin "DQS6N"
					( objectStatus "J6T1.266" )
				)
				( pin "DQS6P"
					( objectStatus "J6T1.267" )
				)
				( pin "DQS7N"
					( objectStatus "J6T1.277" )
				)
				( pin "DQS7P"
					( objectStatus "J6T1.278" )
				)
				( pin "DQS8N"
					( objectStatus "J6T1.196" )
				)
				( pin "DQS8P"
					( objectStatus "J6T1.197" )
				)
				( pin "DQS9N"
					( objectStatus "J6T1.8" )
				)
				( pin "DQS9P"
					( objectStatus "J6T1.7" )
				)
			)
			( gate "@baseboard_fab2_lib.baseboard_fab2(sch_1):page44_i139"
				( objectStatus "F218" )
			)
			( gate "@baseboard_fab2_lib.baseboard_fab2(sch_1):page44_i75"
				( objectStatus "F217" )
			)
			( gate "@baseboard_fab2_lib.baseboard_fab2(sch_1):page46_i14"
				( objectStatus "F216" )
				( pin "A0"
					( objectStatus "J6U1.79" )
				)
				( pin "A1"
					( objectStatus "J6U1.72" )
				)
				( pin "A10"
					( objectStatus "J6U1.225" )
				)
				( pin "A11"
					( objectStatus "J6U1.210" )
				)
				( pin "A12"
					( objectStatus "J6U1.65" )
				)
				( pin "A13"
					( objectStatus "J6U1.232" )
				)
				( pin "A14_WE_N"
					( objectStatus "J6U1.228" )
				)
				( pin "A15_CAS_N"
					( objectStatus "J6U1.86" )
				)
				( pin "A16_RAS_N"
					( objectStatus "J6U1.82" )
				)
				( pin "A17"
					( objectStatus "J6U1.234" )
				)
				( pin "A2"
					( objectStatus "J6U1.216" )
				)
				( pin "A3"
					( objectStatus "J6U1.71" )
				)
				( pin "A4"
					( objectStatus "J6U1.214" )
				)
				( pin "A5"
					( objectStatus "J6U1.213" )
				)
				( pin "A6"
					( objectStatus "J6U1.69" )
				)
				( pin "A7"
					( objectStatus "J6U1.211" )
				)
				( pin "A8"
					( objectStatus "J6U1.68" )
				)
				( pin "A9"
					( objectStatus "J6U1.66" )
				)
				( pin "ACT_N"
					( objectStatus "J6U1.62" )
				)
				( pin "BA(0)"
					( objectStatus "J6U1.81" )
				)
				( pin "BA(1)"
					( objectStatus "J6U1.224" )
				)
				( pin "BG(0)"
					( objectStatus "J6U1.63" )
				)
				( pin "BG(1)"
					( objectStatus "J6U1.207" )
				)
				( pin "C(2)"
					( objectStatus "J6U1.235" )
				)
				( pin "CB(0)"
					( objectStatus "J6U1.49" )
				)
				( pin "CB(1)"
					( objectStatus "J6U1.194" )
				)
				( pin "CB(2)"
					( objectStatus "J6U1.56" )
				)
				( pin "CB(3)"
					( objectStatus "J6U1.201" )
				)
				( pin "CB(4)"
					( objectStatus "J6U1.47" )
				)
				( pin "CB(5)"
					( objectStatus "J6U1.192" )
				)
				( pin "CB(6)"
					( objectStatus "J6U1.54" )
				)
				( pin "CB(7)"
					( objectStatus "J6U1.199" )
				)
				( pin "CKE(0)"
					( objectStatus "J6U1.60" )
				)
				( pin "CKE(1)"
					( objectStatus "J6U1.203" )
				)
				( pin "DQ(0)"
					( objectStatus "J6U1.5" )
				)
				( pin "DQ(10)"
					( objectStatus "J6U1.23" )
				)
				( pin "DQ(11)"
					( objectStatus "J6U1.168" )
				)
				( pin "DQ(12)"
					( objectStatus "J6U1.14" )
				)
				( pin "DQ(13)"
					( objectStatus "J6U1.159" )
				)
				( pin "DQ(14)"
					( objectStatus "J6U1.21" )
				)
				( pin "DQ(15)"
					( objectStatus "J6U1.166" )
				)
				( pin "DQ(16)"
					( objectStatus "J6U1.27" )
				)
				( pin "DQ(17)"
					( objectStatus "J6U1.172" )
				)
				( pin "DQ(18)"
					( objectStatus "J6U1.34" )
				)
				( pin "DQ(19)"
					( objectStatus "J6U1.179" )
				)
				( pin "DQ(1)"
					( objectStatus "J6U1.150" )
				)
				( pin "DQ(20)"
					( objectStatus "J6U1.25" )
				)
				( pin "DQ(21)"
					( objectStatus "J6U1.170" )
				)
				( pin "DQ(22)"
					( objectStatus "J6U1.32" )
				)
				( pin "DQ(23)"
					( objectStatus "J6U1.177" )
				)
				( pin "DQ(24)"
					( objectStatus "J6U1.38" )
				)
				( pin "DQ(25)"
					( objectStatus "J6U1.183" )
				)
				( pin "DQ(26)"
					( objectStatus "J6U1.45" )
				)
				( pin "DQ(27)"
					( objectStatus "J6U1.190" )
				)
				( pin "DQ(28)"
					( objectStatus "J6U1.36" )
				)
				( pin "DQ(29)"
					( objectStatus "J6U1.181" )
				)
				( pin "DQ(2)"
					( objectStatus "J6U1.12" )
				)
				( pin "DQ(30)"
					( objectStatus "J6U1.43" )
				)
				( pin "DQ(31)"
					( objectStatus "J6U1.188" )
				)
				( pin "DQ(32)"
					( objectStatus "J6U1.97" )
				)
				( pin "DQ(33)"
					( objectStatus "J6U1.242" )
				)
				( pin "DQ(34)"
					( objectStatus "J6U1.104" )
				)
				( pin "DQ(35)"
					( objectStatus "J6U1.249" )
				)
				( pin "DQ(36)"
					( objectStatus "J6U1.95" )
				)
				( pin "DQ(37)"
					( objectStatus "J6U1.240" )
				)
				( pin "DQ(38)"
					( objectStatus "J6U1.102" )
				)
				( pin "DQ(39)"
					( objectStatus "J6U1.247" )
				)
				( pin "DQ(3)"
					( objectStatus "J6U1.157" )
				)
				( pin "DQ(40)"
					( objectStatus "J6U1.108" )
				)
				( pin "DQ(41)"
					( objectStatus "J6U1.253" )
				)
				( pin "DQ(42)"
					( objectStatus "J6U1.115" )
				)
				( pin "DQ(43)"
					( objectStatus "J6U1.260" )
				)
				( pin "DQ(44)"
					( objectStatus "J6U1.106" )
				)
				( pin "DQ(45)"
					( objectStatus "J6U1.251" )
				)
				( pin "DQ(46)"
					( objectStatus "J6U1.113" )
				)
				( pin "DQ(47)"
					( objectStatus "J6U1.258" )
				)
				( pin "DQ(48)"
					( objectStatus "J6U1.119" )
				)
				( pin "DQ(49)"
					( objectStatus "J6U1.264" )
				)
				( pin "DQ(4)"
					( objectStatus "J6U1.3" )
				)
				( pin "DQ(50)"
					( objectStatus "J6U1.126" )
				)
				( pin "DQ(51)"
					( objectStatus "J6U1.271" )
				)
				( pin "DQ(52)"
					( objectStatus "J6U1.117" )
				)
				( pin "DQ(53)"
					( objectStatus "J6U1.262" )
				)
				( pin "DQ(54)"
					( objectStatus "J6U1.124" )
				)
				( pin "DQ(55)"
					( objectStatus "J6U1.269" )
				)
				( pin "DQ(56)"
					( objectStatus "J6U1.130" )
				)
				( pin "DQ(57)"
					( objectStatus "J6U1.275" )
				)
				( pin "DQ(58)"
					( objectStatus "J6U1.137" )
				)
				( pin "DQ(59)"
					( objectStatus "J6U1.282" )
				)
				( pin "DQ(5)"
					( objectStatus "J6U1.148" )
				)
				( pin "DQ(60)"
					( objectStatus "J6U1.128" )
				)
				( pin "DQ(61)"
					( objectStatus "J6U1.273" )
				)
				( pin "DQ(62)"
					( objectStatus "J6U1.135" )
				)
				( pin "DQ(63)"
					( objectStatus "J6U1.280" )
				)
				( pin "DQ(6)"
					( objectStatus "J6U1.10" )
				)
				( pin "DQ(7)"
					( objectStatus "J6U1.155" )
				)
				( pin "DQ(8)"
					( objectStatus "J6U1.16" )
				)
				( pin "DQ(9)"
					( objectStatus "J6U1.161" )
				)
				( pin "ODT(0)"
					( objectStatus "J6U1.87" )
				)
				( pin "ODT(1)"
					( objectStatus "J6U1.91" )
				)
				( pin "PAR"
					( objectStatus "J6U1.222" )
				)
				( pin "S0_N"
					( objectStatus "J6U1.84" )
				)
				( pin "S1_N"
					( objectStatus "J6U1.89" )
				)
				( pin "S2_N_C(0)"
					( objectStatus "J6U1.93" )
				)
				( pin "S3_N_C(1)"
					( objectStatus "J6U1.237" )
				)
			)
			( gate "@baseboard_fab2_lib.baseboard_fab2(sch_1):page46_i112"
				( objectStatus "F215" )
				( pin "DQS0N"
					( objectStatus "J6U1.152" )
				)
				( pin "DQS0P"
					( objectStatus "J6U1.153" )
				)
				( pin "DQS10N"
					( objectStatus "J6U1.19" )
				)
				( pin "DQS10P"
					( objectStatus "J6U1.18" )
				)
				( pin "DQS11N"
					( objectStatus "J6U1.30" )
				)
				( pin "DQS11P"
					( objectStatus "J6U1.29" )
				)
				( pin "DQS12N"
					( objectStatus "J6U1.41" )
				)
				( pin "DQS12P"
					( objectStatus "J6U1.40" )
				)
				( pin "DQS13N"
					( objectStatus "J6U1.100" )
				)
				( pin "DQS13P"
					( objectStatus "J6U1.99" )
				)
				( pin "DQS14N"
					( objectStatus "J6U1.111" )
				)
				( pin "DQS14P"
					( objectStatus "J6U1.110" )
				)
				( pin "DQS15N"
					( objectStatus "J6U1.122" )
				)
				( pin "DQS15P"
					( objectStatus "J6U1.121" )
				)
				( pin "DQS16N"
					( objectStatus "J6U1.133" )
				)
				( pin "DQS16P"
					( objectStatus "J6U1.132" )
				)
				( pin "DQS17N"
					( objectStatus "J6U1.52" )
				)
				( pin "DQS17P"
					( objectStatus "J6U1.51" )
				)
				( pin "DQS1N"
					( objectStatus "J6U1.163" )
				)
				( pin "DQS1P"
					( objectStatus "J6U1.164" )
				)
				( pin "DQS2N"
					( objectStatus "J6U1.174" )
				)
				( pin "DQS2P"
					( objectStatus "J6U1.175" )
				)
				( pin "DQS3N"
					( objectStatus "J6U1.185" )
				)
				( pin "DQS3P"
					( objectStatus "J6U1.186" )
				)
				( pin "DQS4N"
					( objectStatus "J6U1.244" )
				)
				( pin "DQS4P"
					( objectStatus "J6U1.245" )
				)
				( pin "DQS5N"
					( objectStatus "J6U1.255" )
				)
				( pin "DQS5P"
					( objectStatus "J6U1.256" )
				)
				( pin "DQS6N"
					( objectStatus "J6U1.266" )
				)
				( pin "DQS6P"
					( objectStatus "J6U1.267" )
				)
				( pin "DQS7N"
					( objectStatus "J6U1.277" )
				)
				( pin "DQS7P"
					( objectStatus "J6U1.278" )
				)
				( pin "DQS8N"
					( objectStatus "J6U1.196" )
				)
				( pin "DQS8P"
					( objectStatus "J6U1.197" )
				)
				( pin "DQS9N"
					( objectStatus "J6U1.8" )
				)
				( pin "DQS9P"
					( objectStatus "J6U1.7" )
				)
			)
			( gate "@baseboard_fab2_lib.baseboard_fab2(sch_1):page46_i138"
				( objectStatus "F214" )
			)
			( gate "@baseboard_fab2_lib.baseboard_fab2(sch_1):page46_i67"
				( objectStatus "F213" )
			)
			( gate "@baseboard_fab2_lib.baseboard_fab2(sch_1):page48_i111"
				( objectStatus "F212" )
				( pin "A0"
					( objectStatus "J6U2.79" )
				)
				( pin "A1"
					( objectStatus "J6U2.72" )
				)
				( pin "A10"
					( objectStatus "J6U2.225" )
				)
				( pin "A11"
					( objectStatus "J6U2.210" )
				)
				( pin "A12"
					( objectStatus "J6U2.65" )
				)
				( pin "A13"
					( objectStatus "J6U2.232" )
				)
				( pin "A14_WE_N"
					( objectStatus "J6U2.228" )
				)
				( pin "A15_CAS_N"
					( objectStatus "J6U2.86" )
				)
				( pin "A16_RAS_N"
					( objectStatus "J6U2.82" )
				)
				( pin "A17"
					( objectStatus "J6U2.234" )
				)
				( pin "A2"
					( objectStatus "J6U2.216" )
				)
				( pin "A3"
					( objectStatus "J6U2.71" )
				)
				( pin "A4"
					( objectStatus "J6U2.214" )
				)
				( pin "A5"
					( objectStatus "J6U2.213" )
				)
				( pin "A6"
					( objectStatus "J6U2.69" )
				)
				( pin "A7"
					( objectStatus "J6U2.211" )
				)
				( pin "A8"
					( objectStatus "J6U2.68" )
				)
				( pin "A9"
					( objectStatus "J6U2.66" )
				)
				( pin "ACT_N"
					( objectStatus "J6U2.62" )
				)
				( pin "BA(0)"
					( objectStatus "J6U2.81" )
				)
				( pin "BA(1)"
					( objectStatus "J6U2.224" )
				)
				( pin "BG(0)"
					( objectStatus "J6U2.63" )
				)
				( pin "BG(1)"
					( objectStatus "J6U2.207" )
				)
				( pin "C(2)"
					( objectStatus "J6U2.235" )
				)
				( pin "CB(0)"
					( objectStatus "J6U2.49" )
				)
				( pin "CB(1)"
					( objectStatus "J6U2.194" )
				)
				( pin "CB(2)"
					( objectStatus "J6U2.56" )
				)
				( pin "CB(3)"
					( objectStatus "J6U2.201" )
				)
				( pin "CB(4)"
					( objectStatus "J6U2.47" )
				)
				( pin "CB(5)"
					( objectStatus "J6U2.192" )
				)
				( pin "CB(6)"
					( objectStatus "J6U2.54" )
				)
				( pin "CB(7)"
					( objectStatus "J6U2.199" )
				)
				( pin "CKE(0)"
					( objectStatus "J6U2.60" )
				)
				( pin "CKE(1)"
					( objectStatus "J6U2.203" )
				)
				( pin "DQ(0)"
					( objectStatus "J6U2.5" )
				)
				( pin "DQ(10)"
					( objectStatus "J6U2.23" )
				)
				( pin "DQ(11)"
					( objectStatus "J6U2.168" )
				)
				( pin "DQ(12)"
					( objectStatus "J6U2.14" )
				)
				( pin "DQ(13)"
					( objectStatus "J6U2.159" )
				)
				( pin "DQ(14)"
					( objectStatus "J6U2.21" )
				)
				( pin "DQ(15)"
					( objectStatus "J6U2.166" )
				)
				( pin "DQ(16)"
					( objectStatus "J6U2.27" )
				)
				( pin "DQ(17)"
					( objectStatus "J6U2.172" )
				)
				( pin "DQ(18)"
					( objectStatus "J6U2.34" )
				)
				( pin "DQ(19)"
					( objectStatus "J6U2.179" )
				)
				( pin "DQ(1)"
					( objectStatus "J6U2.150" )
				)
				( pin "DQ(20)"
					( objectStatus "J6U2.25" )
				)
				( pin "DQ(21)"
					( objectStatus "J6U2.170" )
				)
				( pin "DQ(22)"
					( objectStatus "J6U2.32" )
				)
				( pin "DQ(23)"
					( objectStatus "J6U2.177" )
				)
				( pin "DQ(24)"
					( objectStatus "J6U2.38" )
				)
				( pin "DQ(25)"
					( objectStatus "J6U2.183" )
				)
				( pin "DQ(26)"
					( objectStatus "J6U2.45" )
				)
				( pin "DQ(27)"
					( objectStatus "J6U2.190" )
				)
				( pin "DQ(28)"
					( objectStatus "J6U2.36" )
				)
				( pin "DQ(29)"
					( objectStatus "J6U2.181" )
				)
				( pin "DQ(2)"
					( objectStatus "J6U2.12" )
				)
				( pin "DQ(30)"
					( objectStatus "J6U2.43" )
				)
				( pin "DQ(31)"
					( objectStatus "J6U2.188" )
				)
				( pin "DQ(32)"
					( objectStatus "J6U2.97" )
				)
				( pin "DQ(33)"
					( objectStatus "J6U2.242" )
				)
				( pin "DQ(34)"
					( objectStatus "J6U2.104" )
				)
				( pin "DQ(35)"
					( objectStatus "J6U2.249" )
				)
				( pin "DQ(36)"
					( objectStatus "J6U2.95" )
				)
				( pin "DQ(37)"
					( objectStatus "J6U2.240" )
				)
				( pin "DQ(38)"
					( objectStatus "J6U2.102" )
				)
				( pin "DQ(39)"
					( objectStatus "J6U2.247" )
				)
				( pin "DQ(3)"
					( objectStatus "J6U2.157" )
				)
				( pin "DQ(40)"
					( objectStatus "J6U2.108" )
				)
				( pin "DQ(41)"
					( objectStatus "J6U2.253" )
				)
				( pin "DQ(42)"
					( objectStatus "J6U2.115" )
				)
				( pin "DQ(43)"
					( objectStatus "J6U2.260" )
				)
				( pin "DQ(44)"
					( objectStatus "J6U2.106" )
				)
				( pin "DQ(45)"
					( objectStatus "J6U2.251" )
				)
				( pin "DQ(46)"
					( objectStatus "J6U2.113" )
				)
				( pin "DQ(47)"
					( objectStatus "J6U2.258" )
				)
				( pin "DQ(48)"
					( objectStatus "J6U2.119" )
				)
				( pin "DQ(49)"
					( objectStatus "J6U2.264" )
				)
				( pin "DQ(4)"
					( objectStatus "J6U2.3" )
				)
				( pin "DQ(50)"
					( objectStatus "J6U2.126" )
				)
				( pin "DQ(51)"
					( objectStatus "J6U2.271" )
				)
				( pin "DQ(52)"
					( objectStatus "J6U2.117" )
				)
				( pin "DQ(53)"
					( objectStatus "J6U2.262" )
				)
				( pin "DQ(54)"
					( objectStatus "J6U2.124" )
				)
				( pin "DQ(55)"
					( objectStatus "J6U2.269" )
				)
				( pin "DQ(56)"
					( objectStatus "J6U2.130" )
				)
				( pin "DQ(57)"
					( objectStatus "J6U2.275" )
				)
				( pin "DQ(58)"
					( objectStatus "J6U2.137" )
				)
				( pin "DQ(59)"
					( objectStatus "J6U2.282" )
				)
				( pin "DQ(5)"
					( objectStatus "J6U2.148" )
				)
				( pin "DQ(60)"
					( objectStatus "J6U2.128" )
				)
				( pin "DQ(61)"
					( objectStatus "J6U2.273" )
				)
				( pin "DQ(62)"
					( objectStatus "J6U2.135" )
				)
				( pin "DQ(63)"
					( objectStatus "J6U2.280" )
				)
				( pin "DQ(6)"
					( objectStatus "J6U2.10" )
				)
				( pin "DQ(7)"
					( objectStatus "J6U2.155" )
				)
				( pin "DQ(8)"
					( objectStatus "J6U2.16" )
				)
				( pin "DQ(9)"
					( objectStatus "J6U2.161" )
				)
				( pin "ODT(0)"
					( objectStatus "J6U2.87" )
				)
				( pin "ODT(1)"
					( objectStatus "J6U2.91" )
				)
				( pin "PAR"
					( objectStatus "J6U2.222" )
				)
				( pin "S0_N"
					( objectStatus "J6U2.84" )
				)
				( pin "S1_N"
					( objectStatus "J6U2.89" )
				)
				( pin "S2_N_C(0)"
					( objectStatus "J6U2.93" )
				)
				( pin "S3_N_C(1)"
					( objectStatus "J6U2.237" )
				)
			)
			( gate "@baseboard_fab2_lib.baseboard_fab2(sch_1):page48_i61"
				( objectStatus "F211" )
				( pin "DQS0N"
					( objectStatus "J6U2.152" )
				)
				( pin "DQS0P"
					( objectStatus "J6U2.153" )
				)
				( pin "DQS10N"
					( objectStatus "J6U2.19" )
				)
				( pin "DQS10P"
					( objectStatus "J6U2.18" )
				)
				( pin "DQS11N"
					( objectStatus "J6U2.30" )
				)
				( pin "DQS11P"
					( objectStatus "J6U2.29" )
				)
				( pin "DQS12N"
					( objectStatus "J6U2.41" )
				)
				( pin "DQS12P"
					( objectStatus "J6U2.40" )
				)
				( pin "DQS13N"
					( objectStatus "J6U2.100" )
				)
				( pin "DQS13P"
					( objectStatus "J6U2.99" )
				)
				( pin "DQS14N"
					( objectStatus "J6U2.111" )
				)
				( pin "DQS14P"
					( objectStatus "J6U2.110" )
				)
				( pin "DQS15N"
					( objectStatus "J6U2.122" )
				)
				( pin "DQS15P"
					( objectStatus "J6U2.121" )
				)
				( pin "DQS16N"
					( objectStatus "J6U2.133" )
				)
				( pin "DQS16P"
					( objectStatus "J6U2.132" )
				)
				( pin "DQS17N"
					( objectStatus "J6U2.52" )
				)
				( pin "DQS17P"
					( objectStatus "J6U2.51" )
				)
				( pin "DQS1N"
					( objectStatus "J6U2.163" )
				)
				( pin "DQS1P"
					( objectStatus "J6U2.164" )
				)
				( pin "DQS2N"
					( objectStatus "J6U2.174" )
				)
				( pin "DQS2P"
					( objectStatus "J6U2.175" )
				)
				( pin "DQS3N"
					( objectStatus "J6U2.185" )
				)
				( pin "DQS3P"
					( objectStatus "J6U2.186" )
				)
				( pin "DQS4N"
					( objectStatus "J6U2.244" )
				)
				( pin "DQS4P"
					( objectStatus "J6U2.245" )
				)
				( pin "DQS5N"
					( objectStatus "J6U2.255" )
				)
				( pin "DQS5P"
					( objectStatus "J6U2.256" )
				)
				( pin "DQS6N"
					( objectStatus "J6U2.266" )
				)
				( pin "DQS6P"
					( objectStatus "J6U2.267" )
				)
				( pin "DQS7N"
					( objectStatus "J6U2.277" )
				)
				( pin "DQS7P"
					( objectStatus "J6U2.278" )
				)
				( pin "DQS8N"
					( objectStatus "J6U2.196" )
				)
				( pin "DQS8P"
					( objectStatus "J6U2.197" )
				)
				( pin "DQS9N"
					( objectStatus "J6U2.8" )
				)
				( pin "DQS9P"
					( objectStatus "J6U2.7" )
				)
			)
			( gate "@baseboard_fab2_lib.baseboard_fab2(sch_1):page48_i43"
				( objectStatus "F210" )
			)
			( gate "@baseboard_fab2_lib.baseboard_fab2(sch_1):page48_i171"
				( objectStatus "F209" )
			)
			( gate "@baseboard_fab2_lib.baseboard_fab2(sch_1):page50_i158"
				( objectStatus "F224" )
				( pin "A0"
					( objectStatus "J6M1.79" )
				)
				( pin "A1"
					( objectStatus "J6M1.72" )
				)
				( pin "A10"
					( objectStatus "J6M1.225" )
				)
				( pin "A11"
					( objectStatus "J6M1.210" )
				)
				( pin "A12"
					( objectStatus "J6M1.65" )
				)
				( pin "A13"
					( objectStatus "J6M1.232" )
				)
				( pin "A14_WE_N"
					( objectStatus "J6M1.228" )
				)
				( pin "A15_CAS_N"
					( objectStatus "J6M1.86" )
				)
				( pin "A16_RAS_N"
					( objectStatus "J6M1.82" )
				)
				( pin "A17"
					( objectStatus "J6M1.234" )
				)
				( pin "A2"
					( objectStatus "J6M1.216" )
				)
				( pin "A3"
					( objectStatus "J6M1.71" )
				)
				( pin "A4"
					( objectStatus "J6M1.214" )
				)
				( pin "A5"
					( objectStatus "J6M1.213" )
				)
				( pin "A6"
					( objectStatus "J6M1.69" )
				)
				( pin "A7"
					( objectStatus "J6M1.211" )
				)
				( pin "A8"
					( objectStatus "J6M1.68" )
				)
				( pin "A9"
					( objectStatus "J6M1.66" )
				)
				( pin "ACT_N"
					( objectStatus "J6M1.62" )
				)
				( pin "BA(0)"
					( objectStatus "J6M1.81" )
				)
				( pin "BA(1)"
					( objectStatus "J6M1.224" )
				)
				( pin "BG(0)"
					( objectStatus "J6M1.63" )
				)
				( pin "BG(1)"
					( objectStatus "J6M1.207" )
				)
				( pin "C(2)"
					( objectStatus "J6M1.235" )
				)
				( pin "CB(0)"
					( objectStatus "J6M1.49" )
				)
				( pin "CB(1)"
					( objectStatus "J6M1.194" )
				)
				( pin "CB(2)"
					( objectStatus "J6M1.56" )
				)
				( pin "CB(3)"
					( objectStatus "J6M1.201" )
				)
				( pin "CB(4)"
					( objectStatus "J6M1.47" )
				)
				( pin "CB(5)"
					( objectStatus "J6M1.192" )
				)
				( pin "CB(6)"
					( objectStatus "J6M1.54" )
				)
				( pin "CB(7)"
					( objectStatus "J6M1.199" )
				)
				( pin "CKE(0)"
					( objectStatus "J6M1.60" )
				)
				( pin "CKE(1)"
					( objectStatus "J6M1.203" )
				)
				( pin "DQ(0)"
					( objectStatus "J6M1.5" )
				)
				( pin "DQ(10)"
					( objectStatus "J6M1.23" )
				)
				( pin "DQ(11)"
					( objectStatus "J6M1.168" )
				)
				( pin "DQ(12)"
					( objectStatus "J6M1.14" )
				)
				( pin "DQ(13)"
					( objectStatus "J6M1.159" )
				)
				( pin "DQ(14)"
					( objectStatus "J6M1.21" )
				)
				( pin "DQ(15)"
					( objectStatus "J6M1.166" )
				)
				( pin "DQ(16)"
					( objectStatus "J6M1.27" )
				)
				( pin "DQ(17)"
					( objectStatus "J6M1.172" )
				)
				( pin "DQ(18)"
					( objectStatus "J6M1.34" )
				)
				( pin "DQ(19)"
					( objectStatus "J6M1.179" )
				)
				( pin "DQ(1)"
					( objectStatus "J6M1.150" )
				)
				( pin "DQ(20)"
					( objectStatus "J6M1.25" )
				)
				( pin "DQ(21)"
					( objectStatus "J6M1.170" )
				)
				( pin "DQ(22)"
					( objectStatus "J6M1.32" )
				)
				( pin "DQ(23)"
					( objectStatus "J6M1.177" )
				)
				( pin "DQ(24)"
					( objectStatus "J6M1.38" )
				)
				( pin "DQ(25)"
					( objectStatus "J6M1.183" )
				)
				( pin "DQ(26)"
					( objectStatus "J6M1.45" )
				)
				( pin "DQ(27)"
					( objectStatus "J6M1.190" )
				)
				( pin "DQ(28)"
					( objectStatus "J6M1.36" )
				)
				( pin "DQ(29)"
					( objectStatus "J6M1.181" )
				)
				( pin "DQ(2)"
					( objectStatus "J6M1.12" )
				)
				( pin "DQ(30)"
					( objectStatus "J6M1.43" )
				)
				( pin "DQ(31)"
					( objectStatus "J6M1.188" )
				)
				( pin "DQ(32)"
					( objectStatus "J6M1.97" )
				)
				( pin "DQ(33)"
					( objectStatus "J6M1.242" )
				)
				( pin "DQ(34)"
					( objectStatus "J6M1.104" )
				)
				( pin "DQ(35)"
					( objectStatus "J6M1.249" )
				)
				( pin "DQ(36)"
					( objectStatus "J6M1.95" )
				)
				( pin "DQ(37)"
					( objectStatus "J6M1.240" )
				)
				( pin "DQ(38)"
					( objectStatus "J6M1.102" )
				)
				( pin "DQ(39)"
					( objectStatus "J6M1.247" )
				)
				( pin "DQ(3)"
					( objectStatus "J6M1.157" )
				)
				( pin "DQ(40)"
					( objectStatus "J6M1.108" )
				)
				( pin "DQ(41)"
					( objectStatus "J6M1.253" )
				)
				( pin "DQ(42)"
					( objectStatus "J6M1.115" )
				)
				( pin "DQ(43)"
					( objectStatus "J6M1.260" )
				)
				( pin "DQ(44)"
					( objectStatus "J6M1.106" )
				)
				( pin "DQ(45)"
					( objectStatus "J6M1.251" )
				)
				( pin "DQ(46)"
					( objectStatus "J6M1.113" )
				)
				( pin "DQ(47)"
					( objectStatus "J6M1.258" )
				)
				( pin "DQ(48)"
					( objectStatus "J6M1.119" )
				)
				( pin "DQ(49)"
					( objectStatus "J6M1.264" )
				)
				( pin "DQ(4)"
					( objectStatus "J6M1.3" )
				)
				( pin "DQ(50)"
					( objectStatus "J6M1.126" )
				)
				( pin "DQ(51)"
					( objectStatus "J6M1.271" )
				)
				( pin "DQ(52)"
					( objectStatus "J6M1.117" )
				)
				( pin "DQ(53)"
					( objectStatus "J6M1.262" )
				)
				( pin "DQ(54)"
					( objectStatus "J6M1.124" )
				)
				( pin "DQ(55)"
					( objectStatus "J6M1.269" )
				)
				( pin "DQ(56)"
					( objectStatus "J6M1.130" )
				)
				( pin "DQ(57)"
					( objectStatus "J6M1.275" )
				)
				( pin "DQ(58)"
					( objectStatus "J6M1.137" )
				)
				( pin "DQ(59)"
					( objectStatus "J6M1.282" )
				)
				( pin "DQ(5)"
					( objectStatus "J6M1.148" )
				)
				( pin "DQ(60)"
					( objectStatus "J6M1.128" )
				)
				( pin "DQ(61)"
					( objectStatus "J6M1.273" )
				)
				( pin "DQ(62)"
					( objectStatus "J6M1.135" )
				)
				( pin "DQ(63)"
					( objectStatus "J6M1.280" )
				)
				( pin "DQ(6)"
					( objectStatus "J6M1.10" )
				)
				( pin "DQ(7)"
					( objectStatus "J6M1.155" )
				)
				( pin "DQ(8)"
					( objectStatus "J6M1.16" )
				)
				( pin "DQ(9)"
					( objectStatus "J6M1.161" )
				)
				( pin "ODT(0)"
					( objectStatus "J6M1.87" )
				)
				( pin "ODT(1)"
					( objectStatus "J6M1.91" )
				)
				( pin "PAR"
					( objectStatus "J6M1.222" )
				)
				( pin "S0_N"
					( objectStatus "J6M1.84" )
				)
				( pin "S1_N"
					( objectStatus "J6M1.89" )
				)
				( pin "S2_N_C(0)"
					( objectStatus "J6M1.93" )
				)
				( pin "S3_N_C(1)"
					( objectStatus "J6M1.237" )
				)
			)
			( gate "@baseboard_fab2_lib.baseboard_fab2(sch_1):page50_i46"
				( objectStatus "F223" )
				( pin "DQS0N"
					( objectStatus "J6M1.152" )
				)
				( pin "DQS0P"
					( objectStatus "J6M1.153" )
				)
				( pin "DQS10N"
					( objectStatus "J6M1.19" )
				)
				( pin "DQS10P"
					( objectStatus "J6M1.18" )
				)
				( pin "DQS11N"
					( objectStatus "J6M1.30" )
				)
				( pin "DQS11P"
					( objectStatus "J6M1.29" )
				)
				( pin "DQS12N"
					( objectStatus "J6M1.41" )
				)
				( pin "DQS12P"
					( objectStatus "J6M1.40" )
				)
				( pin "DQS13N"
					( objectStatus "J6M1.100" )
				)
				( pin "DQS13P"
					( objectStatus "J6M1.99" )
				)
				( pin "DQS14N"
					( objectStatus "J6M1.111" )
				)
				( pin "DQS14P"
					( objectStatus "J6M1.110" )
				)
				( pin "DQS15N"
					( objectStatus "J6M1.122" )
				)
				( pin "DQS15P"
					( objectStatus "J6M1.121" )
				)
				( pin "DQS16N"
					( objectStatus "J6M1.133" )
				)
				( pin "DQS16P"
					( objectStatus "J6M1.132" )
				)
				( pin "DQS17N"
					( objectStatus "J6M1.52" )
				)
				( pin "DQS17P"
					( objectStatus "J6M1.51" )
				)
				( pin "DQS1N"
					( objectStatus "J6M1.163" )
				)
				( pin "DQS1P"
					( objectStatus "J6M1.164" )
				)
				( pin "DQS2N"
					( objectStatus "J6M1.174" )
				)
				( pin "DQS2P"
					( objectStatus "J6M1.175" )
				)
				( pin "DQS3N"
					( objectStatus "J6M1.185" )
				)
				( pin "DQS3P"
					( objectStatus "J6M1.186" )
				)
				( pin "DQS4N"
					( objectStatus "J6M1.244" )
				)
				( pin "DQS4P"
					( objectStatus "J6M1.245" )
				)
				( pin "DQS5N"
					( objectStatus "J6M1.255" )
				)
				( pin "DQS5P"
					( objectStatus "J6M1.256" )
				)
				( pin "DQS6N"
					( objectStatus "J6M1.266" )
				)
				( pin "DQS6P"
					( objectStatus "J6M1.267" )
				)
				( pin "DQS7N"
					( objectStatus "J6M1.277" )
				)
				( pin "DQS7P"
					( objectStatus "J6M1.278" )
				)
				( pin "DQS8N"
					( objectStatus "J6M1.196" )
				)
				( pin "DQS8P"
					( objectStatus "J6M1.197" )
				)
				( pin "DQS9N"
					( objectStatus "J6M1.8" )
				)
				( pin "DQS9P"
					( objectStatus "J6M1.7" )
				)
			)
			( gate "@baseboard_fab2_lib.baseboard_fab2(sch_1):page50_i44"
				( objectStatus "F222" )
			)
			( gate "@baseboard_fab2_lib.baseboard_fab2(sch_1):page50_i50"
				( objectStatus "F221" )
			)
			( gate "@baseboard_fab2_lib.baseboard_fab2(sch_1):page52_i12"
				( objectStatus "F228" )
				( pin "A0"
					( objectStatus "J6L2.79" )
				)
				( pin "A1"
					( objectStatus "J6L2.72" )
				)
				( pin "A10"
					( objectStatus "J6L2.225" )
				)
				( pin "A11"
					( objectStatus "J6L2.210" )
				)
				( pin "A12"
					( objectStatus "J6L2.65" )
				)
				( pin "A13"
					( objectStatus "J6L2.232" )
				)
				( pin "A14_WE_N"
					( objectStatus "J6L2.228" )
				)
				( pin "A15_CAS_N"
					( objectStatus "J6L2.86" )
				)
				( pin "A16_RAS_N"
					( objectStatus "J6L2.82" )
				)
				( pin "A17"
					( objectStatus "J6L2.234" )
				)
				( pin "A2"
					( objectStatus "J6L2.216" )
				)
				( pin "A3"
					( objectStatus "J6L2.71" )
				)
				( pin "A4"
					( objectStatus "J6L2.214" )
				)
				( pin "A5"
					( objectStatus "J6L2.213" )
				)
				( pin "A6"
					( objectStatus "J6L2.69" )
				)
				( pin "A7"
					( objectStatus "J6L2.211" )
				)
				( pin "A8"
					( objectStatus "J6L2.68" )
				)
				( pin "A9"
					( objectStatus "J6L2.66" )
				)
				( pin "ACT_N"
					( objectStatus "J6L2.62" )
				)
				( pin "BA(0)"
					( objectStatus "J6L2.81" )
				)
				( pin "BA(1)"
					( objectStatus "J6L2.224" )
				)
				( pin "BG(0)"
					( objectStatus "J6L2.63" )
				)
				( pin "BG(1)"
					( objectStatus "J6L2.207" )
				)
				( pin "C(2)"
					( objectStatus "J6L2.235" )
				)
				( pin "CB(0)"
					( objectStatus "J6L2.49" )
				)
				( pin "CB(1)"
					( objectStatus "J6L2.194" )
				)
				( pin "CB(2)"
					( objectStatus "J6L2.56" )
				)
				( pin "CB(3)"
					( objectStatus "J6L2.201" )
				)
				( pin "CB(4)"
					( objectStatus "J6L2.47" )
				)
				( pin "CB(5)"
					( objectStatus "J6L2.192" )
				)
				( pin "CB(6)"
					( objectStatus "J6L2.54" )
				)
				( pin "CB(7)"
					( objectStatus "J6L2.199" )
				)
				( pin "CKE(0)"
					( objectStatus "J6L2.60" )
				)
				( pin "CKE(1)"
					( objectStatus "J6L2.203" )
				)
				( pin "DQ(0)"
					( objectStatus "J6L2.5" )
				)
				( pin "DQ(10)"
					( objectStatus "J6L2.23" )
				)
				( pin "DQ(11)"
					( objectStatus "J6L2.168" )
				)
				( pin "DQ(12)"
					( objectStatus "J6L2.14" )
				)
				( pin "DQ(13)"
					( objectStatus "J6L2.159" )
				)
				( pin "DQ(14)"
					( objectStatus "J6L2.21" )
				)
				( pin "DQ(15)"
					( objectStatus "J6L2.166" )
				)
				( pin "DQ(16)"
					( objectStatus "J6L2.27" )
				)
				( pin "DQ(17)"
					( objectStatus "J6L2.172" )
				)
				( pin "DQ(18)"
					( objectStatus "J6L2.34" )
				)
				( pin "DQ(19)"
					( objectStatus "J6L2.179" )
				)
				( pin "DQ(1)"
					( objectStatus "J6L2.150" )
				)
				( pin "DQ(20)"
					( objectStatus "J6L2.25" )
				)
				( pin "DQ(21)"
					( objectStatus "J6L2.170" )
				)
				( pin "DQ(22)"
					( objectStatus "J6L2.32" )
				)
				( pin "DQ(23)"
					( objectStatus "J6L2.177" )
				)
				( pin "DQ(24)"
					( objectStatus "J6L2.38" )
				)
				( pin "DQ(25)"
					( objectStatus "J6L2.183" )
				)
				( pin "DQ(26)"
					( objectStatus "J6L2.45" )
				)
				( pin "DQ(27)"
					( objectStatus "J6L2.190" )
				)
				( pin "DQ(28)"
					( objectStatus "J6L2.36" )
				)
				( pin "DQ(29)"
					( objectStatus "J6L2.181" )
				)
				( pin "DQ(2)"
					( objectStatus "J6L2.12" )
				)
				( pin "DQ(30)"
					( objectStatus "J6L2.43" )
				)
				( pin "DQ(31)"
					( objectStatus "J6L2.188" )
				)
				( pin "DQ(32)"
					( objectStatus "J6L2.97" )
				)
				( pin "DQ(33)"
					( objectStatus "J6L2.242" )
				)
				( pin "DQ(34)"
					( objectStatus "J6L2.104" )
				)
				( pin "DQ(35)"
					( objectStatus "J6L2.249" )
				)
				( pin "DQ(36)"
					( objectStatus "J6L2.95" )
				)
				( pin "DQ(37)"
					( objectStatus "J6L2.240" )
				)
				( pin "DQ(38)"
					( objectStatus "J6L2.102" )
				)
				( pin "DQ(39)"
					( objectStatus "J6L2.247" )
				)
				( pin "DQ(3)"
					( objectStatus "J6L2.157" )
				)
				( pin "DQ(40)"
					( objectStatus "J6L2.108" )
				)
				( pin "DQ(41)"
					( objectStatus "J6L2.253" )
				)
				( pin "DQ(42)"
					( objectStatus "J6L2.115" )
				)
				( pin "DQ(43)"
					( objectStatus "J6L2.260" )
				)
				( pin "DQ(44)"
					( objectStatus "J6L2.106" )
				)
				( pin "DQ(45)"
					( objectStatus "J6L2.251" )
				)
				( pin "DQ(46)"
					( objectStatus "J6L2.113" )
				)
				( pin "DQ(47)"
					( objectStatus "J6L2.258" )
				)
				( pin "DQ(48)"
					( objectStatus "J6L2.119" )
				)
				( pin "DQ(49)"
					( objectStatus "J6L2.264" )
				)
				( pin "DQ(4)"
					( objectStatus "J6L2.3" )
				)
				( pin "DQ(50)"
					( objectStatus "J6L2.126" )
				)
				( pin "DQ(51)"
					( objectStatus "J6L2.271" )
				)
				( pin "DQ(52)"
					( objectStatus "J6L2.117" )
				)
				( pin "DQ(53)"
					( objectStatus "J6L2.262" )
				)
				( pin "DQ(54)"
					( objectStatus "J6L2.124" )
				)
				( pin "DQ(55)"
					( objectStatus "J6L2.269" )
				)
				( pin "DQ(56)"
					( objectStatus "J6L2.130" )
				)
				( pin "DQ(57)"
					( objectStatus "J6L2.275" )
				)
				( pin "DQ(58)"
					( objectStatus "J6L2.137" )
				)
				( pin "DQ(59)"
					( objectStatus "J6L2.282" )
				)
				( pin "DQ(5)"
					( objectStatus "J6L2.148" )
				)
				( pin "DQ(60)"
					( objectStatus "J6L2.128" )
				)
				( pin "DQ(61)"
					( objectStatus "J6L2.273" )
				)
				( pin "DQ(62)"
					( objectStatus "J6L2.135" )
				)
				( pin "DQ(63)"
					( objectStatus "J6L2.280" )
				)
				( pin "DQ(6)"
					( objectStatus "J6L2.10" )
				)
				( pin "DQ(7)"
					( objectStatus "J6L2.155" )
				)
				( pin "DQ(8)"
					( objectStatus "J6L2.16" )
				)
				( pin "DQ(9)"
					( objectStatus "J6L2.161" )
				)
				( pin "ODT(0)"
					( objectStatus "J6L2.87" )
				)
				( pin "ODT(1)"
					( objectStatus "J6L2.91" )
				)
				( pin "PAR"
					( objectStatus "J6L2.222" )
				)
				( pin "S0_N"
					( objectStatus "J6L2.84" )
				)
				( pin "S1_N"
					( objectStatus "J6L2.89" )
				)
				( pin "S2_N_C(0)"
					( objectStatus "J6L2.93" )
				)
				( pin "S3_N_C(1)"
					( objectStatus "J6L2.237" )
				)
			)
			( gate "@baseboard_fab2_lib.baseboard_fab2(sch_1):page52_i100"
				( objectStatus "F227" )
				( pin "DQS0N"
					( objectStatus "J6L2.152" )
				)
				( pin "DQS0P"
					( objectStatus "J6L2.153" )
				)
				( pin "DQS10N"
					( objectStatus "J6L2.19" )
				)
				( pin "DQS10P"
					( objectStatus "J6L2.18" )
				)
				( pin "DQS11N"
					( objectStatus "J6L2.30" )
				)
				( pin "DQS11P"
					( objectStatus "J6L2.29" )
				)
				( pin "DQS12N"
					( objectStatus "J6L2.41" )
				)
				( pin "DQS12P"
					( objectStatus "J6L2.40" )
				)
				( pin "DQS13N"
					( objectStatus "J6L2.100" )
				)
				( pin "DQS13P"
					( objectStatus "J6L2.99" )
				)
				( pin "DQS14N"
					( objectStatus "J6L2.111" )
				)
				( pin "DQS14P"
					( objectStatus "J6L2.110" )
				)
				( pin "DQS15N"
					( objectStatus "J6L2.122" )
				)
				( pin "DQS15P"
					( objectStatus "J6L2.121" )
				)
				( pin "DQS16N"
					( objectStatus "J6L2.133" )
				)
				( pin "DQS16P"
					( objectStatus "J6L2.132" )
				)
				( pin "DQS17N"
					( objectStatus "J6L2.52" )
				)
				( pin "DQS17P"
					( objectStatus "J6L2.51" )
				)
				( pin "DQS1N"
					( objectStatus "J6L2.163" )
				)
				( pin "DQS1P"
					( objectStatus "J6L2.164" )
				)
				( pin "DQS2N"
					( objectStatus "J6L2.174" )
				)
				( pin "DQS2P"
					( objectStatus "J6L2.175" )
				)
				( pin "DQS3N"
					( objectStatus "J6L2.185" )
				)
				( pin "DQS3P"
					( objectStatus "J6L2.186" )
				)
				( pin "DQS4N"
					( objectStatus "J6L2.244" )
				)
				( pin "DQS4P"
					( objectStatus "J6L2.245" )
				)
				( pin "DQS5N"
					( objectStatus "J6L2.255" )
				)
				( pin "DQS5P"
					( objectStatus "J6L2.256" )
				)
				( pin "DQS6N"
					( objectStatus "J6L2.266" )
				)
				( pin "DQS6P"
					( objectStatus "J6L2.267" )
				)
				( pin "DQS7N"
					( objectStatus "J6L2.277" )
				)
				( pin "DQS7P"
					( objectStatus "J6L2.278" )
				)
				( pin "DQS8N"
					( objectStatus "J6L2.196" )
				)
				( pin "DQS8P"
					( objectStatus "J6L2.197" )
				)
				( pin "DQS9N"
					( objectStatus "J6L2.8" )
				)
				( pin "DQS9P"
					( objectStatus "J6L2.7" )
				)
			)
			( gate "@baseboard_fab2_lib.baseboard_fab2(sch_1):page52_i138"
				( objectStatus "F226" )
			)
			( gate "@baseboard_fab2_lib.baseboard_fab2(sch_1):page52_i55"
				( objectStatus "F225" )
			)
			( gate "@baseboard_fab2_lib.baseboard_fab2(sch_1):page54_i111"
				( objectStatus "F232" )
				( pin "A0"
					( objectStatus "J6L1.79" )
				)
				( pin "A1"
					( objectStatus "J6L1.72" )
				)
				( pin "A10"
					( objectStatus "J6L1.225" )
				)
				( pin "A11"
					( objectStatus "J6L1.210" )
				)
				( pin "A12"
					( objectStatus "J6L1.65" )
				)
				( pin "A13"
					( objectStatus "J6L1.232" )
				)
				( pin "A14_WE_N"
					( objectStatus "J6L1.228" )
				)
				( pin "A15_CAS_N"
					( objectStatus "J6L1.86" )
				)
				( pin "A16_RAS_N"
					( objectStatus "J6L1.82" )
				)
				( pin "A17"
					( objectStatus "J6L1.234" )
				)
				( pin "A2"
					( objectStatus "J6L1.216" )
				)
				( pin "A3"
					( objectStatus "J6L1.71" )
				)
				( pin "A4"
					( objectStatus "J6L1.214" )
				)
				( pin "A5"
					( objectStatus "J6L1.213" )
				)
				( pin "A6"
					( objectStatus "J6L1.69" )
				)
				( pin "A7"
					( objectStatus "J6L1.211" )
				)
				( pin "A8"
					( objectStatus "J6L1.68" )
				)
				( pin "A9"
					( objectStatus "J6L1.66" )
				)
				( pin "ACT_N"
					( objectStatus "J6L1.62" )
				)
				( pin "BA(0)"
					( objectStatus "J6L1.81" )
				)
				( pin "BA(1)"
					( objectStatus "J6L1.224" )
				)
				( pin "BG(0)"
					( objectStatus "J6L1.63" )
				)
				( pin "BG(1)"
					( objectStatus "J6L1.207" )
				)
				( pin "C(2)"
					( objectStatus "J6L1.235" )
				)
				( pin "CB(0)"
					( objectStatus "J6L1.49" )
				)
				( pin "CB(1)"
					( objectStatus "J6L1.194" )
				)
				( pin "CB(2)"
					( objectStatus "J6L1.56" )
				)
				( pin "CB(3)"
					( objectStatus "J6L1.201" )
				)
				( pin "CB(4)"
					( objectStatus "J6L1.47" )
				)
				( pin "CB(5)"
					( objectStatus "J6L1.192" )
				)
				( pin "CB(6)"
					( objectStatus "J6L1.54" )
				)
				( pin "CB(7)"
					( objectStatus "J6L1.199" )
				)
				( pin "CKE(0)"
					( objectStatus "J6L1.60" )
				)
				( pin "CKE(1)"
					( objectStatus "J6L1.203" )
				)
				( pin "DQ(0)"
					( objectStatus "J6L1.5" )
				)
				( pin "DQ(10)"
					( objectStatus "J6L1.23" )
				)
				( pin "DQ(11)"
					( objectStatus "J6L1.168" )
				)
				( pin "DQ(12)"
					( objectStatus "J6L1.14" )
				)
				( pin "DQ(13)"
					( objectStatus "J6L1.159" )
				)
				( pin "DQ(14)"
					( objectStatus "J6L1.21" )
				)
				( pin "DQ(15)"
					( objectStatus "J6L1.166" )
				)
				( pin "DQ(16)"
					( objectStatus "J6L1.27" )
				)
				( pin "DQ(17)"
					( objectStatus "J6L1.172" )
				)
				( pin "DQ(18)"
					( objectStatus "J6L1.34" )
				)
				( pin "DQ(19)"
					( objectStatus "J6L1.179" )
				)
				( pin "DQ(1)"
					( objectStatus "J6L1.150" )
				)
				( pin "DQ(20)"
					( objectStatus "J6L1.25" )
				)
				( pin "DQ(21)"
					( objectStatus "J6L1.170" )
				)
				( pin "DQ(22)"
					( objectStatus "J6L1.32" )
				)
				( pin "DQ(23)"
					( objectStatus "J6L1.177" )
				)
				( pin "DQ(24)"
					( objectStatus "J6L1.38" )
				)
				( pin "DQ(25)"
					( objectStatus "J6L1.183" )
				)
				( pin "DQ(26)"
					( objectStatus "J6L1.45" )
				)
				( pin "DQ(27)"
					( objectStatus "J6L1.190" )
				)
				( pin "DQ(28)"
					( objectStatus "J6L1.36" )
				)
				( pin "DQ(29)"
					( objectStatus "J6L1.181" )
				)
				( pin "DQ(2)"
					( objectStatus "J6L1.12" )
				)
				( pin "DQ(30)"
					( objectStatus "J6L1.43" )
				)
				( pin "DQ(31)"
					( objectStatus "J6L1.188" )
				)
				( pin "DQ(32)"
					( objectStatus "J6L1.97" )
				)
				( pin "DQ(33)"
					( objectStatus "J6L1.242" )
				)
				( pin "DQ(34)"
					( objectStatus "J6L1.104" )
				)
				( pin "DQ(35)"
					( objectStatus "J6L1.249" )
				)
				( pin "DQ(36)"
					( objectStatus "J6L1.95" )
				)
				( pin "DQ(37)"
					( objectStatus "J6L1.240" )
				)
				( pin "DQ(38)"
					( objectStatus "J6L1.102" )
				)
				( pin "DQ(39)"
					( objectStatus "J6L1.247" )
				)
				( pin "DQ(3)"
					( objectStatus "J6L1.157" )
				)
				( pin "DQ(40)"
					( objectStatus "J6L1.108" )
				)
				( pin "DQ(41)"
					( objectStatus "J6L1.253" )
				)
				( pin "DQ(42)"
					( objectStatus "J6L1.115" )
				)
				( pin "DQ(43)"
					( objectStatus "J6L1.260" )
				)
				( pin "DQ(44)"
					( objectStatus "J6L1.106" )
				)
				( pin "DQ(45)"
					( objectStatus "J6L1.251" )
				)
				( pin "DQ(46)"
					( objectStatus "J6L1.113" )
				)
				( pin "DQ(47)"
					( objectStatus "J6L1.258" )
				)
				( pin "DQ(48)"
					( objectStatus "J6L1.119" )
				)
				( pin "DQ(49)"
					( objectStatus "J6L1.264" )
				)
				( pin "DQ(4)"
					( objectStatus "J6L1.3" )
				)
				( pin "DQ(50)"
					( objectStatus "J6L1.126" )
				)
				( pin "DQ(51)"
					( objectStatus "J6L1.271" )
				)
				( pin "DQ(52)"
					( objectStatus "J6L1.117" )
				)
				( pin "DQ(53)"
					( objectStatus "J6L1.262" )
				)
				( pin "DQ(54)"
					( objectStatus "J6L1.124" )
				)
				( pin "DQ(55)"
					( objectStatus "J6L1.269" )
				)
				( pin "DQ(56)"
					( objectStatus "J6L1.130" )
				)
				( pin "DQ(57)"
					( objectStatus "J6L1.275" )
				)
				( pin "DQ(58)"
					( objectStatus "J6L1.137" )
				)
				( pin "DQ(59)"
					( objectStatus "J6L1.282" )
				)
				( pin "DQ(5)"
					( objectStatus "J6L1.148" )
				)
				( pin "DQ(60)"
					( objectStatus "J6L1.128" )
				)
				( pin "DQ(61)"
					( objectStatus "J6L1.273" )
				)
				( pin "DQ(62)"
					( objectStatus "J6L1.135" )
				)
				( pin "DQ(63)"
					( objectStatus "J6L1.280" )
				)
				( pin "DQ(6)"
					( objectStatus "J6L1.10" )
				)
				( pin "DQ(7)"
					( objectStatus "J6L1.155" )
				)
				( pin "DQ(8)"
					( objectStatus "J6L1.16" )
				)
				( pin "DQ(9)"
					( objectStatus "J6L1.161" )
				)
				( pin "ODT(0)"
					( objectStatus "J6L1.87" )
				)
				( pin "ODT(1)"
					( objectStatus "J6L1.91" )
				)
				( pin "PAR"
					( objectStatus "J6L1.222" )
				)
				( pin "S0_N"
					( objectStatus "J6L1.84" )
				)
				( pin "S1_N"
					( objectStatus "J6L1.89" )
				)
				( pin "S2_N_C(0)"
					( objectStatus "J6L1.93" )
				)
				( pin "S3_N_C(1)"
					( objectStatus "J6L1.237" )
				)
			)
			( gate "@baseboard_fab2_lib.baseboard_fab2(sch_1):page54_i66"
				( objectStatus "F231" )
				( pin "DQS0N"
					( objectStatus "J6L1.152" )
				)
				( pin "DQS0P"
					( objectStatus "J6L1.153" )
				)
				( pin "DQS10N"
					( objectStatus "J6L1.19" )
				)
				( pin "DQS10P"
					( objectStatus "J6L1.18" )
				)
				( pin "DQS11N"
					( objectStatus "J6L1.30" )
				)
				( pin "DQS11P"
					( objectStatus "J6L1.29" )
				)
				( pin "DQS12N"
					( objectStatus "J6L1.41" )
				)
				( pin "DQS12P"
					( objectStatus "J6L1.40" )
				)
				( pin "DQS13N"
					( objectStatus "J6L1.100" )
				)
				( pin "DQS13P"
					( objectStatus "J6L1.99" )
				)
				( pin "DQS14N"
					( objectStatus "J6L1.111" )
				)
				( pin "DQS14P"
					( objectStatus "J6L1.110" )
				)
				( pin "DQS15N"
					( objectStatus "J6L1.122" )
				)
				( pin "DQS15P"
					( objectStatus "J6L1.121" )
				)
				( pin "DQS16N"
					( objectStatus "J6L1.133" )
				)
				( pin "DQS16P"
					( objectStatus "J6L1.132" )
				)
				( pin "DQS17N"
					( objectStatus "J6L1.52" )
				)
				( pin "DQS17P"
					( objectStatus "J6L1.51" )
				)
				( pin "DQS1N"
					( objectStatus "J6L1.163" )
				)
				( pin "DQS1P"
					( objectStatus "J6L1.164" )
				)
				( pin "DQS2N"
					( objectStatus "J6L1.174" )
				)
				( pin "DQS2P"
					( objectStatus "J6L1.175" )
				)
				( pin "DQS3N"
					( objectStatus "J6L1.185" )
				)
				( pin "DQS3P"
					( objectStatus "J6L1.186" )
				)
				( pin "DQS4N"
					( objectStatus "J6L1.244" )
				)
				( pin "DQS4P"
					( objectStatus "J6L1.245" )
				)
				( pin "DQS5N"
					( objectStatus "J6L1.255" )
				)
				( pin "DQS5P"
					( objectStatus "J6L1.256" )
				)
				( pin "DQS6N"
					( objectStatus "J6L1.266" )
				)
				( pin "DQS6P"
					( objectStatus "J6L1.267" )
				)
				( pin "DQS7N"
					( objectStatus "J6L1.277" )
				)
				( pin "DQS7P"
					( objectStatus "J6L1.278" )
				)
				( pin "DQS8N"
					( objectStatus "J6L1.196" )
				)
				( pin "DQS8P"
					( objectStatus "J6L1.197" )
				)
				( pin "DQS9N"
					( objectStatus "J6L1.8" )
				)
				( pin "DQS9P"
					( objectStatus "J6L1.7" )
				)
			)
			( gate "@baseboard_fab2_lib.baseboard_fab2(sch_1):page54_i43"
				( objectStatus "F230" )
			)
			( gate "@baseboard_fab2_lib.baseboard_fab2(sch_1):page54_i170"
				( objectStatus "F229" )
			)
			( gate "@baseboard_fab2_lib.baseboard_fab2(sch_1):page78_i13"
				( objectStatus "F196" )
				( pin "A0"
					( objectStatus "J9T1.79" )
				)
				( pin "A1"
					( objectStatus "J9T1.72" )
				)
				( pin "A10"
					( objectStatus "J9T1.225" )
				)
				( pin "A11"
					( objectStatus "J9T1.210" )
				)
				( pin "A12"
					( objectStatus "J9T1.65" )
				)
				( pin "A13"
					( objectStatus "J9T1.232" )
				)
				( pin "A14_WE_N"
					( objectStatus "J9T1.228" )
				)
				( pin "A15_CAS_N"
					( objectStatus "J9T1.86" )
				)
				( pin "A16_RAS_N"
					( objectStatus "J9T1.82" )
				)
				( pin "A17"
					( objectStatus "J9T1.234" )
				)
				( pin "A2"
					( objectStatus "J9T1.216" )
				)
				( pin "A3"
					( objectStatus "J9T1.71" )
				)
				( pin "A4"
					( objectStatus "J9T1.214" )
				)
				( pin "A5"
					( objectStatus "J9T1.213" )
				)
				( pin "A6"
					( objectStatus "J9T1.69" )
				)
				( pin "A7"
					( objectStatus "J9T1.211" )
				)
				( pin "A8"
					( objectStatus "J9T1.68" )
				)
				( pin "A9"
					( objectStatus "J9T1.66" )
				)
				( pin "ACT_N"
					( objectStatus "J9T1.62" )
				)
				( pin "BA(0)"
					( objectStatus "J9T1.81" )
				)
				( pin "BA(1)"
					( objectStatus "J9T1.224" )
				)
				( pin "BG(0)"
					( objectStatus "J9T1.63" )
				)
				( pin "BG(1)"
					( objectStatus "J9T1.207" )
				)
				( pin "C(2)"
					( objectStatus "J9T1.235" )
				)
				( pin "CB(0)"
					( objectStatus "J9T1.49" )
				)
				( pin "CB(1)"
					( objectStatus "J9T1.194" )
				)
				( pin "CB(2)"
					( objectStatus "J9T1.56" )
				)
				( pin "CB(3)"
					( objectStatus "J9T1.201" )
				)
				( pin "CB(4)"
					( objectStatus "J9T1.47" )
				)
				( pin "CB(5)"
					( objectStatus "J9T1.192" )
				)
				( pin "CB(6)"
					( objectStatus "J9T1.54" )
				)
				( pin "CB(7)"
					( objectStatus "J9T1.199" )
				)
				( pin "CKE(0)"
					( objectStatus "J9T1.60" )
				)
				( pin "CKE(1)"
					( objectStatus "J9T1.203" )
				)
				( pin "DQ(0)"
					( objectStatus "J9T1.5" )
				)
				( pin "DQ(10)"
					( objectStatus "J9T1.23" )
				)
				( pin "DQ(11)"
					( objectStatus "J9T1.168" )
				)
				( pin "DQ(12)"
					( objectStatus "J9T1.14" )
				)
				( pin "DQ(13)"
					( objectStatus "J9T1.159" )
				)
				( pin "DQ(14)"
					( objectStatus "J9T1.21" )
				)
				( pin "DQ(15)"
					( objectStatus "J9T1.166" )
				)
				( pin "DQ(16)"
					( objectStatus "J9T1.27" )
				)
				( pin "DQ(17)"
					( objectStatus "J9T1.172" )
				)
				( pin "DQ(18)"
					( objectStatus "J9T1.34" )
				)
				( pin "DQ(19)"
					( objectStatus "J9T1.179" )
				)
				( pin "DQ(1)"
					( objectStatus "J9T1.150" )
				)
				( pin "DQ(20)"
					( objectStatus "J9T1.25" )
				)
				( pin "DQ(21)"
					( objectStatus "J9T1.170" )
				)
				( pin "DQ(22)"
					( objectStatus "J9T1.32" )
				)
				( pin "DQ(23)"
					( objectStatus "J9T1.177" )
				)
				( pin "DQ(24)"
					( objectStatus "J9T1.38" )
				)
				( pin "DQ(25)"
					( objectStatus "J9T1.183" )
				)
				( pin "DQ(26)"
					( objectStatus "J9T1.45" )
				)
				( pin "DQ(27)"
					( objectStatus "J9T1.190" )
				)
				( pin "DQ(28)"
					( objectStatus "J9T1.36" )
				)
				( pin "DQ(29)"
					( objectStatus "J9T1.181" )
				)
				( pin "DQ(2)"
					( objectStatus "J9T1.12" )
				)
				( pin "DQ(30)"
					( objectStatus "J9T1.43" )
				)
				( pin "DQ(31)"
					( objectStatus "J9T1.188" )
				)
				( pin "DQ(32)"
					( objectStatus "J9T1.97" )
				)
				( pin "DQ(33)"
					( objectStatus "J9T1.242" )
				)
				( pin "DQ(34)"
					( objectStatus "J9T1.104" )
				)
				( pin "DQ(35)"
					( objectStatus "J9T1.249" )
				)
				( pin "DQ(36)"
					( objectStatus "J9T1.95" )
				)
				( pin "DQ(37)"
					( objectStatus "J9T1.240" )
				)
				( pin "DQ(38)"
					( objectStatus "J9T1.102" )
				)
				( pin "DQ(39)"
					( objectStatus "J9T1.247" )
				)
				( pin "DQ(3)"
					( objectStatus "J9T1.157" )
				)
				( pin "DQ(40)"
					( objectStatus "J9T1.108" )
				)
				( pin "DQ(41)"
					( objectStatus "J9T1.253" )
				)
				( pin "DQ(42)"
					( objectStatus "J9T1.115" )
				)
				( pin "DQ(43)"
					( objectStatus "J9T1.260" )
				)
				( pin "DQ(44)"
					( objectStatus "J9T1.106" )
				)
				( pin "DQ(45)"
					( objectStatus "J9T1.251" )
				)
				( pin "DQ(46)"
					( objectStatus "J9T1.113" )
				)
				( pin "DQ(47)"
					( objectStatus "J9T1.258" )
				)
				( pin "DQ(48)"
					( objectStatus "J9T1.119" )
				)
				( pin "DQ(49)"
					( objectStatus "J9T1.264" )
				)
				( pin "DQ(4)"
					( objectStatus "J9T1.3" )
				)
				( pin "DQ(50)"
					( objectStatus "J9T1.126" )
				)
				( pin "DQ(51)"
					( objectStatus "J9T1.271" )
				)
				( pin "DQ(52)"
					( objectStatus "J9T1.117" )
				)
				( pin "DQ(53)"
					( objectStatus "J9T1.262" )
				)
				( pin "DQ(54)"
					( objectStatus "J9T1.124" )
				)
				( pin "DQ(55)"
					( objectStatus "J9T1.269" )
				)
				( pin "DQ(56)"
					( objectStatus "J9T1.130" )
				)
				( pin "DQ(57)"
					( objectStatus "J9T1.275" )
				)
				( pin "DQ(58)"
					( objectStatus "J9T1.137" )
				)
				( pin "DQ(59)"
					( objectStatus "J9T1.282" )
				)
				( pin "DQ(5)"
					( objectStatus "J9T1.148" )
				)
				( pin "DQ(60)"
					( objectStatus "J9T1.128" )
				)
				( pin "DQ(61)"
					( objectStatus "J9T1.273" )
				)
				( pin "DQ(62)"
					( objectStatus "J9T1.135" )
				)
				( pin "DQ(63)"
					( objectStatus "J9T1.280" )
				)
				( pin "DQ(6)"
					( objectStatus "J9T1.10" )
				)
				( pin "DQ(7)"
					( objectStatus "J9T1.155" )
				)
				( pin "DQ(8)"
					( objectStatus "J9T1.16" )
				)
				( pin "DQ(9)"
					( objectStatus "J9T1.161" )
				)
				( pin "ODT(0)"
					( objectStatus "J9T1.87" )
				)
				( pin "ODT(1)"
					( objectStatus "J9T1.91" )
				)
				( pin "PAR"
					( objectStatus "J9T1.222" )
				)
				( pin "S0_N"
					( objectStatus "J9T1.84" )
				)
				( pin "S1_N"
					( objectStatus "J9T1.89" )
				)
				( pin "S2_N_C(0)"
					( objectStatus "J9T1.93" )
				)
				( pin "S3_N_C(1)"
					( objectStatus "J9T1.237" )
				)
				( pin "SCL"
					( objectStatus "J9T1.141" )
				)
				( pin "SDA"
					( objectStatus "J9T1.285" )
				)
			)
			( gate "@baseboard_fab2_lib.baseboard_fab2(sch_1):page78_i120"
				( objectStatus "F195" )
				( pin "DQS0N"
					( objectStatus "J9T1.152" )
				)
				( pin "DQS0P"
					( objectStatus "J9T1.153" )
				)
				( pin "DQS10N"
					( objectStatus "J9T1.19" )
				)
				( pin "DQS10P"
					( objectStatus "J9T1.18" )
				)
				( pin "DQS11N"
					( objectStatus "J9T1.30" )
				)
				( pin "DQS11P"
					( objectStatus "J9T1.29" )
				)
				( pin "DQS12N"
					( objectStatus "J9T1.41" )
				)
				( pin "DQS12P"
					( objectStatus "J9T1.40" )
				)
				( pin "DQS13N"
					( objectStatus "J9T1.100" )
				)
				( pin "DQS13P"
					( objectStatus "J9T1.99" )
				)
				( pin "DQS14N"
					( objectStatus "J9T1.111" )
				)
				( pin "DQS14P"
					( objectStatus "J9T1.110" )
				)
				( pin "DQS15N"
					( objectStatus "J9T1.122" )
				)
				( pin "DQS15P"
					( objectStatus "J9T1.121" )
				)
				( pin "DQS16N"
					( objectStatus "J9T1.133" )
				)
				( pin "DQS16P"
					( objectStatus "J9T1.132" )
				)
				( pin "DQS17N"
					( objectStatus "J9T1.52" )
				)
				( pin "DQS17P"
					( objectStatus "J9T1.51" )
				)
				( pin "DQS1N"
					( objectStatus "J9T1.163" )
				)
				( pin "DQS1P"
					( objectStatus "J9T1.164" )
				)
				( pin "DQS2N"
					( objectStatus "J9T1.174" )
				)
				( pin "DQS2P"
					( objectStatus "J9T1.175" )
				)
				( pin "DQS3N"
					( objectStatus "J9T1.185" )
				)
				( pin "DQS3P"
					( objectStatus "J9T1.186" )
				)
				( pin "DQS4N"
					( objectStatus "J9T1.244" )
				)
				( pin "DQS4P"
					( objectStatus "J9T1.245" )
				)
				( pin "DQS5N"
					( objectStatus "J9T1.255" )
				)
				( pin "DQS5P"
					( objectStatus "J9T1.256" )
				)
				( pin "DQS6N"
					( objectStatus "J9T1.266" )
				)
				( pin "DQS6P"
					( objectStatus "J9T1.267" )
				)
				( pin "DQS7N"
					( objectStatus "J9T1.277" )
				)
				( pin "DQS7P"
					( objectStatus "J9T1.278" )
				)
				( pin "DQS8N"
					( objectStatus "J9T1.196" )
				)
				( pin "DQS8P"
					( objectStatus "J9T1.197" )
				)
				( pin "DQS9N"
					( objectStatus "J9T1.8" )
				)
				( pin "DQS9P"
					( objectStatus "J9T1.7" )
				)
			)
			( gate "@baseboard_fab2_lib.baseboard_fab2(sch_1):page78_i144"
				( objectStatus "F194" )
			)
			( gate "@baseboard_fab2_lib.baseboard_fab2(sch_1):page78_i75"
				( objectStatus "F193" )
			)
			( gate "@baseboard_fab2_lib.baseboard_fab2(sch_1):page80_i24"
				( objectStatus "F192" )
				( pin "A0"
					( objectStatus "J9U1.79" )
				)
				( pin "A1"
					( objectStatus "J9U1.72" )
				)
				( pin "A10"
					( objectStatus "J9U1.225" )
				)
				( pin "A11"
					( objectStatus "J9U1.210" )
				)
				( pin "A12"
					( objectStatus "J9U1.65" )
				)
				( pin "A13"
					( objectStatus "J9U1.232" )
				)
				( pin "A14_WE_N"
					( objectStatus "J9U1.228" )
				)
				( pin "A15_CAS_N"
					( objectStatus "J9U1.86" )
				)
				( pin "A16_RAS_N"
					( objectStatus "J9U1.82" )
				)
				( pin "A17"
					( objectStatus "J9U1.234" )
				)
				( pin "A2"
					( objectStatus "J9U1.216" )
				)
				( pin "A3"
					( objectStatus "J9U1.71" )
				)
				( pin "A4"
					( objectStatus "J9U1.214" )
				)
				( pin "A5"
					( objectStatus "J9U1.213" )
				)
				( pin "A6"
					( objectStatus "J9U1.69" )
				)
				( pin "A7"
					( objectStatus "J9U1.211" )
				)
				( pin "A8"
					( objectStatus "J9U1.68" )
				)
				( pin "A9"
					( objectStatus "J9U1.66" )
				)
				( pin "ACT_N"
					( objectStatus "J9U1.62" )
				)
				( pin "BA(0)"
					( objectStatus "J9U1.81" )
				)
				( pin "BA(1)"
					( objectStatus "J9U1.224" )
				)
				( pin "BG(0)"
					( objectStatus "J9U1.63" )
				)
				( pin "BG(1)"
					( objectStatus "J9U1.207" )
				)
				( pin "C(2)"
					( objectStatus "J9U1.235" )
				)
				( pin "CB(0)"
					( objectStatus "J9U1.49" )
				)
				( pin "CB(1)"
					( objectStatus "J9U1.194" )
				)
				( pin "CB(2)"
					( objectStatus "J9U1.56" )
				)
				( pin "CB(3)"
					( objectStatus "J9U1.201" )
				)
				( pin "CB(4)"
					( objectStatus "J9U1.47" )
				)
				( pin "CB(5)"
					( objectStatus "J9U1.192" )
				)
				( pin "CB(6)"
					( objectStatus "J9U1.54" )
				)
				( pin "CB(7)"
					( objectStatus "J9U1.199" )
				)
				( pin "CKE(0)"
					( objectStatus "J9U1.60" )
				)
				( pin "CKE(1)"
					( objectStatus "J9U1.203" )
				)
				( pin "DQ(0)"
					( objectStatus "J9U1.5" )
				)
				( pin "DQ(10)"
					( objectStatus "J9U1.23" )
				)
				( pin "DQ(11)"
					( objectStatus "J9U1.168" )
				)
				( pin "DQ(12)"
					( objectStatus "J9U1.14" )
				)
				( pin "DQ(13)"
					( objectStatus "J9U1.159" )
				)
				( pin "DQ(14)"
					( objectStatus "J9U1.21" )
				)
				( pin "DQ(15)"
					( objectStatus "J9U1.166" )
				)
				( pin "DQ(16)"
					( objectStatus "J9U1.27" )
				)
				( pin "DQ(17)"
					( objectStatus "J9U1.172" )
				)
				( pin "DQ(18)"
					( objectStatus "J9U1.34" )
				)
				( pin "DQ(19)"
					( objectStatus "J9U1.179" )
				)
				( pin "DQ(1)"
					( objectStatus "J9U1.150" )
				)
				( pin "DQ(20)"
					( objectStatus "J9U1.25" )
				)
				( pin "DQ(21)"
					( objectStatus "J9U1.170" )
				)
				( pin "DQ(22)"
					( objectStatus "J9U1.32" )
				)
				( pin "DQ(23)"
					( objectStatus "J9U1.177" )
				)
				( pin "DQ(24)"
					( objectStatus "J9U1.38" )
				)
				( pin "DQ(25)"
					( objectStatus "J9U1.183" )
				)
				( pin "DQ(26)"
					( objectStatus "J9U1.45" )
				)
				( pin "DQ(27)"
					( objectStatus "J9U1.190" )
				)
				( pin "DQ(28)"
					( objectStatus "J9U1.36" )
				)
				( pin "DQ(29)"
					( objectStatus "J9U1.181" )
				)
				( pin "DQ(2)"
					( objectStatus "J9U1.12" )
				)
				( pin "DQ(30)"
					( objectStatus "J9U1.43" )
				)
				( pin "DQ(31)"
					( objectStatus "J9U1.188" )
				)
				( pin "DQ(32)"
					( objectStatus "J9U1.97" )
				)
				( pin "DQ(33)"
					( objectStatus "J9U1.242" )
				)
				( pin "DQ(34)"
					( objectStatus "J9U1.104" )
				)
				( pin "DQ(35)"
					( objectStatus "J9U1.249" )
				)
				( pin "DQ(36)"
					( objectStatus "J9U1.95" )
				)
				( pin "DQ(37)"
					( objectStatus "J9U1.240" )
				)
				( pin "DQ(38)"
					( objectStatus "J9U1.102" )
				)
				( pin "DQ(39)"
					( objectStatus "J9U1.247" )
				)
				( pin "DQ(3)"
					( objectStatus "J9U1.157" )
				)
				( pin "DQ(40)"
					( objectStatus "J9U1.108" )
				)
				( pin "DQ(41)"
					( objectStatus "J9U1.253" )
				)
				( pin "DQ(42)"
					( objectStatus "J9U1.115" )
				)
				( pin "DQ(43)"
					( objectStatus "J9U1.260" )
				)
				( pin "DQ(44)"
					( objectStatus "J9U1.106" )
				)
				( pin "DQ(45)"
					( objectStatus "J9U1.251" )
				)
				( pin "DQ(46)"
					( objectStatus "J9U1.113" )
				)
				( pin "DQ(47)"
					( objectStatus "J9U1.258" )
				)
				( pin "DQ(48)"
					( objectStatus "J9U1.119" )
				)
				( pin "DQ(49)"
					( objectStatus "J9U1.264" )
				)
				( pin "DQ(4)"
					( objectStatus "J9U1.3" )
				)
				( pin "DQ(50)"
					( objectStatus "J9U1.126" )
				)
				( pin "DQ(51)"
					( objectStatus "J9U1.271" )
				)
				( pin "DQ(52)"
					( objectStatus "J9U1.117" )
				)
				( pin "DQ(53)"
					( objectStatus "J9U1.262" )
				)
				( pin "DQ(54)"
					( objectStatus "J9U1.124" )
				)
				( pin "DQ(55)"
					( objectStatus "J9U1.269" )
				)
				( pin "DQ(56)"
					( objectStatus "J9U1.130" )
				)
				( pin "DQ(57)"
					( objectStatus "J9U1.275" )
				)
				( pin "DQ(58)"
					( objectStatus "J9U1.137" )
				)
				( pin "DQ(59)"
					( objectStatus "J9U1.282" )
				)
				( pin "DQ(5)"
					( objectStatus "J9U1.148" )
				)
				( pin "DQ(60)"
					( objectStatus "J9U1.128" )
				)
				( pin "DQ(61)"
					( objectStatus "J9U1.273" )
				)
				( pin "DQ(62)"
					( objectStatus "J9U1.135" )
				)
				( pin "DQ(63)"
					( objectStatus "J9U1.280" )
				)
				( pin "DQ(6)"
					( objectStatus "J9U1.10" )
				)
				( pin "DQ(7)"
					( objectStatus "J9U1.155" )
				)
				( pin "DQ(8)"
					( objectStatus "J9U1.16" )
				)
				( pin "DQ(9)"
					( objectStatus "J9U1.161" )
				)
				( pin "ODT(0)"
					( objectStatus "J9U1.87" )
				)
				( pin "ODT(1)"
					( objectStatus "J9U1.91" )
				)
				( pin "PAR"
					( objectStatus "J9U1.222" )
				)
				( pin "S0_N"
					( objectStatus "J9U1.84" )
				)
				( pin "S1_N"
					( objectStatus "J9U1.89" )
				)
				( pin "S2_N_C(0)"
					( objectStatus "J9U1.93" )
				)
				( pin "S3_N_C(1)"
					( objectStatus "J9U1.237" )
				)
			)
			( gate "@baseboard_fab2_lib.baseboard_fab2(sch_1):page80_i101"
				( objectStatus "F191" )
				( pin "DQS0N"
					( objectStatus "J9U1.152" )
				)
				( pin "DQS0P"
					( objectStatus "J9U1.153" )
				)
				( pin "DQS10N"
					( objectStatus "J9U1.19" )
				)
				( pin "DQS10P"
					( objectStatus "J9U1.18" )
				)
				( pin "DQS11N"
					( objectStatus "J9U1.30" )
				)
				( pin "DQS11P"
					( objectStatus "J9U1.29" )
				)
				( pin "DQS12N"
					( objectStatus "J9U1.41" )
				)
				( pin "DQS12P"
					( objectStatus "J9U1.40" )
				)
				( pin "DQS13N"
					( objectStatus "J9U1.100" )
				)
				( pin "DQS13P"
					( objectStatus "J9U1.99" )
				)
				( pin "DQS14N"
					( objectStatus "J9U1.111" )
				)
				( pin "DQS14P"
					( objectStatus "J9U1.110" )
				)
				( pin "DQS15N"
					( objectStatus "J9U1.122" )
				)
				( pin "DQS15P"
					( objectStatus "J9U1.121" )
				)
				( pin "DQS16N"
					( objectStatus "J9U1.133" )
				)
				( pin "DQS16P"
					( objectStatus "J9U1.132" )
				)
				( pin "DQS17N"
					( objectStatus "J9U1.52" )
				)
				( pin "DQS17P"
					( objectStatus "J9U1.51" )
				)
				( pin "DQS1N"
					( objectStatus "J9U1.163" )
				)
				( pin "DQS1P"
					( objectStatus "J9U1.164" )
				)
				( pin "DQS2N"
					( objectStatus "J9U1.174" )
				)
				( pin "DQS2P"
					( objectStatus "J9U1.175" )
				)
				( pin "DQS3N"
					( objectStatus "J9U1.185" )
				)
				( pin "DQS3P"
					( objectStatus "J9U1.186" )
				)
				( pin "DQS4N"
					( objectStatus "J9U1.244" )
				)
				( pin "DQS4P"
					( objectStatus "J9U1.245" )
				)
				( pin "DQS5N"
					( objectStatus "J9U1.255" )
				)
				( pin "DQS5P"
					( objectStatus "J9U1.256" )
				)
				( pin "DQS6N"
					( objectStatus "J9U1.266" )
				)
				( pin "DQS6P"
					( objectStatus "J9U1.267" )
				)
				( pin "DQS7N"
					( objectStatus "J9U1.277" )
				)
				( pin "DQS7P"
					( objectStatus "J9U1.278" )
				)
				( pin "DQS8N"
					( objectStatus "J9U1.196" )
				)
				( pin "DQS8P"
					( objectStatus "J9U1.197" )
				)
				( pin "DQS9N"
					( objectStatus "J9U1.8" )
				)
				( pin "DQS9P"
					( objectStatus "J9U1.7" )
				)
			)
			( gate "@baseboard_fab2_lib.baseboard_fab2(sch_1):page80_i138"
				( objectStatus "F190" )
			)
			( gate "@baseboard_fab2_lib.baseboard_fab2(sch_1):page80_i56"
				( objectStatus "F189" )
			)
			( gate "@baseboard_fab2_lib.baseboard_fab2(sch_1):page82_i187"
				( objectStatus "F188" )
				( pin "A0"
					( objectStatus "J9U2.79" )
				)
				( pin "A1"
					( objectStatus "J9U2.72" )
				)
				( pin "A10"
					( objectStatus "J9U2.225" )
				)
				( pin "A11"
					( objectStatus "J9U2.210" )
				)
				( pin "A12"
					( objectStatus "J9U2.65" )
				)
				( pin "A13"
					( objectStatus "J9U2.232" )
				)
				( pin "A14_WE_N"
					( objectStatus "J9U2.228" )
				)
				( pin "A15_CAS_N"
					( objectStatus "J9U2.86" )
				)
				( pin "A16_RAS_N"
					( objectStatus "J9U2.82" )
				)
				( pin "A17"
					( objectStatus "J9U2.234" )
				)
				( pin "A2"
					( objectStatus "J9U2.216" )
				)
				( pin "A3"
					( objectStatus "J9U2.71" )
				)
				( pin "A4"
					( objectStatus "J9U2.214" )
				)
				( pin "A5"
					( objectStatus "J9U2.213" )
				)
				( pin "A6"
					( objectStatus "J9U2.69" )
				)
				( pin "A7"
					( objectStatus "J9U2.211" )
				)
				( pin "A8"
					( objectStatus "J9U2.68" )
				)
				( pin "A9"
					( objectStatus "J9U2.66" )
				)
				( pin "ACT_N"
					( objectStatus "J9U2.62" )
				)
				( pin "BA(0)"
					( objectStatus "J9U2.81" )
				)
				( pin "BA(1)"
					( objectStatus "J9U2.224" )
				)
				( pin "BG(0)"
					( objectStatus "J9U2.63" )
				)
				( pin "BG(1)"
					( objectStatus "J9U2.207" )
				)
				( pin "C(2)"
					( objectStatus "J9U2.235" )
				)
				( pin "CB(0)"
					( objectStatus "J9U2.49" )
				)
				( pin "CB(1)"
					( objectStatus "J9U2.194" )
				)
				( pin "CB(2)"
					( objectStatus "J9U2.56" )
				)
				( pin "CB(3)"
					( objectStatus "J9U2.201" )
				)
				( pin "CB(4)"
					( objectStatus "J9U2.47" )
				)
				( pin "CB(5)"
					( objectStatus "J9U2.192" )
				)
				( pin "CB(6)"
					( objectStatus "J9U2.54" )
				)
				( pin "CB(7)"
					( objectStatus "J9U2.199" )
				)
				( pin "CKE(0)"
					( objectStatus "J9U2.60" )
				)
				( pin "CKE(1)"
					( objectStatus "J9U2.203" )
				)
				( pin "DQ(0)"
					( objectStatus "J9U2.5" )
				)
				( pin "DQ(10)"
					( objectStatus "J9U2.23" )
				)
				( pin "DQ(11)"
					( objectStatus "J9U2.168" )
				)
				( pin "DQ(12)"
					( objectStatus "J9U2.14" )
				)
				( pin "DQ(13)"
					( objectStatus "J9U2.159" )
				)
				( pin "DQ(14)"
					( objectStatus "J9U2.21" )
				)
				( pin "DQ(15)"
					( objectStatus "J9U2.166" )
				)
				( pin "DQ(16)"
					( objectStatus "J9U2.27" )
				)
				( pin "DQ(17)"
					( objectStatus "J9U2.172" )
				)
				( pin "DQ(18)"
					( objectStatus "J9U2.34" )
				)
				( pin "DQ(19)"
					( objectStatus "J9U2.179" )
				)
				( pin "DQ(1)"
					( objectStatus "J9U2.150" )
				)
				( pin "DQ(20)"
					( objectStatus "J9U2.25" )
				)
				( pin "DQ(21)"
					( objectStatus "J9U2.170" )
				)
				( pin "DQ(22)"
					( objectStatus "J9U2.32" )
				)
				( pin "DQ(23)"
					( objectStatus "J9U2.177" )
				)
				( pin "DQ(24)"
					( objectStatus "J9U2.38" )
				)
				( pin "DQ(25)"
					( objectStatus "J9U2.183" )
				)
				( pin "DQ(26)"
					( objectStatus "J9U2.45" )
				)
				( pin "DQ(27)"
					( objectStatus "J9U2.190" )
				)
				( pin "DQ(28)"
					( objectStatus "J9U2.36" )
				)
				( pin "DQ(29)"
					( objectStatus "J9U2.181" )
				)
				( pin "DQ(2)"
					( objectStatus "J9U2.12" )
				)
				( pin "DQ(30)"
					( objectStatus "J9U2.43" )
				)
				( pin "DQ(31)"
					( objectStatus "J9U2.188" )
				)
				( pin "DQ(32)"
					( objectStatus "J9U2.97" )
				)
				( pin "DQ(33)"
					( objectStatus "J9U2.242" )
				)
				( pin "DQ(34)"
					( objectStatus "J9U2.104" )
				)
				( pin "DQ(35)"
					( objectStatus "J9U2.249" )
				)
				( pin "DQ(36)"
					( objectStatus "J9U2.95" )
				)
				( pin "DQ(37)"
					( objectStatus "J9U2.240" )
				)
				( pin "DQ(38)"
					( objectStatus "J9U2.102" )
				)
				( pin "DQ(39)"
					( objectStatus "J9U2.247" )
				)
				( pin "DQ(3)"
					( objectStatus "J9U2.157" )
				)
				( pin "DQ(40)"
					( objectStatus "J9U2.108" )
				)
				( pin "DQ(41)"
					( objectStatus "J9U2.253" )
				)
				( pin "DQ(42)"
					( objectStatus "J9U2.115" )
				)
				( pin "DQ(43)"
					( objectStatus "J9U2.260" )
				)
				( pin "DQ(44)"
					( objectStatus "J9U2.106" )
				)
				( pin "DQ(45)"
					( objectStatus "J9U2.251" )
				)
				( pin "DQ(46)"
					( objectStatus "J9U2.113" )
				)
				( pin "DQ(47)"
					( objectStatus "J9U2.258" )
				)
				( pin "DQ(48)"
					( objectStatus "J9U2.119" )
				)
				( pin "DQ(49)"
					( objectStatus "J9U2.264" )
				)
				( pin "DQ(4)"
					( objectStatus "J9U2.3" )
				)
				( pin "DQ(50)"
					( objectStatus "J9U2.126" )
				)
				( pin "DQ(51)"
					( objectStatus "J9U2.271" )
				)
				( pin "DQ(52)"
					( objectStatus "J9U2.117" )
				)
				( pin "DQ(53)"
					( objectStatus "J9U2.262" )
				)
				( pin "DQ(54)"
					( objectStatus "J9U2.124" )
				)
				( pin "DQ(55)"
					( objectStatus "J9U2.269" )
				)
				( pin "DQ(56)"
					( objectStatus "J9U2.130" )
				)
				( pin "DQ(57)"
					( objectStatus "J9U2.275" )
				)
				( pin "DQ(58)"
					( objectStatus "J9U2.137" )
				)
				( pin "DQ(59)"
					( objectStatus "J9U2.282" )
				)
				( pin "DQ(5)"
					( objectStatus "J9U2.148" )
				)
				( pin "DQ(60)"
					( objectStatus "J9U2.128" )
				)
				( pin "DQ(61)"
					( objectStatus "J9U2.273" )
				)
				( pin "DQ(62)"
					( objectStatus "J9U2.135" )
				)
				( pin "DQ(63)"
					( objectStatus "J9U2.280" )
				)
				( pin "DQ(6)"
					( objectStatus "J9U2.10" )
				)
				( pin "DQ(7)"
					( objectStatus "J9U2.155" )
				)
				( pin "DQ(8)"
					( objectStatus "J9U2.16" )
				)
				( pin "DQ(9)"
					( objectStatus "J9U2.161" )
				)
				( pin "ODT(0)"
					( objectStatus "J9U2.87" )
				)
				( pin "ODT(1)"
					( objectStatus "J9U2.91" )
				)
				( pin "PAR"
					( objectStatus "J9U2.222" )
				)
				( pin "S0_N"
					( objectStatus "J9U2.84" )
				)
				( pin "S1_N"
					( objectStatus "J9U2.89" )
				)
				( pin "S2_N_C(0)"
					( objectStatus "J9U2.93" )
				)
				( pin "S3_N_C(1)"
					( objectStatus "J9U2.237" )
				)
			)
			( gate "@baseboard_fab2_lib.baseboard_fab2(sch_1):page82_i64"
				( objectStatus "F187" )
				( pin "DQS0N"
					( objectStatus "J9U2.152" )
				)
				( pin "DQS0P"
					( objectStatus "J9U2.153" )
				)
				( pin "DQS10N"
					( objectStatus "J9U2.19" )
				)
				( pin "DQS10P"
					( objectStatus "J9U2.18" )
				)
				( pin "DQS11N"
					( objectStatus "J9U2.30" )
				)
				( pin "DQS11P"
					( objectStatus "J9U2.29" )
				)
				( pin "DQS12N"
					( objectStatus "J9U2.41" )
				)
				( pin "DQS12P"
					( objectStatus "J9U2.40" )
				)
				( pin "DQS13N"
					( objectStatus "J9U2.100" )
				)
				( pin "DQS13P"
					( objectStatus "J9U2.99" )
				)
				( pin "DQS14N"
					( objectStatus "J9U2.111" )
				)
				( pin "DQS14P"
					( objectStatus "J9U2.110" )
				)
				( pin "DQS15N"
					( objectStatus "J9U2.122" )
				)
				( pin "DQS15P"
					( objectStatus "J9U2.121" )
				)
				( pin "DQS16N"
					( objectStatus "J9U2.133" )
				)
				( pin "DQS16P"
					( objectStatus "J9U2.132" )
				)
				( pin "DQS17N"
					( objectStatus "J9U2.52" )
				)
				( pin "DQS17P"
					( objectStatus "J9U2.51" )
				)
				( pin "DQS1N"
					( objectStatus "J9U2.163" )
				)
				( pin "DQS1P"
					( objectStatus "J9U2.164" )
				)
				( pin "DQS2N"
					( objectStatus "J9U2.174" )
				)
				( pin "DQS2P"
					( objectStatus "J9U2.175" )
				)
				( pin "DQS3N"
					( objectStatus "J9U2.185" )
				)
				( pin "DQS3P"
					( objectStatus "J9U2.186" )
				)
				( pin "DQS4N"
					( objectStatus "J9U2.244" )
				)
				( pin "DQS4P"
					( objectStatus "J9U2.245" )
				)
				( pin "DQS5N"
					( objectStatus "J9U2.255" )
				)
				( pin "DQS5P"
					( objectStatus "J9U2.256" )
				)
				( pin "DQS6N"
					( objectStatus "J9U2.266" )
				)
				( pin "DQS6P"
					( objectStatus "J9U2.267" )
				)
				( pin "DQS7N"
					( objectStatus "J9U2.277" )
				)
				( pin "DQS7P"
					( objectStatus "J9U2.278" )
				)
				( pin "DQS8N"
					( objectStatus "J9U2.196" )
				)
				( pin "DQS8P"
					( objectStatus "J9U2.197" )
				)
				( pin "DQS9N"
					( objectStatus "J9U2.8" )
				)
				( pin "DQS9P"
					( objectStatus "J9U2.7" )
				)
			)
			( gate "@baseboard_fab2_lib.baseboard_fab2(sch_1):page82_i188"
				( objectStatus "F186" )
			)
			( gate "@baseboard_fab2_lib.baseboard_fab2(sch_1):page82_i171"
				( objectStatus "F185" )
			)
			( gate "@baseboard_fab2_lib.baseboard_fab2(sch_1):page84_i14"
				( objectStatus "F200" )
				( pin "A0"
					( objectStatus "J9M1.79" )
				)
				( pin "A1"
					( objectStatus "J9M1.72" )
				)
				( pin "A10"
					( objectStatus "J9M1.225" )
				)
				( pin "A11"
					( objectStatus "J9M1.210" )
				)
				( pin "A12"
					( objectStatus "J9M1.65" )
				)
				( pin "A13"
					( objectStatus "J9M1.232" )
				)
				( pin "A14_WE_N"
					( objectStatus "J9M1.228" )
				)
				( pin "A15_CAS_N"
					( objectStatus "J9M1.86" )
				)
				( pin "A16_RAS_N"
					( objectStatus "J9M1.82" )
				)
				( pin "A17"
					( objectStatus "J9M1.234" )
				)
				( pin "A2"
					( objectStatus "J9M1.216" )
				)
				( pin "A3"
					( objectStatus "J9M1.71" )
				)
				( pin "A4"
					( objectStatus "J9M1.214" )
				)
				( pin "A5"
					( objectStatus "J9M1.213" )
				)
				( pin "A6"
					( objectStatus "J9M1.69" )
				)
				( pin "A7"
					( objectStatus "J9M1.211" )
				)
				( pin "A8"
					( objectStatus "J9M1.68" )
				)
				( pin "A9"
					( objectStatus "J9M1.66" )
				)
				( pin "ACT_N"
					( objectStatus "J9M1.62" )
				)
				( pin "BA(0)"
					( objectStatus "J9M1.81" )
				)
				( pin "BA(1)"
					( objectStatus "J9M1.224" )
				)
				( pin "BG(0)"
					( objectStatus "J9M1.63" )
				)
				( pin "BG(1)"
					( objectStatus "J9M1.207" )
				)
				( pin "C(2)"
					( objectStatus "J9M1.235" )
				)
				( pin "CB(0)"
					( objectStatus "J9M1.49" )
				)
				( pin "CB(1)"
					( objectStatus "J9M1.194" )
				)
				( pin "CB(2)"
					( objectStatus "J9M1.56" )
				)
				( pin "CB(3)"
					( objectStatus "J9M1.201" )
				)
				( pin "CB(4)"
					( objectStatus "J9M1.47" )
				)
				( pin "CB(5)"
					( objectStatus "J9M1.192" )
				)
				( pin "CB(6)"
					( objectStatus "J9M1.54" )
				)
				( pin "CB(7)"
					( objectStatus "J9M1.199" )
				)
				( pin "CKE(0)"
					( objectStatus "J9M1.60" )
				)
				( pin "CKE(1)"
					( objectStatus "J9M1.203" )
				)
				( pin "DQ(0)"
					( objectStatus "J9M1.5" )
				)
				( pin "DQ(10)"
					( objectStatus "J9M1.23" )
				)
				( pin "DQ(11)"
					( objectStatus "J9M1.168" )
				)
				( pin "DQ(12)"
					( objectStatus "J9M1.14" )
				)
				( pin "DQ(13)"
					( objectStatus "J9M1.159" )
				)
				( pin "DQ(14)"
					( objectStatus "J9M1.21" )
				)
				( pin "DQ(15)"
					( objectStatus "J9M1.166" )
				)
				( pin "DQ(16)"
					( objectStatus "J9M1.27" )
				)
				( pin "DQ(17)"
					( objectStatus "J9M1.172" )
				)
				( pin "DQ(18)"
					( objectStatus "J9M1.34" )
				)
				( pin "DQ(19)"
					( objectStatus "J9M1.179" )
				)
				( pin "DQ(1)"
					( objectStatus "J9M1.150" )
				)
				( pin "DQ(20)"
					( objectStatus "J9M1.25" )
				)
				( pin "DQ(21)"
					( objectStatus "J9M1.170" )
				)
				( pin "DQ(22)"
					( objectStatus "J9M1.32" )
				)
				( pin "DQ(23)"
					( objectStatus "J9M1.177" )
				)
				( pin "DQ(24)"
					( objectStatus "J9M1.38" )
				)
				( pin "DQ(25)"
					( objectStatus "J9M1.183" )
				)
				( pin "DQ(26)"
					( objectStatus "J9M1.45" )
				)
				( pin "DQ(27)"
					( objectStatus "J9M1.190" )
				)
				( pin "DQ(28)"
					( objectStatus "J9M1.36" )
				)
				( pin "DQ(29)"
					( objectStatus "J9M1.181" )
				)
				( pin "DQ(2)"
					( objectStatus "J9M1.12" )
				)
				( pin "DQ(30)"
					( objectStatus "J9M1.43" )
				)
				( pin "DQ(31)"
					( objectStatus "J9M1.188" )
				)
				( pin "DQ(32)"
					( objectStatus "J9M1.97" )
				)
				( pin "DQ(33)"
					( objectStatus "J9M1.242" )
				)
				( pin "DQ(34)"
					( objectStatus "J9M1.104" )
				)
				( pin "DQ(35)"
					( objectStatus "J9M1.249" )
				)
				( pin "DQ(36)"
					( objectStatus "J9M1.95" )
				)
				( pin "DQ(37)"
					( objectStatus "J9M1.240" )
				)
				( pin "DQ(38)"
					( objectStatus "J9M1.102" )
				)
				( pin "DQ(39)"
					( objectStatus "J9M1.247" )
				)
				( pin "DQ(3)"
					( objectStatus "J9M1.157" )
				)
				( pin "DQ(40)"
					( objectStatus "J9M1.108" )
				)
				( pin "DQ(41)"
					( objectStatus "J9M1.253" )
				)
				( pin "DQ(42)"
					( objectStatus "J9M1.115" )
				)
				( pin "DQ(43)"
					( objectStatus "J9M1.260" )
				)
				( pin "DQ(44)"
					( objectStatus "J9M1.106" )
				)
				( pin "DQ(45)"
					( objectStatus "J9M1.251" )
				)
				( pin "DQ(46)"
					( objectStatus "J9M1.113" )
				)
				( pin "DQ(47)"
					( objectStatus "J9M1.258" )
				)
				( pin "DQ(48)"
					( objectStatus "J9M1.119" )
				)
				( pin "DQ(49)"
					( objectStatus "J9M1.264" )
				)
				( pin "DQ(4)"
					( objectStatus "J9M1.3" )
				)
				( pin "DQ(50)"
					( objectStatus "J9M1.126" )
				)
				( pin "DQ(51)"
					( objectStatus "J9M1.271" )
				)
				( pin "DQ(52)"
					( objectStatus "J9M1.117" )
				)
				( pin "DQ(53)"
					( objectStatus "J9M1.262" )
				)
				( pin "DQ(54)"
					( objectStatus "J9M1.124" )
				)
				( pin "DQ(55)"
					( objectStatus "J9M1.269" )
				)
				( pin "DQ(56)"
					( objectStatus "J9M1.130" )
				)
				( pin "DQ(57)"
					( objectStatus "J9M1.275" )
				)
				( pin "DQ(58)"
					( objectStatus "J9M1.137" )
				)
				( pin "DQ(59)"
					( objectStatus "J9M1.282" )
				)
				( pin "DQ(5)"
					( objectStatus "J9M1.148" )
				)
				( pin "DQ(60)"
					( objectStatus "J9M1.128" )
				)
				( pin "DQ(61)"
					( objectStatus "J9M1.273" )
				)
				( pin "DQ(62)"
					( objectStatus "J9M1.135" )
				)
				( pin "DQ(63)"
					( objectStatus "J9M1.280" )
				)
				( pin "DQ(6)"
					( objectStatus "J9M1.10" )
				)
				( pin "DQ(7)"
					( objectStatus "J9M1.155" )
				)
				( pin "DQ(8)"
					( objectStatus "J9M1.16" )
				)
				( pin "DQ(9)"
					( objectStatus "J9M1.161" )
				)
				( pin "ODT(0)"
					( objectStatus "J9M1.87" )
				)
				( pin "ODT(1)"
					( objectStatus "J9M1.91" )
				)
				( pin "PAR"
					( objectStatus "J9M1.222" )
				)
				( pin "S0_N"
					( objectStatus "J9M1.84" )
				)
				( pin "S1_N"
					( objectStatus "J9M1.89" )
				)
				( pin "S2_N_C(0)"
					( objectStatus "J9M1.93" )
				)
				( pin "S3_N_C(1)"
					( objectStatus "J9M1.237" )
				)
			)
			( gate "@baseboard_fab2_lib.baseboard_fab2(sch_1):page84_i102"
				( objectStatus "F199" )
				( pin "DQS0N"
					( objectStatus "J9M1.152" )
				)
				( pin "DQS0P"
					( objectStatus "J9M1.153" )
				)
				( pin "DQS10N"
					( objectStatus "J9M1.19" )
				)
				( pin "DQS10P"
					( objectStatus "J9M1.18" )
				)
				( pin "DQS11N"
					( objectStatus "J9M1.30" )
				)
				( pin "DQS11P"
					( objectStatus "J9M1.29" )
				)
				( pin "DQS12N"
					( objectStatus "J9M1.41" )
				)
				( pin "DQS12P"
					( objectStatus "J9M1.40" )
				)
				( pin "DQS13N"
					( objectStatus "J9M1.100" )
				)
				( pin "DQS13P"
					( objectStatus "J9M1.99" )
				)
				( pin "DQS14N"
					( objectStatus "J9M1.111" )
				)
				( pin "DQS14P"
					( objectStatus "J9M1.110" )
				)
				( pin "DQS15N"
					( objectStatus "J9M1.122" )
				)
				( pin "DQS15P"
					( objectStatus "J9M1.121" )
				)
				( pin "DQS16N"
					( objectStatus "J9M1.133" )
				)
				( pin "DQS16P"
					( objectStatus "J9M1.132" )
				)
				( pin "DQS17N"
					( objectStatus "J9M1.52" )
				)
				( pin "DQS17P"
					( objectStatus "J9M1.51" )
				)
				( pin "DQS1N"
					( objectStatus "J9M1.163" )
				)
				( pin "DQS1P"
					( objectStatus "J9M1.164" )
				)
				( pin "DQS2N"
					( objectStatus "J9M1.174" )
				)
				( pin "DQS2P"
					( objectStatus "J9M1.175" )
				)
				( pin "DQS3N"
					( objectStatus "J9M1.185" )
				)
				( pin "DQS3P"
					( objectStatus "J9M1.186" )
				)
				( pin "DQS4N"
					( objectStatus "J9M1.244" )
				)
				( pin "DQS4P"
					( objectStatus "J9M1.245" )
				)
				( pin "DQS5N"
					( objectStatus "J9M1.255" )
				)
				( pin "DQS5P"
					( objectStatus "J9M1.256" )
				)
				( pin "DQS6N"
					( objectStatus "J9M1.266" )
				)
				( pin "DQS6P"
					( objectStatus "J9M1.267" )
				)
				( pin "DQS7N"
					( objectStatus "J9M1.277" )
				)
				( pin "DQS7P"
					( objectStatus "J9M1.278" )
				)
				( pin "DQS8N"
					( objectStatus "J9M1.196" )
				)
				( pin "DQS8P"
					( objectStatus "J9M1.197" )
				)
				( pin "DQS9N"
					( objectStatus "J9M1.8" )
				)
				( pin "DQS9P"
					( objectStatus "J9M1.7" )
				)
			)
			( gate "@baseboard_fab2_lib.baseboard_fab2(sch_1):page84_i138"
				( objectStatus "F198" )
			)
			( gate "@baseboard_fab2_lib.baseboard_fab2(sch_1):page84_i57"
				( objectStatus "F197" )
			)
			( gate "@baseboard_fab2_lib.baseboard_fab2(sch_1):page86_i12"
				( objectStatus "F204" )
				( pin "A0"
					( objectStatus "J9L2.79" )
				)
				( pin "A1"
					( objectStatus "J9L2.72" )
				)
				( pin "A10"
					( objectStatus "J9L2.225" )
				)
				( pin "A11"
					( objectStatus "J9L2.210" )
				)
				( pin "A12"
					( objectStatus "J9L2.65" )
				)
				( pin "A13"
					( objectStatus "J9L2.232" )
				)
				( pin "A14_WE_N"
					( objectStatus "J9L2.228" )
				)
				( pin "A15_CAS_N"
					( objectStatus "J9L2.86" )
				)
				( pin "A16_RAS_N"
					( objectStatus "J9L2.82" )
				)
				( pin "A17"
					( objectStatus "J9L2.234" )
				)
				( pin "A2"
					( objectStatus "J9L2.216" )
				)
				( pin "A3"
					( objectStatus "J9L2.71" )
				)
				( pin "A4"
					( objectStatus "J9L2.214" )
				)
				( pin "A5"
					( objectStatus "J9L2.213" )
				)
				( pin "A6"
					( objectStatus "J9L2.69" )
				)
				( pin "A7"
					( objectStatus "J9L2.211" )
				)
				( pin "A8"
					( objectStatus "J9L2.68" )
				)
				( pin "A9"
					( objectStatus "J9L2.66" )
				)
				( pin "ACT_N"
					( objectStatus "J9L2.62" )
				)
				( pin "BA(0)"
					( objectStatus "J9L2.81" )
				)
				( pin "BA(1)"
					( objectStatus "J9L2.224" )
				)
				( pin "BG(0)"
					( objectStatus "J9L2.63" )
				)
				( pin "BG(1)"
					( objectStatus "J9L2.207" )
				)
				( pin "C(2)"
					( objectStatus "J9L2.235" )
				)
				( pin "CB(0)"
					( objectStatus "J9L2.49" )
				)
				( pin "CB(1)"
					( objectStatus "J9L2.194" )
				)
				( pin "CB(2)"
					( objectStatus "J9L2.56" )
				)
				( pin "CB(3)"
					( objectStatus "J9L2.201" )
				)
				( pin "CB(4)"
					( objectStatus "J9L2.47" )
				)
				( pin "CB(5)"
					( objectStatus "J9L2.192" )
				)
				( pin "CB(6)"
					( objectStatus "J9L2.54" )
				)
				( pin "CB(7)"
					( objectStatus "J9L2.199" )
				)
				( pin "CKE(0)"
					( objectStatus "J9L2.60" )
				)
				( pin "CKE(1)"
					( objectStatus "J9L2.203" )
				)
				( pin "DQ(0)"
					( objectStatus "J9L2.5" )
				)
				( pin "DQ(10)"
					( objectStatus "J9L2.23" )
				)
				( pin "DQ(11)"
					( objectStatus "J9L2.168" )
				)
				( pin "DQ(12)"
					( objectStatus "J9L2.14" )
				)
				( pin "DQ(13)"
					( objectStatus "J9L2.159" )
				)
				( pin "DQ(14)"
					( objectStatus "J9L2.21" )
				)
				( pin "DQ(15)"
					( objectStatus "J9L2.166" )
				)
				( pin "DQ(16)"
					( objectStatus "J9L2.27" )
				)
				( pin "DQ(17)"
					( objectStatus "J9L2.172" )
				)
				( pin "DQ(18)"
					( objectStatus "J9L2.34" )
				)
				( pin "DQ(19)"
					( objectStatus "J9L2.179" )
				)
				( pin "DQ(1)"
					( objectStatus "J9L2.150" )
				)
				( pin "DQ(20)"
					( objectStatus "J9L2.25" )
				)
				( pin "DQ(21)"
					( objectStatus "J9L2.170" )
				)
				( pin "DQ(22)"
					( objectStatus "J9L2.32" )
				)
				( pin "DQ(23)"
					( objectStatus "J9L2.177" )
				)
				( pin "DQ(24)"
					( objectStatus "J9L2.38" )
				)
				( pin "DQ(25)"
					( objectStatus "J9L2.183" )
				)
				( pin "DQ(26)"
					( objectStatus "J9L2.45" )
				)
				( pin "DQ(27)"
					( objectStatus "J9L2.190" )
				)
				( pin "DQ(28)"
					( objectStatus "J9L2.36" )
				)
				( pin "DQ(29)"
					( objectStatus "J9L2.181" )
				)
				( pin "DQ(2)"
					( objectStatus "J9L2.12" )
				)
				( pin "DQ(30)"
					( objectStatus "J9L2.43" )
				)
				( pin "DQ(31)"
					( objectStatus "J9L2.188" )
				)
				( pin "DQ(32)"
					( objectStatus "J9L2.97" )
				)
				( pin "DQ(33)"
					( objectStatus "J9L2.242" )
				)
				( pin "DQ(34)"
					( objectStatus "J9L2.104" )
				)
				( pin "DQ(35)"
					( objectStatus "J9L2.249" )
				)
				( pin "DQ(36)"
					( objectStatus "J9L2.95" )
				)
				( pin "DQ(37)"
					( objectStatus "J9L2.240" )
				)
				( pin "DQ(38)"
					( objectStatus "J9L2.102" )
				)
				( pin "DQ(39)"
					( objectStatus "J9L2.247" )
				)
				( pin "DQ(3)"
					( objectStatus "J9L2.157" )
				)
				( pin "DQ(40)"
					( objectStatus "J9L2.108" )
				)
				( pin "DQ(41)"
					( objectStatus "J9L2.253" )
				)
				( pin "DQ(42)"
					( objectStatus "J9L2.115" )
				)
				( pin "DQ(43)"
					( objectStatus "J9L2.260" )
				)
				( pin "DQ(44)"
					( objectStatus "J9L2.106" )
				)
				( pin "DQ(45)"
					( objectStatus "J9L2.251" )
				)
				( pin "DQ(46)"
					( objectStatus "J9L2.113" )
				)
				( pin "DQ(47)"
					( objectStatus "J9L2.258" )
				)
				( pin "DQ(48)"
					( objectStatus "J9L2.119" )
				)
				( pin "DQ(49)"
					( objectStatus "J9L2.264" )
				)
				( pin "DQ(4)"
					( objectStatus "J9L2.3" )
				)
				( pin "DQ(50)"
					( objectStatus "J9L2.126" )
				)
				( pin "DQ(51)"
					( objectStatus "J9L2.271" )
				)
				( pin "DQ(52)"
					( objectStatus "J9L2.117" )
				)
				( pin "DQ(53)"
					( objectStatus "J9L2.262" )
				)
				( pin "DQ(54)"
					( objectStatus "J9L2.124" )
				)
				( pin "DQ(55)"
					( objectStatus "J9L2.269" )
				)
				( pin "DQ(56)"
					( objectStatus "J9L2.130" )
				)
				( pin "DQ(57)"
					( objectStatus "J9L2.275" )
				)
				( pin "DQ(58)"
					( objectStatus "J9L2.137" )
				)
				( pin "DQ(59)"
					( objectStatus "J9L2.282" )
				)
				( pin "DQ(5)"
					( objectStatus "J9L2.148" )
				)
				( pin "DQ(60)"
					( objectStatus "J9L2.128" )
				)
				( pin "DQ(61)"
					( objectStatus "J9L2.273" )
				)
				( pin "DQ(62)"
					( objectStatus "J9L2.135" )
				)
				( pin "DQ(63)"
					( objectStatus "J9L2.280" )
				)
				( pin "DQ(6)"
					( objectStatus "J9L2.10" )
				)
				( pin "DQ(7)"
					( objectStatus "J9L2.155" )
				)
				( pin "DQ(8)"
					( objectStatus "J9L2.16" )
				)
				( pin "DQ(9)"
					( objectStatus "J9L2.161" )
				)
				( pin "ODT(0)"
					( objectStatus "J9L2.87" )
				)
				( pin "ODT(1)"
					( objectStatus "J9L2.91" )
				)
				( pin "PAR"
					( objectStatus "J9L2.222" )
				)
				( pin "S0_N"
					( objectStatus "J9L2.84" )
				)
				( pin "S1_N"
					( objectStatus "J9L2.89" )
				)
				( pin "S2_N_C(0)"
					( objectStatus "J9L2.93" )
				)
				( pin "S3_N_C(1)"
					( objectStatus "J9L2.237" )
				)
			)
			( gate "@baseboard_fab2_lib.baseboard_fab2(sch_1):page86_i100"
				( objectStatus "F203" )
				( pin "DQS0N"
					( objectStatus "J9L2.152" )
				)
				( pin "DQS0P"
					( objectStatus "J9L2.153" )
				)
				( pin "DQS10N"
					( objectStatus "J9L2.19" )
				)
				( pin "DQS10P"
					( objectStatus "J9L2.18" )
				)
				( pin "DQS11N"
					( objectStatus "J9L2.30" )
				)
				( pin "DQS11P"
					( objectStatus "J9L2.29" )
				)
				( pin "DQS12N"
					( objectStatus "J9L2.41" )
				)
				( pin "DQS12P"
					( objectStatus "J9L2.40" )
				)
				( pin "DQS13N"
					( objectStatus "J9L2.100" )
				)
				( pin "DQS13P"
					( objectStatus "J9L2.99" )
				)
				( pin "DQS14N"
					( objectStatus "J9L2.111" )
				)
				( pin "DQS14P"
					( objectStatus "J9L2.110" )
				)
				( pin "DQS15N"
					( objectStatus "J9L2.122" )
				)
				( pin "DQS15P"
					( objectStatus "J9L2.121" )
				)
				( pin "DQS16N"
					( objectStatus "J9L2.133" )
				)
				( pin "DQS16P"
					( objectStatus "J9L2.132" )
				)
				( pin "DQS17N"
					( objectStatus "J9L2.52" )
				)
				( pin "DQS17P"
					( objectStatus "J9L2.51" )
				)
				( pin "DQS1N"
					( objectStatus "J9L2.163" )
				)
				( pin "DQS1P"
					( objectStatus "J9L2.164" )
				)
				( pin "DQS2N"
					( objectStatus "J9L2.174" )
				)
				( pin "DQS2P"
					( objectStatus "J9L2.175" )
				)
				( pin "DQS3N"
					( objectStatus "J9L2.185" )
				)
				( pin "DQS3P"
					( objectStatus "J9L2.186" )
				)
				( pin "DQS4N"
					( objectStatus "J9L2.244" )
				)
				( pin "DQS4P"
					( objectStatus "J9L2.245" )
				)
				( pin "DQS5N"
					( objectStatus "J9L2.255" )
				)
				( pin "DQS5P"
					( objectStatus "J9L2.256" )
				)
				( pin "DQS6N"
					( objectStatus "J9L2.266" )
				)
				( pin "DQS6P"
					( objectStatus "J9L2.267" )
				)
				( pin "DQS7N"
					( objectStatus "J9L2.277" )
				)
				( pin "DQS7P"
					( objectStatus "J9L2.278" )
				)
				( pin "DQS8N"
					( objectStatus "J9L2.196" )
				)
				( pin "DQS8P"
					( objectStatus "J9L2.197" )
				)
				( pin "DQS9N"
					( objectStatus "J9L2.8" )
				)
				( pin "DQS9P"
					( objectStatus "J9L2.7" )
				)
			)
			( gate "@baseboard_fab2_lib.baseboard_fab2(sch_1):page86_i138"
				( objectStatus "F202" )
			)
			( gate "@baseboard_fab2_lib.baseboard_fab2(sch_1):page86_i55"
				( objectStatus "F201" )
			)
			( gate "@baseboard_fab2_lib.baseboard_fab2(sch_1):page88_i111"
				( objectStatus "F208" )
				( pin "A0"
					( objectStatus "J9L1.79" )
				)
				( pin "A1"
					( objectStatus "J9L1.72" )
				)
				( pin "A10"
					( objectStatus "J9L1.225" )
				)
				( pin "A11"
					( objectStatus "J9L1.210" )
				)
				( pin "A12"
					( objectStatus "J9L1.65" )
				)
				( pin "A13"
					( objectStatus "J9L1.232" )
				)
				( pin "A14_WE_N"
					( objectStatus "J9L1.228" )
				)
				( pin "A15_CAS_N"
					( objectStatus "J9L1.86" )
				)
				( pin "A16_RAS_N"
					( objectStatus "J9L1.82" )
				)
				( pin "A17"
					( objectStatus "J9L1.234" )
				)
				( pin "A2"
					( objectStatus "J9L1.216" )
				)
				( pin "A3"
					( objectStatus "J9L1.71" )
				)
				( pin "A4"
					( objectStatus "J9L1.214" )
				)
				( pin "A5"
					( objectStatus "J9L1.213" )
				)
				( pin "A6"
					( objectStatus "J9L1.69" )
				)
				( pin "A7"
					( objectStatus "J9L1.211" )
				)
				( pin "A8"
					( objectStatus "J9L1.68" )
				)
				( pin "A9"
					( objectStatus "J9L1.66" )
				)
				( pin "ACT_N"
					( objectStatus "J9L1.62" )
				)
				( pin "BA(0)"
					( objectStatus "J9L1.81" )
				)
				( pin "BA(1)"
					( objectStatus "J9L1.224" )
				)
				( pin "BG(0)"
					( objectStatus "J9L1.63" )
				)
				( pin "BG(1)"
					( objectStatus "J9L1.207" )
				)
				( pin "C(2)"
					( objectStatus "J9L1.235" )
				)
				( pin "CB(0)"
					( objectStatus "J9L1.49" )
				)
				( pin "CB(1)"
					( objectStatus "J9L1.194" )
				)
				( pin "CB(2)"
					( objectStatus "J9L1.56" )
				)
				( pin "CB(3)"
					( objectStatus "J9L1.201" )
				)
				( pin "CB(4)"
					( objectStatus "J9L1.47" )
				)
				( pin "CB(5)"
					( objectStatus "J9L1.192" )
				)
				( pin "CB(6)"
					( objectStatus "J9L1.54" )
				)
				( pin "CB(7)"
					( objectStatus "J9L1.199" )
				)
				( pin "CKE(0)"
					( objectStatus "J9L1.60" )
				)
				( pin "CKE(1)"
					( objectStatus "J9L1.203" )
				)
				( pin "DQ(0)"
					( objectStatus "J9L1.5" )
				)
				( pin "DQ(10)"
					( objectStatus "J9L1.23" )
				)
				( pin "DQ(11)"
					( objectStatus "J9L1.168" )
				)
				( pin "DQ(12)"
					( objectStatus "J9L1.14" )
				)
				( pin "DQ(13)"
					( objectStatus "J9L1.159" )
				)
				( pin "DQ(14)"
					( objectStatus "J9L1.21" )
				)
				( pin "DQ(15)"
					( objectStatus "J9L1.166" )
				)
				( pin "DQ(16)"
					( objectStatus "J9L1.27" )
				)
				( pin "DQ(17)"
					( objectStatus "J9L1.172" )
				)
				( pin "DQ(18)"
					( objectStatus "J9L1.34" )
				)
				( pin "DQ(19)"
					( objectStatus "J9L1.179" )
				)
				( pin "DQ(1)"
					( objectStatus "J9L1.150" )
				)
				( pin "DQ(20)"
					( objectStatus "J9L1.25" )
				)
				( pin "DQ(21)"
					( objectStatus "J9L1.170" )
				)
				( pin "DQ(22)"
					( objectStatus "J9L1.32" )
				)
				( pin "DQ(23)"
					( objectStatus "J9L1.177" )
				)
				( pin "DQ(24)"
					( objectStatus "J9L1.38" )
				)
				( pin "DQ(25)"
					( objectStatus "J9L1.183" )
				)
				( pin "DQ(26)"
					( objectStatus "J9L1.45" )
				)
				( pin "DQ(27)"
					( objectStatus "J9L1.190" )
				)
				( pin "DQ(28)"
					( objectStatus "J9L1.36" )
				)
				( pin "DQ(29)"
					( objectStatus "J9L1.181" )
				)
				( pin "DQ(2)"
					( objectStatus "J9L1.12" )
				)
				( pin "DQ(30)"
					( objectStatus "J9L1.43" )
				)
				( pin "DQ(31)"
					( objectStatus "J9L1.188" )
				)
				( pin "DQ(32)"
					( objectStatus "J9L1.97" )
				)
				( pin "DQ(33)"
					( objectStatus "J9L1.242" )
				)
				( pin "DQ(34)"
					( objectStatus "J9L1.104" )
				)
				( pin "DQ(35)"
					( objectStatus "J9L1.249" )
				)
				( pin "DQ(36)"
					( objectStatus "J9L1.95" )
				)
				( pin "DQ(37)"
					( objectStatus "J9L1.240" )
				)
				( pin "DQ(38)"
					( objectStatus "J9L1.102" )
				)
				( pin "DQ(39)"
					( objectStatus "J9L1.247" )
				)
				( pin "DQ(3)"
					( objectStatus "J9L1.157" )
				)
				( pin "DQ(40)"
					( objectStatus "J9L1.108" )
				)
				( pin "DQ(41)"
					( objectStatus "J9L1.253" )
				)
				( pin "DQ(42)"
					( objectStatus "J9L1.115" )
				)
				( pin "DQ(43)"
					( objectStatus "J9L1.260" )
				)
				( pin "DQ(44)"
					( objectStatus "J9L1.106" )
				)
				( pin "DQ(45)"
					( objectStatus "J9L1.251" )
				)
				( pin "DQ(46)"
					( objectStatus "J9L1.113" )
				)
				( pin "DQ(47)"
					( objectStatus "J9L1.258" )
				)
				( pin "DQ(48)"
					( objectStatus "J9L1.119" )
				)
				( pin "DQ(49)"
					( objectStatus "J9L1.264" )
				)
				( pin "DQ(4)"
					( objectStatus "J9L1.3" )
				)
				( pin "DQ(50)"
					( objectStatus "J9L1.126" )
				)
				( pin "DQ(51)"
					( objectStatus "J9L1.271" )
				)
				( pin "DQ(52)"
					( objectStatus "J9L1.117" )
				)
				( pin "DQ(53)"
					( objectStatus "J9L1.262" )
				)
				( pin "DQ(54)"
					( objectStatus "J9L1.124" )
				)
				( pin "DQ(55)"
					( objectStatus "J9L1.269" )
				)
				( pin "DQ(56)"
					( objectStatus "J9L1.130" )
				)
				( pin "DQ(57)"
					( objectStatus "J9L1.275" )
				)
				( pin "DQ(58)"
					( objectStatus "J9L1.137" )
				)
				( pin "DQ(59)"
					( objectStatus "J9L1.282" )
				)
				( pin "DQ(5)"
					( objectStatus "J9L1.148" )
				)
				( pin "DQ(60)"
					( objectStatus "J9L1.128" )
				)
				( pin "DQ(61)"
					( objectStatus "J9L1.273" )
				)
				( pin "DQ(62)"
					( objectStatus "J9L1.135" )
				)
				( pin "DQ(63)"
					( objectStatus "J9L1.280" )
				)
				( pin "DQ(6)"
					( objectStatus "J9L1.10" )
				)
				( pin "DQ(7)"
					( objectStatus "J9L1.155" )
				)
				( pin "DQ(8)"
					( objectStatus "J9L1.16" )
				)
				( pin "DQ(9)"
					( objectStatus "J9L1.161" )
				)
				( pin "ODT(0)"
					( objectStatus "J9L1.87" )
				)
				( pin "ODT(1)"
					( objectStatus "J9L1.91" )
				)
				( pin "PAR"
					( objectStatus "J9L1.222" )
				)
				( pin "S0_N"
					( objectStatus "J9L1.84" )
				)
				( pin "S1_N"
					( objectStatus "J9L1.89" )
				)
				( pin "S2_N_C(0)"
					( objectStatus "J9L1.93" )
				)
				( pin "S3_N_C(1)"
					( objectStatus "J9L1.237" )
				)
			)
			( gate "@baseboard_fab2_lib.baseboard_fab2(sch_1):page88_i87"
				( objectStatus "F207" )
				( pin "DQS0N"
					( objectStatus "J9L1.152" )
				)
				( pin "DQS0P"
					( objectStatus "J9L1.153" )
				)
				( pin "DQS10N"
					( objectStatus "J9L1.19" )
				)
				( pin "DQS10P"
					( objectStatus "J9L1.18" )
				)
				( pin "DQS11N"
					( objectStatus "J9L1.30" )
				)
				( pin "DQS11P"
					( objectStatus "J9L1.29" )
				)
				( pin "DQS12N"
					( objectStatus "J9L1.41" )
				)
				( pin "DQS12P"
					( objectStatus "J9L1.40" )
				)
				( pin "DQS13N"
					( objectStatus "J9L1.100" )
				)
				( pin "DQS13P"
					( objectStatus "J9L1.99" )
				)
				( pin "DQS14N"
					( objectStatus "J9L1.111" )
				)
				( pin "DQS14P"
					( objectStatus "J9L1.110" )
				)
				( pin "DQS15N"
					( objectStatus "J9L1.122" )
				)
				( pin "DQS15P"
					( objectStatus "J9L1.121" )
				)
				( pin "DQS16N"
					( objectStatus "J9L1.133" )
				)
				( pin "DQS16P"
					( objectStatus "J9L1.132" )
				)
				( pin "DQS17N"
					( objectStatus "J9L1.52" )
				)
				( pin "DQS17P"
					( objectStatus "J9L1.51" )
				)
				( pin "DQS1N"
					( objectStatus "J9L1.163" )
				)
				( pin "DQS1P"
					( objectStatus "J9L1.164" )
				)
				( pin "DQS2N"
					( objectStatus "J9L1.174" )
				)
				( pin "DQS2P"
					( objectStatus "J9L1.175" )
				)
				( pin "DQS3N"
					( objectStatus "J9L1.185" )
				)
				( pin "DQS3P"
					( objectStatus "J9L1.186" )
				)
				( pin "DQS4N"
					( objectStatus "J9L1.244" )
				)
				( pin "DQS4P"
					( objectStatus "J9L1.245" )
				)
				( pin "DQS5N"
					( objectStatus "J9L1.255" )
				)
				( pin "DQS5P"
					( objectStatus "J9L1.256" )
				)
				( pin "DQS6N"
					( objectStatus "J9L1.266" )
				)
				( pin "DQS6P"
					( objectStatus "J9L1.267" )
				)
				( pin "DQS7N"
					( objectStatus "J9L1.277" )
				)
				( pin "DQS7P"
					( objectStatus "J9L1.278" )
				)
				( pin "DQS8N"
					( objectStatus "J9L1.196" )
				)
				( pin "DQS8P"
					( objectStatus "J9L1.197" )
				)
				( pin "DQS9N"
					( objectStatus "J9L1.8" )
				)
				( pin "DQS9P"
					( objectStatus "J9L1.7" )
				)
			)
			( gate "@baseboard_fab2_lib.baseboard_fab2(sch_1):page88_i25"
				( objectStatus "F206" )
			)
			( gate "@baseboard_fab2_lib.baseboard_fab2(sch_1):page88_i168"
				( objectStatus "F205" )
			)
			( gate "@baseboard_fab2_lib.baseboard_fab2(sch_1):page187_i119"
				( objectStatus "F132" )
				( pin "IO10"
					( objectStatus "J8E3.10" )
				)
				( pin "IO12"
					( objectStatus "J8E3.12" )
				)
				( pin "IO13"
					( objectStatus "J8E3.13" )
				)
				( pin "IO15"
					( objectStatus "J8E3.15" )
				)
				( pin "IO18"
					( objectStatus "J8E3.18" )
				)
				( pin "IO20"
					( objectStatus "J8E3.20" )
				)
				( pin "IO21"
					( objectStatus "J8E3.21" )
				)
				( pin "IO23"
					( objectStatus "J8E3.23" )
				)
				( pin "IO26"
					( objectStatus "J8E3.26" )
				)
				( pin "IO28"
					( objectStatus "J8E3.28" )
				)
				( pin "IO29"
					( objectStatus "J8E3.29" )
				)
				( pin "IO31"
					( objectStatus "J8E3.31" )
				)
				( pin "IO34"
					( objectStatus "J8E3.34" )
				)
				( pin "IO36"
					( objectStatus "J8E3.36" )
				)
				( pin "IO37"
					( objectStatus "J8E3.37" )
				)
				( pin "IO39"
					( objectStatus "J8E3.39" )
				)
				( pin "IO42"
					( objectStatus "J8E3.42" )
				)
				( pin "IO44"
					( objectStatus "J8E3.44" )
				)
				( pin "IO45"
					( objectStatus "J8E3.45" )
				)
				( pin "IO47"
					( objectStatus "J8E3.47" )
				)
				( pin "IO5"
					( objectStatus "J8E3.5" )
				)
				( pin "IO50"
					( objectStatus "J8E3.50" )
				)
				( pin "IO52"
					( objectStatus "J8E3.52" )
				)
				( pin "IO53"
					( objectStatus "J8E3.53" )
				)
				( pin "IO55"
					( objectStatus "J8E3.55" )
				)
				( pin "IO58"
					( objectStatus "J8E3.58" )
				)
				( pin "IO60"
					( objectStatus "J8E3.60" )
				)
				( pin "IO61"
					( objectStatus "J8E3.61" )
				)
				( pin "IO63"
					( objectStatus "J8E3.63" )
				)
				( pin "IO66"
					( objectStatus "J8E3.66" )
				)
				( pin "IO68"
					( objectStatus "J8E3.68" )
				)
				( pin "IO69"
					( objectStatus "J8E3.69" )
				)
				( pin "IO7"
					( objectStatus "J8E3.7" )
				)
				( pin "IO71"
					( objectStatus "J8E3.71" )
				)
				( pin "IO74"
					( objectStatus "J8E3.74" )
				)
				( pin "IO76"
					( objectStatus "J8E3.76" )
				)
			)
			( gate "@baseboard_fab2_lib.baseboard_fab2(sch_1):page194_i156"
				( objectStatus "F1063" )
			)
			( gate "@baseboard_fab2_lib.baseboard_fab2(sch_1):page199_i102"
				( objectStatus "F1064" )
			)
			( gate "@baseboard_fab2_lib.baseboard_fab2(sch_1):page223_i78"
				( objectStatus "F388" )
			)
			( gate "@baseboard_fab2_lib.baseboard_fab2(sch_1):page226_i77"
				( objectStatus "F389" )
			)
			( gate "@baseboard_fab2_lib.baseboard_fab2(sch_1):page186_i336"
				( objectStatus "F240" )
				( pin "IO101"
					( objectStatus "J9B3.101" )
				)
				( pin "IO104"
					( objectStatus "J9B3.104" )
				)
				( pin "IO106"
					( objectStatus "J9B3.106" )
				)
				( pin "IO107"
					( objectStatus "J9B3.107" )
				)
				( pin "IO109"
					( objectStatus "J9B3.109" )
				)
				( pin "IO112"
					( objectStatus "J9B3.112" )
				)
				( pin "IO114"
					( objectStatus "J9B3.114" )
				)
				( pin "IO115"
					( objectStatus "J9B3.115" )
				)
				( pin "IO117"
					( objectStatus "J9B3.117" )
				)
				( pin "IO30"
					( objectStatus "J9B3.30" )
				)
				( pin "IO32"
					( objectStatus "J9B3.32" )
				)
				( pin "IO35"
					( objectStatus "J9B3.35" )
				)
				( pin "IO37"
					( objectStatus "J9B3.37" )
				)
				( pin "IO48"
					( objectStatus "J9B3.48" )
				)
				( pin "IO50"
					( objectStatus "J9B3.50" )
				)
				( pin "IO51"
					( objectStatus "J9B3.51" )
				)
				( pin "IO53"
					( objectStatus "J9B3.53" )
				)
				( pin "IO56"
					( objectStatus "J9B3.56" )
				)
				( pin "IO58"
					( objectStatus "J9B3.58" )
				)
				( pin "IO59"
					( objectStatus "J9B3.59" )
				)
				( pin "IO61"
					( objectStatus "J9B3.61" )
				)
				( pin "IO64"
					( objectStatus "J9B3.64" )
				)
				( pin "IO66"
					( objectStatus "J9B3.66" )
				)
				( pin "IO67"
					( objectStatus "J9B3.67" )
				)
				( pin "IO69"
					( objectStatus "J9B3.69" )
				)
				( pin "IO72"
					( objectStatus "J9B3.72" )
				)
				( pin "IO74"
					( objectStatus "J9B3.74" )
				)
				( pin "IO75"
					( objectStatus "J9B3.75" )
				)
				( pin "IO77"
					( objectStatus "J9B3.77" )
				)
				( pin "IO80"
					( objectStatus "J9B3.80" )
				)
				( pin "IO82"
					( objectStatus "J9B3.82" )
				)
				( pin "IO83"
					( objectStatus "J9B3.83" )
				)
				( pin "IO85"
					( objectStatus "J9B3.85" )
				)
				( pin "IO88"
					( objectStatus "J9B3.88" )
				)
				( pin "IO90"
					( objectStatus "J9B3.90" )
				)
				( pin "IO91"
					( objectStatus "J9B3.91" )
				)
				( pin "IO93"
					( objectStatus "J9B3.93" )
				)
				( pin "IO96"
					( objectStatus "J9B3.96" )
				)
				( pin "IO98"
					( objectStatus "J9B3.98" )
				)
				( pin "IO99"
					( objectStatus "J9B3.99" )
				)
			)
			( gate "@baseboard_fab2_lib.baseboard_fab2(sch_1):page111_i94"
				( objectStatus "F1998" )
				( pin "E(0)"
					( objectStatus "Q9A1.4" )
				)
			)
			( gate "@baseboard_fab2_lib.baseboard_fab2(sch_1):page111_i93"
				( objectStatus "F1997" )
				( pin "E(0)"
					( objectStatus "Q9A1.1" )
				)
			)
			( gate "@baseboard_fab2_lib.baseboard_fab2(sch_1):page161_i50"
				( objectStatus "F2216" )
			)
			( gate "@baseboard_fab2_lib.baseboard_fab2(sch_1):page161_i64"
				( objectStatus "F2217" )
				( pin "A"
					( objectStatus "CR1B1.2" )
				)
			)
			( gate "@baseboard_fab2_lib.baseboard_fab2(sch_1):page184_i104"
				( objectStatus "F66" )
			)
			( gate "@baseboard_fab2_lib.baseboard_fab2(sch_1):page172_i25"
				( objectStatus "F2244" )
				( pin "IO2"
					( objectStatus "J8A4.2" )
				)
				( pin "IO3"
					( objectStatus "J8A4.3" )
				)
				( pin "IO4"
					( objectStatus "J8A4.4" )
				)
			)
			( gate "@baseboard_fab2_lib.baseboard_fab2(sch_1):page161_i133"
				( objectStatus "F2212" )
			)
			( gate "@baseboard_fab2_lib.baseboard_fab2(sch_1):page161_i123"
				( objectStatus "F2214" )
			)
			( gate "@baseboard_fab2_lib.baseboard_fab2(sch_1):page161_i42"
				( objectStatus "F2213" )
				( pin "A"
					( objectStatus "CR1F1.2" )
				)
				( pin "C"
					( objectStatus "CR1F1.1" )
				)
			)
			( gate "@baseboard_fab2_lib.baseboard_fab2(sch_1):page161_i62"
				( objectStatus "F2215" )
				( pin "A"
					( objectStatus "CR1B2.2" )
				)
				( pin "C"
					( objectStatus "CR1B2.1" )
				)
			)
			( gate "@baseboard_fab2_lib.baseboard_fab2(sch_1):page181_i178"
				( objectStatus "F2210" )
			)
			( gate "@baseboard_fab2_lib.baseboard_fab2(sch_1):page181_i180"
				( objectStatus "F2211" )
			)
			( gate "@baseboard_fab2_lib.baseboard_fab2(sch_1):page201_i102"
				( objectStatus "F1036" )
			)
			( gate "@baseboard_fab2_lib.baseboard_fab2(sch_1):page201_i103"
				( objectStatus "F1035" )
			)
			( gate "@baseboard_fab2_lib.baseboard_fab2(sch_1):page199_i85"
				( objectStatus "F315" )
			)
			( gate "@baseboard_fab2_lib.baseboard_fab2(sch_1):page199_i9"
				( objectStatus "F314" )
			)
			( gate "@baseboard_fab2_lib.baseboard_fab2(sch_1):page200_i173"
				( objectStatus "F1111" )
			)
			( gate "@baseboard_fab2_lib.baseboard_fab2(sch_1):page155_i191"
				( objectStatus "F901" )
			)
			( gate "@baseboard_fab2_lib.baseboard_fab2(sch_1):page177_i33"
				( objectStatus "F759" )
			)
			( gate "@baseboard_fab2_lib.baseboard_fab2(sch_1):page200_i155"
				( objectStatus "F2286" )
			)
			( gate "@baseboard_fab2_lib.baseboard_fab2(sch_1):page189_i47"
				( objectStatus "F2235" )
				( pin "IO1"
					( objectStatus "J7G2.1" )
				)
				( pin "IO2"
					( objectStatus "J7G2.2" )
				)
				( pin "IO3"
					( objectStatus "J7G2.3" )
				)
				( pin "IO4"
					( objectStatus "J7G2.4" )
				)
				( pin "IO5"
					( objectStatus "J7G2.5" )
				)
				( pin "IO6"
					( objectStatus "J7G2.6" )
				)
				( pin "IO7"
					( objectStatus "J7G2.7" )
				)
				( pin "IO8"
					( objectStatus "J7G2.8" )
				)
			)
			( gate "@baseboard_fab2_lib.baseboard_fab2(sch_1):page234_i210"
				( objectStatus "F4104" )
			)
			( gate "@baseboard_fab2_lib.baseboard_fab2(sch_1):page231_i217"
				( objectStatus "F4105" )
			)
			( gate "@baseboard_fab2_lib.baseboard_fab2(sch_1):page232_i267"
				( objectStatus "F4106" )
			)
			( gate "@baseboard_fab2_lib.baseboard_fab2(sch_1):page233_i256"
				( objectStatus "F4107" )
			)
			( gate "@baseboard_fab2_lib.baseboard_fab2(sch_1):page193_i140"
				( objectStatus "F2730" )
			)
			( gate "@baseboard_fab2_lib.baseboard_fab2(sch_1):page193_i141"
				( objectStatus "F2727" )
			)
			( gate "@baseboard_fab2_lib.baseboard_fab2(sch_1):page194_i150"
				( objectStatus "F2728" )
			)
			( gate "@baseboard_fab2_lib.baseboard_fab2(sch_1):page194_i149"
				( objectStatus "F2729" )
			)
			( gate "@baseboard_fab2_lib.baseboard_fab2(sch_1):page217_i212"
				( objectStatus "F2710" )
			)
			( gate "@baseboard_fab2_lib.baseboard_fab2(sch_1):page217_i211"
				( objectStatus "F2707" )
			)
			( gate "@baseboard_fab2_lib.baseboard_fab2(sch_1):page217_i210"
				( objectStatus "F2706" )
			)
			( gate "@baseboard_fab2_lib.baseboard_fab2(sch_1):page217_i209"
				( objectStatus "F2705" )
			)
			( gate "@baseboard_fab2_lib.baseboard_fab2(sch_1):page217_i208"
				( objectStatus "F2709" )
			)
			( gate "@baseboard_fab2_lib.baseboard_fab2(sch_1):page225_i200"
				( objectStatus "F2731" )
			)
			( gate "@baseboard_fab2_lib.baseboard_fab2(sch_1):page225_i201"
				( objectStatus "F2734" )
			)
			( gate "@baseboard_fab2_lib.baseboard_fab2(sch_1):page225_i202"
				( objectStatus "F2693" )
			)
			( gate "@baseboard_fab2_lib.baseboard_fab2(sch_1):page225_i203"
				( objectStatus "F2688" )
			)
			( gate "@baseboard_fab2_lib.baseboard_fab2(sch_1):page225_i204"
				( objectStatus "F2689" )
			)
			( gate "@baseboard_fab2_lib.baseboard_fab2(sch_1):page228_i202"
				( objectStatus "F2702" )
			)
			( gate "@baseboard_fab2_lib.baseboard_fab2(sch_1):page228_i203"
				( objectStatus "F2695" )
			)
			( gate "@baseboard_fab2_lib.baseboard_fab2(sch_1):page228_i204"
				( objectStatus "F2735" )
			)
			( gate "@baseboard_fab2_lib.baseboard_fab2(sch_1):page228_i205"
				( objectStatus "F2696" )
			)
			( gate "@baseboard_fab2_lib.baseboard_fab2(sch_1):page228_i206"
				( objectStatus "F2698" )
			)
			( gate "@baseboard_fab2_lib.baseboard_fab2(sch_1):page220_i199"
				( objectStatus "F2715" )
			)
			( gate "@baseboard_fab2_lib.baseboard_fab2(sch_1):page220_i200"
				( objectStatus "F2712" )
			)
			( gate "@baseboard_fab2_lib.baseboard_fab2(sch_1):page221_i52"
				( objectStatus "F2703" )
			)
			( gate "@baseboard_fab2_lib.baseboard_fab2(sch_1):page221_i50"
				( objectStatus "F2704" )
			)
			( gate "@baseboard_fab2_lib.baseboard_fab2(sch_1):page221_i51"
				( objectStatus "F2708" )
			)
			( gate "@baseboard_fab2_lib.baseboard_fab2(sch_1):page222_i47"
				( objectStatus "F2718" )
			)
			( gate "@baseboard_fab2_lib.baseboard_fab2(sch_1):page222_i48"
				( objectStatus "F2711" )
			)
			( gate "@baseboard_fab2_lib.baseboard_fab2(sch_1):page222_i49"
				( objectStatus "F2717" )
			)
			( gate "@baseboard_fab2_lib.baseboard_fab2(sch_1):page229_i47"
				( objectStatus "F2733" )
			)
			( gate "@baseboard_fab2_lib.baseboard_fab2(sch_1):page229_i48"
				( objectStatus "F2691" )
			)
			( gate "@baseboard_fab2_lib.baseboard_fab2(sch_1):page229_i49"
				( objectStatus "F2687" )
			)
			( gate "@baseboard_fab2_lib.baseboard_fab2(sch_1):page230_i47"
				( objectStatus "F2694" )
			)
			( gate "@baseboard_fab2_lib.baseboard_fab2(sch_1):page230_i48"
				( objectStatus "F2701" )
			)
			( gate "@baseboard_fab2_lib.baseboard_fab2(sch_1):page230_i49"
				( objectStatus "F2700" )
			)
			( gate "@baseboard_fab2_lib.baseboard_fab2(sch_1):page220_i196"
				( objectStatus "F2726" )
			)
			( gate "@baseboard_fab2_lib.baseboard_fab2(sch_1):page220_i195"
				( objectStatus "F2714" )
			)
			( gate "@baseboard_fab2_lib.baseboard_fab2(sch_1):page220_i198"
				( objectStatus "F2713" )
			)
			( gate "@baseboard_fab2_lib.baseboard_fab2(sch_1):page217_i205"
				( objectStatus "F2721" )
			)
			( gate "@baseboard_fab2_lib.baseboard_fab2(sch_1):page217_i206"
				( objectStatus "F2722" )
			)
			( gate "@baseboard_fab2_lib.baseboard_fab2(sch_1):page217_i207"
				( objectStatus "F2720" )
			)
			( gate "@baseboard_fab2_lib.baseboard_fab2(sch_1):page220_i192"
				( objectStatus "F2716" )
			)
			( gate "@baseboard_fab2_lib.baseboard_fab2(sch_1):page220_i197"
				( objectStatus "F2723" )
			)
			( gate "@baseboard_fab2_lib.baseboard_fab2(sch_1):page220_i193"
				( objectStatus "F2725" )
			)
			( gate "@baseboard_fab2_lib.baseboard_fab2(sch_1):page220_i194"
				( objectStatus "F2724" )
			)
			( gate "@baseboard_fab2_lib.baseboard_fab2(sch_1):page225_i199"
				( objectStatus "F2686" )
			)
			( gate "@baseboard_fab2_lib.baseboard_fab2(sch_1):page225_i196"
				( objectStatus "F2690" )
			)
			( gate "@baseboard_fab2_lib.baseboard_fab2(sch_1):page225_i197"
				( objectStatus "F2732" )
			)
			( gate "@baseboard_fab2_lib.baseboard_fab2(sch_1):page225_i198"
				( objectStatus "F2692" )
			)
			( gate "@baseboard_fab2_lib.baseboard_fab2(sch_1):page228_i201"
				( objectStatus "F2699" )
			)
			( gate "@baseboard_fab2_lib.baseboard_fab2(sch_1):page228_i198"
				( objectStatus "F2697" )
			)
			( gate "@baseboard_fab2_lib.baseboard_fab2(sch_1):page228_i199"
				( objectStatus "F2737" )
			)
			( gate "@baseboard_fab2_lib.baseboard_fab2(sch_1):page228_i200"
				( objectStatus "F2736" )
			)
			( gate "@baseboard_fab2_lib.baseboard_fab2(sch_1):page217_i213"
				( objectStatus "F2719" )
			)
			( gate "@baseboard_fab2_lib.baseboard_fab2(sch_1):page195_i82"
				( objectStatus "F4108" )
			)
			( gate "@baseboard_fab2_lib.baseboard_fab2(sch_1):page195_i83"
				( objectStatus "F4109" )
			)
			( gate "@baseboard_fab2_lib.baseboard_fab2(sch_1):page195_i84"
				( objectStatus "F4111" )
			)
			( gate "@baseboard_fab2_lib.baseboard_fab2(sch_1):page195_i85"
				( objectStatus "F4110" )
			)
			( gate "@baseboard_fab2_lib.baseboard_fab2(sch_1):page172_i38"
				( objectStatus "F2128" )
			)
			( gate "@baseboard_fab2_lib.baseboard_fab2(sch_1):page172_i41"
				( objectStatus "F2127" )
			)
			( gate "@baseboard_fab2_lib.baseboard_fab2(sch_1):page145_i133"
				( objectStatus "F659" )
			)
			( gate "@baseboard_fab2_lib.baseboard_fab2(sch_1):page155_i171"
				( objectStatus "F2253" )
				( pin "IO1"
					( objectStatus "J9A2.1" )
				)
				( pin "IO10"
					( objectStatus "J9A2.10" )
				)
				( pin "IO11"
					( objectStatus "J9A2.11" )
				)
				( pin "IO12"
					( objectStatus "J9A2.12" )
				)
				( pin "IO13"
					( objectStatus "J9A2.13" )
				)
				( pin "IO14"
					( objectStatus "J9A2.14" )
				)
				( pin "IO2"
					( objectStatus "J9A2.2" )
				)
				( pin "IO3"
					( objectStatus "J9A2.3" )
				)
				( pin "IO4"
					( objectStatus "J9A2.4" )
				)
				( pin "IO5"
					( objectStatus "J9A2.5" )
				)
				( pin "IO6"
					( objectStatus "J9A2.6" )
				)
				( pin "IO7"
					( objectStatus "J9A2.7" )
				)
				( pin "IO8"
					( objectStatus "J9A2.8" )
				)
				( pin "IO9"
					( objectStatus "J9A2.9" )
				)
			)
			( gate "@baseboard_fab2_lib.baseboard_fab2(sch_1):page195_i26"
				( objectStatus "F2246" )
			)
			( gate "@baseboard_fab2_lib.baseboard_fab2(sch_1):page134_i22"
				( objectStatus "F2245" )
				( pin "IO1"
					( objectStatus "J9A1.1" )
				)
				( pin "IO2"
					( objectStatus "J9A1.2" )
				)
				( pin "IO3"
					( objectStatus "J9A1.3" )
				)
				( pin "IO4"
					( objectStatus "J9A1.4" )
				)
			)
			( gate "@baseboard_fab2_lib.baseboard_fab2(sch_1):page181_i189"
				( objectStatus "F2234" )
				( pin "IO1"
					( objectStatus "J1F3.1" )
				)
				( pin "IO2"
					( objectStatus "J1F3.2" )
				)
				( pin "IO3"
					( objectStatus "J1F3.3" )
				)
				( pin "IO4"
					( objectStatus "J1F3.4" )
				)
				( pin "IO5"
					( objectStatus "J1F3.5" )
				)
				( pin "IO6"
					( objectStatus "J1F3.6" )
				)
				( pin "IO7"
					( objectStatus "J1F3.7" )
				)
				( pin "IO8"
					( objectStatus "J1F3.8" )
				)
			)
			( gate "@baseboard_fab2_lib.baseboard_fab2(sch_1):page176_i69"
				( objectStatus "F2233" )
				( pin "DN"
					( objectStatus "J9B1.2" )
				)
				( pin "DP"
					( objectStatus "J9B1.3" )
				)
				( pin "GND"
					( objectStatus "J9B1.4" )
				)
				( pin "GND_DRAIN"
					( objectStatus "J9B1.7" )
				)
				( pin "MH1"
					( objectStatus "J9B1.MH1" )
				)
				( pin "MH2"
					( objectStatus "J9B1.MH2" )
				)
				( pin "MH3"
					( objectStatus "J9B1.MH3" )
				)
				( pin "MH4"
					( objectStatus "J9B1.MH4" )
				)
				( pin "STDA_SSRXN"
					( objectStatus "J9B1.5" )
				)
				( pin "STDA_SSRXP"
					( objectStatus "J9B1.6" )
				)
				( pin "STDA_SSTXN"
					( objectStatus "J9B1.8" )
				)
				( pin "STDA_SSTXP"
					( objectStatus "J9B1.9" )
				)
				( pin "VBUS"
					( objectStatus "J9B1.1" )
				)
			)
			( gate "@baseboard_fab2_lib.baseboard_fab2(sch_1):page241_i54"
				( objectStatus "F844" )
			)
			( gate "@baseboard_fab2_lib.baseboard_fab2(sch_1):page158_i134"
				( objectStatus "F2030" )
			)
			( gate "@baseboard_fab2_lib.baseboard_fab2(sch_1):page158_i130"
				( objectStatus "F2031" )
			)
			( gate "@baseboard_fab2_lib.baseboard_fab2(sch_1):page175_i57"
				( objectStatus "F21" )
			)
			( gate "@baseboard_fab2_lib.baseboard_fab2(sch_1):page195_i100"
				( objectStatus "F4125" )
			)
			( gate "@baseboard_fab2_lib.baseboard_fab2(sch_1):page195_i113"
				( objectStatus "F4124" )
			)
			( gate "@baseboard_fab2_lib.baseboard_fab2(sch_1):page195_i96"
				( objectStatus "F4118" )
			)
			( gate "@baseboard_fab2_lib.baseboard_fab2(sch_1):page195_i112"
				( objectStatus "F4119" )
			)
			( gate "@baseboard_fab2_lib.baseboard_fab2(sch_1):page195_i97"
				( objectStatus "F4120" )
			)
			( gate "@baseboard_fab2_lib.baseboard_fab2(sch_1):page195_i111"
				( objectStatus "F4112" )
			)
			( gate "@baseboard_fab2_lib.baseboard_fab2(sch_1):page195_i103"
				( objectStatus "F4127" )
			)
			( gate "@baseboard_fab2_lib.baseboard_fab2(sch_1):page195_i109"
				( objectStatus "F4115" )
			)
			( gate "@baseboard_fab2_lib.baseboard_fab2(sch_1):page195_i101"
				( objectStatus "F4126" )
			)
			( gate "@baseboard_fab2_lib.baseboard_fab2(sch_1):page195_i108"
				( objectStatus "F4114" )
			)
			( gate "@baseboard_fab2_lib.baseboard_fab2(sch_1):page195_i99"
				( objectStatus "F4113" )
			)
			( gate "@baseboard_fab2_lib.baseboard_fab2(sch_1):page195_i104"
				( objectStatus "F4122" )
			)
			( gate "@baseboard_fab2_lib.baseboard_fab2(sch_1):page195_i98"
				( objectStatus "F4123" )
			)
			( gate "@baseboard_fab2_lib.baseboard_fab2(sch_1):page195_i106"
				( objectStatus "F4121" )
			)
			( gate "@baseboard_fab2_lib.baseboard_fab2(sch_1):page195_i102"
				( objectStatus "F4117" )
			)
			( gate "@baseboard_fab2_lib.baseboard_fab2(sch_1):page195_i105"
				( objectStatus "F4116" )
			)
			( gate "@baseboard_fab2_lib.baseboard_fab2(sch_1):page241_i63"
				( objectStatus "F3491" )
			)
			( gate "@baseboard_fab2_lib.baseboard_fab2(sch_1):page103_i121"
				( objectStatus "F470" )
			)
			( gate "@baseboard_fab2_lib.baseboard_fab2(sch_1):page103_i123"
				( objectStatus "F469" )
			)
			( gate "@baseboard_fab2_lib.baseboard_fab2(sch_1):page103_i125"
				( objectStatus "F472" )
			)
			( gate "@baseboard_fab2_lib.baseboard_fab2(sch_1):page103_i127"
				( objectStatus "F471" )
			)
			( gate "@baseboard_fab2_lib.baseboard_fab2(sch_1):page103_i129"
				( objectStatus "F474" )
			)
			( gate "@baseboard_fab2_lib.baseboard_fab2(sch_1):page103_i131"
				( objectStatus "F473" )
			)
			( gate "@baseboard_fab2_lib.baseboard_fab2(sch_1):page103_i133"
				( objectStatus "F476" )
			)
			( gate "@baseboard_fab2_lib.baseboard_fab2(sch_1):page103_i135"
				( objectStatus "F475" )
			)
			( gate "@baseboard_fab2_lib.baseboard_fab2(sch_1):page103_i139"
				( objectStatus "F483" )
			)
			( gate "@baseboard_fab2_lib.baseboard_fab2(sch_1):page103_i141"
				( objectStatus "F486" )
			)
			( gate "@baseboard_fab2_lib.baseboard_fab2(sch_1):page103_i143"
				( objectStatus "F485" )
			)
			( gate "@baseboard_fab2_lib.baseboard_fab2(sch_1):page103_i145"
				( objectStatus "F488" )
			)
			( gate "@baseboard_fab2_lib.baseboard_fab2(sch_1):page103_i147"
				( objectStatus "F487" )
			)
			( gate "@baseboard_fab2_lib.baseboard_fab2(sch_1):page103_i149"
				( objectStatus "F490" )
			)
			( gate "@baseboard_fab2_lib.baseboard_fab2(sch_1):page103_i151"
				( objectStatus "F489" )
			)
			( gate "@baseboard_fab2_lib.baseboard_fab2(sch_1):page103_i153"
				( objectStatus "F481" )
			)
			( gate "@baseboard_fab2_lib.baseboard_fab2(sch_1):page103_i155"
				( objectStatus "F482" )
			)
			( gate "@baseboard_fab2_lib.baseboard_fab2(sch_1):page103_i157"
				( objectStatus "F479" )
			)
			( gate "@baseboard_fab2_lib.baseboard_fab2(sch_1):page103_i159"
				( objectStatus "F480" )
			)
			( gate "@baseboard_fab2_lib.baseboard_fab2(sch_1):page103_i161"
				( objectStatus "F491" )
			)
			( gate "@baseboard_fab2_lib.baseboard_fab2(sch_1):page103_i163"
				( objectStatus "F492" )
			)
			( gate "@baseboard_fab2_lib.baseboard_fab2(sch_1):page103_i165"
				( objectStatus "F477" )
			)
			( gate "@baseboard_fab2_lib.baseboard_fab2(sch_1):page103_i167"
				( objectStatus "F478" )
			)
			( gate "@baseboard_fab2_lib.baseboard_fab2(sch_1):page103_i137"
				( objectStatus "F484" )
			)
			( gate "@baseboard_fab2_lib.baseboard_fab2(sch_1):page199_i55"
				( objectStatus "F1107" )
			)
			( gate "@baseboard_fab2_lib.baseboard_fab2(sch_1):page199_i19"
				( objectStatus "F255" )
			)
			( gate "@baseboard_fab2_lib.baseboard_fab2(sch_1):page240_i173"
				( objectStatus "F2092" )
			)
			( gate "@baseboard_fab2_lib.baseboard_fab2(sch_1):page241_i90"
				( objectStatus "F2082" )
			)
			( gate "@baseboard_fab2_lib.baseboard_fab2(sch_1):page231_i194"
				( objectStatus "F4087" )
			)
			( gate "@baseboard_fab2_lib.baseboard_fab2(sch_1):page232_i197"
				( objectStatus "F4088" )
			)
			( gate "@baseboard_fab2_lib.baseboard_fab2(sch_1):page233_i194"
				( objectStatus "F4089" )
			)
			( gate "@baseboard_fab2_lib.baseboard_fab2(sch_1):page234_i146"
				( objectStatus "F4090" )
			)
			( gate "@baseboard_fab2_lib.baseboard_fab2(sch_1):page196_i75"
				( objectStatus "F369" )
			)
			( gate "@baseboard_fab2_lib.baseboard_fab2(sch_1):page231_i166"
				( objectStatus "F365" )
			)
			( gate "@baseboard_fab2_lib.baseboard_fab2(sch_1):page232_i304"
				( objectStatus "F366" )
			)
			( gate "@baseboard_fab2_lib.baseboard_fab2(sch_1):page233_i269"
				( objectStatus "F367" )
			)
			( gate "@baseboard_fab2_lib.baseboard_fab2(sch_1):page234_i216"
				( objectStatus "F368" )
			)
			( gate "@baseboard_fab2_lib.baseboard_fab2(sch_1):page240_i106"
				( objectStatus "F358" )
			)
			( gate "@baseboard_fab2_lib.baseboard_fab2(sch_1):page231_i134"
				( objectStatus "F307" )
			)
			( gate "@baseboard_fab2_lib.baseboard_fab2(sch_1):page231_i201"
				( objectStatus "F306" )
			)
			( gate "@baseboard_fab2_lib.baseboard_fab2(sch_1):page232_i300"
				( objectStatus "F308" )
			)
			( gate "@baseboard_fab2_lib.baseboard_fab2(sch_1):page232_i193"
				( objectStatus "F309" )
			)
			( gate "@baseboard_fab2_lib.baseboard_fab2(sch_1):page233_i184"
				( objectStatus "F311" )
			)
			( gate "@baseboard_fab2_lib.baseboard_fab2(sch_1):page234_i140"
				( objectStatus "F313" )
			)
			( gate "@baseboard_fab2_lib.baseboard_fab2(sch_1):page233_i272"
				( objectStatus "F310" )
			)
			( gate "@baseboard_fab2_lib.baseboard_fab2(sch_1):page234_i213"
				( objectStatus "F312" )
			)
			( gate "@baseboard_fab2_lib.baseboard_fab2(sch_1):page200_i145"
				( objectStatus "F806" )
			)
			( gate "@baseboard_fab2_lib.baseboard_fab2(sch_1):page200_i107"
				( objectStatus "F781" )
			)
			( gate "@baseboard_fab2_lib.baseboard_fab2(sch_1):page108_i258"
				( objectStatus "F235" )
				( pin "IO100"
					( objectStatus "J8G1.100" )
				)
				( pin "IO15"
					( objectStatus "J8G1.15" )
				)
				( pin "IO17"
					( objectStatus "J8G1.17" )
				)
				( pin "IO33"
					( objectStatus "J8G1.33" )
				)
				( pin "IO35"
					( objectStatus "J8G1.35" )
				)
				( pin "IO36"
					( objectStatus "J8G1.36" )
				)
				( pin "IO38"
					( objectStatus "J8G1.38" )
				)
				( pin "IO39"
					( objectStatus "J8G1.39" )
				)
				( pin "IO41"
					( objectStatus "J8G1.41" )
				)
				( pin "IO42"
					( objectStatus "J8G1.42" )
				)
				( pin "IO44"
					( objectStatus "J8G1.44" )
				)
				( pin "IO45"
					( objectStatus "J8G1.45" )
				)
				( pin "IO47"
					( objectStatus "J8G1.47" )
				)
				( pin "IO48"
					( objectStatus "J8G1.48" )
				)
				( pin "IO50"
					( objectStatus "J8G1.50" )
				)
				( pin "IO51"
					( objectStatus "J8G1.51" )
				)
				( pin "IO53"
					( objectStatus "J8G1.53" )
				)
				( pin "IO54"
					( objectStatus "J8G1.54" )
				)
				( pin "IO56"
					( objectStatus "J8G1.56" )
				)
				( pin "IO57"
					( objectStatus "J8G1.57" )
				)
				( pin "IO59"
					( objectStatus "J8G1.59" )
				)
				( pin "IO60"
					( objectStatus "J8G1.60" )
				)
				( pin "IO62"
					( objectStatus "J8G1.62" )
				)
				( pin "IO67"
					( objectStatus "J8G1.67" )
				)
				( pin "IO69"
					( objectStatus "J8G1.69" )
				)
				( pin "IO70"
					( objectStatus "J8G1.70" )
				)
				( pin "IO72"
					( objectStatus "J8G1.72" )
				)
				( pin "IO73"
					( objectStatus "J8G1.73" )
				)
				( pin "IO75"
					( objectStatus "J8G1.75" )
				)
				( pin "IO76"
					( objectStatus "J8G1.76" )
				)
				( pin "IO78"
					( objectStatus "J8G1.78" )
				)
				( pin "IO79"
					( objectStatus "J8G1.79" )
				)
				( pin "IO81"
					( objectStatus "J8G1.81" )
				)
				( pin "IO82"
					( objectStatus "J8G1.82" )
				)
				( pin "IO84"
					( objectStatus "J8G1.84" )
				)
				( pin "IO85"
					( objectStatus "J8G1.85" )
				)
				( pin "IO87"
					( objectStatus "J8G1.87" )
				)
				( pin "IO88"
					( objectStatus "J8G1.88" )
				)
				( pin "IO90"
					( objectStatus "J8G1.90" )
				)
				( pin "IO91"
					( objectStatus "J8G1.91" )
				)
				( pin "IO93"
					( objectStatus "J8G1.93" )
				)
				( pin "IO94"
					( objectStatus "J8G1.94" )
				)
				( pin "IO96"
					( objectStatus "J8G1.96" )
				)
				( pin "IO97"
					( objectStatus "J8G1.97" )
				)
				( pin "IO99"
					( objectStatus "J8G1.99" )
				)
			)
			( gate "@baseboard_fab2_lib.baseboard_fab2(sch_1):page109_i243"
				( objectStatus "F234" )
				( pin "IO102"
					( objectStatus "J8G1.102" )
				)
				( pin "IO103"
					( objectStatus "J8G1.103" )
				)
				( pin "IO105"
					( objectStatus "J8G1.105" )
				)
				( pin "IO106"
					( objectStatus "J8G1.106" )
				)
				( pin "IO108"
					( objectStatus "J8G1.108" )
				)
				( pin "IO109"
					( objectStatus "J8G1.109" )
				)
				( pin "IO111"
					( objectStatus "J8G1.111" )
				)
				( pin "IO112"
					( objectStatus "J8G1.112" )
				)
				( pin "IO114"
					( objectStatus "J8G1.114" )
				)
				( pin "IO115"
					( objectStatus "J8G1.115" )
				)
				( pin "IO117"
					( objectStatus "J8G1.117" )
				)
				( pin "IO118"
					( objectStatus "J8G1.118" )
				)
				( pin "IO120"
					( objectStatus "J8G1.120" )
				)
				( pin "IO121"
					( objectStatus "J8G1.121" )
				)
				( pin "IO123"
					( objectStatus "J8G1.123" )
				)
				( pin "IO124"
					( objectStatus "J8G1.124" )
				)
				( pin "IO126"
					( objectStatus "J8G1.126" )
				)
				( pin "IO127"
					( objectStatus "J8G1.127" )
				)
				( pin "IO129"
					( objectStatus "J8G1.129" )
				)
				( pin "IO130"
					( objectStatus "J8G1.130" )
				)
				( pin "IO132"
					( objectStatus "J8G1.132" )
				)
				( pin "IO133"
					( objectStatus "J8G1.133" )
				)
				( pin "IO135"
					( objectStatus "J8G1.135" )
				)
				( pin "IO136"
					( objectStatus "J8G1.136" )
				)
				( pin "IO138"
					( objectStatus "J8G1.138" )
				)
				( pin "IO139"
					( objectStatus "J8G1.139" )
				)
				( pin "IO141"
					( objectStatus "J8G1.141" )
				)
				( pin "IO142"
					( objectStatus "J8G1.142" )
				)
				( pin "IO144"
					( objectStatus "J8G1.144" )
				)
				( pin "IO145"
					( objectStatus "J8G1.145" )
				)
				( pin "IO147"
					( objectStatus "J8G1.147" )
				)
				( pin "IO148"
					( objectStatus "J8G1.148" )
				)
				( pin "IO150"
					( objectStatus "J8G1.150" )
				)
				( pin "IO151"
					( objectStatus "J8G1.151" )
				)
				( pin "IO153"
					( objectStatus "J8G1.153" )
				)
				( pin "IO154"
					( objectStatus "J8G1.154" )
				)
				( pin "IO156"
					( objectStatus "J8G1.156" )
				)
				( pin "IO157"
					( objectStatus "J8G1.157" )
				)
				( pin "IO159"
					( objectStatus "J8G1.159" )
				)
				( pin "IO160"
					( objectStatus "J8G1.160" )
				)
				( pin "IO162"
					( objectStatus "J8G1.162" )
				)
				( pin "IO163"
					( objectStatus "J8G1.163" )
				)
				( pin "IO165"
					( objectStatus "J8G1.165" )
				)
				( pin "IO166"
					( objectStatus "J8G1.166" )
				)
				( pin "IO168"
					( objectStatus "J8G1.168" )
				)
				( pin "IO169"
					( objectStatus "J8G1.169" )
				)
				( pin "IO171"
					( objectStatus "J8G1.171" )
				)
				( pin "IO172"
					( objectStatus "J8G1.172" )
				)
				( pin "IO174"
					( objectStatus "J8G1.174" )
				)
				( pin "IO175"
					( objectStatus "J8G1.175" )
				)
				( pin "IO177"
					( objectStatus "J8G1.177" )
				)
				( pin "IO178"
					( objectStatus "J8G1.178" )
				)
				( pin "IO180"
					( objectStatus "J8G1.180" )
				)
				( pin "IO181"
					( objectStatus "J8G1.181" )
				)
				( pin "IO183"
					( objectStatus "J8G1.183" )
				)
				( pin "IO184"
					( objectStatus "J8G1.184" )
				)
				( pin "IO186"
					( objectStatus "J8G1.186" )
				)
				( pin "IO187"
					( objectStatus "J8G1.187" )
				)
				( pin "IO189"
					( objectStatus "J8G1.189" )
				)
				( pin "IO190"
					( objectStatus "J8G1.190" )
				)
				( pin "IO192"
					( objectStatus "J8G1.192" )
				)
				( pin "IO193"
					( objectStatus "J8G1.193" )
				)
				( pin "IO195"
					( objectStatus "J8G1.195" )
				)
				( pin "IO196"
					( objectStatus "J8G1.196" )
				)
				( pin "IO198"
					( objectStatus "J8G1.198" )
				)
			)
			( gate "@baseboard_fab2_lib.baseboard_fab2(sch_1):page196_i104"
				( objectStatus "F49" )
			)
			( gate "@baseboard_fab2_lib.baseboard_fab2(sch_1):page200_i200"
				( objectStatus "F47" )
			)
			( gate "@baseboard_fab2_lib.baseboard_fab2(sch_1):page200_i170"
				( objectStatus "F50" )
			)
			( gate "@baseboard_fab2_lib.baseboard_fab2(sch_1):page200_i163"
				( objectStatus "F48" )
			)
			( gate "@baseboard_fab2_lib.baseboard_fab2(sch_1):page199_i99"
				( objectStatus "F0" )
			)
			( gate "@baseboard_fab2_lib.baseboard_fab2(sch_1):page175_i50"
				( objectStatus "F2038" )
			)
			( gate "@baseboard_fab2_lib.baseboard_fab2(sch_1):page175_i67"
				( objectStatus "F2036" )
			)
			( gate "@baseboard_fab2_lib.baseboard_fab2(sch_1):page170_i42"
				( objectStatus "F3098" )
			)
			( gate "@baseboard_fab2_lib.baseboard_fab2(sch_1):page181_i224"
				( objectStatus "F3099" )
			)
			( gate "@baseboard_fab2_lib.baseboard_fab2(sch_1):page114_i124"
				( objectStatus "F400" )
			)
			( gate "@baseboard_fab2_lib.baseboard_fab2(sch_1):page118_i67"
				( objectStatus "F403" )
			)
			( gate "@baseboard_fab2_lib.baseboard_fab2(sch_1):page215_i330"
				( objectStatus "F401" )
				( pin "B"
					( objectStatus "R3T11.2" )
				)
			)
			( gate "@baseboard_fab2_lib.baseboard_fab2(sch_1):page223_i50"
				( objectStatus "F399" )
			)
			( gate "@baseboard_fab2_lib.baseboard_fab2(sch_1):page211_i28"
				( objectStatus "F402" )
			)
			( gate "@baseboard_fab2_lib.baseboard_fab2(sch_1):page196_i51"
				( objectStatus "F4" )
				( pin "P1"
					( objectStatus "XBT8G1.1" )
				)
				( pin "P2"
					( objectStatus "XBT8G1.2" )
				)
			)
			( gate "@baseboard_fab2_lib.baseboard_fab2(sch_1):page189_i49"
				( objectStatus "F2209" )
			)
			( gate "@baseboard_fab2_lib.baseboard_fab2(sch_1):page200_i172"
				( objectStatus "F1067" )
			)
			( gate "@baseboard_fab2_lib.baseboard_fab2(sch_1):page199_i33"
				( objectStatus "F1066" )
			)
			( gate "@baseboard_fab2_lib.baseboard_fab2(sch_1):page157_i351"
				( objectStatus "F64" )
			)
			( gate "@baseboard_fab2_lib.baseboard_fab2(sch_1):page231_i180"
				( objectStatus "F4099" )
			)
			( gate "@baseboard_fab2_lib.baseboard_fab2(sch_1):page232_i229"
				( objectStatus "F4100" )
			)
			( gate "@baseboard_fab2_lib.baseboard_fab2(sch_1):page233_i217"
				( objectStatus "F4101" )
			)
			( gate "@baseboard_fab2_lib.baseboard_fab2(sch_1):page234_i167"
				( objectStatus "F4102" )
			)
			( gate "@baseboard_fab2_lib.baseboard_fab2(sch_1):page240_i154"
				( objectStatus "F4128" )
			)
			( gate "@baseboard_fab2_lib.baseboard_fab2(sch_1):page240_i155"
				( objectStatus "F4129" )
			)
			( gate "@baseboard_fab2_lib.baseboard_fab2(sch_1):page241_i8"
				( objectStatus "F4130" )
			)
			( gate "@baseboard_fab2_lib.baseboard_fab2(sch_1):page158_i74"
				( objectStatus "F2129" )
			)
			( gate "@baseboard_fab2_lib.baseboard_fab2(sch_1):page158_i75"
				( objectStatus "F2130" )
			)
			( gate "@baseboard_fab2_lib.baseboard_fab2(sch_1):page110_i7"
				( objectStatus "F1967" )
				( pin "GND"
					( objectStatus "TC1A1.1" )
				)
				( pin "IO1"
					( objectStatus "TC1A1.2" )
				)
				( pin "IO2"
					( objectStatus "TC1A1.3" )
				)
			)
			( gate "@baseboard_fab2_lib.baseboard_fab2(sch_1):page110_i9"
				( objectStatus "F1965" )
				( pin "GND"
					( objectStatus "TC9A1.1" )
				)
				( pin "IO1"
					( objectStatus "TC9A1.2" )
				)
				( pin "IO2"
					( objectStatus "TC9A1.3" )
				)
			)
			( gate "@baseboard_fab2_lib.baseboard_fab2(sch_1):page110_i3"
				( objectStatus "F1966" )
				( pin "GND"
					( objectStatus "TC1G1.1" )
				)
				( pin "IO1"
					( objectStatus "TC1G1.2" )
				)
				( pin "IO2"
					( objectStatus "TC1G1.3" )
				)
			)
			( gate "@baseboard_fab2_lib.baseboard_fab2(sch_1):page110_i1"
				( objectStatus "F1964" )
				( pin "GND"
					( objectStatus "TC9F1.1" )
				)
				( pin "IO1"
					( objectStatus "TC9F1.2" )
				)
				( pin "IO2"
					( objectStatus "TC9F1.3" )
				)
			)
			( gate "@baseboard_fab2_lib.baseboard_fab2(sch_1):page110_i11"
				( objectStatus "TF-12953" )
			)
			( gate "@baseboard_fab2_lib.baseboard_fab2(sch_1):page110_i12"
				( objectStatus "TF-12952" )
			)
			( gate "@baseboard_fab2_lib.baseboard_fab2(sch_1):page110_i13"
				( objectStatus "TF-12951" )
			)
			( gate "@baseboard_fab2_lib.baseboard_fab2(sch_1):page110_i14"
				( objectStatus "TF-12950" )
			)
			( gate "@baseboard_fab2_lib.baseboard_fab2(sch_1):page110_i15"
				( objectStatus "TF-12949" )
			)
			( gate "@baseboard_fab2_lib.baseboard_fab2(sch_1):page175_i84"
				( objectStatus "F63" )
			)
			( gate "@baseboard_fab2_lib.baseboard_fab2(sch_1):page176_i100"
				( objectStatus "F51" )
			)
			( gate "@baseboard_fab2_lib.baseboard_fab2(sch_1):page141_i100"
				( objectStatus "F3102" )
				( pin "B"
					( objectStatus "C9G12.2" )
				)
			)
			( gate "@baseboard_fab2_lib.baseboard_fab2(sch_1):page141_i102"
				( objectStatus "F3101" )
				( pin "B"
					( objectStatus "C9G13.2" )
				)
			)
			( gate "@baseboard_fab2_lib.baseboard_fab2(sch_1):page141_i99"
				( objectStatus "F3103" )
				( pin "B"
					( objectStatus "C9G9.2" )
				)
			)
			( gate "@baseboard_fab2_lib.baseboard_fab2(sch_1):page141_i101"
				( objectStatus "F3100" )
				( pin "B"
					( objectStatus "C9G16.2" )
				)
			)
			( gate "@baseboard_fab2_lib.baseboard_fab2(sch_1):page217_i91"
				( objectStatus "F2584" )
			)
			( gate "@baseboard_fab2_lib.baseboard_fab2(sch_1):page217_i83"
				( objectStatus "F2572" )
			)
			( gate "@baseboard_fab2_lib.baseboard_fab2(sch_1):page217_i89"
				( objectStatus "F2570" )
			)
			( gate "@baseboard_fab2_lib.baseboard_fab2(sch_1):page217_i88"
				( objectStatus "F2573" )
			)
			( gate "@baseboard_fab2_lib.baseboard_fab2(sch_1):page217_i82"
				( objectStatus "F2571" )
			)
			( gate "@baseboard_fab2_lib.baseboard_fab2(sch_1):page217_i90"
				( objectStatus "F2569" )
			)
			( gate "@baseboard_fab2_lib.baseboard_fab2(sch_1):page217_i92"
				( objectStatus "F2581" )
			)
			( gate "@baseboard_fab2_lib.baseboard_fab2(sch_1):page217_i110"
				( objectStatus "F2580" )
			)
			( gate "@baseboard_fab2_lib.baseboard_fab2(sch_1):page225_i110"
				( objectStatus "F2585" )
			)
			( gate "@baseboard_fab2_lib.baseboard_fab2(sch_1):page225_i92"
				( objectStatus "F2586" )
			)
			( gate "@baseboard_fab2_lib.baseboard_fab2(sch_1):page225_i91"
				( objectStatus "F2566" )
			)
			( gate "@baseboard_fab2_lib.baseboard_fab2(sch_1):page225_i90"
				( objectStatus "F2567" )
			)
			( gate "@baseboard_fab2_lib.baseboard_fab2(sch_1):page225_i89"
				( objectStatus "F2558" )
			)
			( gate "@baseboard_fab2_lib.baseboard_fab2(sch_1):page225_i88"
				( objectStatus "F2557" )
			)
			( gate "@baseboard_fab2_lib.baseboard_fab2(sch_1):page225_i83"
				( objectStatus "F2559" )
			)
			( gate "@baseboard_fab2_lib.baseboard_fab2(sch_1):page225_i82"
				( objectStatus "F2560" )
			)
			( gate "@baseboard_fab2_lib.baseboard_fab2(sch_1):page228_i110"
				( objectStatus "F2565" )
			)
			( gate "@baseboard_fab2_lib.baseboard_fab2(sch_1):page228_i92"
				( objectStatus "F2568" )
			)
			( gate "@baseboard_fab2_lib.baseboard_fab2(sch_1):page228_i91"
				( objectStatus "F2561" )
			)
			( gate "@baseboard_fab2_lib.baseboard_fab2(sch_1):page228_i90"
				( objectStatus "F2562" )
			)
			( gate "@baseboard_fab2_lib.baseboard_fab2(sch_1):page228_i89"
				( objectStatus "F2587" )
			)
			( gate "@baseboard_fab2_lib.baseboard_fab2(sch_1):page228_i88"
				( objectStatus "F2563" )
			)
			( gate "@baseboard_fab2_lib.baseboard_fab2(sch_1):page228_i83"
				( objectStatus "F2564" )
			)
			( gate "@baseboard_fab2_lib.baseboard_fab2(sch_1):page228_i82"
				( objectStatus "F2588" )
			)
			( gate "@baseboard_fab2_lib.baseboard_fab2(sch_1):page220_i110"
				( objectStatus "F2583" )
			)
			( gate "@baseboard_fab2_lib.baseboard_fab2(sch_1):page220_i91"
				( objectStatus "F2579" )
			)
			( gate "@baseboard_fab2_lib.baseboard_fab2(sch_1):page220_i89"
				( objectStatus "F2577" )
			)
			( gate "@baseboard_fab2_lib.baseboard_fab2(sch_1):page220_i83"
				( objectStatus "F2576" )
			)
			( gate "@baseboard_fab2_lib.baseboard_fab2(sch_1):page220_i82"
				( objectStatus "F2575" )
			)
			( gate "@baseboard_fab2_lib.baseboard_fab2(sch_1):page220_i92"
				( objectStatus "F2582" )
			)
			( gate "@baseboard_fab2_lib.baseboard_fab2(sch_1):page220_i90"
				( objectStatus "F2578" )
			)
			( gate "@baseboard_fab2_lib.baseboard_fab2(sch_1):page220_i88"
				( objectStatus "F2574" )
			)
			( gate "@baseboard_fab2_lib.baseboard_fab2(sch_1):page183_i19"
				( objectStatus "F2228" )
			)
			( gate "@baseboard_fab2_lib.baseboard_fab2(sch_1):page240_i143"
				( objectStatus "F845" )
			)
			( gate "@baseboard_fab2_lib.baseboard_fab2(sch_1):page240_i170"
				( objectStatus "F2226" )
			)
			( gate "@baseboard_fab2_lib.baseboard_fab2(sch_1):page183_i1"
				( objectStatus "F1979" )
				( pin "SCL"
					( objectStatus "EU9F3.17" )
				)
				( pin "SDA"
					( objectStatus "EU9F3.3" )
				)
			)
			( gate "@baseboard_fab2_lib.baseboard_fab2(sch_1):page240_i125"
				( objectStatus "F246" )
			)
			( gate "@baseboard_fab2_lib.baseboard_fab2(sch_1):page184_i87"
				( objectStatus "F241" )
				( pin "IO1"
					( objectStatus "J8E1.1" )
				)
				( pin "IO10"
					( objectStatus "J8E1.10" )
				)
				( pin "IO3"
					( objectStatus "J8E1.3" )
				)
				( pin "IO4"
					( objectStatus "J8E1.4" )
				)
				( pin "IO5"
					( objectStatus "J8E1.5" )
				)
				( pin "IO6"
					( objectStatus "J8E1.6" )
				)
			)
			( gate "@baseboard_fab2_lib.baseboard_fab2(sch_1):page91_i1"
				( objectStatus "F233" )
			)
			( gate "@baseboard_fab2_lib.baseboard_fab2(sch_1):page190_i179"
				( objectStatus "F2041" )
				( pin "PL9C"
					( objectStatus "U8D7.H5" )
				)
			)
			( gate "@baseboard_fab2_lib.baseboard_fab2(sch_1):page191_i59"
				( objectStatus "F2040" )
			)
			( gate "@baseboard_fab2_lib.baseboard_fab2(sch_1):page192_i14"
				( objectStatus "F2039" )
			)
			( gate "@baseboard_fab2_lib.baseboard_fab2(sch_1):page191_i166"
				( objectStatus "F383" )
			)
			( gate "@baseboard_fab2_lib.baseboard_fab2(sch_1):page144_i547"
				( objectStatus "F386" )
			)
			( gate "@baseboard_fab2_lib.baseboard_fab2(sch_1):page144_i546"
				( objectStatus "F385" )
			)
			( gate "@baseboard_fab2_lib.baseboard_fab2(sch_1):page144_i548"
				( objectStatus "F384" )
			)
			( gate "@baseboard_fab2_lib.baseboard_fab2(sch_1):page155_i129"
				( objectStatus "F2126" )
			)
			( gate "@baseboard_fab2_lib.baseboard_fab2(sch_1):page239_i15"
				( objectStatus "F1105" )
			)
			( gate "@baseboard_fab2_lib.baseboard_fab2(sch_1):page175_i78"
				( objectStatus "F65" )
			)
			( gate "@baseboard_fab2_lib.baseboard_fab2(sch_1):page216_i55"
				( objectStatus "F2102" )
			)
			( gate "@baseboard_fab2_lib.baseboard_fab2(sch_1):page216_i65"
				( objectStatus "F2101" )
			)
			( gate "@baseboard_fab2_lib.baseboard_fab2(sch_1):page219_i55"
				( objectStatus "F2104" )
			)
			( gate "@baseboard_fab2_lib.baseboard_fab2(sch_1):page219_i65"
				( objectStatus "F2103" )
			)
			( gate "@baseboard_fab2_lib.baseboard_fab2(sch_1):page227_i55"
				( objectStatus "F2117" )
			)
			( gate "@baseboard_fab2_lib.baseboard_fab2(sch_1):page227_i65"
				( objectStatus "F2118" )
			)
			( gate "@baseboard_fab2_lib.baseboard_fab2(sch_1):page224_i55"
				( objectStatus "F2110" )
			)
			( gate "@baseboard_fab2_lib.baseboard_fab2(sch_1):page224_i65"
				( objectStatus "F2111" )
			)
			( gate "@baseboard_fab2_lib.baseboard_fab2(sch_1):page203_i15"
				( objectStatus "F2107" )
			)
			( gate "@baseboard_fab2_lib.baseboard_fab2(sch_1):page203_i24"
				( objectStatus "F2108" )
			)
			( gate "@baseboard_fab2_lib.baseboard_fab2(sch_1):page204_i5"
				( objectStatus "F2109" )
			)
			( gate "@baseboard_fab2_lib.baseboard_fab2(sch_1):page202_i29"
				( objectStatus "F2106" )
			)
			( gate "@baseboard_fab2_lib.baseboard_fab2(sch_1):page202_i5"
				( objectStatus "F2105" )
			)
			( gate "@baseboard_fab2_lib.baseboard_fab2(sch_1):page207_i16"
				( objectStatus "F2113" )
			)
			( gate "@baseboard_fab2_lib.baseboard_fab2(sch_1):page207_i10"
				( objectStatus "F2112" )
			)
			( gate "@baseboard_fab2_lib.baseboard_fab2(sch_1):page208_i11"
				( objectStatus "F2114" )
			)
			( gate "@baseboard_fab2_lib.baseboard_fab2(sch_1):page208_i20"
				( objectStatus "F2115" )
			)
			( gate "@baseboard_fab2_lib.baseboard_fab2(sch_1):page209_i40"
				( objectStatus "F2116" )
			)
			( gate "@baseboard_fab2_lib.baseboard_fab2(sch_1):page239_i14"
				( objectStatus "F1106" )
			)
			( gate "@baseboard_fab2_lib.baseboard_fab2(sch_1):page238_i40"
				( objectStatus "F244" )
			)
			( gate "@baseboard_fab2_lib.baseboard_fab2(sch_1):page237_i86"
				( objectStatus "F245" )
			)
			( gate "@baseboard_fab2_lib.baseboard_fab2(sch_1):page239_i70"
				( objectStatus "F243" )
			)
			( gate "@baseboard_fab2_lib.baseboard_fab2(sch_1):page196_i70"
				( objectStatus "F4198" )
			)
			( gate "@baseboard_fab2_lib.baseboard_fab2(sch_1):page196_i60"
				( objectStatus "F4086" )
			)
			( gate "@baseboard_fab2_lib.baseboard_fab2(sch_1):page196_i105"
				( objectStatus "F4077" )
			)
			( gate "@baseboard_fab2_lib.baseboard_fab2(sch_1):page163_i10"
				( objectStatus "F4078" )
			)
			( gate "@baseboard_fab2_lib.baseboard_fab2(sch_1):page163_i12"
				( objectStatus "F4079" )
			)
			( gate "@baseboard_fab2_lib.baseboard_fab2(sch_1):page196_i94"
				( objectStatus "F4080" )
			)
			( gate "@baseboard_fab2_lib.baseboard_fab2(sch_1):page196_i81"
				( objectStatus "F4082" )
			)
			( gate "@baseboard_fab2_lib.baseboard_fab2(sch_1):page196_i72"
				( objectStatus "F4081" )
			)
			( gate "@baseboard_fab2_lib.baseboard_fab2(sch_1):page156_i331"
				( objectStatus "F768" )
			)
			( gate "@baseboard_fab2_lib.baseboard_fab2(sch_1):page156_i336"
				( objectStatus "F767" )
			)
			( gate "@baseboard_fab2_lib.baseboard_fab2(sch_1):page140_i14"
				( objectStatus "F769" )
			)
			( gate "@baseboard_fab2_lib.baseboard_fab2(sch_1):page169_i114"
				( objectStatus "F293" )
			)
			( gate "@baseboard_fab2_lib.baseboard_fab2(sch_1):page169_i149"
				( objectStatus "F294" )
			)
			( gate "@baseboard_fab2_lib.baseboard_fab2(sch_1):page144_i461"
				( objectStatus "F295" )
			)
			( gate "@baseboard_fab2_lib.baseboard_fab2(sch_1):page185_i95"
				( objectStatus "F3607" )
				( pin "A"
					( objectStatus "C8F6.1" )
				)
				( pin "B"
					( objectStatus "C8F6.2" )
				)
			)
			( gate "@baseboard_fab2_lib.baseboard_fab2(sch_1):page185_i97"
				( objectStatus "F3606" )
				( pin "A"
					( objectStatus "C8F11.1" )
				)
				( pin "B"
					( objectStatus "C8F11.2" )
				)
			)
			( gate "@baseboard_fab2_lib.baseboard_fab2(sch_1):page185_i99"
				( objectStatus "F3605" )
				( pin "A"
					( objectStatus "C8F13.1" )
				)
			)
			( gate "@baseboard_fab2_lib.baseboard_fab2(sch_1):page185_i90"
				( objectStatus "F3604" )
				( pin "A"
					( objectStatus "C8F15.1" )
				)
			)
			( gate "@baseboard_fab2_lib.baseboard_fab2(sch_1):page176_i51"
				( objectStatus "F2260" )
				( pin "\2\"
					( objectStatus "L1L1.2" )
				)
				( pin "\3\"
					( objectStatus "L1L1.3" )
				)
			)
			( gate "@baseboard_fab2_lib.baseboard_fab2(sch_1):page176_i62"
				( objectStatus "F2259" )
				( pin "\2\"
					( objectStatus "L1M1.2" )
				)
				( pin "\3\"
					( objectStatus "L1M1.3" )
				)
			)
			( gate "@baseboard_fab2_lib.baseboard_fab2(sch_1):page232_i218"
				( objectStatus "F1032" )
			)
			( gate "@baseboard_fab2_lib.baseboard_fab2(sch_1):page233_i208"
				( objectStatus "F1033" )
			)
			( gate "@baseboard_fab2_lib.baseboard_fab2(sch_1):page234_i162"
				( objectStatus "F1034" )
			)
			( gate "@baseboard_fab2_lib.baseboard_fab2(sch_1):page231_i174"
				( objectStatus "F1031" )
			)
			( gate "@baseboard_fab2_lib.baseboard_fab2(sch_1):page240_i148"
				( objectStatus "F1030" )
			)
			( gate "@baseboard_fab2_lib.baseboard_fab2(sch_1):page158_i131"
				( objectStatus "F665" )
			)
			( gate "@baseboard_fab2_lib.baseboard_fab2(sch_1):page158_i136"
				( objectStatus "F664" )
			)
			( gate "@baseboard_fab2_lib.baseboard_fab2(sch_1):page240_i152"
				( objectStatus "F1407" )
			)
			( gate "@baseboard_fab2_lib.baseboard_fab2(sch_1):page241_i9"
				( objectStatus "F1402" )
			)
			( gate "@baseboard_fab2_lib.baseboard_fab2(sch_1):page231_i218"
				( objectStatus "F1403" )
			)
			( gate "@baseboard_fab2_lib.baseboard_fab2(sch_1):page232_i298"
				( objectStatus "F1404" )
			)
			( gate "@baseboard_fab2_lib.baseboard_fab2(sch_1):page233_i266"
				( objectStatus "F1405" )
			)
			( gate "@baseboard_fab2_lib.baseboard_fab2(sch_1):page234_i219"
				( objectStatus "F1406" )
			)
			( gate "@baseboard_fab2_lib.baseboard_fab2(sch_1):page118_i96"
				( objectStatus "F1408" )
			)
			( gate "@baseboard_fab2_lib.baseboard_fab2(sch_1):page118_i99"
				( objectStatus "F1409" )
			)
			( gate "@baseboard_fab2_lib.baseboard_fab2(sch_1):page241_i51"
				( objectStatus "F1395" )
			)
			( gate "@baseboard_fab2_lib.baseboard_fab2(sch_1):page156_i320"
				( objectStatus "F1233" )
			)
			( gate "@baseboard_fab2_lib.baseboard_fab2(sch_1):page145_i252"
				( objectStatus "F1234" )
			)
			( gate "@baseboard_fab2_lib.baseboard_fab2(sch_1):page176_i111"
				( objectStatus "F1235" )
			)
			( gate "@baseboard_fab2_lib.baseboard_fab2(sch_1):page196_i121"
				( objectStatus "F1237" )
			)
			( gate "@baseboard_fab2_lib.baseboard_fab2(sch_1):page196_i120"
				( objectStatus "F1238" )
			)
			( gate "@baseboard_fab2_lib.baseboard_fab2(sch_1):page196_i122"
				( objectStatus "F1236" )
			)
			( gate "@baseboard_fab2_lib.baseboard_fab2(sch_1):page115_i114"
				( objectStatus "F1239" )
			)
			( gate "@baseboard_fab2_lib.baseboard_fab2(sch_1):page185_i136"
				( objectStatus "F1332" )
			)
			( gate "@baseboard_fab2_lib.baseboard_fab2(sch_1):page139_i213"
				( objectStatus "F1322" )
			)
			( gate "@baseboard_fab2_lib.baseboard_fab2(sch_1):page116_i230"
				( objectStatus "F1293" )
			)
			( gate "@baseboard_fab2_lib.baseboard_fab2(sch_1):page116_i229"
				( objectStatus "F1292" )
			)
			( gate "@baseboard_fab2_lib.baseboard_fab2(sch_1):page121_i73"
				( objectStatus "F1288" )
			)
			( gate "@baseboard_fab2_lib.baseboard_fab2(sch_1):page118_i144"
				( objectStatus "F1286" )
			)
			( gate "@baseboard_fab2_lib.baseboard_fab2(sch_1):page189_i53"
				( objectStatus "F1273" )
			)
			( gate "@baseboard_fab2_lib.baseboard_fab2(sch_1):page189_i51"
				( objectStatus "F1272" )
			)
			( gate "@baseboard_fab2_lib.baseboard_fab2(sch_1):page189_i50"
				( objectStatus "F1258" )
			)
			( gate "@baseboard_fab2_lib.baseboard_fab2(sch_1):page133_i267"
				( objectStatus "F1316" )
			)
			( gate "@baseboard_fab2_lib.baseboard_fab2(sch_1):page89_i34"
				( objectStatus "F1266" )
			)
			( gate "@baseboard_fab2_lib.baseboard_fab2(sch_1):page89_i7"
				( objectStatus "F1296" )
			)
			( gate "@baseboard_fab2_lib.baseboard_fab2(sch_1):page145_i127"
				( objectStatus "F1318" )
			)
			( gate "@baseboard_fab2_lib.baseboard_fab2(sch_1):page200_i215"
				( objectStatus "F1244" )
			)
			( gate "@baseboard_fab2_lib.baseboard_fab2(sch_1):page134_i34"
				( objectStatus "F1281" )
			)
			( gate "@baseboard_fab2_lib.baseboard_fab2(sch_1):page177_i9"
				( objectStatus "F1326" )
			)
			( gate "@baseboard_fab2_lib.baseboard_fab2(sch_1):page177_i8"
				( objectStatus "F1325" )
			)
			( gate "@baseboard_fab2_lib.baseboard_fab2(sch_1):page97_i80"
				( objectStatus "F1300" )
			)
			( gate "@baseboard_fab2_lib.baseboard_fab2(sch_1):page97_i81"
				( objectStatus "F1271" )
			)
			( gate "@baseboard_fab2_lib.baseboard_fab2(sch_1):page154_i128"
				( objectStatus "F1319" )
			)
			( gate "@baseboard_fab2_lib.baseboard_fab2(sch_1):page147_i142"
				( objectStatus "F1315" )
			)
			( gate "@baseboard_fab2_lib.baseboard_fab2(sch_1):page153_i178"
				( objectStatus "F1305" )
			)
			( gate "@baseboard_fab2_lib.baseboard_fab2(sch_1):page153_i174"
				( objectStatus "F1306" )
				( pin "B"
					( objectStatus "R3T4.2" )
				)
			)
			( gate "@baseboard_fab2_lib.baseboard_fab2(sch_1):page200_i191"
				( objectStatus "F1327" )
			)
			( gate "@baseboard_fab2_lib.baseboard_fab2(sch_1):page200_i189"
				( objectStatus "F1331" )
			)
			( gate "@baseboard_fab2_lib.baseboard_fab2(sch_1):page200_i192"
				( objectStatus "F1241" )
			)
			( gate "@baseboard_fab2_lib.baseboard_fab2(sch_1):page200_i108"
				( objectStatus "F1240" )
			)
			( gate "@baseboard_fab2_lib.baseboard_fab2(sch_1):page200_i174"
				( objectStatus "F1330" )
			)
			( gate "@baseboard_fab2_lib.baseboard_fab2(sch_1):page200_i175"
				( objectStatus "F1329" )
			)
			( gate "@baseboard_fab2_lib.baseboard_fab2(sch_1):page200_i146"
				( objectStatus "F1242" )
			)
			( gate "@baseboard_fab2_lib.baseboard_fab2(sch_1):page200_i158"
				( objectStatus "F1328" )
			)
			( gate "@baseboard_fab2_lib.baseboard_fab2(sch_1):page136_i156"
				( objectStatus "F1280" )
			)
			( gate "@baseboard_fab2_lib.baseboard_fab2(sch_1):page233_i182"
				( objectStatus "F1303" )
			)
			( gate "@baseboard_fab2_lib.baseboard_fab2(sch_1):page176_i105"
				( objectStatus "F1254" )
			)
			( gate "@baseboard_fab2_lib.baseboard_fab2(sch_1):page231_i136"
				( objectStatus "F1276" )
			)
			( gate "@baseboard_fab2_lib.baseboard_fab2(sch_1):page240_i142"
				( objectStatus "F1262" )
			)
			( gate "@baseboard_fab2_lib.baseboard_fab2(sch_1):page192_i41"
				( objectStatus "F1311" )
			)
			( gate "@baseboard_fab2_lib.baseboard_fab2(sch_1):page192_i38"
				( objectStatus "F1279" )
			)
			( gate "@baseboard_fab2_lib.baseboard_fab2(sch_1):page118_i128"
				( objectStatus "F1317" )
			)
			( gate "@baseboard_fab2_lib.baseboard_fab2(sch_1):page192_i33"
				( objectStatus "F1278" )
			)
			( gate "@baseboard_fab2_lib.baseboard_fab2(sch_1):page192_i34"
				( objectStatus "F1312" )
			)
			( gate "@baseboard_fab2_lib.baseboard_fab2(sch_1):page200_i149"
				( objectStatus "F1243" )
			)
			( gate "@baseboard_fab2_lib.baseboard_fab2(sch_1):page133_i297"
				( objectStatus "F1291" )
			)
			( gate "@baseboard_fab2_lib.baseboard_fab2(sch_1):page133_i296"
				( objectStatus "F1290" )
			)
			( gate "@baseboard_fab2_lib.baseboard_fab2(sch_1):page133_i295"
				( objectStatus "F1294" )
			)
			( gate "@baseboard_fab2_lib.baseboard_fab2(sch_1):page133_i237"
				( objectStatus "F1282" )
			)
			( gate "@baseboard_fab2_lib.baseboard_fab2(sch_1):page137_i67"
				( objectStatus "F1289" )
			)
			( gate "@baseboard_fab2_lib.baseboard_fab2(sch_1):page136_i147"
				( objectStatus "F1270" )
			)
			( gate "@baseboard_fab2_lib.baseboard_fab2(sch_1):page133_i355"
				( objectStatus "F1265" )
			)
			( gate "@baseboard_fab2_lib.baseboard_fab2(sch_1):page134_i17"
				( objectStatus "F1313" )
			)
			( gate "@baseboard_fab2_lib.baseboard_fab2(sch_1):page136_i101"
				( objectStatus "F1307" )
			)
			( gate "@baseboard_fab2_lib.baseboard_fab2(sch_1):page142_i28"
				( objectStatus "F1261" )
			)
			( gate "@baseboard_fab2_lib.baseboard_fab2(sch_1):page239_i6"
				( objectStatus "F1246" )
			)
			( gate "@baseboard_fab2_lib.baseboard_fab2(sch_1):page133_i247"
				( objectStatus "F1314" )
			)
			( gate "@baseboard_fab2_lib.baseboard_fab2(sch_1):page135_i58"
				( objectStatus "F1287" )
			)
			( gate "@baseboard_fab2_lib.baseboard_fab2(sch_1):page136_i140"
				( objectStatus "F1264" )
			)
			( gate "@baseboard_fab2_lib.baseboard_fab2(sch_1):page21_i240"
				( objectStatus "F1298" )
			)
			( gate "@baseboard_fab2_lib.baseboard_fab2(sch_1):page21_i239"
				( objectStatus "F1297" )
			)
			( gate "@baseboard_fab2_lib.baseboard_fab2(sch_1):page21_i238"
				( objectStatus "F1299" )
			)
			( gate "@baseboard_fab2_lib.baseboard_fab2(sch_1):page55_i159"
				( objectStatus "F1256" )
			)
			( gate "@baseboard_fab2_lib.baseboard_fab2(sch_1):page55_i160"
				( objectStatus "F1255" )
			)
			( gate "@baseboard_fab2_lib.baseboard_fab2(sch_1):page55_i161"
				( objectStatus "F1257" )
			)
			( gate "@baseboard_fab2_lib.baseboard_fab2(sch_1):page139_i179"
				( objectStatus "F1253" )
			)
			( gate "@baseboard_fab2_lib.baseboard_fab2(sch_1):page139_i178"
				( objectStatus "F1251" )
			)
			( gate "@baseboard_fab2_lib.baseboard_fab2(sch_1):page139_i177"
				( objectStatus "F1252" )
			)
			( gate "@baseboard_fab2_lib.baseboard_fab2(sch_1):page139_i181"
				( objectStatus "F1248" )
			)
			( gate "@baseboard_fab2_lib.baseboard_fab2(sch_1):page238_i21"
				( objectStatus "F1245" )
			)
			( gate "@baseboard_fab2_lib.baseboard_fab2(sch_1):page238_i14"
				( objectStatus "F1247" )
			)
			( gate "@baseboard_fab2_lib.baseboard_fab2(sch_1):page125_i52"
				( objectStatus "F1268" )
			)
			( gate "@baseboard_fab2_lib.baseboard_fab2(sch_1):page221_i45"
				( objectStatus "F1301" )
			)
			( gate "@baseboard_fab2_lib.baseboard_fab2(sch_1):page133_i200"
				( objectStatus "F1284" )
			)
			( gate "@baseboard_fab2_lib.baseboard_fab2(sch_1):page133_i245"
				( objectStatus "F1285" )
			)
			( gate "@baseboard_fab2_lib.baseboard_fab2(sch_1):page133_i202"
				( objectStatus "F1283" )
			)
			( gate "@baseboard_fab2_lib.baseboard_fab2(sch_1):page156_i211"
				( objectStatus "F1260" )
			)
			( gate "@baseboard_fab2_lib.baseboard_fab2(sch_1):page156_i210"
				( objectStatus "F1309" )
			)
			( gate "@baseboard_fab2_lib.baseboard_fab2(sch_1):page153_i140"
				( objectStatus "F1274" )
				( pin "B"
					( objectStatus "R7F32.2" )
				)
			)
			( gate "@baseboard_fab2_lib.baseboard_fab2(sch_1):page153_i168"
				( objectStatus "F1275" )
			)
			( gate "@baseboard_fab2_lib.baseboard_fab2(sch_1):page154_i106"
				( objectStatus "F1310" )
				( pin "B"
					( objectStatus "R2T8.2" )
				)
			)
			( gate "@baseboard_fab2_lib.baseboard_fab2(sch_1):page222_i19"
				( objectStatus "F1295" )
			)
			( gate "@baseboard_fab2_lib.baseboard_fab2(sch_1):page229_i14"
				( objectStatus "F1302" )
			)
			( gate "@baseboard_fab2_lib.baseboard_fab2(sch_1):page230_i17"
				( objectStatus "F1304" )
			)
			( gate "@baseboard_fab2_lib.baseboard_fab2(sch_1):page185_i111"
				( objectStatus "F1267" )
			)
			( gate "@baseboard_fab2_lib.baseboard_fab2(sch_1):page185_i113"
				( objectStatus "F1269" )
			)
			( gate "@baseboard_fab2_lib.baseboard_fab2(sch_1):page139_i200"
				( objectStatus "F1250" )
			)
			( gate "@baseboard_fab2_lib.baseboard_fab2(sch_1):page142_i23"
				( objectStatus "F1263" )
			)
			( gate "@baseboard_fab2_lib.baseboard_fab2(sch_1):page147_i109"
				( objectStatus "F1321" )
			)
			( gate "@baseboard_fab2_lib.baseboard_fab2(sch_1):page147_i108"
				( objectStatus "F1323" )
			)
			( gate "@baseboard_fab2_lib.baseboard_fab2(sch_1):page147_i118"
				( objectStatus "F1259" )
			)
			( gate "@baseboard_fab2_lib.baseboard_fab2(sch_1):page147_i119"
				( objectStatus "F1324" )
			)
			( gate "@baseboard_fab2_lib.baseboard_fab2(sch_1):page139_i212"
				( objectStatus "F1249" )
			)
			( gate "@baseboard_fab2_lib.baseboard_fab2(sch_1):page139_i214"
				( objectStatus "F1320" )
			)
			( gate "@baseboard_fab2_lib.baseboard_fab2(sch_1):page121_i37"
				( objectStatus "F1308" )
			)
			( gate "@baseboard_fab2_lib.baseboard_fab2(sch_1):page241_i50"
				( objectStatus "F1277" )
			)
			( gate "@baseboard_fab2_lib.baseboard_fab2(sch_1):page196_i114"
				( objectStatus "F396" )
			)
			( gate "@baseboard_fab2_lib.baseboard_fab2(sch_1):page147_i78"
				( objectStatus "F397" )
			)
			( gate "@baseboard_fab2_lib.baseboard_fab2(sch_1):page237_i80"
				( objectStatus "F398" )
			)
			( gate "@baseboard_fab2_lib.baseboard_fab2(sch_1):page241_i18"
				( objectStatus "F299" )
			)
			( gate "@baseboard_fab2_lib.baseboard_fab2(sch_1):page241_i83"
				( objectStatus "F46" )
			)
			( gate "@baseboard_fab2_lib.baseboard_fab2(sch_1):page165_i52"
				( objectStatus "F4199" )
				( pin "SCL"
					( objectStatus "EU9G1.3" )
				)
				( pin "SDA"
					( objectStatus "EU9G1.2" )
				)
			)
			( gate "@baseboard_fab2_lib.baseboard_fab2(sch_1):page114_i50"
				( objectStatus "F3157" )
			)
			( gate "@baseboard_fab2_lib.baseboard_fab2(sch_1):page114_i47"
				( objectStatus "F3156" )
			)
			( gate "@baseboard_fab2_lib.baseboard_fab2(sch_1):page118_i79"
				( objectStatus "F3119" )
			)
			( gate "@baseboard_fab2_lib.baseboard_fab2(sch_1):page118_i77"
				( objectStatus "F3118" )
			)
			( gate "@baseboard_fab2_lib.baseboard_fab2(sch_1):page118_i76"
				( objectStatus "F2231" )
			)
			( gate "@baseboard_fab2_lib.baseboard_fab2(sch_1):page91_i35"
				( objectStatus "F1380" )
			)
			( gate "@baseboard_fab2_lib.baseboard_fab2(sch_1):page91_i36"
				( objectStatus "F1381" )
			)
			( gate "@baseboard_fab2_lib.baseboard_fab2(sch_1):page91_i37"
				( objectStatus "F1382" )
			)
			( gate "@baseboard_fab2_lib.baseboard_fab2(sch_1):page91_i34"
				( objectStatus "F1379" )
			)
			( gate "@baseboard_fab2_lib.baseboard_fab2(sch_1):page21_i227"
				( objectStatus "F1384" )
			)
			( gate "@baseboard_fab2_lib.baseboard_fab2(sch_1):page55_i157"
				( objectStatus "F1378" )
			)
			( gate "@baseboard_fab2_lib.baseboard_fab2(sch_1):page21_i241"
				( objectStatus "F1383" )
			)
			( gate "@baseboard_fab2_lib.baseboard_fab2(sch_1):page55_i158"
				( objectStatus "F1377" )
			)
			( gate "@baseboard_fab2_lib.baseboard_fab2(sch_1):page114_i149"
				( objectStatus "F1065" )
			)
			( gate "@baseboard_fab2_lib.baseboard_fab2(sch_1):page114_i48"
				( objectStatus "F257" )
			)
			( gate "@baseboard_fab2_lib.baseboard_fab2(sch_1):page161_i120"
				( objectStatus "F1232" )
			)
			( gate "@baseboard_fab2_lib.baseboard_fab2(sch_1):page240_i111"
				( objectStatus "F1222" )
			)
			( gate "@baseboard_fab2_lib.baseboard_fab2(sch_1):page133_i122"
				( objectStatus "F1231" )
			)
			( gate "@baseboard_fab2_lib.baseboard_fab2(sch_1):page189_i45"
				( objectStatus "F1228" )
			)
			( gate "@baseboard_fab2_lib.baseboard_fab2(sch_1):page153_i170"
				( objectStatus "F1224" )
			)
			( gate "@baseboard_fab2_lib.baseboard_fab2(sch_1):page153_i179"
				( objectStatus "F1227" )
			)
			( gate "@baseboard_fab2_lib.baseboard_fab2(sch_1):page196_i71"
				( objectStatus "F1229" )
			)
			( gate "@baseboard_fab2_lib.baseboard_fab2(sch_1):page125_i71"
				( objectStatus "F1223" )
			)
			( gate "@baseboard_fab2_lib.baseboard_fab2(sch_1):page102_i38"
				( objectStatus "F1226" )
			)
			( gate "@baseboard_fab2_lib.baseboard_fab2(sch_1):page102_i37"
				( objectStatus "F1225" )
			)
			( gate "@baseboard_fab2_lib.baseboard_fab2(sch_1):page200_i70"
				( objectStatus "F1221" )
			)
			( gate "@baseboard_fab2_lib.baseboard_fab2(sch_1):page145_i205"
				( objectStatus "F1230" )
			)
			( gate "@baseboard_fab2_lib.baseboard_fab2(sch_1):page37_i303"
				( objectStatus "F807" )
			)
			( gate "@baseboard_fab2_lib.baseboard_fab2(sch_1):page71_i43"
				( objectStatus "F808" )
			)
			( gate "@baseboard_fab2_lib.baseboard_fab2(sch_1):page238_i17"
				( objectStatus "F387" )
			)
			( gate "@baseboard_fab2_lib.baseboard_fab2(sch_1):page103_i9"
				( objectStatus "F785" )
			)
			( gate "@baseboard_fab2_lib.baseboard_fab2(sch_1):page103_i14"
				( objectStatus "F783" )
			)
			( gate "@baseboard_fab2_lib.baseboard_fab2(sch_1):page103_i19"
				( objectStatus "F789" )
			)
			( gate "@baseboard_fab2_lib.baseboard_fab2(sch_1):page103_i24"
				( objectStatus "F787" )
			)
			( gate "@baseboard_fab2_lib.baseboard_fab2(sch_1):page103_i29"
				( objectStatus "F793" )
			)
			( gate "@baseboard_fab2_lib.baseboard_fab2(sch_1):page103_i34"
				( objectStatus "F791" )
			)
			( gate "@baseboard_fab2_lib.baseboard_fab2(sch_1):page103_i39"
				( objectStatus "F797" )
			)
			( gate "@baseboard_fab2_lib.baseboard_fab2(sch_1):page103_i44"
				( objectStatus "F795" )
			)
			( gate "@baseboard_fab2_lib.baseboard_fab2(sch_1):page103_i54"
				( objectStatus "F805" )
			)
			( gate "@baseboard_fab2_lib.baseboard_fab2(sch_1):page103_i59"
				( objectStatus "F802" )
			)
			( gate "@baseboard_fab2_lib.baseboard_fab2(sch_1):page103_i64"
				( objectStatus "F803" )
			)
			( gate "@baseboard_fab2_lib.baseboard_fab2(sch_1):page103_i74"
				( objectStatus "F800" )
			)
			( gate "@baseboard_fab2_lib.baseboard_fab2(sch_1):page103_i79"
				( objectStatus "F801" )
			)
			( gate "@baseboard_fab2_lib.baseboard_fab2(sch_1):page103_i84"
				( objectStatus "F798" )
			)
			( gate "@baseboard_fab2_lib.baseboard_fab2(sch_1):page103_i89"
				( objectStatus "F799" )
			)
			( gate "@baseboard_fab2_lib.baseboard_fab2(sch_1):page103_i94"
				( objectStatus "F794" )
			)
			( gate "@baseboard_fab2_lib.baseboard_fab2(sch_1):page103_i99"
				( objectStatus "F796" )
			)
			( gate "@baseboard_fab2_lib.baseboard_fab2(sch_1):page103_i104"
				( objectStatus "F790" )
			)
			( gate "@baseboard_fab2_lib.baseboard_fab2(sch_1):page103_i109"
				( objectStatus "F792" )
			)
			( gate "@baseboard_fab2_lib.baseboard_fab2(sch_1):page103_i114"
				( objectStatus "F786" )
			)
			( gate "@baseboard_fab2_lib.baseboard_fab2(sch_1):page103_i119"
				( objectStatus "F788" )
			)
			( gate "@baseboard_fab2_lib.baseboard_fab2(sch_1):page103_i69"
				( objectStatus "F782" )
			)
			( gate "@baseboard_fab2_lib.baseboard_fab2(sch_1):page103_i1"
				( objectStatus "F784" )
			)
			( gate "@baseboard_fab2_lib.baseboard_fab2(sch_1):page103_i49"
				( objectStatus "F804" )
			)
			( gate "@baseboard_fab2_lib.baseboard_fab2(sch_1):page204_i46"
				( objectStatus "F2090" )
			)
			( gate "@baseboard_fab2_lib.baseboard_fab2(sch_1):page209_i32"
				( objectStatus "F2091" )
			)
			( gate "@baseboard_fab2_lib.baseboard_fab2(sch_1):page217_i124"
				( objectStatus "F2085" )
			)
			( gate "@baseboard_fab2_lib.baseboard_fab2(sch_1):page225_i124"
				( objectStatus "F2088" )
			)
			( gate "@baseboard_fab2_lib.baseboard_fab2(sch_1):page228_i124"
				( objectStatus "F2089" )
			)
			( gate "@baseboard_fab2_lib.baseboard_fab2(sch_1):page220_i124"
				( objectStatus "F2087" )
			)
			( gate "@baseboard_fab2_lib.baseboard_fab2(sch_1):page212_i56"
				( objectStatus "F2086" )
			)
			( gate "@baseboard_fab2_lib.baseboard_fab2(sch_1):page102_i1"
				( objectStatus "F2006" )
				( pin "DIF_0N"
					( objectStatus "EU4D2.18" )
				)
				( pin "DIF_0P"
					( objectStatus "EU4D2.17" )
				)
				( pin "DIF_10N"
					( objectStatus "EU4D2.60" )
				)
				( pin "DIF_10P"
					( objectStatus "EU4D2.59" )
				)
				( pin "DIF_11N"
					( objectStatus "EU4D2.64" )
				)
				( pin "DIF_11P"
					( objectStatus "EU4D2.63" )
				)
				( pin "DIF_1N"
					( objectStatus "EU4D2.22" )
				)
				( pin "DIF_1P"
					( objectStatus "EU4D2.21" )
				)
				( pin "DIF_2N"
					( objectStatus "EU4D2.27" )
				)
				( pin "DIF_2P"
					( objectStatus "EU4D2.26" )
				)
				( pin "DIF_3N"
					( objectStatus "EU4D2.31" )
				)
				( pin "DIF_3P"
					( objectStatus "EU4D2.30" )
				)
				( pin "DIF_4N"
					( objectStatus "EU4D2.35" )
				)
				( pin "DIF_4P"
					( objectStatus "EU4D2.34" )
				)
				( pin "DIF_5N"
					( objectStatus "EU4D2.39" )
				)
				( pin "DIF_5P"
					( objectStatus "EU4D2.38" )
				)
				( pin "DIF_6N"
					( objectStatus "EU4D2.43" )
				)
				( pin "DIF_6P"
					( objectStatus "EU4D2.42" )
				)
				( pin "DIF_7N"
					( objectStatus "EU4D2.47" )
				)
				( pin "DIF_7P"
					( objectStatus "EU4D2.46" )
				)
				( pin "DIF_8N"
					( objectStatus "EU4D2.51" )
				)
				( pin "DIF_8P"
					( objectStatus "EU4D2.50" )
				)
				( pin "DIF_9N"
					( objectStatus "EU4D2.55" )
				)
				( pin "DIF_9P"
					( objectStatus "EU4D2.54" )
				)
			)
			( gate "@baseboard_fab2_lib.baseboard_fab2(sch_1):page168_i19"
				( objectStatus "F2180" )
			)
			( gate "@baseboard_fab2_lib.baseboard_fab2(sch_1):page168_i18"
				( objectStatus "F2179" )
			)
			( gate "@baseboard_fab2_lib.baseboard_fab2(sch_1):page199_i86"
				( objectStatus "F2182" )
			)
			( gate "@baseboard_fab2_lib.baseboard_fab2(sch_1):page199_i82"
				( objectStatus "F2181" )
			)
			( gate "@baseboard_fab2_lib.baseboard_fab2(sch_1):page200_i196"
				( objectStatus "F2178" )
			)
			( gate "@baseboard_fab2_lib.baseboard_fab2(sch_1):page200_i199"
				( objectStatus "F2177" )
			)
			( gate "@baseboard_fab2_lib.baseboard_fab2(sch_1):page235_i217"
				( objectStatus "F995" )
			)
			( gate "@baseboard_fab2_lib.baseboard_fab2(sch_1):page174_i26"
				( objectStatus "F2251" )
				( pin "GND1"
					( objectStatus "J8A2.A3" )
				)
				( pin "GND10"
					( objectStatus "J8A2.D3" )
				)
				( pin "GND11"
					( objectStatus "J8A2.D6" )
				)
				( pin "GND12"
					( objectStatus "J8A2.D9" )
				)
				( pin "GND2"
					( objectStatus "J8A2.A6" )
				)
				( pin "GND3"
					( objectStatus "J8A2.A9" )
				)
				( pin "GND4"
					( objectStatus "J8A2.B3" )
				)
				( pin "GND5"
					( objectStatus "J8A2.B6" )
				)
				( pin "GND6"
					( objectStatus "J8A2.B9" )
				)
				( pin "GND7"
					( objectStatus "J8A2.C3" )
				)
				( pin "GND8"
					( objectStatus "J8A2.C6" )
				)
				( pin "GND9"
					( objectStatus "J8A2.C9" )
				)
				( pin "RXA0_DN"
					( objectStatus "J8A2.B5" )
				)
				( pin "RXA0_DP"
					( objectStatus "J8A2.B4" )
				)
				( pin "RXA1_DN"
					( objectStatus "J8A2.A5" )
				)
				( pin "RXA1_DP"
					( objectStatus "J8A2.A4" )
				)
				( pin "RXA2_DN"
					( objectStatus "J8A2.B8" )
				)
				( pin "RXA2_DP"
					( objectStatus "J8A2.B7" )
				)
				( pin "RXA3_DN"
					( objectStatus "J8A2.A8" )
				)
				( pin "RXA3_DP"
					( objectStatus "J8A2.A7" )
				)
				( pin "SIDEBAND0"
					( objectStatus "J8A2.A2" )
				)
				( pin "SIDEBAND1"
					( objectStatus "J8A2.B2" )
				)
				( pin "SIDEBAND2"
					( objectStatus "J8A2.C2" )
				)
				( pin "SIDEBAND3"
					( objectStatus "J8A2.B1" )
				)
				( pin "SIDEBAND4"
					( objectStatus "J8A2.C1" )
				)
				( pin "SIDEBAND5"
					( objectStatus "J8A2.D1" )
				)
				( pin "SIDEBAND6"
					( objectStatus "J8A2.D2" )
				)
				( pin "SIDEBAND7"
					( objectStatus "J8A2.A1" )
				)
				( pin "TXA0_DN"
					( objectStatus "J8A2.D5" )
				)
				( pin "TXA0_DP"
					( objectStatus "J8A2.D4" )
				)
				( pin "TXA1_DN"
					( objectStatus "J8A2.C5" )
				)
				( pin "TXA1_DP"
					( objectStatus "J8A2.C4" )
				)
				( pin "TXA2_DN"
					( objectStatus "J8A2.D8" )
				)
				( pin "TXA2_DP"
					( objectStatus "J8A2.D7" )
				)
				( pin "TXA3_DN"
					( objectStatus "J8A2.C8" )
				)
				( pin "TXA3_DP"
					( objectStatus "J8A2.C7" )
				)
			)
			( gate "@baseboard_fab2_lib.baseboard_fab2(sch_1):page173_i163"
				( objectStatus "F2240" )
				( pin "GND(0)"
					( objectStatus "J8A1.2D9" )
				)
				( pin "GND(10)"
					( objectStatus "J8A1.2A6" )
				)
				( pin "GND(11)"
					( objectStatus "J8A1.2A3" )
				)
				( pin "GND(12)"
					( objectStatus "J8A1.1D9" )
				)
				( pin "GND(13)"
					( objectStatus "J8A1.1D6" )
				)
				( pin "GND(14)"
					( objectStatus "J8A1.1D3" )
				)
				( pin "GND(15)"
					( objectStatus "J8A1.1C9" )
				)
				( pin "GND(16)"
					( objectStatus "J8A1.1C6" )
				)
				( pin "GND(17)"
					( objectStatus "J8A1.1C3" )
				)
				( pin "GND(18)"
					( objectStatus "J8A1.1B9" )
				)
				( pin "GND(19)"
					( objectStatus "J8A1.1B6" )
				)
				( pin "GND(1)"
					( objectStatus "J8A1.2D6" )
				)
				( pin "GND(20)"
					( objectStatus "J8A1.1B3" )
				)
				( pin "GND(21)"
					( objectStatus "J8A1.1A9" )
				)
				( pin "GND(22)"
					( objectStatus "J8A1.1A6" )
				)
				( pin "GND(23)"
					( objectStatus "J8A1.1A3" )
				)
				( pin "GND(2)"
					( objectStatus "J8A1.2D3" )
				)
				( pin "GND(3)"
					( objectStatus "J8A1.2C9" )
				)
				( pin "GND(4)"
					( objectStatus "J8A1.2C6" )
				)
				( pin "GND(5)"
					( objectStatus "J8A1.2C3" )
				)
				( pin "GND(6)"
					( objectStatus "J8A1.2B9" )
				)
				( pin "GND(7)"
					( objectStatus "J8A1.2B6" )
				)
				( pin "GND(8)"
					( objectStatus "J8A1.2B3" )
				)
				( pin "GND(9)"
					( objectStatus "J8A1.2A9" )
				)
				( pin "RXA0_DN"
					( objectStatus "J8A1.1B5" )
				)
				( pin "RXA0_DP"
					( objectStatus "J8A1.1B4" )
				)
				( pin "RXA1_DN"
					( objectStatus "J8A1.1A5" )
				)
				( pin "RXA1_DP"
					( objectStatus "J8A1.1A4" )
				)
				( pin "RXA2_DN"
					( objectStatus "J8A1.1B8" )
				)
				( pin "RXA2_DP"
					( objectStatus "J8A1.1B7" )
				)
				( pin "RXA3_DN"
					( objectStatus "J8A1.1A8" )
				)
				( pin "RXA3_DP"
					( objectStatus "J8A1.1A7" )
				)
				( pin "RXB0_DN"
					( objectStatus "J8A1.2B5" )
				)
				( pin "RXB0_DP"
					( objectStatus "J8A1.2B4" )
				)
				( pin "RXB1_DN"
					( objectStatus "J8A1.2A5" )
				)
				( pin "RXB1_DP"
					( objectStatus "J8A1.2A4" )
				)
				( pin "RXB2_DN"
					( objectStatus "J8A1.2B8" )
				)
				( pin "RXB2_DP"
					( objectStatus "J8A1.2B7" )
				)
				( pin "RXB3_DN"
					( objectStatus "J8A1.2A8" )
				)
				( pin "RXB3_DP"
					( objectStatus "J8A1.2A7" )
				)
				( pin "SIDEBANDA_0"
					( objectStatus "J8A1.1A2" )
				)
				( pin "SIDEBANDA_1"
					( objectStatus "J8A1.1B2" )
				)
				( pin "SIDEBANDA_2"
					( objectStatus "J8A1.1C2" )
				)
				( pin "SIDEBANDA_3"
					( objectStatus "J8A1.1B1" )
				)
				( pin "SIDEBANDA_4"
					( objectStatus "J8A1.1C1" )
				)
				( pin "SIDEBANDA_5"
					( objectStatus "J8A1.1D1" )
				)
				( pin "SIDEBANDA_6"
					( objectStatus "J8A1.1D2" )
				)
				( pin "SIDEBANDA_7"
					( objectStatus "J8A1.1A1" )
				)
				( pin "SIDEBANDB_0"
					( objectStatus "J8A1.2A2" )
				)
				( pin "SIDEBANDB_1"
					( objectStatus "J8A1.2B2" )
				)
				( pin "SIDEBANDB_2"
					( objectStatus "J8A1.2C2" )
				)
				( pin "SIDEBANDB_3"
					( objectStatus "J8A1.2B1" )
				)
				( pin "SIDEBANDB_4"
					( objectStatus "J8A1.2C1" )
				)
				( pin "SIDEBANDB_5"
					( objectStatus "J8A1.2D1" )
				)
				( pin "SIDEBANDB_6"
					( objectStatus "J8A1.2D2" )
				)
				( pin "SIDEBANDB_7"
					( objectStatus "J8A1.2A1" )
				)
				( pin "TXA0_DN"
					( objectStatus "J8A1.1D5" )
				)
				( pin "TXA0_DP"
					( objectStatus "J8A1.1D4" )
				)
				( pin "TXA1_DN"
					( objectStatus "J8A1.1C5" )
				)
				( pin "TXA1_DP"
					( objectStatus "J8A1.1C4" )
				)
				( pin "TXA2_DN"
					( objectStatus "J8A1.1D8" )
				)
				( pin "TXA2_DP"
					( objectStatus "J8A1.1D7" )
				)
				( pin "TXA3_DN"
					( objectStatus "J8A1.1C8" )
				)
				( pin "TXA3_DP"
					( objectStatus "J8A1.1C7" )
				)
				( pin "TXB0_DN"
					( objectStatus "J8A1.2D5" )
				)
				( pin "TXB0_DP"
					( objectStatus "J8A1.2D4" )
				)
				( pin "TXB1_DN"
					( objectStatus "J8A1.2C5" )
				)
				( pin "TXB1_DP"
					( objectStatus "J8A1.2C4" )
				)
				( pin "TXB2_DN"
					( objectStatus "J8A1.2D8" )
				)
				( pin "TXB2_DP"
					( objectStatus "J8A1.2D7" )
				)
				( pin "TXB3_DN"
					( objectStatus "J8A1.2C8" )
				)
				( pin "TXB3_DP"
					( objectStatus "J8A1.2C7" )
				)
			)
			( gate "@baseboard_fab2_lib.baseboard_fab2(sch_1):page153_i146"
				( objectStatus "F1" )
				( pin "CLK"
					( objectStatus "U7F1.16" )
				)
				( pin "CS_N"
					( objectStatus "U7F1.7" )
				)
				( pin "DI_IO(0)"
					( objectStatus "U7F1.15" )
				)
				( pin "DO_IO(1)"
					( objectStatus "U7F1.8" )
				)
				( pin "HOLD_N_IO(3)"
					( objectStatus "U7F1.1" )
				)
			)
			( gate "@baseboard_fab2_lib.baseboard_fab2(sch_1):page153_i165"
				( objectStatus "F2" )
				( pin "CLK"
					( objectStatus "U3T1.16" )
				)
				( pin "CS_N"
					( objectStatus "U3T1.7" )
				)
				( pin "DI_IO(0)"
					( objectStatus "U3T1.15" )
				)
				( pin "DO_IO(1)"
					( objectStatus "U3T1.8" )
				)
				( pin "HOLD_N_IO(3)"
					( objectStatus "U3T1.1" )
				)
			)
			( gate "@baseboard_fab2_lib.baseboard_fab2(sch_1):page175_i58"
				( objectStatus "F468" )
			)
			( gate "@baseboard_fab2_lib.baseboard_fab2(sch_1):page157_i357"
				( objectStatus "F18" )
			)
			( gate "@baseboard_fab2_lib.baseboard_fab2(sch_1):page157_i356"
				( objectStatus "F17" )
			)
			( gate "@baseboard_fab2_lib.baseboard_fab2(sch_1):page175_i9"
				( objectStatus "F14" )
			)
			( gate "@baseboard_fab2_lib.baseboard_fab2(sch_1):page175_i10"
				( objectStatus "F13" )
			)
			( gate "@baseboard_fab2_lib.baseboard_fab2(sch_1):page175_i18"
				( objectStatus "F16" )
			)
			( gate "@baseboard_fab2_lib.baseboard_fab2(sch_1):page175_i15"
				( objectStatus "F15" )
			)
			( gate "@baseboard_fab2_lib.baseboard_fab2(sch_1):page195_i76"
				( objectStatus "TF-10868" )
			)
			( gate "@baseboard_fab2_lib.baseboard_fab2(sch_1):page156_i269"
				( objectStatus "F19" )
			)
			( gate "@baseboard_fab2_lib.baseboard_fab2(sch_1):page156_i201"
				( objectStatus "F20" )
			)
			( gate "@baseboard_fab2_lib.baseboard_fab2(sch_1):page165_i79"
				( objectStatus "F2185" )
			)
			( gate "@baseboard_fab2_lib.baseboard_fab2(sch_1):page185_i53"
				( objectStatus "F133" )
				( pin "PERN1"
					( objectStatus "J8F1.29" )
				)
				( pin "PERN2"
					( objectStatus "J8F1.17" )
				)
				( pin "PERN3"
					( objectStatus "J8F1.5" )
				)
				( pin "PERP1"
					( objectStatus "J8F1.31" )
				)
				( pin "PERP2"
					( objectStatus "J8F1.19" )
				)
				( pin "PERP3"
					( objectStatus "J8F1.7" )
				)
				( pin "PETN0_SATA_AN"
					( objectStatus "J8F1.47" )
				)
				( pin "PETN1"
					( objectStatus "J8F1.35" )
				)
				( pin "PETN2"
					( objectStatus "J8F1.23" )
				)
				( pin "PETN3"
					( objectStatus "J8F1.11" )
				)
				( pin "PETP0_SATA_AP"
					( objectStatus "J8F1.49" )
				)
				( pin "PETP1"
					( objectStatus "J8F1.37" )
				)
				( pin "PETP2"
					( objectStatus "J8F1.25" )
				)
				( pin "PETP3"
					( objectStatus "J8F1.13" )
				)
				( pin "REFCLKN"
					( objectStatus "J8F1.53" )
				)
				( pin "REFCLKP"
					( objectStatus "J8F1.55" )
				)
			)
			( gate "@baseboard_fab2_lib.baseboard_fab2(sch_1):page157_i374"
				( objectStatus "F38" )
			)
			( gate "@baseboard_fab2_lib.baseboard_fab2(sch_1):page155_i178"
				( objectStatus "F34" )
			)
			( gate "@baseboard_fab2_lib.baseboard_fab2(sch_1):page111_i85"
				( objectStatus "F41" )
			)
			( gate "@baseboard_fab2_lib.baseboard_fab2(sch_1):page170_i46"
				( objectStatus "F40" )
			)
			( gate "@baseboard_fab2_lib.baseboard_fab2(sch_1):page170_i4"
				( objectStatus "F37" )
			)
			( gate "@baseboard_fab2_lib.baseboard_fab2(sch_1):page185_i110"
				( objectStatus "F39" )
			)
			( gate "@baseboard_fab2_lib.baseboard_fab2(sch_1):page161_i88"
				( objectStatus "F36" )
				( pin "Y"
					( objectStatus "U8G2.4" )
				)
			)
			( gate "@baseboard_fab2_lib.baseboard_fab2(sch_1):page161_i92"
				( objectStatus "F35" )
				( pin "Y"
					( objectStatus "U8G3.4" )
				)
			)
			( gate "@baseboard_fab2_lib.baseboard_fab2(sch_1):page151_i69"
				( objectStatus "F33" )
			)
			( gate "@baseboard_fab2_lib.baseboard_fab2(sch_1):page196_i128"
				( objectStatus "F2208" )
			)
			( gate "@baseboard_fab2_lib.baseboard_fab2(sch_1):page196_i103"
				( objectStatus "F2207" )
			)
			( gate "@baseboard_fab2_lib.baseboard_fab2(sch_1):page200_i213"
				( objectStatus "F2205" )
			)
			( gate "@baseboard_fab2_lib.baseboard_fab2(sch_1):page200_i214"
				( objectStatus "F2206" )
			)
			( gate "@baseboard_fab2_lib.baseboard_fab2(sch_1):page199_i100"
				( objectStatus "F494" )
			)
			( gate "@baseboard_fab2_lib.baseboard_fab2(sch_1):page168_i7"
				( objectStatus "F493" )
			)
			( gate "@baseboard_fab2_lib.baseboard_fab2(sch_1):page223_i77"
				( objectStatus "F658" )
			)
			( gate "@baseboard_fab2_lib.baseboard_fab2(sch_1):page235_i176"
				( objectStatus "F657" )
			)
			( gate "@baseboard_fab2_lib.baseboard_fab2(sch_1):page211_i65"
				( objectStatus "F656" )
			)
			( gate "@baseboard_fab2_lib.baseboard_fab2(sch_1):page201_i120"
				( objectStatus "F655" )
			)
			( gate "@baseboard_fab2_lib.baseboard_fab2(sch_1):page201_i121"
				( objectStatus "F654" )
			)
			( gate "@baseboard_fab2_lib.baseboard_fab2(sch_1):page215_i321"
				( objectStatus "F653" )
			)
			( gate "@baseboard_fab2_lib.baseboard_fab2(sch_1):page206_i112"
				( objectStatus "F652" )
			)
			( gate "@baseboard_fab2_lib.baseboard_fab2(sch_1):page194_i155"
				( objectStatus "F651" )
			)
			( gate "@baseboard_fab2_lib.baseboard_fab2(sch_1):page218_i37"
				( objectStatus "F298" )
			)
			( gate "@baseboard_fab2_lib.baseboard_fab2(sch_1):page215_i317"
				( objectStatus "F297" )
			)
			( gate "@baseboard_fab2_lib.baseboard_fab2(sch_1):page193_i169"
				( objectStatus "F296" )
			)
			( gate "@baseboard_fab2_lib.baseboard_fab2(sch_1):page217_i250"
				( objectStatus "F2864" )
			)
			( gate "@baseboard_fab2_lib.baseboard_fab2(sch_1):page217_i240"
				( objectStatus "F2862" )
			)
			( gate "@baseboard_fab2_lib.baseboard_fab2(sch_1):page225_i236"
				( objectStatus "F2758" )
			)
			( gate "@baseboard_fab2_lib.baseboard_fab2(sch_1):page217_i231"
				( objectStatus "F2872" )
			)
			( gate "@baseboard_fab2_lib.baseboard_fab2(sch_1):page217_i223"
				( objectStatus "F2861" )
			)
			( gate "@baseboard_fab2_lib.baseboard_fab2(sch_1):page220_i219"
				( objectStatus "F2938" )
			)
			( gate "@baseboard_fab2_lib.baseboard_fab2(sch_1):page220_i214"
				( objectStatus "F2937" )
			)
			( gate "@baseboard_fab2_lib.baseboard_fab2(sch_1):page220_i210"
				( objectStatus "F2936" )
			)
			( gate "@baseboard_fab2_lib.baseboard_fab2(sch_1):page220_i206"
				( objectStatus "F2935" )
			)
			( gate "@baseboard_fab2_lib.baseboard_fab2(sch_1):page225_i241"
				( objectStatus "F2754" )
			)
			( gate "@baseboard_fab2_lib.baseboard_fab2(sch_1):page225_i232"
				( objectStatus "F2755" )
			)
			( gate "@baseboard_fab2_lib.baseboard_fab2(sch_1):page225_i228"
				( objectStatus "F2756" )
			)
			( gate "@baseboard_fab2_lib.baseboard_fab2(sch_1):page228_i243"
				( objectStatus "F2770" )
			)
			( gate "@baseboard_fab2_lib.baseboard_fab2(sch_1):page228_i238"
				( objectStatus "F2796" )
			)
			( gate "@baseboard_fab2_lib.baseboard_fab2(sch_1):page228_i234"
				( objectStatus "F3057" )
			)
			( gate "@baseboard_fab2_lib.baseboard_fab2(sch_1):page228_i230"
				( objectStatus "F3058" )
			)
			( gate "@baseboard_fab2_lib.baseboard_fab2(sch_1):page217_i246"
				( objectStatus "F2863" )
			)
			( gate "@baseboard_fab2_lib.baseboard_fab2(sch_1):page217_i245"
				( objectStatus "F2871" )
			)
			( gate "@baseboard_fab2_lib.baseboard_fab2(sch_1):page217_i241"
				( objectStatus "F2869" )
			)
			( gate "@baseboard_fab2_lib.baseboard_fab2(sch_1):page217_i237"
				( objectStatus "F2867" )
			)
			( gate "@baseboard_fab2_lib.baseboard_fab2(sch_1):page217_i235"
				( objectStatus "F2868" )
			)
			( gate "@baseboard_fab2_lib.baseboard_fab2(sch_1):page217_i234"
				( objectStatus "F2866" )
			)
			( gate "@baseboard_fab2_lib.baseboard_fab2(sch_1):page217_i230"
				( objectStatus "F2865" )
			)
			( gate "@baseboard_fab2_lib.baseboard_fab2(sch_1):page217_i227"
				( objectStatus "F2857" )
			)
			( gate "@baseboard_fab2_lib.baseboard_fab2(sch_1):page217_i226"
				( objectStatus "F2858" )
			)
			( gate "@baseboard_fab2_lib.baseboard_fab2(sch_1):page217_i221"
				( objectStatus "F2859" )
			)
			( gate "@baseboard_fab2_lib.baseboard_fab2(sch_1):page217_i220"
				( objectStatus "F2860" )
			)
			( gate "@baseboard_fab2_lib.baseboard_fab2(sch_1):page217_i217"
				( objectStatus "F2870" )
			)
			( gate "@baseboard_fab2_lib.baseboard_fab2(sch_1):page220_i217"
				( objectStatus "F2926" )
			)
			( gate "@baseboard_fab2_lib.baseboard_fab2(sch_1):page220_i216"
				( objectStatus "F2929" )
			)
			( gate "@baseboard_fab2_lib.baseboard_fab2(sch_1):page220_i215"
				( objectStatus "F2928" )
			)
			( gate "@baseboard_fab2_lib.baseboard_fab2(sch_1):page220_i213"
				( objectStatus "F2927" )
			)
			( gate "@baseboard_fab2_lib.baseboard_fab2(sch_1):page220_i212"
				( objectStatus "F2934" )
			)
			( gate "@baseboard_fab2_lib.baseboard_fab2(sch_1):page220_i211"
				( objectStatus "F2933" )
			)
			( gate "@baseboard_fab2_lib.baseboard_fab2(sch_1):page220_i209"
				( objectStatus "F2932" )
			)
			( gate "@baseboard_fab2_lib.baseboard_fab2(sch_1):page220_i208"
				( objectStatus "F2931" )
			)
			( gate "@baseboard_fab2_lib.baseboard_fab2(sch_1):page220_i207"
				( objectStatus "F2925" )
			)
			( gate "@baseboard_fab2_lib.baseboard_fab2(sch_1):page220_i205"
				( objectStatus "F2924" )
			)
			( gate "@baseboard_fab2_lib.baseboard_fab2(sch_1):page220_i204"
				( objectStatus "F2923" )
			)
			( gate "@baseboard_fab2_lib.baseboard_fab2(sch_1):page220_i203"
				( objectStatus "F2922" )
			)
			( gate "@baseboard_fab2_lib.baseboard_fab2(sch_1):page225_i239"
				( objectStatus "F2759" )
			)
			( gate "@baseboard_fab2_lib.baseboard_fab2(sch_1):page225_i238"
				( objectStatus "F2786" )
			)
			( gate "@baseboard_fab2_lib.baseboard_fab2(sch_1):page225_i237"
				( objectStatus "F2787" )
			)
			( gate "@baseboard_fab2_lib.baseboard_fab2(sch_1):page225_i235"
				( objectStatus "F2789" )
			)
			( gate "@baseboard_fab2_lib.baseboard_fab2(sch_1):page225_i234"
				( objectStatus "F2788" )
			)
			( gate "@baseboard_fab2_lib.baseboard_fab2(sch_1):page225_i233"
				( objectStatus "F2765" )
			)
			( gate "@baseboard_fab2_lib.baseboard_fab2(sch_1):page225_i231"
				( objectStatus "F2764" )
			)
			( gate "@baseboard_fab2_lib.baseboard_fab2(sch_1):page225_i230"
				( objectStatus "F2763" )
			)
			( gate "@baseboard_fab2_lib.baseboard_fab2(sch_1):page225_i229"
				( objectStatus "F2762" )
			)
			( gate "@baseboard_fab2_lib.baseboard_fab2(sch_1):page225_i227"
				( objectStatus "F2761" )
			)
			( gate "@baseboard_fab2_lib.baseboard_fab2(sch_1):page225_i226"
				( objectStatus "F2760" )
			)
			( gate "@baseboard_fab2_lib.baseboard_fab2(sch_1):page225_i225"
				( objectStatus "F2757" )
			)
			( gate "@baseboard_fab2_lib.baseboard_fab2(sch_1):page228_i241"
				( objectStatus "F2776" )
			)
			( gate "@baseboard_fab2_lib.baseboard_fab2(sch_1):page228_i240"
				( objectStatus "F2775" )
			)
			( gate "@baseboard_fab2_lib.baseboard_fab2(sch_1):page228_i239"
				( objectStatus "F2774" )
			)
			( gate "@baseboard_fab2_lib.baseboard_fab2(sch_1):page228_i237"
				( objectStatus "F2773" )
			)
			( gate "@baseboard_fab2_lib.baseboard_fab2(sch_1):page228_i236"
				( objectStatus "F2772" )
			)
			( gate "@baseboard_fab2_lib.baseboard_fab2(sch_1):page228_i235"
				( objectStatus "F2766" )
			)
			( gate "@baseboard_fab2_lib.baseboard_fab2(sch_1):page228_i233"
				( objectStatus "F2768" )
			)
			( gate "@baseboard_fab2_lib.baseboard_fab2(sch_1):page228_i232"
				( objectStatus "F2793" )
			)
			( gate "@baseboard_fab2_lib.baseboard_fab2(sch_1):page228_i231"
				( objectStatus "F2794" )
			)
			( gate "@baseboard_fab2_lib.baseboard_fab2(sch_1):page228_i229"
				( objectStatus "F2771" )
			)
			( gate "@baseboard_fab2_lib.baseboard_fab2(sch_1):page228_i228"
				( objectStatus "F2767" )
			)
			( gate "@baseboard_fab2_lib.baseboard_fab2(sch_1):page228_i227"
				( objectStatus "F2769" )
			)
			( gate "@baseboard_fab2_lib.baseboard_fab2(sch_1):page225_i218"
				( objectStatus "F3006" )
			)
			( gate "@baseboard_fab2_lib.baseboard_fab2(sch_1):page225_i223"
				( objectStatus "F3005" )
			)
			( gate "@baseboard_fab2_lib.baseboard_fab2(sch_1):page225_i221"
				( objectStatus "F3004" )
			)
			( gate "@baseboard_fab2_lib.baseboard_fab2(sch_1):page225_i220"
				( objectStatus "F3003" )
			)
			( gate "@baseboard_fab2_lib.baseboard_fab2(sch_1):page225_i219"
				( objectStatus "F3012" )
			)
			( gate "@baseboard_fab2_lib.baseboard_fab2(sch_1):page225_i217"
				( objectStatus "F3011" )
			)
			( gate "@baseboard_fab2_lib.baseboard_fab2(sch_1):page225_i216"
				( objectStatus "F3010" )
			)
			( gate "@baseboard_fab2_lib.baseboard_fab2(sch_1):page225_i215"
				( objectStatus "F3009" )
			)
			( gate "@baseboard_fab2_lib.baseboard_fab2(sch_1):page225_i214"
				( objectStatus "F3008" )
			)
			( gate "@baseboard_fab2_lib.baseboard_fab2(sch_1):page225_i213"
				( objectStatus "F3007" )
			)
			( gate "@baseboard_fab2_lib.baseboard_fab2(sch_1):page225_i212"
				( objectStatus "F2967" )
			)
			( gate "@baseboard_fab2_lib.baseboard_fab2(sch_1):page225_i211"
				( objectStatus "F2966" )
			)
			( gate "@baseboard_fab2_lib.baseboard_fab2(sch_1):page225_i210"
				( objectStatus "F3002" )
			)
			( gate "@baseboard_fab2_lib.baseboard_fab2(sch_1):page225_i209"
				( objectStatus "F3001" )
			)
			( gate "@baseboard_fab2_lib.baseboard_fab2(sch_1):page225_i208"
				( objectStatus "F2965" )
			)
			( gate "@baseboard_fab2_lib.baseboard_fab2(sch_1):page225_i207"
				( objectStatus "F2964" )
			)
			( gate "@baseboard_fab2_lib.baseboard_fab2(sch_1):page228_i225"
				( objectStatus "F2795" )
			)
			( gate "@baseboard_fab2_lib.baseboard_fab2(sch_1):page228_i223"
				( objectStatus "F2992" )
			)
			( gate "@baseboard_fab2_lib.baseboard_fab2(sch_1):page228_i222"
				( objectStatus "F2993" )
			)
			( gate "@baseboard_fab2_lib.baseboard_fab2(sch_1):page228_i221"
				( objectStatus "F3048" )
			)
			( gate "@baseboard_fab2_lib.baseboard_fab2(sch_1):page228_i220"
				( objectStatus "F3049" )
			)
			( gate "@baseboard_fab2_lib.baseboard_fab2(sch_1):page228_i219"
				( objectStatus "F3056" )
			)
			( gate "@baseboard_fab2_lib.baseboard_fab2(sch_1):page228_i218"
				( objectStatus "F3055" )
			)
			( gate "@baseboard_fab2_lib.baseboard_fab2(sch_1):page228_i217"
				( objectStatus "F2995" )
			)
			( gate "@baseboard_fab2_lib.baseboard_fab2(sch_1):page228_i216"
				( objectStatus "F2994" )
			)
			( gate "@baseboard_fab2_lib.baseboard_fab2(sch_1):page228_i215"
				( objectStatus "F3054" )
			)
			( gate "@baseboard_fab2_lib.baseboard_fab2(sch_1):page228_i214"
				( objectStatus "F3053" )
			)
			( gate "@baseboard_fab2_lib.baseboard_fab2(sch_1):page228_i213"
				( objectStatus "F3052" )
			)
			( gate "@baseboard_fab2_lib.baseboard_fab2(sch_1):page228_i212"
				( objectStatus "F3050" )
			)
			( gate "@baseboard_fab2_lib.baseboard_fab2(sch_1):page228_i211"
				( objectStatus "F3051" )
			)
			( gate "@baseboard_fab2_lib.baseboard_fab2(sch_1):page228_i210"
				( objectStatus "F3060" )
			)
			( gate "@baseboard_fab2_lib.baseboard_fab2(sch_1):page228_i209"
				( objectStatus "F3059" )
			)
			( gate "@baseboard_fab2_lib.baseboard_fab2(sch_1):page217_i247"
				( objectStatus "F2834" )
			)
			( gate "@baseboard_fab2_lib.baseboard_fab2(sch_1):page217_i244"
				( objectStatus "F2833" )
			)
			( gate "@baseboard_fab2_lib.baseboard_fab2(sch_1):page217_i243"
				( objectStatus "F2832" )
			)
			( gate "@baseboard_fab2_lib.baseboard_fab2(sch_1):page217_i239"
				( objectStatus "F2831" )
			)
			( gate "@baseboard_fab2_lib.baseboard_fab2(sch_1):page217_i238"
				( objectStatus "F2830" )
			)
			( gate "@baseboard_fab2_lib.baseboard_fab2(sch_1):page217_i236"
				( objectStatus "F2829" )
			)
			( gate "@baseboard_fab2_lib.baseboard_fab2(sch_1):page217_i233"
				( objectStatus "F2828" )
			)
			( gate "@baseboard_fab2_lib.baseboard_fab2(sch_1):page217_i232"
				( objectStatus "F2827" )
			)
			( gate "@baseboard_fab2_lib.baseboard_fab2(sch_1):page217_i229"
				( objectStatus "F2835" )
			)
			( gate "@baseboard_fab2_lib.baseboard_fab2(sch_1):page217_i228"
				( objectStatus "F2836" )
			)
			( gate "@baseboard_fab2_lib.baseboard_fab2(sch_1):page217_i225"
				( objectStatus "F2837" )
			)
			( gate "@baseboard_fab2_lib.baseboard_fab2(sch_1):page217_i224"
				( objectStatus "F2838" )
			)
			( gate "@baseboard_fab2_lib.baseboard_fab2(sch_1):page217_i222"
				( objectStatus "F2839" )
			)
			( gate "@baseboard_fab2_lib.baseboard_fab2(sch_1):page217_i219"
				( objectStatus "F2840" )
			)
			( gate "@baseboard_fab2_lib.baseboard_fab2(sch_1):page217_i218"
				( objectStatus "F2841" )
			)
			( gate "@baseboard_fab2_lib.baseboard_fab2(sch_1):page217_i216"
				( objectStatus "F2842" )
			)
			( gate "@baseboard_fab2_lib.baseboard_fab2(sch_1):page220_i237"
				( objectStatus "F2856" )
			)
			( gate "@baseboard_fab2_lib.baseboard_fab2(sch_1):page220_i236"
				( objectStatus "F2855" )
			)
			( gate "@baseboard_fab2_lib.baseboard_fab2(sch_1):page220_i234"
				( objectStatus "F2854" )
			)
			( gate "@baseboard_fab2_lib.baseboard_fab2(sch_1):page220_i233"
				( objectStatus "F2853" )
			)
			( gate "@baseboard_fab2_lib.baseboard_fab2(sch_1):page220_i232"
				( objectStatus "F2852" )
			)
			( gate "@baseboard_fab2_lib.baseboard_fab2(sch_1):page220_i231"
				( objectStatus "F2851" )
			)
			( gate "@baseboard_fab2_lib.baseboard_fab2(sch_1):page220_i230"
				( objectStatus "F2850" )
			)
			( gate "@baseboard_fab2_lib.baseboard_fab2(sch_1):page220_i229"
				( objectStatus "F2849" )
			)
			( gate "@baseboard_fab2_lib.baseboard_fab2(sch_1):page220_i228"
				( objectStatus "F2843" )
			)
			( gate "@baseboard_fab2_lib.baseboard_fab2(sch_1):page220_i227"
				( objectStatus "F2844" )
			)
			( gate "@baseboard_fab2_lib.baseboard_fab2(sch_1):page220_i226"
				( objectStatus "F2845" )
			)
			( gate "@baseboard_fab2_lib.baseboard_fab2(sch_1):page220_i225"
				( objectStatus "F2846" )
			)
			( gate "@baseboard_fab2_lib.baseboard_fab2(sch_1):page220_i224"
				( objectStatus "F2847" )
			)
			( gate "@baseboard_fab2_lib.baseboard_fab2(sch_1):page220_i223"
				( objectStatus "F2848" )
			)
			( gate "@baseboard_fab2_lib.baseboard_fab2(sch_1):page220_i222"
				( objectStatus "F2941" )
			)
			( gate "@baseboard_fab2_lib.baseboard_fab2(sch_1):page220_i221"
				( objectStatus "F2930" )
			)
			( gate "@baseboard_fab2_lib.baseboard_fab2(sch_1):page42_i142"
				( objectStatus "F2886" )
			)
			( gate "@baseboard_fab2_lib.baseboard_fab2(sch_1):page42_i127"
				( objectStatus "F2918" )
			)
			( gate "@baseboard_fab2_lib.baseboard_fab2(sch_1):page42_i130"
				( objectStatus "F2919" )
			)
			( gate "@baseboard_fab2_lib.baseboard_fab2(sch_1):page42_i136"
				( objectStatus "F2920" )
			)
			( gate "@baseboard_fab2_lib.baseboard_fab2(sch_1):page42_i126"
				( objectStatus "F2921" )
			)
			( gate "@baseboard_fab2_lib.baseboard_fab2(sch_1):page42_i129"
				( objectStatus "F2875" )
			)
			( gate "@baseboard_fab2_lib.baseboard_fab2(sch_1):page42_i135"
				( objectStatus "F2888" )
			)
			( gate "@baseboard_fab2_lib.baseboard_fab2(sch_1):page42_i125"
				( objectStatus "F2917" )
			)
			( gate "@baseboard_fab2_lib.baseboard_fab2(sch_1):page42_i128"
				( objectStatus "F2911" )
			)
			( gate "@baseboard_fab2_lib.baseboard_fab2(sch_1):page42_i134"
				( objectStatus "F2912" )
			)
			( gate "@baseboard_fab2_lib.baseboard_fab2(sch_1):page42_i118"
				( objectStatus "F2913" )
			)
			( gate "@baseboard_fab2_lib.baseboard_fab2(sch_1):page42_i123"
				( objectStatus "F2914" )
			)
			( gate "@baseboard_fab2_lib.baseboard_fab2(sch_1):page42_i132"
				( objectStatus "F2915" )
			)
			( gate "@baseboard_fab2_lib.baseboard_fab2(sch_1):page42_i117"
				( objectStatus "F2916" )
			)
			( gate "@baseboard_fab2_lib.baseboard_fab2(sch_1):page42_i120"
				( objectStatus "F2876" )
			)
			( gate "@baseboard_fab2_lib.baseboard_fab2(sch_1):page42_i131"
				( objectStatus "F2887" )
			)
			( gate "@baseboard_fab2_lib.baseboard_fab2(sch_1):page42_i112"
				( objectStatus "F2874" )
			)
			( gate "@baseboard_fab2_lib.baseboard_fab2(sch_1):page42_i103"
				( objectStatus "F2898" )
			)
			( gate "@baseboard_fab2_lib.baseboard_fab2(sch_1):page42_i106"
				( objectStatus "F2899" )
			)
			( gate "@baseboard_fab2_lib.baseboard_fab2(sch_1):page42_i111"
				( objectStatus "F2900" )
			)
			( gate "@baseboard_fab2_lib.baseboard_fab2(sch_1):page42_i102"
				( objectStatus "F2901" )
			)
			( gate "@baseboard_fab2_lib.baseboard_fab2(sch_1):page42_i154"
				( objectStatus "F2904" )
			)
			( gate "@baseboard_fab2_lib.baseboard_fab2(sch_1):page42_i138"
				( objectStatus "F2906" )
			)
			( gate "@baseboard_fab2_lib.baseboard_fab2(sch_1):page42_i140"
				( objectStatus "F2891" )
			)
			( gate "@baseboard_fab2_lib.baseboard_fab2(sch_1):page42_i115"
				( objectStatus "F2890" )
			)
			( gate "@baseboard_fab2_lib.baseboard_fab2(sch_1):page42_i114"
				( objectStatus "F2889" )
			)
			( gate "@baseboard_fab2_lib.baseboard_fab2(sch_1):page42_i113"
				( objectStatus "F2873" )
			)
			( gate "@baseboard_fab2_lib.baseboard_fab2(sch_1):page42_i104"
				( objectStatus "F2883" )
			)
			( gate "@baseboard_fab2_lib.baseboard_fab2(sch_1):page42_i107"
				( objectStatus "F2884" )
			)
			( gate "@baseboard_fab2_lib.baseboard_fab2(sch_1):page76_i196"
				( objectStatus "F2983" )
			)
			( gate "@baseboard_fab2_lib.baseboard_fab2(sch_1):page76_i122"
				( objectStatus "F3022" )
			)
			( gate "@baseboard_fab2_lib.baseboard_fab2(sch_1):page76_i124"
				( objectStatus "F3040" )
			)
			( gate "@baseboard_fab2_lib.baseboard_fab2(sch_1):page76_i70"
				( objectStatus "F3020" )
			)
			( gate "@baseboard_fab2_lib.baseboard_fab2(sch_1):page76_i119"
				( objectStatus "F3019" )
			)
			( gate "@baseboard_fab2_lib.baseboard_fab2(sch_1):page76_i123"
				( objectStatus "F3015" )
			)
			( gate "@baseboard_fab2_lib.baseboard_fab2(sch_1):page76_i69"
				( objectStatus "F2990" )
			)
			( gate "@baseboard_fab2_lib.baseboard_fab2(sch_1):page76_i111"
				( objectStatus "F2991" )
			)
			( gate "@baseboard_fab2_lib.baseboard_fab2(sch_1):page76_i116"
				( objectStatus "F3047" )
			)
			( gate "@baseboard_fab2_lib.baseboard_fab2(sch_1):page76_i197"
				( objectStatus "F3038" )
			)
			( gate "@baseboard_fab2_lib.baseboard_fab2(sch_1):page76_i114"
				( objectStatus "F3039" )
			)
			( gate "@baseboard_fab2_lib.baseboard_fab2(sch_1):page76_i66"
				( objectStatus "F3029" )
			)
			( gate "@baseboard_fab2_lib.baseboard_fab2(sch_1):page76_i108"
				( objectStatus "F3030" )
			)
			( gate "@baseboard_fab2_lib.baseboard_fab2(sch_1):page76_i112"
				( objectStatus "F3033" )
			)
			( gate "@baseboard_fab2_lib.baseboard_fab2(sch_1):page76_i65"
				( objectStatus "F3035" )
			)
			( gate "@baseboard_fab2_lib.baseboard_fab2(sch_1):page76_i85"
				( objectStatus "F3023" )
			)
			( gate "@baseboard_fab2_lib.baseboard_fab2(sch_1):page76_i90"
				( objectStatus "F3024" )
			)
			( gate "@baseboard_fab2_lib.baseboard_fab2(sch_1):page76_i63"
				( objectStatus "F3025" )
			)
			( gate "@baseboard_fab2_lib.baseboard_fab2(sch_1):page76_i83"
				( objectStatus "F3026" )
			)
			( gate "@baseboard_fab2_lib.baseboard_fab2(sch_1):page76_i199"
				( objectStatus "F3027" )
			)
			( gate "@baseboard_fab2_lib.baseboard_fab2(sch_1):page76_i198"
				( objectStatus "F3028" )
			)
			( gate "@baseboard_fab2_lib.baseboard_fab2(sch_1):page76_i82"
				( objectStatus "F3031" )
			)
			( gate "@baseboard_fab2_lib.baseboard_fab2(sch_1):page76_i80"
				( objectStatus "F3032" )
			)
			( gate "@baseboard_fab2_lib.baseboard_fab2(sch_1):page76_i61"
				( objectStatus "F3034" )
			)
			( gate "@baseboard_fab2_lib.baseboard_fab2(sch_1):page76_i75"
				( objectStatus "F3037" )
			)
			( gate "@baseboard_fab2_lib.baseboard_fab2(sch_1):page76_i79"
				( objectStatus "F3036" )
			)
			( gate "@baseboard_fab2_lib.baseboard_fab2(sch_1):page76_i59"
				( objectStatus "F3044" )
			)
			( gate "@baseboard_fab2_lib.baseboard_fab2(sch_1):page76_i159"
				( objectStatus "F3041" )
			)
			( gate "@baseboard_fab2_lib.baseboard_fab2(sch_1):page214_i108"
				( objectStatus "F2968" )
			)
			( gate "@baseboard_fab2_lib.baseboard_fab2(sch_1):page212_i23"
				( objectStatus "F2800" )
			)
			( gate "@baseboard_fab2_lib.baseboard_fab2(sch_1):page214_i65"
				( objectStatus "F2790" )
			)
			( gate "@baseboard_fab2_lib.baseboard_fab2(sch_1):page212_i77"
				( objectStatus "F2798" )
			)
			( gate "@baseboard_fab2_lib.baseboard_fab2(sch_1):page202_i27"
				( objectStatus "F2942" )
			)
			( gate "@baseboard_fab2_lib.baseboard_fab2(sch_1):page204_i9"
				( objectStatus "F2945" )
			)
			( gate "@baseboard_fab2_lib.baseboard_fab2(sch_1):page205_i5"
				( objectStatus "F2817" )
			)
			( gate "@baseboard_fab2_lib.baseboard_fab2(sch_1):page202_i9"
				( objectStatus "F2812" )
			)
			( gate "@baseboard_fab2_lib.baseboard_fab2(sch_1):page207_i8"
				( objectStatus "F2748" )
			)
			( gate "@baseboard_fab2_lib.baseboard_fab2(sch_1):page207_i18"
				( objectStatus "F3062" )
			)
			( gate "@baseboard_fab2_lib.baseboard_fab2(sch_1):page208_i9"
				( objectStatus "F3064" )
			)
			( gate "@baseboard_fab2_lib.baseboard_fab2(sch_1):page208_i22"
				( objectStatus "F3065" )
			)
			( gate "@baseboard_fab2_lib.baseboard_fab2(sch_1):page210_i8"
				( objectStatus "F3066" )
			)
			( gate "@baseboard_fab2_lib.baseboard_fab2(sch_1):page203_i25"
				( objectStatus "F2816" )
			)
			( gate "@baseboard_fab2_lib.baseboard_fab2(sch_1):page209_i42"
				( objectStatus "F3063" )
			)
			( gate "@baseboard_fab2_lib.baseboard_fab2(sch_1):page203_i66"
				( objectStatus "F2814" )
			)
			( gate "@baseboard_fab2_lib.baseboard_fab2(sch_1):page202_i62"
				( objectStatus "F2815" )
			)
			( gate "@baseboard_fab2_lib.baseboard_fab2(sch_1):page202_i61"
				( objectStatus "F2943" )
			)
			( gate "@baseboard_fab2_lib.baseboard_fab2(sch_1):page203_i68"
				( objectStatus "F2944" )
			)
			( gate "@baseboard_fab2_lib.baseboard_fab2(sch_1):page203_i69"
				( objectStatus "F2946" )
			)
			( gate "@baseboard_fab2_lib.baseboard_fab2(sch_1):page204_i70"
				( objectStatus "F2813" )
			)
			( gate "@baseboard_fab2_lib.baseboard_fab2(sch_1):page205_i43"
				( objectStatus "F2947" )
			)
			( gate "@baseboard_fab2_lib.baseboard_fab2(sch_1):page207_i59"
				( objectStatus "F2752" )
			)
			( gate "@baseboard_fab2_lib.baseboard_fab2(sch_1):page207_i58"
				( objectStatus "F3061" )
			)
			( gate "@baseboard_fab2_lib.baseboard_fab2(sch_1):page208_i67"
				( objectStatus "F2749" )
			)
			( gate "@baseboard_fab2_lib.baseboard_fab2(sch_1):page208_i66"
				( objectStatus "F2751" )
			)
			( gate "@baseboard_fab2_lib.baseboard_fab2(sch_1):page209_i55"
				( objectStatus "F2750" )
			)
			( gate "@baseboard_fab2_lib.baseboard_fab2(sch_1):page210_i44"
				( objectStatus "F2753" )
			)
			( gate "@baseboard_fab2_lib.baseboard_fab2(sch_1):page76_i208"
				( objectStatus "F2974" )
			)
			( gate "@baseboard_fab2_lib.baseboard_fab2(sch_1):page42_i180"
				( objectStatus "F2878" )
			)
			( gate "@baseboard_fab2_lib.baseboard_fab2(sch_1):page42_i174"
				( objectStatus "F2897" )
			)
			( gate "@baseboard_fab2_lib.baseboard_fab2(sch_1):page42_i175"
				( objectStatus "F2896" )
			)
			( gate "@baseboard_fab2_lib.baseboard_fab2(sch_1):page42_i179"
				( objectStatus "F2877" )
			)
			( gate "@baseboard_fab2_lib.baseboard_fab2(sch_1):page76_i202"
				( objectStatus "F3045" )
			)
			( gate "@baseboard_fab2_lib.baseboard_fab2(sch_1):page76_i201"
				( objectStatus "F3046" )
			)
			( gate "@baseboard_fab2_lib.baseboard_fab2(sch_1):page76_i207"
				( objectStatus "F2973" )
			)
			( gate "@baseboard_fab2_lib.baseboard_fab2(sch_1):page42_i173"
				( objectStatus "F2910" )
			)
			( gate "@baseboard_fab2_lib.baseboard_fab2(sch_1):page42_i100"
				( objectStatus "F2902" )
			)
			( gate "@baseboard_fab2_lib.baseboard_fab2(sch_1):page42_i109"
				( objectStatus "F2903" )
			)
			( gate "@baseboard_fab2_lib.baseboard_fab2(sch_1):page42_i176"
				( objectStatus "F2895" )
			)
			( gate "@baseboard_fab2_lib.baseboard_fab2(sch_1):page42_i155"
				( objectStatus "F2905" )
			)
			( gate "@baseboard_fab2_lib.baseboard_fab2(sch_1):page42_i156"
				( objectStatus "F2885" )
			)
			( gate "@baseboard_fab2_lib.baseboard_fab2(sch_1):page76_i204"
				( objectStatus "F3014" )
			)
			( gate "@baseboard_fab2_lib.baseboard_fab2(sch_1):page76_i73"
				( objectStatus "F3043" )
			)
			( gate "@baseboard_fab2_lib.baseboard_fab2(sch_1):page76_i76"
				( objectStatus "F3042" )
			)
			( gate "@baseboard_fab2_lib.baseboard_fab2(sch_1):page76_i203"
				( objectStatus "F3013" )
			)
			( gate "@baseboard_fab2_lib.baseboard_fab2(sch_1):page76_i160"
				( objectStatus "F3018" )
			)
			( gate "@baseboard_fab2_lib.baseboard_fab2(sch_1):page76_i205"
				( objectStatus "F2969" )
			)
			( gate "@baseboard_fab2_lib.baseboard_fab2(sch_1):page76_i161"
				( objectStatus "F3021" )
			)
			( gate "@baseboard_fab2_lib.baseboard_fab2(sch_1):page76_i179"
				( objectStatus "F2792" )
			)
			( gate "@baseboard_fab2_lib.baseboard_fab2(sch_1):page42_i90"
				( objectStatus "F2882" )
			)
			( gate "@baseboard_fab2_lib.baseboard_fab2(sch_1):page42_i68"
				( objectStatus "F2820" )
			)
			( gate "@baseboard_fab2_lib.baseboard_fab2(sch_1):page42_i89"
				( objectStatus "F2880" )
			)
			( gate "@baseboard_fab2_lib.baseboard_fab2(sch_1):page42_i151"
				( objectStatus "F2894" )
			)
			( gate "@baseboard_fab2_lib.baseboard_fab2(sch_1):page42_i88"
				( objectStatus "F2909" )
			)
			( gate "@baseboard_fab2_lib.baseboard_fab2(sch_1):page42_i152"
				( objectStatus "F2881" )
			)
			( gate "@baseboard_fab2_lib.baseboard_fab2(sch_1):page42_i83"
				( objectStatus "F2879" )
			)
			( gate "@baseboard_fab2_lib.baseboard_fab2(sch_1):page42_i77"
				( objectStatus "F2826" )
			)
			( gate "@baseboard_fab2_lib.baseboard_fab2(sch_1):page42_i75"
				( objectStatus "F2823" )
			)
			( gate "@baseboard_fab2_lib.baseboard_fab2(sch_1):page42_i70"
				( objectStatus "F2893" )
			)
			( gate "@baseboard_fab2_lib.baseboard_fab2(sch_1):page42_i69"
				( objectStatus "F2892" )
			)
			( gate "@baseboard_fab2_lib.baseboard_fab2(sch_1):page76_i165"
				( objectStatus "F3017" )
			)
			( gate "@baseboard_fab2_lib.baseboard_fab2(sch_1):page76_i166"
				( objectStatus "F2976" )
			)
			( gate "@baseboard_fab2_lib.baseboard_fab2(sch_1):page76_i169"
				( objectStatus "F2975" )
			)
			( gate "@baseboard_fab2_lib.baseboard_fab2(sch_1):page76_i10"
				( objectStatus "F3016" )
			)
			( gate "@baseboard_fab2_lib.baseboard_fab2(sch_1):page76_i171"
				( objectStatus "F2979" )
			)
			( gate "@baseboard_fab2_lib.baseboard_fab2(sch_1):page76_i8"
				( objectStatus "F2980" )
			)
			( gate "@baseboard_fab2_lib.baseboard_fab2(sch_1):page76_i170"
				( objectStatus "F2987" )
			)
			( gate "@baseboard_fab2_lib.baseboard_fab2(sch_1):page76_i7"
				( objectStatus "F2982" )
			)
			( gate "@baseboard_fab2_lib.baseboard_fab2(sch_1):page76_i5"
				( objectStatus "F2989" )
			)
			( gate "@baseboard_fab2_lib.baseboard_fab2(sch_1):page76_i176"
				( objectStatus "F2977" )
			)
			( gate "@baseboard_fab2_lib.baseboard_fab2(sch_1):page76_i4"
				( objectStatus "F2981" )
			)
			( gate "@baseboard_fab2_lib.baseboard_fab2(sch_1):page76_i18"
				( objectStatus "F2985" )
			)
			( gate "@baseboard_fab2_lib.baseboard_fab2(sch_1):page76_i3"
				( objectStatus "F2988" )
			)
			( gate "@baseboard_fab2_lib.baseboard_fab2(sch_1):page76_i15"
				( objectStatus "F2984" )
			)
			( gate "@baseboard_fab2_lib.baseboard_fab2(sch_1):page76_i1"
				( objectStatus "F2972" )
			)
			( gate "@baseboard_fab2_lib.baseboard_fab2(sch_1):page42_i153"
				( objectStatus "F2908" )
			)
			( gate "@baseboard_fab2_lib.baseboard_fab2(sch_1):page76_i172"
				( objectStatus "F2971" )
			)
			( gate "@baseboard_fab2_lib.baseboard_fab2(sch_1):page76_i206"
				( objectStatus "F2791" )
			)
			( gate "@baseboard_fab2_lib.baseboard_fab2(sch_1):page76_i174"
				( objectStatus "F2978" )
			)
			( gate "@baseboard_fab2_lib.baseboard_fab2(sch_1):page42_i178"
				( objectStatus "F2939" )
			)
			( gate "@baseboard_fab2_lib.baseboard_fab2(sch_1):page42_i147"
				( objectStatus "F2818" )
			)
			( gate "@baseboard_fab2_lib.baseboard_fab2(sch_1):page42_i145"
				( objectStatus "F2819" )
			)
			( gate "@baseboard_fab2_lib.baseboard_fab2(sch_1):page42_i164"
				( objectStatus "F2940" )
			)
			( gate "@baseboard_fab2_lib.baseboard_fab2(sch_1):page76_i164"
				( objectStatus "F2986" )
			)
			( gate "@baseboard_fab2_lib.baseboard_fab2(sch_1):page42_i98"
				( objectStatus "F2907" )
			)
			( gate "@baseboard_fab2_lib.baseboard_fab2(sch_1):page42_i72"
				( objectStatus "F2821" )
			)
			( gate "@baseboard_fab2_lib.baseboard_fab2(sch_1):page42_i81"
				( objectStatus "F2822" )
			)
			( gate "@baseboard_fab2_lib.baseboard_fab2(sch_1):page42_i80"
				( objectStatus "F2825" )
			)
			( gate "@baseboard_fab2_lib.baseboard_fab2(sch_1):page42_i74"
				( objectStatus "F2824" )
			)
			( gate "@baseboard_fab2_lib.baseboard_fab2(sch_1):page76_i175"
				( objectStatus "F2970" )
			)
			( gate "@baseboard_fab2_lib.baseboard_fab2(sch_1):page132_i56"
				( objectStatus "F2961" )
			)
			( gate "@baseboard_fab2_lib.baseboard_fab2(sch_1):page132_i54"
				( objectStatus "F2963" )
			)
			( gate "@baseboard_fab2_lib.baseboard_fab2(sch_1):page132_i52"
				( objectStatus "F2962" )
			)
			( gate "@baseboard_fab2_lib.baseboard_fab2(sch_1):page132_i6"
				( objectStatus "F2957" )
			)
			( gate "@baseboard_fab2_lib.baseboard_fab2(sch_1):page132_i19"
				( objectStatus "F2954" )
			)
			( gate "@baseboard_fab2_lib.baseboard_fab2(sch_1):page132_i20"
				( objectStatus "F2948" )
			)
			( gate "@baseboard_fab2_lib.baseboard_fab2(sch_1):page132_i4"
				( objectStatus "F2958" )
			)
			( gate "@baseboard_fab2_lib.baseboard_fab2(sch_1):page132_i13"
				( objectStatus "F2955" )
			)
			( gate "@baseboard_fab2_lib.baseboard_fab2(sch_1):page132_i17"
				( objectStatus "F2950" )
			)
			( gate "@baseboard_fab2_lib.baseboard_fab2(sch_1):page132_i3"
				( objectStatus "F2959" )
			)
			( gate "@baseboard_fab2_lib.baseboard_fab2(sch_1):page132_i12"
				( objectStatus "F2953" )
			)
			( gate "@baseboard_fab2_lib.baseboard_fab2(sch_1):page132_i16"
				( objectStatus "F2952" )
			)
			( gate "@baseboard_fab2_lib.baseboard_fab2(sch_1):page132_i2"
				( objectStatus "F2956" )
			)
			( gate "@baseboard_fab2_lib.baseboard_fab2(sch_1):page132_i11"
				( objectStatus "F2811" )
			)
			( gate "@baseboard_fab2_lib.baseboard_fab2(sch_1):page132_i9"
				( objectStatus "F2949" )
			)
			( gate "@baseboard_fab2_lib.baseboard_fab2(sch_1):page132_i7"
				( objectStatus "F2799" )
			)
			( gate "@baseboard_fab2_lib.baseboard_fab2(sch_1):page132_i1"
				( objectStatus "F2960" )
			)
			( gate "@baseboard_fab2_lib.baseboard_fab2(sch_1):page132_i8"
				( objectStatus "F2951" )
			)
			( gate "@baseboard_fab2_lib.baseboard_fab2(sch_1):page130_i45"
				( objectStatus "F2999" )
			)
			( gate "@baseboard_fab2_lib.baseboard_fab2(sch_1):page130_i39"
				( objectStatus "F2782" )
			)
			( gate "@baseboard_fab2_lib.baseboard_fab2(sch_1):page130_i38"
				( objectStatus "F2797" )
			)
			( gate "@baseboard_fab2_lib.baseboard_fab2(sch_1):page130_i43"
				( objectStatus "F3000" )
			)
			( gate "@baseboard_fab2_lib.baseboard_fab2(sch_1):page130_i30"
				( objectStatus "F2784" )
			)
			( gate "@baseboard_fab2_lib.baseboard_fab2(sch_1):page130_i41"
				( objectStatus "F2785" )
			)
			( gate "@baseboard_fab2_lib.baseboard_fab2(sch_1):page131_i18"
				( objectStatus "F2808" )
			)
			( gate "@baseboard_fab2_lib.baseboard_fab2(sch_1):page131_i6"
				( objectStatus "F2805" )
			)
			( gate "@baseboard_fab2_lib.baseboard_fab2(sch_1):page131_i12"
				( objectStatus "F2807" )
			)
			( gate "@baseboard_fab2_lib.baseboard_fab2(sch_1):page131_i4"
				( objectStatus "F2804" )
			)
			( gate "@baseboard_fab2_lib.baseboard_fab2(sch_1):page131_i11"
				( objectStatus "F2801" )
			)
			( gate "@baseboard_fab2_lib.baseboard_fab2(sch_1):page131_i3"
				( objectStatus "F2809" )
			)
			( gate "@baseboard_fab2_lib.baseboard_fab2(sch_1):page131_i10"
				( objectStatus "F2803" )
			)
			( gate "@baseboard_fab2_lib.baseboard_fab2(sch_1):page131_i2"
				( objectStatus "F2806" )
			)
			( gate "@baseboard_fab2_lib.baseboard_fab2(sch_1):page131_i7"
				( objectStatus "F2802" )
			)
			( gate "@baseboard_fab2_lib.baseboard_fab2(sch_1):page131_i1"
				( objectStatus "F2810" )
			)
			( gate "@baseboard_fab2_lib.baseboard_fab2(sch_1):page131_i20"
				( objectStatus "F2778" )
			)
			( gate "@baseboard_fab2_lib.baseboard_fab2(sch_1):page131_i16"
				( objectStatus "F2777" )
			)
			( gate "@baseboard_fab2_lib.baseboard_fab2(sch_1):page131_i15"
				( objectStatus "F2779" )
			)
			( gate "@baseboard_fab2_lib.baseboard_fab2(sch_1):page131_i14"
				( objectStatus "F2781" )
			)
			( gate "@baseboard_fab2_lib.baseboard_fab2(sch_1):page131_i8"
				( objectStatus "F2780" )
			)
			( gate "@baseboard_fab2_lib.baseboard_fab2(sch_1):page130_i32"
				( objectStatus "F2783" )
			)
			( gate "@baseboard_fab2_lib.baseboard_fab2(sch_1):page131_i52"
				( objectStatus "F2998" )
			)
			( gate "@baseboard_fab2_lib.baseboard_fab2(sch_1):page131_i50"
				( objectStatus "F2996" )
			)
			( gate "@baseboard_fab2_lib.baseboard_fab2(sch_1):page131_i48"
				( objectStatus "F2997" )
			)
			( gate "@baseboard_fab2_lib.baseboard_fab2(sch_1):page55_i140"
				( objectStatus "F284" )
			)
			( gate "@baseboard_fab2_lib.baseboard_fab2(sch_1):page21_i181"
				( objectStatus "F288" )
			)
			( gate "@baseboard_fab2_lib.baseboard_fab2(sch_1):page21_i180"
				( objectStatus "F289" )
			)
			( gate "@baseboard_fab2_lib.baseboard_fab2(sch_1):page21_i178"
				( objectStatus "F286" )
			)
			( gate "@baseboard_fab2_lib.baseboard_fab2(sch_1):page21_i177"
				( objectStatus "F287" )
			)
			( gate "@baseboard_fab2_lib.baseboard_fab2(sch_1):page55_i119"
				( objectStatus "F285" )
			)
			( gate "@baseboard_fab2_lib.baseboard_fab2(sch_1):page55_i117"
				( objectStatus "F290" )
			)
			( gate "@baseboard_fab2_lib.baseboard_fab2(sch_1):page55_i116"
				( objectStatus "F291" )
			)
			( gate "@baseboard_fab2_lib.baseboard_fab2(sch_1):page169_i126"
				( objectStatus "F889" )
			)
			( gate "@baseboard_fab2_lib.baseboard_fab2(sch_1):page147_i75"
				( objectStatus "F4085" )
			)
			( gate "@baseboard_fab2_lib.baseboard_fab2(sch_1):page147_i79"
				( objectStatus "F4084" )
			)
			( gate "@baseboard_fab2_lib.baseboard_fab2(sch_1):page147_i76"
				( objectStatus "F4083" )
			)
			( gate "@baseboard_fab2_lib.baseboard_fab2(sch_1):page95_i119"
				( objectStatus "F2142" )
			)
			( gate "@baseboard_fab2_lib.baseboard_fab2(sch_1):page196_i124"
				( objectStatus "F2143" )
			)
			( gate "@baseboard_fab2_lib.baseboard_fab2(sch_1):page135_i100"
				( objectStatus "F2144" )
			)
			( gate "@baseboard_fab2_lib.baseboard_fab2(sch_1):page95_i104"
				( objectStatus "F2139" )
			)
			( gate "@baseboard_fab2_lib.baseboard_fab2(sch_1):page89_i18"
				( objectStatus "F2141" )
			)
			( gate "@baseboard_fab2_lib.baseboard_fab2(sch_1):page135_i76"
				( objectStatus "F2140" )
			)
			( gate "@baseboard_fab2_lib.baseboard_fab2(sch_1):page167_i49"
				( objectStatus "F4186" )
			)
			( gate "@baseboard_fab2_lib.baseboard_fab2(sch_1):page167_i7"
				( objectStatus "F3104" )
			)
			( gate "@baseboard_fab2_lib.baseboard_fab2(sch_1):page167_i24"
				( objectStatus "F3105" )
			)
			( gate "@baseboard_fab2_lib.baseboard_fab2(sch_1):page127_i71"
				( objectStatus "F2081" )
			)
			( gate "@baseboard_fab2_lib.baseboard_fab2(sch_1):page167_i3"
				( objectStatus "F1977" )
				( pin "B"
					( objectStatus "Q9B1.1" )
				)
				( pin "C"
					( objectStatus "Q9B1.3" )
				)
				( pin "E"
					( objectStatus "Q9B1.2" )
				)
			)
			( gate "@baseboard_fab2_lib.baseboard_fab2(sch_1):page167_i27"
				( objectStatus "F1978" )
				( pin "B"
					( objectStatus "Q1E1.1" )
				)
				( pin "C"
					( objectStatus "Q1E1.3" )
				)
				( pin "E"
					( objectStatus "Q1E1.2" )
				)
			)
			( gate "@baseboard_fab2_lib.baseboard_fab2(sch_1):page167_i1"
				( objectStatus "F61" )
				( pin "SCL"
					( objectStatus "U9B4.7" )
				)
				( pin "SDA"
					( objectStatus "U9B4.6" )
				)
			)
			( gate "@baseboard_fab2_lib.baseboard_fab2(sch_1):page167_i30"
				( objectStatus "F62" )
				( pin "SCL"
					( objectStatus "U1E1.7" )
				)
				( pin "SDA"
					( objectStatus "U1E1.6" )
				)
			)
			( gate "@baseboard_fab2_lib.baseboard_fab2(sch_1):page238_i39"
				( objectStatus "F3759" )
			)
			( gate "@baseboard_fab2_lib.baseboard_fab2(sch_1):page199_i119"
				( objectStatus "F3817" )
			)
			( gate "@baseboard_fab2_lib.baseboard_fab2(sch_1):page202_i34"
				( objectStatus "F3786" )
			)
			( gate "@baseboard_fab2_lib.baseboard_fab2(sch_1):page212_i39"
				( objectStatus "F3768" )
			)
			( gate "@baseboard_fab2_lib.baseboard_fab2(sch_1):page212_i36"
				( objectStatus "F3767" )
			)
			( gate "@baseboard_fab2_lib.baseboard_fab2(sch_1):page231_i161"
				( objectStatus "F3801" )
			)
			( gate "@baseboard_fab2_lib.baseboard_fab2(sch_1):page240_i139"
				( objectStatus "F3760" )
			)
			( gate "@baseboard_fab2_lib.baseboard_fab2(sch_1):page232_i207"
				( objectStatus "F3803" )
			)
			( gate "@baseboard_fab2_lib.baseboard_fab2(sch_1):page233_i196"
				( objectStatus "F3782" )
			)
			( gate "@baseboard_fab2_lib.baseboard_fab2(sch_1):page234_i152"
				( objectStatus "F3777" )
			)
			( gate "@baseboard_fab2_lib.baseboard_fab2(sch_1):page205_i20"
				( objectStatus "F3796" )
			)
			( gate "@baseboard_fab2_lib.baseboard_fab2(sch_1):page202_i47"
				( objectStatus "F3787" )
			)
			( gate "@baseboard_fab2_lib.baseboard_fab2(sch_1):page202_i36"
				( objectStatus "F3784" )
			)
			( gate "@baseboard_fab2_lib.baseboard_fab2(sch_1):page202_i45"
				( objectStatus "F3788" )
			)
			( gate "@baseboard_fab2_lib.baseboard_fab2(sch_1):page203_i47"
				( objectStatus "F3789" )
			)
			( gate "@baseboard_fab2_lib.baseboard_fab2(sch_1):page203_i53"
				( objectStatus "F3791" )
			)
			( gate "@baseboard_fab2_lib.baseboard_fab2(sch_1):page203_i45"
				( objectStatus "F3790" )
			)
			( gate "@baseboard_fab2_lib.baseboard_fab2(sch_1):page203_i51"
				( objectStatus "F3792" )
			)
			( gate "@baseboard_fab2_lib.baseboard_fab2(sch_1):page204_i34"
				( objectStatus "F3794" )
			)
			( gate "@baseboard_fab2_lib.baseboard_fab2(sch_1):page216_i48"
				( objectStatus "F3762" )
			)
			( gate "@baseboard_fab2_lib.baseboard_fab2(sch_1):page216_i79"
				( objectStatus "F3764" )
			)
			( gate "@baseboard_fab2_lib.baseboard_fab2(sch_1):page216_i50"
				( objectStatus "F3763" )
			)
			( gate "@baseboard_fab2_lib.baseboard_fab2(sch_1):page205_i32"
				( objectStatus "F3795" )
			)
			( gate "@baseboard_fab2_lib.baseboard_fab2(sch_1):page216_i77"
				( objectStatus "F3761" )
			)
			( gate "@baseboard_fab2_lib.baseboard_fab2(sch_1):page219_i79"
				( objectStatus "F3770" )
			)
			( gate "@baseboard_fab2_lib.baseboard_fab2(sch_1):page219_i50"
				( objectStatus "F3771" )
			)
			( gate "@baseboard_fab2_lib.baseboard_fab2(sch_1):page219_i77"
				( objectStatus "F3769" )
			)
			( gate "@baseboard_fab2_lib.baseboard_fab2(sch_1):page227_i48"
				( objectStatus "F3825" )
			)
			( gate "@baseboard_fab2_lib.baseboard_fab2(sch_1):page227_i79"
				( objectStatus "F3827" )
			)
			( gate "@baseboard_fab2_lib.baseboard_fab2(sch_1):page227_i50"
				( objectStatus "F3826" )
			)
			( gate "@baseboard_fab2_lib.baseboard_fab2(sch_1):page224_i48"
				( objectStatus "F3809" )
			)
			( gate "@baseboard_fab2_lib.baseboard_fab2(sch_1):page224_i79"
				( objectStatus "F3807" )
			)
			( gate "@baseboard_fab2_lib.baseboard_fab2(sch_1):page224_i50"
				( objectStatus "F3808" )
			)
			( gate "@baseboard_fab2_lib.baseboard_fab2(sch_1):page224_i77"
				( objectStatus "F3810" )
			)
			( gate "@baseboard_fab2_lib.baseboard_fab2(sch_1):page207_i32"
				( objectStatus "F3812" )
			)
			( gate "@baseboard_fab2_lib.baseboard_fab2(sch_1):page207_i40"
				( objectStatus "F3814" )
			)
			( gate "@baseboard_fab2_lib.baseboard_fab2(sch_1):page207_i42"
				( objectStatus "F3813" )
			)
			( gate "@baseboard_fab2_lib.baseboard_fab2(sch_1):page207_i34"
				( objectStatus "F3811" )
			)
			( gate "@baseboard_fab2_lib.baseboard_fab2(sch_1):page208_i45"
				( objectStatus "F3816" )
			)
			( gate "@baseboard_fab2_lib.baseboard_fab2(sch_1):page208_i52"
				( objectStatus "F3819" )
			)
			( gate "@baseboard_fab2_lib.baseboard_fab2(sch_1):page208_i43"
				( objectStatus "F3818" )
			)
			( gate "@baseboard_fab2_lib.baseboard_fab2(sch_1):page208_i50"
				( objectStatus "F3820" )
			)
			( gate "@baseboard_fab2_lib.baseboard_fab2(sch_1):page210_i28"
				( objectStatus "F3823" )
			)
			( gate "@baseboard_fab2_lib.baseboard_fab2(sch_1):page210_i26"
				( objectStatus "F3824" )
			)
			( gate "@baseboard_fab2_lib.baseboard_fab2(sch_1):page204_i36"
				( objectStatus "F3793" )
			)
			( gate "@baseboard_fab2_lib.baseboard_fab2(sch_1):page241_i30"
				( objectStatus "F3765" )
			)
			( gate "@baseboard_fab2_lib.baseboard_fab2(sch_1):page227_i77"
				( objectStatus "F3828" )
			)
			( gate "@baseboard_fab2_lib.baseboard_fab2(sch_1):page209_i16"
				( objectStatus "F3821" )
			)
			( gate "@baseboard_fab2_lib.baseboard_fab2(sch_1):page209_i18"
				( objectStatus "F3822" )
			)
			( gate "@baseboard_fab2_lib.baseboard_fab2(sch_1):page219_i48"
				( objectStatus "F3772" )
			)
			( gate "@baseboard_fab2_lib.baseboard_fab2(sch_1):page214_i79"
				( objectStatus "F3785" )
			)
			( gate "@baseboard_fab2_lib.baseboard_fab2(sch_1):page214_i76"
				( objectStatus "F3783" )
			)
			( gate "@baseboard_fab2_lib.baseboard_fab2(sch_1):page236_i33"
				( objectStatus "F3774" )
			)
			( gate "@baseboard_fab2_lib.baseboard_fab2(sch_1):page236_i22"
				( objectStatus "F3775" )
			)
			( gate "@baseboard_fab2_lib.baseboard_fab2(sch_1):page236_i19"
				( objectStatus "F3776" )
			)
			( gate "@baseboard_fab2_lib.baseboard_fab2(sch_1):page236_i36"
				( objectStatus "F3773" )
			)
			( gate "@baseboard_fab2_lib.baseboard_fab2(sch_1):page199_i3"
				( objectStatus "F3815" )
			)
			( gate "@baseboard_fab2_lib.baseboard_fab2(sch_1):page112_i140"
				( objectStatus "F3805" )
			)
			( gate "@baseboard_fab2_lib.baseboard_fab2(sch_1):page112_i136"
				( objectStatus "F3806" )
			)
			( gate "@baseboard_fab2_lib.baseboard_fab2(sch_1):page92_i79"
				( objectStatus "F3766" )
			)
			( gate "@baseboard_fab2_lib.baseboard_fab2(sch_1):page92_i84"
				( objectStatus "F3802" )
			)
			( gate "@baseboard_fab2_lib.baseboard_fab2(sch_1):page152_i18"
				( objectStatus "F3804" )
			)
			( gate "@baseboard_fab2_lib.baseboard_fab2(sch_1):page221_i24"
				( objectStatus "F3781" )
			)
			( gate "@baseboard_fab2_lib.baseboard_fab2(sch_1):page221_i34"
				( objectStatus "F3780" )
			)
			( gate "@baseboard_fab2_lib.baseboard_fab2(sch_1):page222_i21"
				( objectStatus "F3799" )
			)
			( gate "@baseboard_fab2_lib.baseboard_fab2(sch_1):page229_i21"
				( objectStatus "F3778" )
			)
			( gate "@baseboard_fab2_lib.baseboard_fab2(sch_1):page230_i21"
				( objectStatus "F3797" )
			)
			( gate "@baseboard_fab2_lib.baseboard_fab2(sch_1):page222_i28"
				( objectStatus "F3798" )
			)
			( gate "@baseboard_fab2_lib.baseboard_fab2(sch_1):page229_i27"
				( objectStatus "F3779" )
			)
			( gate "@baseboard_fab2_lib.baseboard_fab2(sch_1):page230_i28"
				( objectStatus "F3800" )
			)
			( gate "@baseboard_fab2_lib.baseboard_fab2(sch_1):page221_i1"
				( objectStatus "F2021" )
			)
			( gate "@baseboard_fab2_lib.baseboard_fab2(sch_1):page222_i31"
				( objectStatus "F2024" )
			)
			( gate "@baseboard_fab2_lib.baseboard_fab2(sch_1):page229_i24"
				( objectStatus "F2022" )
			)
			( gate "@baseboard_fab2_lib.baseboard_fab2(sch_1):page230_i31"
				( objectStatus "F2023" )
			)
			( gate "@baseboard_fab2_lib.baseboard_fab2(sch_1):page197_i97"
				( objectStatus "F2025" )
			)
			( gate "@baseboard_fab2_lib.baseboard_fab2(sch_1):page197_i120"
				( objectStatus "F2026" )
			)
			( gate "@baseboard_fab2_lib.baseboard_fab2(sch_1):page197_i133"
				( objectStatus "F2027" )
			)
			( gate "@baseboard_fab2_lib.baseboard_fab2(sch_1):page197_i144"
				( objectStatus "F2028" )
			)
			( gate "@baseboard_fab2_lib.baseboard_fab2(sch_1):page197_i99"
				( objectStatus "F252" )
			)
			( gate "@baseboard_fab2_lib.baseboard_fab2(sch_1):page197_i121"
				( objectStatus "F253" )
			)
			( gate "@baseboard_fab2_lib.baseboard_fab2(sch_1):page197_i131"
				( objectStatus "F254" )
			)
			( gate "@baseboard_fab2_lib.baseboard_fab2(sch_1):page197_i142"
				( objectStatus "F251" )
			)
			( gate "@baseboard_fab2_lib.baseboard_fab2(sch_1):page107_i272"
				( objectStatus "F3971" )
				( pin "A"
					( objectStatus "C2U3.1" )
				)
			)
			( gate "@baseboard_fab2_lib.baseboard_fab2(sch_1):page107_i257"
				( objectStatus "F3970" )
				( pin "A"
					( objectStatus "C2U4.1" )
				)
			)
			( gate "@baseboard_fab2_lib.baseboard_fab2(sch_1):page107_i274"
				( objectStatus "F3969" )
				( pin "A"
					( objectStatus "C2U5.1" )
				)
			)
			( gate "@baseboard_fab2_lib.baseboard_fab2(sch_1):page107_i260"
				( objectStatus "F3968" )
				( pin "A"
					( objectStatus "C2U6.1" )
				)
			)
			( gate "@baseboard_fab2_lib.baseboard_fab2(sch_1):page107_i277"
				( objectStatus "F3967" )
				( pin "A"
					( objectStatus "C2U7.1" )
				)
			)
			( gate "@baseboard_fab2_lib.baseboard_fab2(sch_1):page107_i264"
				( objectStatus "F3966" )
				( pin "A"
					( objectStatus "C2U8.1" )
				)
			)
			( gate "@baseboard_fab2_lib.baseboard_fab2(sch_1):page107_i279"
				( objectStatus "F3965" )
				( pin "A"
					( objectStatus "C2U9.1" )
				)
			)
			( gate "@baseboard_fab2_lib.baseboard_fab2(sch_1):page107_i267"
				( objectStatus "F3964" )
				( pin "A"
					( objectStatus "C2U10.1" )
				)
			)
			( gate "@baseboard_fab2_lib.baseboard_fab2(sch_1):page107_i278"
				( objectStatus "F3963" )
				( pin "A"
					( objectStatus "C2U11.1" )
				)
			)
			( gate "@baseboard_fab2_lib.baseboard_fab2(sch_1):page107_i265"
				( objectStatus "F3962" )
				( pin "A"
					( objectStatus "C2U12.1" )
				)
			)
			( gate "@baseboard_fab2_lib.baseboard_fab2(sch_1):page107_i297"
				( objectStatus "F3961" )
				( pin "A"
					( objectStatus "C2U13.1" )
				)
			)
			( gate "@baseboard_fab2_lib.baseboard_fab2(sch_1):page107_i287"
				( objectStatus "F3960" )
				( pin "A"
					( objectStatus "C2U14.1" )
				)
			)
			( gate "@baseboard_fab2_lib.baseboard_fab2(sch_1):page107_i296"
				( objectStatus "F3959" )
				( pin "A"
					( objectStatus "C2U15.1" )
				)
			)
			( gate "@baseboard_fab2_lib.baseboard_fab2(sch_1):page107_i286"
				( objectStatus "F3958" )
				( pin "A"
					( objectStatus "C2U16.1" )
				)
			)
			( gate "@baseboard_fab2_lib.baseboard_fab2(sch_1):page107_i300"
				( objectStatus "F3957" )
				( pin "A"
					( objectStatus "C2U17.1" )
				)
			)
			( gate "@baseboard_fab2_lib.baseboard_fab2(sch_1):page107_i294"
				( objectStatus "F3956" )
				( pin "A"
					( objectStatus "C2U18.1" )
				)
			)
			( gate "@baseboard_fab2_lib.baseboard_fab2(sch_1):page107_i212"
				( objectStatus "F3931" )
				( pin "B"
					( objectStatus "C3P11.2" )
				)
			)
			( gate "@baseboard_fab2_lib.baseboard_fab2(sch_1):page107_i207"
				( objectStatus "F3930" )
				( pin "B"
					( objectStatus "C3P13.2" )
				)
			)
			( gate "@baseboard_fab2_lib.baseboard_fab2(sch_1):page107_i226"
				( objectStatus "F3929" )
				( pin "B"
					( objectStatus "C3P15.2" )
				)
			)
			( gate "@baseboard_fab2_lib.baseboard_fab2(sch_1):page107_i208"
				( objectStatus "F3928" )
				( pin "B"
					( objectStatus "C3P17.2" )
				)
			)
			( gate "@baseboard_fab2_lib.baseboard_fab2(sch_1):page107_i219"
				( objectStatus "F3927" )
				( pin "B"
					( objectStatus "C3P18.2" )
				)
			)
			( gate "@baseboard_fab2_lib.baseboard_fab2(sch_1):page107_i215"
				( objectStatus "F3926" )
				( pin "B"
					( objectStatus "C3P20.2" )
				)
			)
			( gate "@baseboard_fab2_lib.baseboard_fab2(sch_1):page107_i229"
				( objectStatus "F3925" )
				( pin "B"
					( objectStatus "C3P23.2" )
				)
			)
			( gate "@baseboard_fab2_lib.baseboard_fab2(sch_1):page107_i216"
				( objectStatus "F3924" )
				( pin "B"
					( objectStatus "C3P25.2" )
				)
			)
			( gate "@baseboard_fab2_lib.baseboard_fab2(sch_1):page107_i223"
				( objectStatus "F3923" )
				( pin "B"
					( objectStatus "C3P27.2" )
				)
			)
			( gate "@baseboard_fab2_lib.baseboard_fab2(sch_1):page107_i232"
				( objectStatus "F3922" )
				( pin "B"
					( objectStatus "C3P28.2" )
				)
			)
			( gate "@baseboard_fab2_lib.baseboard_fab2(sch_1):page107_i245"
				( objectStatus "F3921" )
				( pin "B"
					( objectStatus "C3P30.2" )
				)
			)
			( gate "@baseboard_fab2_lib.baseboard_fab2(sch_1):page107_i234"
				( objectStatus "F3920" )
				( pin "B"
					( objectStatus "C3P32.2" )
				)
			)
			( gate "@baseboard_fab2_lib.baseboard_fab2(sch_1):page107_i240"
				( objectStatus "F3919" )
				( pin "B"
					( objectStatus "C3P35.2" )
				)
			)
			( gate "@baseboard_fab2_lib.baseboard_fab2(sch_1):page107_i235"
				( objectStatus "F3918" )
				( pin "B"
					( objectStatus "C3P37.2" )
				)
			)
			( gate "@baseboard_fab2_lib.baseboard_fab2(sch_1):page107_i248"
				( objectStatus "F3917" )
				( pin "B"
					( objectStatus "C3P39.2" )
				)
			)
			( gate "@baseboard_fab2_lib.baseboard_fab2(sch_1):page107_i241"
				( objectStatus "F3916" )
				( pin "B"
					( objectStatus "C3P40.2" )
				)
			)
			( gate "@baseboard_fab2_lib.baseboard_fab2(sch_1):page185_i96"
				( objectStatus "F3856" )
				( pin "A"
					( objectStatus "C8F7.1" )
				)
				( pin "B"
					( objectStatus "C8F7.2" )
				)
			)
			( gate "@baseboard_fab2_lib.baseboard_fab2(sch_1):page185_i98"
				( objectStatus "F3855" )
				( pin "A"
					( objectStatus "C8F12.1" )
				)
				( pin "B"
					( objectStatus "C8F12.2" )
				)
			)
			( gate "@baseboard_fab2_lib.baseboard_fab2(sch_1):page105_i247"
				( objectStatus "F3954" )
				( pin "A"
					( objectStatus "C3M2.1" )
				)
				( pin "B"
					( objectStatus "C3M2.2" )
				)
			)
			( gate "@baseboard_fab2_lib.baseboard_fab2(sch_1):page105_i255"
				( objectStatus "F3955" )
				( pin "A"
					( objectStatus "C3M1.1" )
				)
				( pin "B"
					( objectStatus "C3M1.2" )
				)
			)
			( gate "@baseboard_fab2_lib.baseboard_fab2(sch_1):page105_i234"
				( objectStatus "F3951" )
				( pin "A"
					( objectStatus "C3M11.1" )
				)
				( pin "B"
					( objectStatus "C3M11.2" )
				)
			)
			( gate "@baseboard_fab2_lib.baseboard_fab2(sch_1):page105_i246"
				( objectStatus "F3950" )
				( pin "A"
					( objectStatus "C3M12.1" )
				)
				( pin "B"
					( objectStatus "C3M12.2" )
				)
			)
			( gate "@baseboard_fab2_lib.baseboard_fab2(sch_1):page105_i239"
				( objectStatus "F3949" )
				( pin "A"
					( objectStatus "C3M13.1" )
				)
				( pin "B"
					( objectStatus "C3M13.2" )
				)
			)
			( gate "@baseboard_fab2_lib.baseboard_fab2(sch_1):page105_i253"
				( objectStatus "F3948" )
				( pin "A"
					( objectStatus "C3M14.1" )
				)
				( pin "B"
					( objectStatus "C3M14.2" )
				)
			)
			( gate "@baseboard_fab2_lib.baseboard_fab2(sch_1):page105_i232"
				( objectStatus "F3953" )
				( pin "A"
					( objectStatus "C3M3.1" )
				)
				( pin "B"
					( objectStatus "C3M3.2" )
				)
			)
			( gate "@baseboard_fab2_lib.baseboard_fab2(sch_1):page105_i244"
				( objectStatus "F3952" )
				( pin "A"
					( objectStatus "C3M4.1" )
				)
				( pin "B"
					( objectStatus "C3M4.2" )
				)
			)
			( gate "@baseboard_fab2_lib.baseboard_fab2(sch_1):page105_i205"
				( objectStatus "F3947" )
				( pin "A"
					( objectStatus "C3M25.1" )
				)
				( pin "B"
					( objectStatus "C3M25.2" )
				)
			)
			( gate "@baseboard_fab2_lib.baseboard_fab2(sch_1):page105_i229"
				( objectStatus "F3946" )
				( pin "A"
					( objectStatus "C3M26.1" )
				)
				( pin "B"
					( objectStatus "C3M26.2" )
				)
			)
			( gate "@baseboard_fab2_lib.baseboard_fab2(sch_1):page105_i212"
				( objectStatus "F3945" )
				( pin "A"
					( objectStatus "C3M28.1" )
				)
				( pin "B"
					( objectStatus "C3M28.2" )
				)
			)
			( gate "@baseboard_fab2_lib.baseboard_fab2(sch_1):page105_i223"
				( objectStatus "F3944" )
				( pin "A"
					( objectStatus "C3M32.1" )
				)
				( pin "B"
					( objectStatus "C3M32.2" )
				)
			)
			( gate "@baseboard_fab2_lib.baseboard_fab2(sch_1):page105_i218"
				( objectStatus "F3940" )
				( pin "A"
					( objectStatus "C3M36.1" )
				)
				( pin "B"
					( objectStatus "C3M36.2" )
				)
			)
			( gate "@baseboard_fab2_lib.baseboard_fab2(sch_1):page105_i225"
				( objectStatus "F3941" )
				( pin "A"
					( objectStatus "C3M35.1" )
				)
				( pin "B"
					( objectStatus "C3M35.2" )
				)
			)
			( gate "@baseboard_fab2_lib.baseboard_fab2(sch_1):page105_i206"
				( objectStatus "F3942" )
				( pin "A"
					( objectStatus "C3M34.1" )
				)
				( pin "B"
					( objectStatus "C3M34.2" )
				)
			)
			( gate "@baseboard_fab2_lib.baseboard_fab2(sch_1):page105_i217"
				( objectStatus "F3943" )
				( pin "A"
					( objectStatus "C3M33.1" )
				)
				( pin "B"
					( objectStatus "C3M33.2" )
				)
			)
			( gate "@baseboard_fab2_lib.baseboard_fab2(sch_1):page105_i196"
				( objectStatus "F3908" )
				( pin "A"
					( objectStatus "C6B4.1" )
				)
				( pin "B"
					( objectStatus "C6B4.2" )
				)
			)
			( gate "@baseboard_fab2_lib.baseboard_fab2(sch_1):page105_i201"
				( objectStatus "F3907" )
				( pin "A"
					( objectStatus "C6B5.1" )
				)
				( pin "B"
					( objectStatus "C6B5.2" )
				)
			)
			( gate "@baseboard_fab2_lib.baseboard_fab2(sch_1):page105_i169"
				( objectStatus "F3906" )
				( pin "A"
					( objectStatus "C6B6.1" )
				)
				( pin "B"
					( objectStatus "C6B6.2" )
				)
			)
			( gate "@baseboard_fab2_lib.baseboard_fab2(sch_1):page105_i198"
				( objectStatus "F3905" )
				( pin "A"
					( objectStatus "C6B8.1" )
				)
				( pin "B"
					( objectStatus "C6B8.2" )
				)
			)
			( gate "@baseboard_fab2_lib.baseboard_fab2(sch_1):page105_i185"
				( objectStatus "F3904" )
				( pin "A"
					( objectStatus "C6B9.1" )
				)
				( pin "B"
					( objectStatus "C6B9.2" )
				)
			)
			( gate "@baseboard_fab2_lib.baseboard_fab2(sch_1):page105_i193"
				( objectStatus "F3903" )
				( pin "A"
					( objectStatus "C6B10.1" )
				)
				( pin "B"
					( objectStatus "C6B10.2" )
				)
			)
			( gate "@baseboard_fab2_lib.baseboard_fab2(sch_1):page105_i166"
				( objectStatus "F3902" )
				( pin "A"
					( objectStatus "C6B11.1" )
				)
				( pin "B"
					( objectStatus "C6B11.2" )
				)
			)
			( gate "@baseboard_fab2_lib.baseboard_fab2(sch_1):page105_i187"
				( objectStatus "F3901" )
				( pin "A"
					( objectStatus "C6B12.1" )
				)
				( pin "B"
					( objectStatus "C6B12.2" )
				)
			)
			( gate "@baseboard_fab2_lib.baseboard_fab2(sch_1):page105_i181"
				( objectStatus "F3899" )
				( pin "A"
					( objectStatus "C6B14.1" )
				)
				( pin "B"
					( objectStatus "C6B14.2" )
				)
			)
			( gate "@baseboard_fab2_lib.baseboard_fab2(sch_1):page105_i189"
				( objectStatus "F3900" )
				( pin "A"
					( objectStatus "C6B13.1" )
				)
				( pin "B"
					( objectStatus "C6B13.2" )
				)
			)
			( gate "@baseboard_fab2_lib.baseboard_fab2(sch_1):page105_i163"
				( objectStatus "F3898" )
				( pin "A"
					( objectStatus "C6B15.1" )
				)
				( pin "B"
					( objectStatus "C6B15.2" )
				)
			)
			( gate "@baseboard_fab2_lib.baseboard_fab2(sch_1):page105_i180"
				( objectStatus "F3897" )
				( pin "A"
					( objectStatus "C6B16.1" )
				)
				( pin "B"
					( objectStatus "C6B16.2" )
				)
			)
			( gate "@baseboard_fab2_lib.baseboard_fab2(sch_1):page105_i175"
				( objectStatus "F3896" )
				( pin "A"
					( objectStatus "C6B17.1" )
				)
				( pin "B"
					( objectStatus "C6B17.2" )
				)
			)
			( gate "@baseboard_fab2_lib.baseboard_fab2(sch_1):page105_i153"
				( objectStatus "F3895" )
				( pin "A"
					( objectStatus "C6B18.1" )
				)
				( pin "B"
					( objectStatus "C6B18.2" )
				)
			)
			( gate "@baseboard_fab2_lib.baseboard_fab2(sch_1):page105_i160"
				( objectStatus "F3894" )
				( pin "A"
					( objectStatus "C6B19.1" )
				)
				( pin "B"
					( objectStatus "C6B19.2" )
				)
			)
			( gate "@baseboard_fab2_lib.baseboard_fab2(sch_1):page105_i173"
				( objectStatus "F3893" )
				( pin "A"
					( objectStatus "C6B20.1" )
				)
				( pin "B"
					( objectStatus "C6B20.2" )
				)
			)
			( gate "@baseboard_fab2_lib.baseboard_fab2(sch_1):page106_i55"
				( objectStatus "F3989" )
				( pin "A"
					( objectStatus "C1R8.1" )
				)
				( pin "B"
					( objectStatus "C1R8.2" )
				)
			)
			( gate "@baseboard_fab2_lib.baseboard_fab2(sch_1):page106_i70"
				( objectStatus "F3990" )
				( pin "A"
					( objectStatus "C1R7.1" )
				)
				( pin "B"
					( objectStatus "C1R7.2" )
				)
			)
			( gate "@baseboard_fab2_lib.baseboard_fab2(sch_1):page106_i40"
				( objectStatus "F3991" )
				( pin "A"
					( objectStatus "C1R6.1" )
				)
				( pin "B"
					( objectStatus "C1R6.2" )
				)
			)
			( gate "@baseboard_fab2_lib.baseboard_fab2(sch_1):page106_i59"
				( objectStatus "F3992" )
				( pin "A"
					( objectStatus "C1R5.1" )
				)
				( pin "B"
					( objectStatus "C1R5.2" )
				)
			)
			( gate "@baseboard_fab2_lib.baseboard_fab2(sch_1):page106_i26"
				( objectStatus "F3993" )
				( pin "A"
					( objectStatus "C1R4.1" )
				)
				( pin "B"
					( objectStatus "C1R4.2" )
				)
			)
			( gate "@baseboard_fab2_lib.baseboard_fab2(sch_1):page106_i37"
				( objectStatus "F3994" )
				( pin "A"
					( objectStatus "C1R3.1" )
				)
				( pin "B"
					( objectStatus "C1R3.2" )
				)
			)
			( gate "@baseboard_fab2_lib.baseboard_fab2(sch_1):page106_i142"
				( objectStatus "F3978" )
				( pin "A"
					( objectStatus "C2R10.1" )
				)
				( pin "B"
					( objectStatus "C2R10.2" )
				)
			)
			( gate "@baseboard_fab2_lib.baseboard_fab2(sch_1):page106_i147"
				( objectStatus "F3979" )
				( pin "A"
					( objectStatus "C2R9.1" )
				)
				( pin "B"
					( objectStatus "C2R9.2" )
				)
			)
			( gate "@baseboard_fab2_lib.baseboard_fab2(sch_1):page106_i141"
				( objectStatus "F3980" )
				( pin "A"
					( objectStatus "C2R8.1" )
				)
				( pin "B"
					( objectStatus "C2R8.2" )
				)
			)
			( gate "@baseboard_fab2_lib.baseboard_fab2(sch_1):page106_i123"
				( objectStatus "F3981" )
				( pin "A"
					( objectStatus "C2R7.1" )
				)
				( pin "B"
					( objectStatus "C2R7.2" )
				)
			)
			( gate "@baseboard_fab2_lib.baseboard_fab2(sch_1):page106_i130"
				( objectStatus "F3985" )
				( pin "A"
					( objectStatus "C2R14.1" )
				)
				( pin "B"
					( objectStatus "C2R14.2" )
				)
			)
			( gate "@baseboard_fab2_lib.baseboard_fab2(sch_1):page106_i10"
				( objectStatus "F3995" )
				( pin "A"
					( objectStatus "C1R2.1" )
				)
				( pin "B"
					( objectStatus "C1R2.2" )
				)
			)
			( gate "@baseboard_fab2_lib.baseboard_fab2(sch_1):page106_i29"
				( objectStatus "F3996" )
				( pin "A"
					( objectStatus "C1R1.1" )
				)
				( pin "B"
					( objectStatus "C1R1.2" )
				)
			)
			( gate "@baseboard_fab2_lib.baseboard_fab2(sch_1):page106_i137"
				( objectStatus "F3986" )
				( pin "A"
					( objectStatus "C2R13.1" )
				)
				( pin "B"
					( objectStatus "C2R13.2" )
				)
			)
			( gate "@baseboard_fab2_lib.baseboard_fab2(sch_1):page106_i128"
				( objectStatus "F3987" )
				( pin "A"
					( objectStatus "C1R10.1" )
				)
				( pin "B"
					( objectStatus "C1R10.2" )
				)
			)
			( gate "@baseboard_fab2_lib.baseboard_fab2(sch_1):page106_i134"
				( objectStatus "F3988" )
				( pin "A"
					( objectStatus "C1R9.1" )
				)
				( pin "B"
					( objectStatus "C1R9.2" )
				)
			)
			( gate "@baseboard_fab2_lib.baseboard_fab2(sch_1):page106_i109"
				( objectStatus "F4010" )
				( pin "A"
					( objectStatus "C1M6.1" )
				)
				( pin "B"
					( objectStatus "C1M6.2" )
				)
			)
			( gate "@baseboard_fab2_lib.baseboard_fab2(sch_1):page106_i122"
				( objectStatus "F4009" )
				( pin "A"
					( objectStatus "C1M7.1" )
				)
				( pin "B"
					( objectStatus "C1M7.2" )
				)
			)
			( gate "@baseboard_fab2_lib.baseboard_fab2(sch_1):page106_i105"
				( objectStatus "F4008" )
				( pin "A"
					( objectStatus "C1M8.1" )
				)
				( pin "B"
					( objectStatus "C1M8.2" )
				)
			)
			( gate "@baseboard_fab2_lib.baseboard_fab2(sch_1):page106_i114"
				( objectStatus "F4007" )
				( pin "A"
					( objectStatus "C1M9.1" )
				)
				( pin "B"
					( objectStatus "C1M9.2" )
				)
			)
			( gate "@baseboard_fab2_lib.baseboard_fab2(sch_1):page106_i102"
				( objectStatus "F4006" )
				( pin "A"
					( objectStatus "C1M10.1" )
				)
				( pin "B"
					( objectStatus "C1M10.2" )
				)
			)
			( gate "@baseboard_fab2_lib.baseboard_fab2(sch_1):page106_i117"
				( objectStatus "F4005" )
				( pin "A"
					( objectStatus "C1M11.1" )
				)
				( pin "B"
					( objectStatus "C1M11.2" )
				)
			)
			( gate "@baseboard_fab2_lib.baseboard_fab2(sch_1):page106_i100"
				( objectStatus "F4004" )
				( pin "A"
					( objectStatus "C1M12.1" )
				)
				( pin "B"
					( objectStatus "C1M12.2" )
				)
			)
			( gate "@baseboard_fab2_lib.baseboard_fab2(sch_1):page106_i111"
				( objectStatus "F4003" )
				( pin "A"
					( objectStatus "C1M13.1" )
				)
				( pin "B"
					( objectStatus "C1M13.2" )
				)
			)
			( gate "@baseboard_fab2_lib.baseboard_fab2(sch_1):page106_i85"
				( objectStatus "F4002" )
				( pin "A"
					( objectStatus "C1M14.1" )
				)
				( pin "B"
					( objectStatus "C1M14.2" )
				)
			)
			( gate "@baseboard_fab2_lib.baseboard_fab2(sch_1):page106_i95"
				( objectStatus "F4001" )
				( pin "A"
					( objectStatus "C1M15.1" )
				)
				( pin "B"
					( objectStatus "C1M15.2" )
				)
			)
			( gate "@baseboard_fab2_lib.baseboard_fab2(sch_1):page106_i82"
				( objectStatus "F4000" )
				( pin "A"
					( objectStatus "C1M16.1" )
				)
				( pin "B"
					( objectStatus "C1M16.2" )
				)
			)
			( gate "@baseboard_fab2_lib.baseboard_fab2(sch_1):page106_i92"
				( objectStatus "F3999" )
				( pin "A"
					( objectStatus "C1M17.1" )
				)
				( pin "B"
					( objectStatus "C1M17.2" )
				)
			)
			( gate "@baseboard_fab2_lib.baseboard_fab2(sch_1):page106_i78"
				( objectStatus "F3998" )
				( pin "A"
					( objectStatus "C1M18.1" )
				)
				( pin "B"
					( objectStatus "C1M18.2" )
				)
			)
			( gate "@baseboard_fab2_lib.baseboard_fab2(sch_1):page106_i90"
				( objectStatus "F3997" )
				( pin "A"
					( objectStatus "C1M19.1" )
				)
				( pin "B"
					( objectStatus "C1M19.2" )
				)
			)
			( gate "@baseboard_fab2_lib.baseboard_fab2(sch_1):page106_i76"
				( objectStatus "F3983" )
				( pin "A"
					( objectStatus "C2M14.1" )
				)
				( pin "B"
					( objectStatus "C2M14.2" )
				)
			)
			( gate "@baseboard_fab2_lib.baseboard_fab2(sch_1):page106_i86"
				( objectStatus "F3982" )
				( pin "A"
					( objectStatus "C2M15.1" )
				)
				( pin "B"
					( objectStatus "C2M15.2" )
				)
			)
			( gate "@baseboard_fab2_lib.baseboard_fab2(sch_1):page105_i51"
				( objectStatus "F3864" )
				( pin "A"
					( objectStatus "C7G21.1" )
				)
				( pin "B"
					( objectStatus "C7G21.2" )
				)
			)
			( gate "@baseboard_fab2_lib.baseboard_fab2(sch_1):page105_i37"
				( objectStatus "F3863" )
				( pin "A"
					( objectStatus "C7G22.1" )
				)
				( pin "B"
					( objectStatus "C7G22.2" )
				)
			)
			( gate "@baseboard_fab2_lib.baseboard_fab2(sch_1):page105_i52"
				( objectStatus "F3862" )
				( pin "A"
					( objectStatus "C7G23.1" )
				)
				( pin "B"
					( objectStatus "C7G23.2" )
				)
			)
			( gate "@baseboard_fab2_lib.baseboard_fab2(sch_1):page105_i1"
				( objectStatus "F3861" )
				( pin "A"
					( objectStatus "C7G24.1" )
				)
				( pin "B"
					( objectStatus "C7G24.2" )
				)
			)
			( gate "@baseboard_fab2_lib.baseboard_fab2(sch_1):page105_i69"
				( objectStatus "F3860" )
				( pin "A"
					( objectStatus "C7G25.1" )
				)
				( pin "B"
					( objectStatus "C7G25.2" )
				)
			)
			( gate "@baseboard_fab2_lib.baseboard_fab2(sch_1):page105_i55"
				( objectStatus "F3859" )
				( pin "A"
					( objectStatus "C7G26.1" )
				)
				( pin "B"
					( objectStatus "C7G26.2" )
				)
			)
			( gate "@baseboard_fab2_lib.baseboard_fab2(sch_1):page105_i70"
				( objectStatus "F3854" )
				( pin "A"
					( objectStatus "C8G1.1" )
				)
				( pin "B"
					( objectStatus "C8G1.2" )
				)
			)
			( gate "@baseboard_fab2_lib.baseboard_fab2(sch_1):page105_i58"
				( objectStatus "F3853" )
				( pin "A"
					( objectStatus "C8G2.1" )
				)
				( pin "B"
					( objectStatus "C8G2.2" )
				)
			)
			( gate "@baseboard_fab2_lib.baseboard_fab2(sch_1):page105_i71"
				( objectStatus "F3852" )
				( pin "A"
					( objectStatus "C8G3.1" )
				)
				( pin "B"
					( objectStatus "C8G3.2" )
				)
			)
			( gate "@baseboard_fab2_lib.baseboard_fab2(sch_1):page105_i56"
				( objectStatus "F3851" )
				( pin "A"
					( objectStatus "C8G4.1" )
				)
				( pin "B"
					( objectStatus "C8G4.2" )
				)
			)
			( gate "@baseboard_fab2_lib.baseboard_fab2(sch_1):page105_i75"
				( objectStatus "F3850" )
				( pin "A"
					( objectStatus "C8G5.1" )
				)
				( pin "B"
					( objectStatus "C8G5.2" )
				)
			)
			( gate "@baseboard_fab2_lib.baseboard_fab2(sch_1):page105_i61"
				( objectStatus "F3849" )
				( pin "A"
					( objectStatus "C8G6.1" )
				)
				( pin "B"
					( objectStatus "C8G6.2" )
				)
			)
			( gate "@baseboard_fab2_lib.baseboard_fab2(sch_1):page105_i76"
				( objectStatus "F3847" )
				( pin "A"
					( objectStatus "C8G8.1" )
				)
				( pin "B"
					( objectStatus "C8G8.2" )
				)
			)
			( gate "@baseboard_fab2_lib.baseboard_fab2(sch_1):page105_i62"
				( objectStatus "F3848" )
				( pin "A"
					( objectStatus "C8G7.1" )
				)
				( pin "B"
					( objectStatus "C8G7.2" )
				)
			)
			( gate "@baseboard_fab2_lib.baseboard_fab2(sch_1):page105_i93"
				( objectStatus "F3846" )
				( pin "A"
					( objectStatus "C8G9.1" )
				)
				( pin "B"
					( objectStatus "C8G9.2" )
				)
			)
			( gate "@baseboard_fab2_lib.baseboard_fab2(sch_1):page105_i96"
				( objectStatus "F3845" )
				( pin "A"
					( objectStatus "C8G10.1" )
				)
				( pin "B"
					( objectStatus "C8G10.2" )
				)
			)
			( gate "@baseboard_fab2_lib.baseboard_fab2(sch_1):page105_i20"
				( objectStatus "F3880" )
				( pin "A"
					( objectStatus "C7G5.1" )
				)
				( pin "B"
					( objectStatus "C7G5.2" )
				)
			)
			( gate "@baseboard_fab2_lib.baseboard_fab2(sch_1):page105_i7"
				( objectStatus "F3878" )
				( pin "A"
					( objectStatus "C7G7.1" )
				)
				( pin "B"
					( objectStatus "C7G7.2" )
				)
			)
			( gate "@baseboard_fab2_lib.baseboard_fab2(sch_1):page105_i21"
				( objectStatus "F3876" )
				( pin "A"
					( objectStatus "C7G9.1" )
				)
				( pin "B"
					( objectStatus "C7G9.2" )
				)
			)
			( gate "@baseboard_fab2_lib.baseboard_fab2(sch_1):page105_i8"
				( objectStatus "F3875" )
				( pin "A"
					( objectStatus "C7G10.1" )
				)
				( pin "B"
					( objectStatus "C7G10.2" )
				)
			)
			( gate "@baseboard_fab2_lib.baseboard_fab2(sch_1):page105_i27"
				( objectStatus "F3874" )
				( pin "A"
					( objectStatus "C7G11.1" )
				)
				( pin "B"
					( objectStatus "C7G11.2" )
				)
			)
			( gate "@baseboard_fab2_lib.baseboard_fab2(sch_1):page105_i12"
				( objectStatus "F3873" )
				( pin "A"
					( objectStatus "C7G12.1" )
				)
				( pin "B"
					( objectStatus "C7G12.2" )
				)
			)
			( gate "@baseboard_fab2_lib.baseboard_fab2(sch_1):page105_i28"
				( objectStatus "F3871" )
				( pin "A"
					( objectStatus "C7G14.1" )
				)
				( pin "B"
					( objectStatus "C7G14.2" )
				)
			)
			( gate "@baseboard_fab2_lib.baseboard_fab2(sch_1):page105_i13"
				( objectStatus "F3872" )
				( pin "A"
					( objectStatus "C7G13.1" )
				)
				( pin "B"
					( objectStatus "C7G13.2" )
				)
			)
			( gate "@baseboard_fab2_lib.baseboard_fab2(sch_1):page105_i45"
				( objectStatus "F3870" )
				( pin "A"
					( objectStatus "C7G15.1" )
				)
				( pin "B"
					( objectStatus "C7G15.2" )
				)
			)
			( gate "@baseboard_fab2_lib.baseboard_fab2(sch_1):page105_i31"
				( objectStatus "F3869" )
				( pin "A"
					( objectStatus "C7G16.1" )
				)
				( pin "B"
					( objectStatus "C7G16.2" )
				)
			)
			( gate "@baseboard_fab2_lib.baseboard_fab2(sch_1):page105_i44"
				( objectStatus "F3868" )
				( pin "A"
					( objectStatus "C7G17.1" )
				)
				( pin "B"
					( objectStatus "C7G17.2" )
				)
			)
			( gate "@baseboard_fab2_lib.baseboard_fab2(sch_1):page105_i32"
				( objectStatus "F3867" )
				( pin "A"
					( objectStatus "C7G18.1" )
				)
				( pin "B"
					( objectStatus "C7G18.2" )
				)
			)
			( gate "@baseboard_fab2_lib.baseboard_fab2(sch_1):page105_i46"
				( objectStatus "F3866" )
				( pin "A"
					( objectStatus "C7G19.1" )
				)
				( pin "B"
					( objectStatus "C7G19.2" )
				)
			)
			( gate "@baseboard_fab2_lib.baseboard_fab2(sch_1):page105_i34"
				( objectStatus "F3865" )
				( pin "A"
					( objectStatus "C7G20.1" )
				)
				( pin "B"
					( objectStatus "C7G20.2" )
				)
			)
			( gate "@baseboard_fab2_lib.baseboard_fab2(sch_1):page105_i6"
				( objectStatus "F3879" )
				( pin "A"
					( objectStatus "C7G6.1" )
				)
				( pin "B"
					( objectStatus "C7G6.2" )
				)
			)
			( gate "@baseboard_fab2_lib.baseboard_fab2(sch_1):page105_i22"
				( objectStatus "F3877" )
				( pin "A"
					( objectStatus "C7G8.1" )
				)
				( pin "B"
					( objectStatus "C7G8.2" )
				)
			)
			( gate "@baseboard_fab2_lib.baseboard_fab2(sch_1):page182_i12"
				( objectStatus "F3830" )
				( pin "A"
					( objectStatus "C9N17.1" )
				)
				( pin "B"
					( objectStatus "C9N17.2" )
				)
			)
			( gate "@baseboard_fab2_lib.baseboard_fab2(sch_1):page182_i16"
				( objectStatus "F3834" )
				( pin "A"
					( objectStatus "C9N12.1" )
				)
				( pin "B"
					( objectStatus "C9N12.2" )
				)
			)
			( gate "@baseboard_fab2_lib.baseboard_fab2(sch_1):page182_i15"
				( objectStatus "F3843" )
				( pin "A"
					( objectStatus "C9N2.1" )
				)
				( pin "B"
					( objectStatus "C9N2.2" )
				)
			)
			( gate "@baseboard_fab2_lib.baseboard_fab2(sch_1):page182_i53"
				( objectStatus "F3835" )
				( pin "A"
					( objectStatus "C9N10.1" )
				)
				( pin "B"
					( objectStatus "C9N10.2" )
				)
			)
			( gate "@baseboard_fab2_lib.baseboard_fab2(sch_1):page182_i54"
				( objectStatus "F3838" )
				( pin "A"
					( objectStatus "C9N7.1" )
				)
				( pin "B"
					( objectStatus "C9N7.2" )
				)
			)
			( gate "@baseboard_fab2_lib.baseboard_fab2(sch_1):page182_i55"
				( objectStatus "F3841" )
				( pin "A"
					( objectStatus "C9N4.1" )
				)
				( pin "B"
					( objectStatus "C9N4.2" )
				)
			)
			( gate "@baseboard_fab2_lib.baseboard_fab2(sch_1):page182_i56"
				( objectStatus "F3833" )
				( pin "A"
					( objectStatus "C9N14.1" )
				)
				( pin "B"
					( objectStatus "C9N14.2" )
				)
			)
			( gate "@baseboard_fab2_lib.baseboard_fab2(sch_1):page182_i83"
				( objectStatus "F3840" )
				( pin "A"
					( objectStatus "C9N5.1" )
				)
				( pin "B"
					( objectStatus "C9N5.2" )
				)
			)
			( gate "@baseboard_fab2_lib.baseboard_fab2(sch_1):page182_i50"
				( objectStatus "F3837" )
				( pin "A"
					( objectStatus "C9N8.1" )
				)
				( pin "B"
					( objectStatus "C9N8.2" )
				)
			)
			( gate "@baseboard_fab2_lib.baseboard_fab2(sch_1):page182_i49"
				( objectStatus "F3836" )
				( pin "A"
					( objectStatus "C9N9.1" )
				)
				( pin "B"
					( objectStatus "C9N9.2" )
				)
			)
			( gate "@baseboard_fab2_lib.baseboard_fab2(sch_1):page182_i51"
				( objectStatus "F3842" )
				( pin "A"
					( objectStatus "C9N3.1" )
				)
				( pin "B"
					( objectStatus "C9N3.2" )
				)
			)
			( gate "@baseboard_fab2_lib.baseboard_fab2(sch_1):page182_i52"
				( objectStatus "F3831" )
				( pin "A"
					( objectStatus "C9N16.1" )
				)
				( pin "B"
					( objectStatus "C9N16.2" )
				)
			)
			( gate "@baseboard_fab2_lib.baseboard_fab2(sch_1):page182_i81"
				( objectStatus "F3839" )
				( pin "A"
					( objectStatus "C9N6.1" )
				)
				( pin "B"
					( objectStatus "C9N6.2" )
				)
			)
			( gate "@baseboard_fab2_lib.baseboard_fab2(sch_1):page182_i9"
				( objectStatus "F3829" )
				( pin "A"
					( objectStatus "C9N18.1" )
				)
				( pin "B"
					( objectStatus "C9N18.2" )
				)
			)
			( gate "@baseboard_fab2_lib.baseboard_fab2(sch_1):page182_i13"
				( objectStatus "F3832" )
				( pin "A"
					( objectStatus "C9N15.1" )
				)
				( pin "B"
					( objectStatus "C9N15.2" )
				)
			)
			( gate "@baseboard_fab2_lib.baseboard_fab2(sch_1):page182_i14"
				( objectStatus "F3844" )
				( pin "A"
					( objectStatus "C9N1.1" )
				)
				( pin "B"
					( objectStatus "C9N1.2" )
				)
			)
			( gate "@baseboard_fab2_lib.baseboard_fab2(sch_1):page236_i39"
				( objectStatus "F3984" )
			)
			( gate "@baseboard_fab2_lib.baseboard_fab2(sch_1):page236_i16"
				( objectStatus "F3892" )
			)
			( gate "@baseboard_fab2_lib.baseboard_fab2(sch_1):page214_i73"
				( objectStatus "F3909" )
			)
			( gate "@baseboard_fab2_lib.baseboard_fab2(sch_1):page203_i48"
				( objectStatus "F3913" )
			)
			( gate "@baseboard_fab2_lib.baseboard_fab2(sch_1):page203_i40"
				( objectStatus "F3912" )
			)
			( gate "@baseboard_fab2_lib.baseboard_fab2(sch_1):page185_i66"
				( objectStatus "F3973" )
				( pin "A"
					( objectStatus "C2T20.1" )
				)
				( pin "B"
					( objectStatus "C2T20.2" )
				)
			)
			( gate "@baseboard_fab2_lib.baseboard_fab2(sch_1):page185_i67"
				( objectStatus "F3972" )
				( pin "A"
					( objectStatus "C2T23.1" )
				)
				( pin "B"
					( objectStatus "C2T23.2" )
				)
			)
			( gate "@baseboard_fab2_lib.baseboard_fab2(sch_1):page185_i64"
				( objectStatus "F3975" )
				( pin "A"
					( objectStatus "C2T13.1" )
				)
				( pin "B"
					( objectStatus "C2T13.2" )
				)
			)
			( gate "@baseboard_fab2_lib.baseboard_fab2(sch_1):page185_i65"
				( objectStatus "F3974" )
				( pin "A"
					( objectStatus "C2T14.1" )
				)
				( pin "B"
					( objectStatus "C2T14.2" )
				)
			)
			( gate "@baseboard_fab2_lib.baseboard_fab2(sch_1):page185_i63"
				( objectStatus "F3977" )
				( pin "A"
					( objectStatus "C2T10.1" )
				)
				( pin "B"
					( objectStatus "C2T10.2" )
				)
			)
			( gate "@baseboard_fab2_lib.baseboard_fab2(sch_1):page185_i62"
				( objectStatus "F3976" )
				( pin "A"
					( objectStatus "C2T11.1" )
				)
				( pin "B"
					( objectStatus "C2T11.2" )
				)
			)
			( gate "@baseboard_fab2_lib.baseboard_fab2(sch_1):page129_i35"
				( objectStatus "F3889" )
				( pin "A"
					( objectStatus "C7B25.1" )
				)
				( pin "B"
					( objectStatus "C7B25.2" )
				)
			)
			( gate "@baseboard_fab2_lib.baseboard_fab2(sch_1):page129_i70"
				( objectStatus "F3886" )
				( pin "A"
					( objectStatus "C7B28.1" )
				)
				( pin "B"
					( objectStatus "C7B28.2" )
				)
			)
			( gate "@baseboard_fab2_lib.baseboard_fab2(sch_1):page129_i75"
				( objectStatus "F3934" )
				( pin "A"
					( objectStatus "C3N8.1" )
				)
				( pin "B"
					( objectStatus "C3N8.2" )
				)
			)
			( gate "@baseboard_fab2_lib.baseboard_fab2(sch_1):page129_i73"
				( objectStatus "F3939" )
				( pin "A"
					( objectStatus "C3M37.1" )
				)
				( pin "B"
					( objectStatus "C3M37.2" )
				)
			)
			( gate "@baseboard_fab2_lib.baseboard_fab2(sch_1):page129_i69"
				( objectStatus "F3887" )
				( pin "A"
					( objectStatus "C7B27.1" )
				)
				( pin "B"
					( objectStatus "C7B27.2" )
				)
			)
			( gate "@baseboard_fab2_lib.baseboard_fab2(sch_1):page129_i71"
				( objectStatus "F3883" )
				( pin "A"
					( objectStatus "C7C2.1" )
				)
				( pin "B"
					( objectStatus "C7C2.2" )
				)
			)
			( gate "@baseboard_fab2_lib.baseboard_fab2(sch_1):page129_i74"
				( objectStatus "F3933" )
				( pin "A"
					( objectStatus "C3N9.1" )
				)
				( pin "B"
					( objectStatus "C3N9.2" )
				)
			)
			( gate "@baseboard_fab2_lib.baseboard_fab2(sch_1):page129_i72"
				( objectStatus "F3938" )
				( pin "A"
					( objectStatus "C3M40.1" )
				)
				( pin "B"
					( objectStatus "C3M40.2" )
				)
			)
			( gate "@baseboard_fab2_lib.baseboard_fab2(sch_1):page129_i79"
				( objectStatus "F3888" )
				( pin "A"
					( objectStatus "C7B26.1" )
				)
				( pin "B"
					( objectStatus "C7B26.2" )
				)
			)
			( gate "@baseboard_fab2_lib.baseboard_fab2(sch_1):page129_i77"
				( objectStatus "F3884" )
				( pin "A"
					( objectStatus "C7C1.1" )
				)
				( pin "B"
					( objectStatus "C7C1.2" )
				)
			)
			( gate "@baseboard_fab2_lib.baseboard_fab2(sch_1):page129_i83"
				( objectStatus "F3932" )
				( pin "A"
					( objectStatus "C3N13.1" )
				)
				( pin "B"
					( objectStatus "C3N13.2" )
				)
			)
			( gate "@baseboard_fab2_lib.baseboard_fab2(sch_1):page129_i81"
				( objectStatus "F3937" )
				( pin "A"
					( objectStatus "C3M41.1" )
				)
				( pin "B"
					( objectStatus "C3M41.2" )
				)
			)
			( gate "@baseboard_fab2_lib.baseboard_fab2(sch_1):page129_i78"
				( objectStatus "F3885" )
				( pin "A"
					( objectStatus "C7B29.1" )
				)
				( pin "B"
					( objectStatus "C7B29.2" )
				)
			)
			( gate "@baseboard_fab2_lib.baseboard_fab2(sch_1):page129_i76"
				( objectStatus "F3882" )
				( pin "A"
					( objectStatus "C7C3.1" )
				)
				( pin "B"
					( objectStatus "C7C3.2" )
				)
			)
			( gate "@baseboard_fab2_lib.baseboard_fab2(sch_1):page129_i82"
				( objectStatus "F3935" )
				( pin "A"
					( objectStatus "C3M45.1" )
				)
				( pin "B"
					( objectStatus "C3M45.2" )
				)
			)
			( gate "@baseboard_fab2_lib.baseboard_fab2(sch_1):page129_i80"
				( objectStatus "F3936" )
				( pin "A"
					( objectStatus "C3M44.1" )
				)
				( pin "B"
					( objectStatus "C3M44.2" )
				)
			)
			( gate "@baseboard_fab2_lib.baseboard_fab2(sch_1):page202_i24"
				( objectStatus "F3911" )
			)
			( gate "@baseboard_fab2_lib.baseboard_fab2(sch_1):page202_i18"
				( objectStatus "F3910" )
			)
			( gate "@baseboard_fab2_lib.baseboard_fab2(sch_1):page204_i18"
				( objectStatus "F3914" )
			)
			( gate "@baseboard_fab2_lib.baseboard_fab2(sch_1):page205_i16"
				( objectStatus "F3915" )
			)
			( gate "@baseboard_fab2_lib.baseboard_fab2(sch_1):page216_i54"
				( objectStatus "F3858" )
			)
			( gate "@baseboard_fab2_lib.baseboard_fab2(sch_1):page216_i72"
				( objectStatus "F3857" )
			)
			( gate "@baseboard_fab2_lib.baseboard_fab2(sch_1):page219_i54"
				( objectStatus "F3891" )
			)
			( gate "@baseboard_fab2_lib.baseboard_fab2(sch_1):page219_i72"
				( objectStatus "F3890" )
			)
			( gate "@baseboard_fab2_lib.baseboard_fab2(sch_1):page227_i54"
				( objectStatus "F4036" )
			)
			( gate "@baseboard_fab2_lib.baseboard_fab2(sch_1):page227_i72"
				( objectStatus "F4035" )
			)
			( gate "@baseboard_fab2_lib.baseboard_fab2(sch_1):page224_i54"
				( objectStatus "F4011" )
			)
			( gate "@baseboard_fab2_lib.baseboard_fab2(sch_1):page224_i72"
				( objectStatus "F4012" )
			)
			( gate "@baseboard_fab2_lib.baseboard_fab2(sch_1):page207_i36"
				( objectStatus "F4030" )
			)
			( gate "@baseboard_fab2_lib.baseboard_fab2(sch_1):page207_i28"
				( objectStatus "F4029" )
			)
			( gate "@baseboard_fab2_lib.baseboard_fab2(sch_1):page208_i38"
				( objectStatus "F4031" )
			)
			( gate "@baseboard_fab2_lib.baseboard_fab2(sch_1):page208_i46"
				( objectStatus "F4032" )
			)
			( gate "@baseboard_fab2_lib.baseboard_fab2(sch_1):page210_i22"
				( objectStatus "F4034" )
			)
			( gate "@baseboard_fab2_lib.baseboard_fab2(sch_1):page181_i167"
				( objectStatus "F4027" )
				( pin "A"
					( objectStatus "C1F3.1" )
				)
				( pin "B"
					( objectStatus "C1F3.2" )
				)
			)
			( gate "@baseboard_fab2_lib.baseboard_fab2(sch_1):page181_i168"
				( objectStatus "F4020" )
				( pin "A"
					( objectStatus "C1F12.1" )
				)
				( pin "B"
					( objectStatus "C1F12.2" )
				)
			)
			( gate "@baseboard_fab2_lib.baseboard_fab2(sch_1):page181_i169"
				( objectStatus "F4021" )
				( pin "A"
					( objectStatus "C1F11.1" )
				)
				( pin "B"
					( objectStatus "C1F11.2" )
				)
			)
			( gate "@baseboard_fab2_lib.baseboard_fab2(sch_1):page181_i170"
				( objectStatus "F4023" )
				( pin "A"
					( objectStatus "C1F8.1" )
				)
				( pin "B"
					( objectStatus "C1F8.2" )
				)
			)
			( gate "@baseboard_fab2_lib.baseboard_fab2(sch_1):page181_i171"
				( objectStatus "F4014" )
				( pin "A"
					( objectStatus "C1F18.1" )
				)
				( pin "B"
					( objectStatus "C1F18.2" )
				)
			)
			( gate "@baseboard_fab2_lib.baseboard_fab2(sch_1):page181_i173"
				( objectStatus "F4015" )
				( pin "A"
					( objectStatus "C1F17.1" )
				)
				( pin "B"
					( objectStatus "C1F17.2" )
				)
			)
			( gate "@baseboard_fab2_lib.baseboard_fab2(sch_1):page181_i175"
				( objectStatus "F4018" )
				( pin "A"
					( objectStatus "C1F14.1" )
				)
				( pin "B"
					( objectStatus "C1F14.2" )
				)
			)
			( gate "@baseboard_fab2_lib.baseboard_fab2(sch_1):page181_i161"
				( objectStatus "F4025" )
				( pin "A"
					( objectStatus "C1F5.1" )
				)
				( pin "B"
					( objectStatus "C1F5.2" )
				)
			)
			( gate "@baseboard_fab2_lib.baseboard_fab2(sch_1):page181_i160"
				( objectStatus "F4026" )
				( pin "A"
					( objectStatus "C1F4.1" )
				)
				( pin "B"
					( objectStatus "C1F4.2" )
				)
			)
			( gate "@baseboard_fab2_lib.baseboard_fab2(sch_1):page181_i162"
				( objectStatus "F4028" )
				( pin "A"
					( objectStatus "C1F2.1" )
				)
				( pin "B"
					( objectStatus "C1F2.2" )
				)
			)
			( gate "@baseboard_fab2_lib.baseboard_fab2(sch_1):page181_i163"
				( objectStatus "F4019" )
				( pin "A"
					( objectStatus "C1F13.1" )
				)
				( pin "B"
					( objectStatus "C1F13.2" )
				)
			)
			( gate "@baseboard_fab2_lib.baseboard_fab2(sch_1):page181_i164"
				( objectStatus "F4022" )
				( pin "A"
					( objectStatus "C1F10.1" )
				)
				( pin "B"
					( objectStatus "C1F10.2" )
				)
			)
			( gate "@baseboard_fab2_lib.baseboard_fab2(sch_1):page181_i165"
				( objectStatus "F4024" )
				( pin "A"
					( objectStatus "C1F6.1" )
				)
				( pin "B"
					( objectStatus "C1F6.2" )
				)
			)
			( gate "@baseboard_fab2_lib.baseboard_fab2(sch_1):page181_i166"
				( objectStatus "F4013" )
				( pin "A"
					( objectStatus "C1F20.1" )
				)
				( pin "B"
					( objectStatus "C1F20.2" )
				)
			)
			( gate "@baseboard_fab2_lib.baseboard_fab2(sch_1):page181_i172"
				( objectStatus "F4016" )
				( pin "A"
					( objectStatus "C1F16.1" )
				)
				( pin "B"
					( objectStatus "C1F16.2" )
				)
			)
			( gate "@baseboard_fab2_lib.baseboard_fab2(sch_1):page181_i174"
				( objectStatus "F4017" )
				( pin "A"
					( objectStatus "C1F15.1" )
				)
				( pin "B"
					( objectStatus "C1F15.2" )
				)
			)
			( gate "@baseboard_fab2_lib.baseboard_fab2(sch_1):page209_i22"
				( objectStatus "F4033" )
			)
			( gate "@baseboard_fab2_lib.baseboard_fab2(sch_1):page212_i33"
				( objectStatus "F3881" )
			)
			( gate "@baseboard_fab2_lib.baseboard_fab2(sch_1):page141_i48"
				( objectStatus "F3758" )
			)
			( gate "@baseboard_fab2_lib.baseboard_fab2(sch_1):page236_i65"
				( objectStatus "F2278" )
			)
			( gate "@baseboard_fab2_lib.baseboard_fab2(sch_1):page236_i63"
				( objectStatus "F2279" )
			)
			( gate "@baseboard_fab2_lib.baseboard_fab2(sch_1):page212_i54"
				( objectStatus "F2277" )
			)
			( gate "@baseboard_fab2_lib.baseboard_fab2(sch_1):page212_i51"
				( objectStatus "F2276" )
			)
			( gate "@baseboard_fab2_lib.baseboard_fab2(sch_1):page214_i29"
				( objectStatus "F2282" )
			)
			( gate "@baseboard_fab2_lib.baseboard_fab2(sch_1):page214_i8"
				( objectStatus "F2281" )
			)
			( gate "@baseboard_fab2_lib.baseboard_fab2(sch_1):page214_i31"
				( objectStatus "F2280" )
			)
			( gate "@baseboard_fab2_lib.baseboard_fab2(sch_1):page161_i99"
				( objectStatus "F853" )
			)
			( gate "@baseboard_fab2_lib.baseboard_fab2(sch_1):page161_i102"
				( objectStatus "F852" )
				( pin "B"
					( objectStatus "R2U44.2" )
				)
			)
			( gate "@baseboard_fab2_lib.baseboard_fab2(sch_1):page177_i72"
				( objectStatus "F846" )
			)
			( gate "@baseboard_fab2_lib.baseboard_fab2(sch_1):page119_i178"
				( objectStatus "F848" )
			)
			( gate "@baseboard_fab2_lib.baseboard_fab2(sch_1):page21_i152"
				( objectStatus "F850" )
				( pin "A"
					( objectStatus "R6B3.1" )
				)
				( pin "B"
					( objectStatus "R6B3.2" )
				)
			)
			( gate "@baseboard_fab2_lib.baseboard_fab2(sch_1):page21_i149"
				( objectStatus "F849" )
				( pin "A"
					( objectStatus "R6N10.1" )
				)
				( pin "B"
					( objectStatus "R6N10.2" )
				)
			)
			( gate "@baseboard_fab2_lib.baseboard_fab2(sch_1):page55_i26"
				( objectStatus "F855" )
				( pin "A"
					( objectStatus "R1C1.1" )
				)
				( pin "B"
					( objectStatus "R1C1.2" )
				)
			)
			( gate "@baseboard_fab2_lib.baseboard_fab2(sch_1):page55_i27"
				( objectStatus "F851" )
				( pin "A"
					( objectStatus "R3B1.1" )
				)
				( pin "B"
					( objectStatus "R3B1.2" )
				)
			)
			( gate "@baseboard_fab2_lib.baseboard_fab2(sch_1):page147_i57"
				( objectStatus "F847" )
			)
			( gate "@baseboard_fab2_lib.baseboard_fab2(sch_1):page175_i45"
				( objectStatus "F854" )
			)
			( gate "@baseboard_fab2_lib.baseboard_fab2(sch_1):page138_i91"
				( objectStatus "F763" )
			)
			( gate "@baseboard_fab2_lib.baseboard_fab2(sch_1):page138_i92"
				( objectStatus "F764" )
			)
			( gate "@baseboard_fab2_lib.baseboard_fab2(sch_1):page138_i95"
				( objectStatus "F766" )
				( pin "B"
					( objectStatus "R8B24.2" )
				)
			)
			( gate "@baseboard_fab2_lib.baseboard_fab2(sch_1):page138_i96"
				( objectStatus "F765" )
			)
			( gate "@baseboard_fab2_lib.baseboard_fab2(sch_1):page237_i15"
				( objectStatus "F256" )
			)
			( gate "@baseboard_fab2_lib.baseboard_fab2(sch_1):page200_i218"
				( objectStatus "F495" )
			)
			( gate "@baseboard_fab2_lib.baseboard_fab2(sch_1):page139_i174"
				( objectStatus "F496" )
			)
			( gate "@baseboard_fab2_lib.baseboard_fab2(sch_1):page139_i140"
				( objectStatus "F2274" )
			)
			( gate "@baseboard_fab2_lib.baseboard_fab2(sch_1):page139_i155"
				( objectStatus "F2275" )
			)
			( gate "@baseboard_fab2_lib.baseboard_fab2(sch_1):page114_i49"
				( objectStatus "F2230" )
			)
			( gate "@baseboard_fab2_lib.baseboard_fab2(sch_1):page101_i52"
				( objectStatus "F2229" )
			)
			( gate "@baseboard_fab2_lib.baseboard_fab2(sch_1):page114_i55"
				( objectStatus "F2227" )
			)
			( gate "@baseboard_fab2_lib.baseboard_fab2(sch_1):page168_i2"
				( objectStatus "F2222" )
			)
			( gate "@baseboard_fab2_lib.baseboard_fab2(sch_1):page168_i3"
				( objectStatus "F2221" )
			)
			( gate "@baseboard_fab2_lib.baseboard_fab2(sch_1):page168_i4"
				( objectStatus "F2220" )
			)
			( gate "@baseboard_fab2_lib.baseboard_fab2(sch_1):page168_i5"
				( objectStatus "F2219" )
			)
			( gate "@baseboard_fab2_lib.baseboard_fab2(sch_1):page102_i8"
				( objectStatus "F2183" )
			)
			( gate "@baseboard_fab2_lib.baseboard_fab2(sch_1):page101_i114"
				( objectStatus "F2184" )
			)
			( gate "@baseboard_fab2_lib.baseboard_fab2(sch_1):page101_i34"
				( objectStatus "F2119" )
				( pin "RMII(1)"
					( objectStatus "EU8F2.32" )
				)
				( pin "RMII(2)"
					( objectStatus "EU8F2.29" )
				)
			)
			( gate "@baseboard_fab2_lib.baseboard_fab2(sch_1):page102_i26"
				( objectStatus "F258" )
			)
			( gate "@baseboard_fab2_lib.baseboard_fab2(sch_1):page102_i21"
				( objectStatus "F259" )
			)
			( gate "@baseboard_fab2_lib.baseboard_fab2(sch_1):page101_i105"
				( objectStatus "F262" )
			)
			( gate "@baseboard_fab2_lib.baseboard_fab2(sch_1):page101_i95"
				( objectStatus "F260" )
			)
			( gate "@baseboard_fab2_lib.baseboard_fab2(sch_1):page101_i94"
				( objectStatus "F261" )
			)
			( gate "@baseboard_fab2_lib.baseboard_fab2(sch_1):page139_i76"
				( objectStatus "F3490" )
			)
			( gate "@baseboard_fab2_lib.baseboard_fab2(sch_1):page177_i42"
				( objectStatus "F2037" )
			)
			( gate "@baseboard_fab2_lib.baseboard_fab2(sch_1):page139_i72"
				( objectStatus "F67" )
				( pin "MDI_MINUS0_SFP_I2C_DATA"
					( objectStatus "EU9E1.57" )
				)
				( pin "MDI_MINUS1_SRDS_SIG_DET"
					( objectStatus "EU9E1.54" )
				)
				( pin "MDI_PLUS0_NC"
					( objectStatus "EU9E1.58" )
				)
				( pin "MDI_PLUS1_SFP_I2C_CLK"
					( objectStatus "EU9E1.55" )
				)
				( pin "NVM_CS_N"
					( objectStatus "EU9E1.15" )
				)
				( pin "NVM_SI"
					( objectStatus "EU9E1.12" )
				)
				( pin "NVM_SK"
					( objectStatus "EU9E1.13" )
				)
				( pin "NVM_SO"
					( objectStatus "EU9E1.14" )
				)
				( pin "PECLKN"
					( objectStatus "EU9E1.25" )
				)
				( pin "PECLKP"
					( objectStatus "EU9E1.26" )
				)
				( pin "SMB_CLK"
					( objectStatus "EU9E1.34" )
				)
				( pin "SMB_DATA"
					( objectStatus "EU9E1.36" )
				)
			)
			( gate "@baseboard_fab2_lib.baseboard_fab2(sch_1):page195_i56"
				( objectStatus "F2013" )
			)
			( gate "@baseboard_fab2_lib.baseboard_fab2(sch_1):page195_i62"
				( objectStatus "F2012" )
			)
			( gate "@baseboard_fab2_lib.baseboard_fab2(sch_1):page195_i65"
				( objectStatus "F2010" )
			)
			( gate "@baseboard_fab2_lib.baseboard_fab2(sch_1):page195_i54"
				( objectStatus "F2008" )
			)
			( gate "@baseboard_fab2_lib.baseboard_fab2(sch_1):page195_i49"
				( objectStatus "F2011" )
			)
			( gate "@baseboard_fab2_lib.baseboard_fab2(sch_1):page195_i67"
				( objectStatus "F2009" )
			)
			( gate "@baseboard_fab2_lib.baseboard_fab2(sch_1):page195_i52"
				( objectStatus "F2007" )
			)
			( gate "@baseboard_fab2_lib.baseboard_fab2(sch_1):page213_i30"
				( objectStatus "F1110" )
			)
			( gate "@baseboard_fab2_lib.baseboard_fab2(sch_1):page115_i90"
				( objectStatus "F1109" )
			)
			( gate "@baseboard_fab2_lib.baseboard_fab2(sch_1):page199_i13"
				( objectStatus "F1108" )
			)
			( gate "@baseboard_fab2_lib.baseboard_fab2(sch_1):page169_i163"
				( objectStatus "F991" )
			)
			( gate "@baseboard_fab2_lib.baseboard_fab2(sch_1):page169_i164"
				( objectStatus "F987" )
			)
			( gate "@baseboard_fab2_lib.baseboard_fab2(sch_1):page164_i14"
				( objectStatus "F994" )
			)
			( gate "@baseboard_fab2_lib.baseboard_fab2(sch_1):page164_i28"
				( objectStatus "F993" )
			)
			( gate "@baseboard_fab2_lib.baseboard_fab2(sch_1):page164_i25"
				( objectStatus "F992" )
			)
			( gate "@baseboard_fab2_lib.baseboard_fab2(sch_1):page200_i210"
				( objectStatus "F989" )
			)
			( gate "@baseboard_fab2_lib.baseboard_fab2(sch_1):page200_i86"
				( objectStatus "F988" )
			)
			( gate "@baseboard_fab2_lib.baseboard_fab2(sch_1):page144_i457"
				( objectStatus "F990" )
			)
			( gate "@baseboard_fab2_lib.baseboard_fab2(sch_1):page21_i217"
				( objectStatus "TF-6347" )
			)
			( gate "@baseboard_fab2_lib.baseboard_fab2(sch_1):page55_i153"
				( objectStatus "TF-6346" )
			)
			( gate "@baseboard_fab2_lib.baseboard_fab2(sch_1):page21_i216"
				( objectStatus "TF-6345" )
			)
			( gate "@baseboard_fab2_lib.baseboard_fab2(sch_1):page55_i152"
				( objectStatus "TF-6344" )
			)
			( gate "@baseboard_fab2_lib.baseboard_fab2(sch_1):page149_i140"
				( objectStatus "F2187" )
			)
			( gate "@baseboard_fab2_lib.baseboard_fab2(sch_1):page149_i107"
				( objectStatus "F2186" )
			)
			( gate "@baseboard_fab2_lib.baseboard_fab2(sch_1):page149_i122"
				( objectStatus "F2188" )
			)
			( gate "@baseboard_fab2_lib.baseboard_fab2(sch_1):page236_i45"
				( objectStatus "F2097" )
			)
			( gate "@baseboard_fab2_lib.baseboard_fab2(sch_1):page236_i10"
				( objectStatus "F2098" )
			)
			( gate "@baseboard_fab2_lib.baseboard_fab2(sch_1):page205_i7"
				( objectStatus "F2099" )
			)
			( gate "@baseboard_fab2_lib.baseboard_fab2(sch_1):page210_i10"
				( objectStatus "F2100" )
			)
			( gate "@baseboard_fab2_lib.baseboard_fab2(sch_1):page232_i239"
				( objectStatus "F2094" )
			)
			( gate "@baseboard_fab2_lib.baseboard_fab2(sch_1):page233_i277"
				( objectStatus "F2095" )
			)
			( gate "@baseboard_fab2_lib.baseboard_fab2(sch_1):page234_i164"
				( objectStatus "F2096" )
			)
			( gate "@baseboard_fab2_lib.baseboard_fab2(sch_1):page231_i178"
				( objectStatus "F2093" )
			)
			( gate "@baseboard_fab2_lib.baseboard_fab2(sch_1):page195_i78"
				( objectStatus "F2255" )
				( pin "A1"
					( objectStatus "J1D1.A1" )
				)
				( pin "A2"
					( objectStatus "J1D1.A2" )
				)
				( pin "A3"
					( objectStatus "J1D1.A3" )
				)
				( pin "B1"
					( objectStatus "J1D1.B1" )
				)
				( pin "B2"
					( objectStatus "J1D1.B2" )
				)
				( pin "B3"
					( objectStatus "J1D1.B3" )
				)
				( pin "C1"
					( objectStatus "J1D1.C1" )
				)
				( pin "C2"
					( objectStatus "J1D1.C2" )
				)
				( pin "C3"
					( objectStatus "J1D1.C3" )
				)
				( pin "D1"
					( objectStatus "J1D1.D1" )
				)
				( pin "D2"
					( objectStatus "J1D1.D2" )
				)
				( pin "D3"
					( objectStatus "J1D1.D3" )
				)
			)
			( gate "@baseboard_fab2_lib.baseboard_fab2(sch_1):page195_i29"
				( objectStatus "F2254" )
				( pin "A1"
					( objectStatus "J1E1.A1" )
				)
				( pin "A2"
					( objectStatus "J1E1.A2" )
				)
				( pin "A3"
					( objectStatus "J1E1.A3" )
				)
				( pin "B1"
					( objectStatus "J1E1.B1" )
				)
				( pin "B2"
					( objectStatus "J1E1.B2" )
				)
				( pin "B3"
					( objectStatus "J1E1.B3" )
				)
				( pin "C1"
					( objectStatus "J1E1.C1" )
				)
				( pin "C2"
					( objectStatus "J1E1.C2" )
				)
				( pin "C3"
					( objectStatus "J1E1.C3" )
				)
				( pin "D1"
					( objectStatus "J1E1.D1" )
				)
				( pin "D2"
					( objectStatus "J1E1.D2" )
				)
				( pin "D3"
					( objectStatus "J1E1.D3" )
				)
			)
			( gate "@baseboard_fab2_lib.baseboard_fab2(sch_1):page127_i8"
				( objectStatus "F2202" )
			)
			( gate "@baseboard_fab2_lib.baseboard_fab2(sch_1):page127_i17"
				( objectStatus "F2201" )
			)
			( gate "@baseboard_fab2_lib.baseboard_fab2(sch_1):page127_i26"
				( objectStatus "F2200" )
			)
			( gate "@baseboard_fab2_lib.baseboard_fab2(sch_1):page127_i56"
				( objectStatus "F2199" )
			)
			( gate "@baseboard_fab2_lib.baseboard_fab2(sch_1):page127_i46"
				( objectStatus "F2204" )
			)
			( gate "@baseboard_fab2_lib.baseboard_fab2(sch_1):page127_i69"
				( objectStatus "F2203" )
			)
			( gate "@baseboard_fab2_lib.baseboard_fab2(sch_1):page141_i28"
				( objectStatus "F661" )
			)
			( gate "@baseboard_fab2_lib.baseboard_fab2(sch_1):page141_i30"
				( objectStatus "F662" )
			)
			( gate "@baseboard_fab2_lib.baseboard_fab2(sch_1):page141_i54"
				( objectStatus "F663" )
			)
			( gate "@baseboard_fab2_lib.baseboard_fab2(sch_1):page164_i5"
				( objectStatus "F1428" )
			)
			( gate "@baseboard_fab2_lib.baseboard_fab2(sch_1):page164_i21"
				( objectStatus "F1427" )
			)
			( gate "@baseboard_fab2_lib.baseboard_fab2(sch_1):page164_i19"
				( objectStatus "F1426" )
			)
			( gate "@baseboard_fab2_lib.baseboard_fab2(sch_1):page192_i57"
				( objectStatus "F1410" )
			)
			( gate "@baseboard_fab2_lib.baseboard_fab2(sch_1):page113_i199"
				( objectStatus "F1411" )
			)
			( gate "@baseboard_fab2_lib.baseboard_fab2(sch_1):page125_i83"
				( objectStatus "F1425" )
			)
			( gate "@baseboard_fab2_lib.baseboard_fab2(sch_1):page126_i6"
				( objectStatus "F1418" )
			)
			( gate "@baseboard_fab2_lib.baseboard_fab2(sch_1):page125_i21"
				( objectStatus "F1414" )
			)
			( gate "@baseboard_fab2_lib.baseboard_fab2(sch_1):page125_i78"
				( objectStatus "F1421" )
				( pin "B"
					( objectStatus "R3N17.2" )
				)
			)
			( gate "@baseboard_fab2_lib.baseboard_fab2(sch_1):page134_i18"
				( objectStatus "F1424" )
			)
			( gate "@baseboard_fab2_lib.baseboard_fab2(sch_1):page170_i63"
				( objectStatus "F1423" )
			)
			( gate "@baseboard_fab2_lib.baseboard_fab2(sch_1):page111_i95"
				( objectStatus "F1412" )
			)
			( gate "@baseboard_fab2_lib.baseboard_fab2(sch_1):page162_i24"
				( objectStatus "F1413" )
			)
			( gate "@baseboard_fab2_lib.baseboard_fab2(sch_1):page125_i41"
				( objectStatus "F1417" )
			)
			( gate "@baseboard_fab2_lib.baseboard_fab2(sch_1):page125_i24"
				( objectStatus "F1415" )
			)
			( gate "@baseboard_fab2_lib.baseboard_fab2(sch_1):page125_i11"
				( objectStatus "F1422" )
			)
			( gate "@baseboard_fab2_lib.baseboard_fab2(sch_1):page125_i50"
				( objectStatus "F1416" )
			)
			( gate "@baseboard_fab2_lib.baseboard_fab2(sch_1):page209_i3"
				( objectStatus "F1429" )
			)
			( gate "@baseboard_fab2_lib.baseboard_fab2(sch_1):page205_i37"
				( objectStatus "F1420" )
			)
			( gate "@baseboard_fab2_lib.baseboard_fab2(sch_1):page204_i63"
				( objectStatus "F1419" )
			)
			( gate "@baseboard_fab2_lib.baseboard_fab2(sch_1):page210_i34"
				( objectStatus "F1430" )
			)
			( gate "@baseboard_fab2_lib.baseboard_fab2(sch_1):page126_i10"
				( objectStatus "F1401" )
			)
			( gate "@baseboard_fab2_lib.baseboard_fab2(sch_1):page222_i37"
				( objectStatus "F1400" )
			)
			( gate "@baseboard_fab2_lib.baseboard_fab2(sch_1):page229_i34"
				( objectStatus "F1398" )
			)
			( gate "@baseboard_fab2_lib.baseboard_fab2(sch_1):page221_i37"
				( objectStatus "F1397" )
			)
			( gate "@baseboard_fab2_lib.baseboard_fab2(sch_1):page230_i37"
				( objectStatus "F1399" )
			)
			( gate "@baseboard_fab2_lib.baseboard_fab2(sch_1):page137_i11"
				( objectStatus "F1396" )
			)
			( gate "@baseboard_fab2_lib.baseboard_fab2(sch_1):page226_i58"
				( objectStatus "F1394" )
			)
			( gate "@baseboard_fab2_lib.baseboard_fab2(sch_1):page206_i56"
				( objectStatus "F1393" )
			)
			( gate "@baseboard_fab2_lib.baseboard_fab2(sch_1):page223_i58"
				( objectStatus "F1392" )
			)
			( gate "@baseboard_fab2_lib.baseboard_fab2(sch_1):page235_i166"
				( objectStatus "F1390" )
			)
			( gate "@baseboard_fab2_lib.baseboard_fab2(sch_1):page211_i32"
				( objectStatus "F1389" )
			)
			( gate "@baseboard_fab2_lib.baseboard_fab2(sch_1):page201_i55"
				( objectStatus "F1388" )
			)
			( gate "@baseboard_fab2_lib.baseboard_fab2(sch_1):page213_i32"
				( objectStatus "F1387" )
			)
			( gate "@baseboard_fab2_lib.baseboard_fab2(sch_1):page218_i54"
				( objectStatus "F1386" )
			)
			( gate "@baseboard_fab2_lib.baseboard_fab2(sch_1):page215_i337"
				( objectStatus "F1385" )
			)
			( gate "@baseboard_fab2_lib.baseboard_fab2(sch_1):page144_i557"
				( objectStatus "F1391" )
			)
			( gate "@baseboard_fab2_lib.baseboard_fab2(sch_1):page181_i183"
				( objectStatus "F1103" )
			)
			( gate "@baseboard_fab2_lib.baseboard_fab2(sch_1):page199_i41"
				( objectStatus "F1104" )
			)
			( gate "@baseboard_fab2_lib.baseboard_fab2(sch_1):page163_i15"
				( objectStatus "F1037" )
				( pin "B"
					( objectStatus "R9M17.2" )
				)
			)
			( gate "@baseboard_fab2_lib.baseboard_fab2(sch_1):page163_i16"
				( objectStatus "F1038" )
			)
			( gate "@baseboard_fab2_lib.baseboard_fab2(sch_1):page138_i87"
				( objectStatus "F1039" )
			)
			( gate "@baseboard_fab2_lib.baseboard_fab2(sch_1):page138_i88"
				( objectStatus "F1040" )
			)
			( gate "@baseboard_fab2_lib.baseboard_fab2(sch_1):page133_i120"
				( objectStatus "F1041" )
			)
			( gate "@baseboard_fab2_lib.baseboard_fab2(sch_1):page178_i2"
				( objectStatus "F1045" )
			)
			( gate "@baseboard_fab2_lib.baseboard_fab2(sch_1):page178_i20"
				( objectStatus "F1048" )
			)
			( gate "@baseboard_fab2_lib.baseboard_fab2(sch_1):page178_i18"
				( objectStatus "F1049" )
			)
			( gate "@baseboard_fab2_lib.baseboard_fab2(sch_1):page178_i12"
				( objectStatus "F1044" )
			)
			( gate "@baseboard_fab2_lib.baseboard_fab2(sch_1):page178_i17"
				( objectStatus "F1047" )
			)
			( gate "@baseboard_fab2_lib.baseboard_fab2(sch_1):page178_i13"
				( objectStatus "F1046" )
			)
			( gate "@baseboard_fab2_lib.baseboard_fab2(sch_1):page173_i263"
				( objectStatus "F1043" )
			)
			( gate "@baseboard_fab2_lib.baseboard_fab2(sch_1):page173_i261"
				( objectStatus "F1042" )
			)
			( gate "@baseboard_fab2_lib.baseboard_fab2(sch_1):page174_i25"
				( objectStatus "F1050" )
			)
			( gate "@baseboard_fab2_lib.baseboard_fab2(sch_1):page155_i80"
				( objectStatus "F1026" )
			)
			( gate "@baseboard_fab2_lib.baseboard_fab2(sch_1):page188_i88"
				( objectStatus "F1023" )
			)
			( gate "@baseboard_fab2_lib.baseboard_fab2(sch_1):page188_i89"
				( objectStatus "F1022" )
			)
			( gate "@baseboard_fab2_lib.baseboard_fab2(sch_1):page188_i91"
				( objectStatus "F1021" )
			)
			( gate "@baseboard_fab2_lib.baseboard_fab2(sch_1):page188_i90"
				( objectStatus "F1020" )
			)
			( gate "@baseboard_fab2_lib.baseboard_fab2(sch_1):page188_i93"
				( objectStatus "F1019" )
			)
			( gate "@baseboard_fab2_lib.baseboard_fab2(sch_1):page188_i94"
				( objectStatus "F1018" )
			)
			( gate "@baseboard_fab2_lib.baseboard_fab2(sch_1):page188_i95"
				( objectStatus "F1017" )
			)
			( gate "@baseboard_fab2_lib.baseboard_fab2(sch_1):page188_i92"
				( objectStatus "F1016" )
			)
			( gate "@baseboard_fab2_lib.baseboard_fab2(sch_1):page94_i100"
				( objectStatus "F1028" )
			)
			( gate "@baseboard_fab2_lib.baseboard_fab2(sch_1):page157_i296"
				( objectStatus "F1027" )
			)
			( gate "@baseboard_fab2_lib.baseboard_fab2(sch_1):page157_i298"
				( objectStatus "F1029" )
			)
			( gate "@baseboard_fab2_lib.baseboard_fab2(sch_1):page134_i12"
				( objectStatus "F1024" )
			)
			( gate "@baseboard_fab2_lib.baseboard_fab2(sch_1):page134_i11"
				( objectStatus "F1025" )
			)
			( gate "@baseboard_fab2_lib.baseboard_fab2(sch_1):page159_i212"
				( objectStatus "F996" )
				( pin "B"
					( objectStatus "R8G6.2" )
				)
			)
			( gate "@baseboard_fab2_lib.baseboard_fab2(sch_1):page159_i210"
				( objectStatus "F997" )
				( pin "B"
					( objectStatus "R8G3.2" )
				)
			)
			( gate "@baseboard_fab2_lib.baseboard_fab2(sch_1):page159_i216"
				( objectStatus "F1005" )
				( pin "B"
					( objectStatus "R2U13.2" )
				)
			)
			( gate "@baseboard_fab2_lib.baseboard_fab2(sch_1):page159_i214"
				( objectStatus "F1006" )
			)
			( gate "@baseboard_fab2_lib.baseboard_fab2(sch_1):page235_i148"
				( objectStatus "F998" )
			)
			( gate "@baseboard_fab2_lib.baseboard_fab2(sch_1):page213_i14"
				( objectStatus "F1001" )
			)
			( gate "@baseboard_fab2_lib.baseboard_fab2(sch_1):page211_i60"
				( objectStatus "F1004" )
			)
			( gate "@baseboard_fab2_lib.baseboard_fab2(sch_1):page218_i14"
				( objectStatus "F1000" )
			)
			( gate "@baseboard_fab2_lib.baseboard_fab2(sch_1):page223_i13"
				( objectStatus "F1007" )
			)
			( gate "@baseboard_fab2_lib.baseboard_fab2(sch_1):page226_i13"
				( objectStatus "F1010" )
			)
			( gate "@baseboard_fab2_lib.baseboard_fab2(sch_1):page201_i116"
				( objectStatus "F1003" )
			)
			( gate "@baseboard_fab2_lib.baseboard_fab2(sch_1):page215_i300"
				( objectStatus "F999" )
			)
			( gate "@baseboard_fab2_lib.baseboard_fab2(sch_1):page201_i22"
				( objectStatus "F1002" )
			)
			( gate "@baseboard_fab2_lib.baseboard_fab2(sch_1):page206_i33"
				( objectStatus "F1009" )
			)
			( gate "@baseboard_fab2_lib.baseboard_fab2(sch_1):page206_i34"
				( objectStatus "F1008" )
			)
			( gate "@baseboard_fab2_lib.baseboard_fab2(sch_1):page140_i12"
				( objectStatus "F909" )
			)
			( gate "@baseboard_fab2_lib.baseboard_fab2(sch_1):page231_i167"
				( objectStatus "F903" )
			)
			( gate "@baseboard_fab2_lib.baseboard_fab2(sch_1):page232_i303"
				( objectStatus "F905" )
			)
			( gate "@baseboard_fab2_lib.baseboard_fab2(sch_1):page233_i270"
				( objectStatus "F906" )
			)
			( gate "@baseboard_fab2_lib.baseboard_fab2(sch_1):page234_i215"
				( objectStatus "F907" )
			)
			( gate "@baseboard_fab2_lib.baseboard_fab2(sch_1):page155_i136"
				( objectStatus "F902" )
			)
			( gate "@baseboard_fab2_lib.baseboard_fab2(sch_1):page137_i19"
				( objectStatus "F908" )
			)
			( gate "@baseboard_fab2_lib.baseboard_fab2(sch_1):page137_i13"
				( objectStatus "F904" )
			)
			( gate "@baseboard_fab2_lib.baseboard_fab2(sch_1):page147_i116"
				( objectStatus "F860" )
				( pin "A"
					( objectStatus "R8F33.1" )
				)
			)
			( gate "@baseboard_fab2_lib.baseboard_fab2(sch_1):page147_i154"
				( objectStatus "F862" )
			)
			( gate "@baseboard_fab2_lib.baseboard_fab2(sch_1):page101_i125"
				( objectStatus "F878" )
			)
			( gate "@baseboard_fab2_lib.baseboard_fab2(sch_1):page101_i124"
				( objectStatus "F880" )
			)
			( gate "@baseboard_fab2_lib.baseboard_fab2(sch_1):page213_i13"
				( objectStatus "F874" )
			)
			( gate "@baseboard_fab2_lib.baseboard_fab2(sch_1):page238_i41"
				( objectStatus "F856" )
			)
			( gate "@baseboard_fab2_lib.baseboard_fab2(sch_1):page239_i72"
				( objectStatus "F885" )
			)
			( gate "@baseboard_fab2_lib.baseboard_fab2(sch_1):page237_i90"
				( objectStatus "F867" )
			)
			( gate "@baseboard_fab2_lib.baseboard_fab2(sch_1):page240_i171"
				( objectStatus "F865" )
			)
			( gate "@baseboard_fab2_lib.baseboard_fab2(sch_1):page241_i89"
				( objectStatus "F870" )
			)
			( gate "@baseboard_fab2_lib.baseboard_fab2(sch_1):page206_i113"
				( objectStatus "F887" )
			)
			( gate "@baseboard_fab2_lib.baseboard_fab2(sch_1):page232_i257"
				( objectStatus "F871" )
			)
			( gate "@baseboard_fab2_lib.baseboard_fab2(sch_1):page233_i247"
				( objectStatus "F872" )
			)
			( gate "@baseboard_fab2_lib.baseboard_fab2(sch_1):page231_i208"
				( objectStatus "F869" )
			)
			( gate "@baseboard_fab2_lib.baseboard_fab2(sch_1):page234_i201"
				( objectStatus "F875" )
			)
			( gate "@baseboard_fab2_lib.baseboard_fab2(sch_1):page201_i124"
				( objectStatus "F873" )
			)
			( gate "@baseboard_fab2_lib.baseboard_fab2(sch_1):page215_i296"
				( objectStatus "F868" )
			)
			( gate "@baseboard_fab2_lib.baseboard_fab2(sch_1):page218_i11"
				( objectStatus "F877" )
			)
			( gate "@baseboard_fab2_lib.baseboard_fab2(sch_1):page223_i14"
				( objectStatus "F886" )
			)
			( gate "@baseboard_fab2_lib.baseboard_fab2(sch_1):page226_i14"
				( objectStatus "F888" )
			)
			( gate "@baseboard_fab2_lib.baseboard_fab2(sch_1):page211_i58"
				( objectStatus "F876" )
			)
			( gate "@baseboard_fab2_lib.baseboard_fab2(sch_1):page235_i147"
				( objectStatus "F882" )
			)
			( gate "@baseboard_fab2_lib.baseboard_fab2(sch_1):page145_i203"
				( objectStatus "F881" )
			)
			( gate "@baseboard_fab2_lib.baseboard_fab2(sch_1):page146_i35"
				( objectStatus "F884" )
				( pin "A"
					( objectStatus "R1T26.1" )
				)
				( pin "B"
					( objectStatus "R1T26.2" )
				)
			)
			( gate "@baseboard_fab2_lib.baseboard_fab2(sch_1):page147_i115"
				( objectStatus "F879" )
			)
			( gate "@baseboard_fab2_lib.baseboard_fab2(sch_1):page147_i125"
				( objectStatus "F863" )
			)
			( gate "@baseboard_fab2_lib.baseboard_fab2(sch_1):page147_i126"
				( objectStatus "F861" )
			)
			( gate "@baseboard_fab2_lib.baseboard_fab2(sch_1):page139_i229"
				( objectStatus "F859" )
			)
			( gate "@baseboard_fab2_lib.baseboard_fab2(sch_1):page139_i228"
				( objectStatus "F858" )
			)
			( gate "@baseboard_fab2_lib.baseboard_fab2(sch_1):page147_i121"
				( objectStatus "F883" )
			)
			( gate "@baseboard_fab2_lib.baseboard_fab2(sch_1):page139_i225"
				( objectStatus "F857" )
			)
			( gate "@baseboard_fab2_lib.baseboard_fab2(sch_1):page196_i90"
				( objectStatus "F866" )
			)
			( gate "@baseboard_fab2_lib.baseboard_fab2(sch_1):page101_i129"
				( objectStatus "F864" )
			)
			( gate "@baseboard_fab2_lib.baseboard_fab2(sch_1):page139_i193"
				( objectStatus "F771" )
			)
			( gate "@baseboard_fab2_lib.baseboard_fab2(sch_1):page140_i11"
				( objectStatus "F773" )
			)
			( gate "@baseboard_fab2_lib.baseboard_fab2(sch_1):page140_i10"
				( objectStatus "F772" )
			)
			( gate "@baseboard_fab2_lib.baseboard_fab2(sch_1):page139_i173"
				( objectStatus "F770" )
			)
			( gate "@baseboard_fab2_lib.baseboard_fab2(sch_1):page169_i142"
				( objectStatus "F762" )
			)
			( gate "@baseboard_fab2_lib.baseboard_fab2(sch_1):page169_i116"
				( objectStatus "F761" )
			)
			( gate "@baseboard_fab2_lib.baseboard_fab2(sch_1):page150_i43"
				( objectStatus "F525" )
			)
			( gate "@baseboard_fab2_lib.baseboard_fab2(sch_1):page150_i48"
				( objectStatus "F522" )
			)
			( gate "@baseboard_fab2_lib.baseboard_fab2(sch_1):page166_i14"
				( objectStatus "F513" )
			)
			( gate "@baseboard_fab2_lib.baseboard_fab2(sch_1):page192_i55"
				( objectStatus "F497" )
			)
			( gate "@baseboard_fab2_lib.baseboard_fab2(sch_1):page150_i112"
				( objectStatus "F523" )
			)
			( gate "@baseboard_fab2_lib.baseboard_fab2(sch_1):page175_i24"
				( objectStatus "F526" )
			)
			( gate "@baseboard_fab2_lib.baseboard_fab2(sch_1):page198_i78"
				( objectStatus "F511" )
			)
			( gate "@baseboard_fab2_lib.baseboard_fab2(sch_1):page125_i72"
				( objectStatus "F517" )
			)
			( gate "@baseboard_fab2_lib.baseboard_fab2(sch_1):page102_i47"
				( objectStatus "F515" )
			)
			( gate "@baseboard_fab2_lib.baseboard_fab2(sch_1):page183_i14"
				( objectStatus "F500" )
			)
			( gate "@baseboard_fab2_lib.baseboard_fab2(sch_1):page183_i13"
				( objectStatus "F501" )
			)
			( gate "@baseboard_fab2_lib.baseboard_fab2(sch_1):page150_i44"
				( objectStatus "F505" )
			)
			( gate "@baseboard_fab2_lib.baseboard_fab2(sch_1):page150_i46"
				( objectStatus "F508" )
			)
			( gate "@baseboard_fab2_lib.baseboard_fab2(sch_1):page150_i49"
				( objectStatus "F520" )
			)
			( gate "@baseboard_fab2_lib.baseboard_fab2(sch_1):page150_i50"
				( objectStatus "F518" )
			)
			( gate "@baseboard_fab2_lib.baseboard_fab2(sch_1):page150_i53"
				( objectStatus "F519" )
			)
			( gate "@baseboard_fab2_lib.baseboard_fab2(sch_1):page150_i55"
				( objectStatus "F504" )
			)
			( gate "@baseboard_fab2_lib.baseboard_fab2(sch_1):page150_i57"
				( objectStatus "F521" )
			)
			( gate "@baseboard_fab2_lib.baseboard_fab2(sch_1):page150_i59"
				( objectStatus "F503" )
			)
			( gate "@baseboard_fab2_lib.baseboard_fab2(sch_1):page150_i60"
				( objectStatus "F509" )
			)
			( gate "@baseboard_fab2_lib.baseboard_fab2(sch_1):page150_i61"
				( objectStatus "F524" )
			)
			( gate "@baseboard_fab2_lib.baseboard_fab2(sch_1):page150_i62"
				( objectStatus "F507" )
			)
			( gate "@baseboard_fab2_lib.baseboard_fab2(sch_1):page150_i63"
				( objectStatus "F506" )
			)
			( gate "@baseboard_fab2_lib.baseboard_fab2(sch_1):page150_i64"
				( objectStatus "F502" )
			)
			( gate "@baseboard_fab2_lib.baseboard_fab2(sch_1):page199_i37"
				( objectStatus "F527" )
			)
			( gate "@baseboard_fab2_lib.baseboard_fab2(sch_1):page199_i38"
				( objectStatus "F528" )
			)
			( gate "@baseboard_fab2_lib.baseboard_fab2(sch_1):page102_i46"
				( objectStatus "F514" )
			)
			( gate "@baseboard_fab2_lib.baseboard_fab2(sch_1):page165_i58"
				( objectStatus "F498" )
			)
			( gate "@baseboard_fab2_lib.baseboard_fab2(sch_1):page165_i57"
				( objectStatus "F499" )
			)
			( gate "@baseboard_fab2_lib.baseboard_fab2(sch_1):page153_i150"
				( objectStatus "F516" )
			)
			( gate "@baseboard_fab2_lib.baseboard_fab2(sch_1):page162_i8"
				( objectStatus "F510" )
			)
			( gate "@baseboard_fab2_lib.baseboard_fab2(sch_1):page153_i90"
				( objectStatus "F512" )
			)
			( gate "@baseboard_fab2_lib.baseboard_fab2(sch_1):page101_i28"
				( objectStatus "F467" )
			)
			( gate "@baseboard_fab2_lib.baseboard_fab2(sch_1):page111_i55"
				( objectStatus "F466" )
			)
			( gate "@baseboard_fab2_lib.baseboard_fab2(sch_1):page237_i3"
				( objectStatus "F390" )
			)
			( gate "@baseboard_fab2_lib.baseboard_fab2(sch_1):page169_i141"
				( objectStatus "F394" )
			)
			( gate "@baseboard_fab2_lib.baseboard_fab2(sch_1):page169_i148"
				( objectStatus "F395" )
			)
			( gate "@baseboard_fab2_lib.baseboard_fab2(sch_1):page169_i115"
				( objectStatus "F391" )
			)
			( gate "@baseboard_fab2_lib.baseboard_fab2(sch_1):page169_i82"
				( objectStatus "F393" )
			)
			( gate "@baseboard_fab2_lib.baseboard_fab2(sch_1):page169_i88"
				( objectStatus "F392" )
			)
			( gate "@baseboard_fab2_lib.baseboard_fab2(sch_1):page221_i55"
				( objectStatus "F377" )
			)
			( gate "@baseboard_fab2_lib.baseboard_fab2(sch_1):page222_i52"
				( objectStatus "F381" )
			)
			( gate "@baseboard_fab2_lib.baseboard_fab2(sch_1):page229_i52"
				( objectStatus "F378" )
			)
			( gate "@baseboard_fab2_lib.baseboard_fab2(sch_1):page230_i52"
				( objectStatus "F380" )
			)
			( gate "@baseboard_fab2_lib.baseboard_fab2(sch_1):page214_i109"
				( objectStatus "F374" )
			)
			( gate "@baseboard_fab2_lib.baseboard_fab2(sch_1):page205_i45"
				( objectStatus "F379" )
			)
			( gate "@baseboard_fab2_lib.baseboard_fab2(sch_1):page210_i45"
				( objectStatus "F372" )
			)
			( gate "@baseboard_fab2_lib.baseboard_fab2(sch_1):page212_i78"
				( objectStatus "F376" )
			)
			( gate "@baseboard_fab2_lib.baseboard_fab2(sch_1):page157_i302"
				( objectStatus "F382" )
			)
			( gate "@baseboard_fab2_lib.baseboard_fab2(sch_1):page112_i61"
				( objectStatus "F375" )
				( pin "A"
					( objectStatus "R7P29.1" )
				)
			)
			( gate "@baseboard_fab2_lib.baseboard_fab2(sch_1):page112_i95"
				( objectStatus "F373" )
				( pin "A"
					( objectStatus "R8B1.1" )
				)
			)
			( gate "@baseboard_fab2_lib.baseboard_fab2(sch_1):page181_i185"
				( objectStatus "F370" )
			)
			( gate "@baseboard_fab2_lib.baseboard_fab2(sch_1):page199_i43"
				( objectStatus "F371" )
			)
			( gate "@baseboard_fab2_lib.baseboard_fab2(sch_1):page177_i43"
				( objectStatus "F363" )
			)
			( gate "@baseboard_fab2_lib.baseboard_fab2(sch_1):page96_i28"
				( objectStatus "F359" )
			)
			( gate "@baseboard_fab2_lib.baseboard_fab2(sch_1):page96_i30"
				( objectStatus "F362" )
			)
			( gate "@baseboard_fab2_lib.baseboard_fab2(sch_1):page96_i7"
				( objectStatus "F360" )
			)
			( gate "@baseboard_fab2_lib.baseboard_fab2(sch_1):page96_i5"
				( objectStatus "F361" )
			)
			( gate "@baseboard_fab2_lib.baseboard_fab2(sch_1):page160_i46"
				( objectStatus "F356" )
			)
			( gate "@baseboard_fab2_lib.baseboard_fab2(sch_1):page160_i49"
				( objectStatus "F357" )
				( pin "B"
					( objectStatus "R1T2.2" )
				)
			)
			( gate "@baseboard_fab2_lib.baseboard_fab2(sch_1):page138_i83"
				( objectStatus "F353" )
			)
			( gate "@baseboard_fab2_lib.baseboard_fab2(sch_1):page167_i83"
				( objectStatus "F348" )
			)
			( gate "@baseboard_fab2_lib.baseboard_fab2(sch_1):page138_i84"
				( objectStatus "F352" )
			)
			( gate "@baseboard_fab2_lib.baseboard_fab2(sch_1):page167_i80"
				( objectStatus "F349" )
			)
			( gate "@baseboard_fab2_lib.baseboard_fab2(sch_1):page138_i97"
				( objectStatus "F350" )
			)
			( gate "@baseboard_fab2_lib.baseboard_fab2(sch_1):page138_i98"
				( objectStatus "F351" )
			)
			( gate "@baseboard_fab2_lib.baseboard_fab2(sch_1):page138_i89"
				( objectStatus "F354" )
				( pin "B"
					( objectStatus "R2N8.2" )
				)
			)
			( gate "@baseboard_fab2_lib.baseboard_fab2(sch_1):page138_i90"
				( objectStatus "F355" )
			)
			( gate "@baseboard_fab2_lib.baseboard_fab2(sch_1):page99_i13"
				( objectStatus "F345" )
				( pin "B"
					( objectStatus "R4T7.2" )
				)
			)
			( gate "@baseboard_fab2_lib.baseboard_fab2(sch_1):page99_i106"
				( objectStatus "F343" )
				( pin "B"
					( objectStatus "R6U17.2" )
				)
			)
			( gate "@baseboard_fab2_lib.baseboard_fab2(sch_1):page99_i109"
				( objectStatus "F341" )
				( pin "B"
					( objectStatus "R7M1.2" )
				)
			)
			( gate "@baseboard_fab2_lib.baseboard_fab2(sch_1):page99_i103"
				( objectStatus "F347" )
				( pin "B"
					( objectStatus "R3R5.2" )
				)
			)
			( gate "@baseboard_fab2_lib.baseboard_fab2(sch_1):page99_i11"
				( objectStatus "F344" )
				( pin "B"
					( objectStatus "R4T8.2" )
				)
			)
			( gate "@baseboard_fab2_lib.baseboard_fab2(sch_1):page99_i104"
				( objectStatus "F342" )
				( pin "B"
					( objectStatus "R6U18.2" )
				)
			)
			( gate "@baseboard_fab2_lib.baseboard_fab2(sch_1):page99_i107"
				( objectStatus "F340" )
				( pin "B"
					( objectStatus "R7M6.2" )
				)
			)
			( gate "@baseboard_fab2_lib.baseboard_fab2(sch_1):page99_i101"
				( objectStatus "F346" )
				( pin "B"
					( objectStatus "R3R12.2" )
				)
			)
			( gate "@baseboard_fab2_lib.baseboard_fab2(sch_1):page235_i154"
				( objectStatus "F277" )
			)
			( gate "@baseboard_fab2_lib.baseboard_fab2(sch_1):page199_i2"
				( objectStatus "F276" )
			)
			( gate "@baseboard_fab2_lib.baseboard_fab2(sch_1):page203_i67"
				( objectStatus "F274" )
			)
			( gate "@baseboard_fab2_lib.baseboard_fab2(sch_1):page208_i7"
				( objectStatus "F275" )
			)
			( gate "@baseboard_fab2_lib.baseboard_fab2(sch_1):page114_i54"
				( objectStatus "F271" )
			)
			( gate "@baseboard_fab2_lib.baseboard_fab2(sch_1):page231_i177"
				( objectStatus "F263" )
			)
			( gate "@baseboard_fab2_lib.baseboard_fab2(sch_1):page232_i227"
				( objectStatus "F264" )
			)
			( gate "@baseboard_fab2_lib.baseboard_fab2(sch_1):page233_i211"
				( objectStatus "F266" )
			)
			( gate "@baseboard_fab2_lib.baseboard_fab2(sch_1):page234_i183"
				( objectStatus "F267" )
			)
			( gate "@baseboard_fab2_lib.baseboard_fab2(sch_1):page217_i58"
				( objectStatus "F268" )
			)
			( gate "@baseboard_fab2_lib.baseboard_fab2(sch_1):page225_i58"
				( objectStatus "F269" )
			)
			( gate "@baseboard_fab2_lib.baseboard_fab2(sch_1):page228_i58"
				( objectStatus "F270" )
			)
			( gate "@baseboard_fab2_lib.baseboard_fab2(sch_1):page220_i58"
				( objectStatus "F265" )
			)
			( gate "@baseboard_fab2_lib.baseboard_fab2(sch_1):page166_i15"
				( objectStatus "F1811" )
				( pin "A"
					( objectStatus "R7C19.1" )
				)
			)
			( gate "@baseboard_fab2_lib.baseboard_fab2(sch_1):page145_i132"
				( objectStatus "F1752" )
			)
			( gate "@baseboard_fab2_lib.baseboard_fab2(sch_1):page156_i299"
				( objectStatus "F1688" )
			)
			( gate "@baseboard_fab2_lib.baseboard_fab2(sch_1):page156_i300"
				( objectStatus "F1687" )
			)
			( gate "@baseboard_fab2_lib.baseboard_fab2(sch_1):page156_i322"
				( objectStatus "F1686" )
			)
			( gate "@baseboard_fab2_lib.baseboard_fab2(sch_1):page156_i324"
				( objectStatus "F1685" )
			)
			( gate "@baseboard_fab2_lib.baseboard_fab2(sch_1):page156_i321"
				( objectStatus "F1684" )
			)
			( gate "@baseboard_fab2_lib.baseboard_fab2(sch_1):page156_i323"
				( objectStatus "F1683" )
			)
			( gate "@baseboard_fab2_lib.baseboard_fab2(sch_1):page113_i239"
				( objectStatus "F1682" )
			)
			( gate "@baseboard_fab2_lib.baseboard_fab2(sch_1):page113_i240"
				( objectStatus "F1681" )
			)
			( gate "@baseboard_fab2_lib.baseboard_fab2(sch_1):page145_i256"
				( objectStatus "F1690" )
			)
			( gate "@baseboard_fab2_lib.baseboard_fab2(sch_1):page108_i341"
				( objectStatus "F1689" )
			)
			( gate "@baseboard_fab2_lib.baseboard_fab2(sch_1):page93_i111"
				( objectStatus "F1706" )
			)
			( gate "@baseboard_fab2_lib.baseboard_fab2(sch_1):page93_i112"
				( objectStatus "F1705" )
			)
			( gate "@baseboard_fab2_lib.baseboard_fab2(sch_1):page93_i113"
				( objectStatus "F1704" )
			)
			( gate "@baseboard_fab2_lib.baseboard_fab2(sch_1):page93_i114"
				( objectStatus "F1703" )
			)
			( gate "@baseboard_fab2_lib.baseboard_fab2(sch_1):page93_i119"
				( objectStatus "F1702" )
			)
			( gate "@baseboard_fab2_lib.baseboard_fab2(sch_1):page93_i121"
				( objectStatus "F1701" )
			)
			( gate "@baseboard_fab2_lib.baseboard_fab2(sch_1):page93_i122"
				( objectStatus "F1700" )
			)
			( gate "@baseboard_fab2_lib.baseboard_fab2(sch_1):page93_i123"
				( objectStatus "F1699" )
			)
			( gate "@baseboard_fab2_lib.baseboard_fab2(sch_1):page152_i74"
				( objectStatus "F1698" )
			)
			( gate "@baseboard_fab2_lib.baseboard_fab2(sch_1):page152_i73"
				( objectStatus "F1697" )
			)
			( gate "@baseboard_fab2_lib.baseboard_fab2(sch_1):page152_i72"
				( objectStatus "F1696" )
			)
			( gate "@baseboard_fab2_lib.baseboard_fab2(sch_1):page152_i71"
				( objectStatus "F1695" )
			)
			( gate "@baseboard_fab2_lib.baseboard_fab2(sch_1):page152_i79"
				( objectStatus "F1694" )
			)
			( gate "@baseboard_fab2_lib.baseboard_fab2(sch_1):page152_i92"
				( objectStatus "F1693" )
			)
			( gate "@baseboard_fab2_lib.baseboard_fab2(sch_1):page152_i93"
				( objectStatus "F1692" )
			)
			( gate "@baseboard_fab2_lib.baseboard_fab2(sch_1):page152_i94"
				( objectStatus "F1691" )
			)
			( gate "@baseboard_fab2_lib.baseboard_fab2(sch_1):page93_i103"
				( objectStatus "F1712" )
			)
			( gate "@baseboard_fab2_lib.baseboard_fab2(sch_1):page93_i102"
				( objectStatus "F1711" )
			)
			( gate "@baseboard_fab2_lib.baseboard_fab2(sch_1):page152_i45"
				( objectStatus "F1710" )
			)
			( gate "@baseboard_fab2_lib.baseboard_fab2(sch_1):page152_i49"
				( objectStatus "F1709" )
			)
			( gate "@baseboard_fab2_lib.baseboard_fab2(sch_1):page152_i64"
				( objectStatus "F1708" )
			)
			( gate "@baseboard_fab2_lib.baseboard_fab2(sch_1):page152_i65"
				( objectStatus "F1707" )
			)
			( gate "@baseboard_fab2_lib.baseboard_fab2(sch_1):page104_i69"
				( objectStatus "F1896" )
			)
			( gate "@baseboard_fab2_lib.baseboard_fab2(sch_1):page104_i70"
				( objectStatus "F1895" )
			)
			( gate "@baseboard_fab2_lib.baseboard_fab2(sch_1):page104_i67"
				( objectStatus "F1841" )
			)
			( gate "@baseboard_fab2_lib.baseboard_fab2(sch_1):page104_i68"
				( objectStatus "F1840" )
			)
			( gate "@baseboard_fab2_lib.baseboard_fab2(sch_1):page104_i93"
				( objectStatus "F1714" )
			)
			( gate "@baseboard_fab2_lib.baseboard_fab2(sch_1):page104_i96"
				( objectStatus "F1713" )
			)
			( gate "@baseboard_fab2_lib.baseboard_fab2(sch_1):page230_i34"
				( objectStatus "F1839" )
			)
			( gate "@baseboard_fab2_lib.baseboard_fab2(sch_1):page181_i268"
				( objectStatus "F1945" )
				( pin "A"
					( objectStatus "R1F8.1" )
				)
			)
			( gate "@baseboard_fab2_lib.baseboard_fab2(sch_1):page159_i223"
				( objectStatus "F1923" )
				( pin "A"
					( objectStatus "R1U8.1" )
				)
			)
			( gate "@baseboard_fab2_lib.baseboard_fab2(sch_1):page159_i222"
				( objectStatus "F1922" )
				( pin "A"
					( objectStatus "R1U11.1" )
				)
			)
			( gate "@baseboard_fab2_lib.baseboard_fab2(sch_1):page223_i22"
				( objectStatus "F1941" )
				( pin "A"
					( objectStatus "R1G21.1" )
				)
				( pin "B"
					( objectStatus "R1G21.2" )
				)
			)
			( gate "@baseboard_fab2_lib.baseboard_fab2(sch_1):page223_i21"
				( objectStatus "F1942" )
				( pin "A"
					( objectStatus "R1G19.1" )
				)
				( pin "B"
					( objectStatus "R1G19.2" )
				)
			)
			( gate "@baseboard_fab2_lib.baseboard_fab2(sch_1):page141_i112"
				( objectStatus "F1921" )
			)
			( gate "@baseboard_fab2_lib.baseboard_fab2(sch_1):page141_i114"
				( objectStatus "F1924" )
			)
			( gate "@baseboard_fab2_lib.baseboard_fab2(sch_1):page154_i92"
				( objectStatus "F1911" )
				( pin "A"
					( objectStatus "R2T2.1" )
				)
				( pin "B"
					( objectStatus "R2T2.2" )
				)
			)
			( gate "@baseboard_fab2_lib.baseboard_fab2(sch_1):page189_i17"
				( objectStatus "F1770" )
			)
			( gate "@baseboard_fab2_lib.baseboard_fab2(sch_1):page189_i20"
				( objectStatus "F1767" )
			)
			( gate "@baseboard_fab2_lib.baseboard_fab2(sch_1):page189_i25"
				( objectStatus "F1766" )
			)
			( gate "@baseboard_fab2_lib.baseboard_fab2(sch_1):page189_i37"
				( objectStatus "F1797" )
			)
			( gate "@baseboard_fab2_lib.baseboard_fab2(sch_1):page189_i7"
				( objectStatus "F1769" )
				( pin "B"
					( objectStatus "R8G10.2" )
				)
			)
			( gate "@baseboard_fab2_lib.baseboard_fab2(sch_1):page118_i131"
				( objectStatus "F1810" )
			)
			( gate "@baseboard_fab2_lib.baseboard_fab2(sch_1):page121_i31"
				( objectStatus "F1812" )
				( pin "A"
					( objectStatus "R7C15.1" )
				)
			)
			( gate "@baseboard_fab2_lib.baseboard_fab2(sch_1):page154_i119"
				( objectStatus "F1775" )
				( pin "B"
					( objectStatus "R8F6.2" )
				)
			)
			( gate "@baseboard_fab2_lib.baseboard_fab2(sch_1):page154_i93"
				( objectStatus "F1912" )
			)
			( gate "@baseboard_fab2_lib.baseboard_fab2(sch_1):page186_i339"
				( objectStatus "F1930" )
			)
			( gate "@baseboard_fab2_lib.baseboard_fab2(sch_1):page186_i338"
				( objectStatus "F1928" )
			)
			( gate "@baseboard_fab2_lib.baseboard_fab2(sch_1):page186_i337"
				( objectStatus "F1929" )
			)
			( gate "@baseboard_fab2_lib.baseboard_fab2(sch_1):page186_i340"
				( objectStatus "F1927" )
			)
			( gate "@baseboard_fab2_lib.baseboard_fab2(sch_1):page206_i122"
				( objectStatus "F1728" )
			)
			( gate "@baseboard_fab2_lib.baseboard_fab2(sch_1):page206_i128"
				( objectStatus "F1732" )
			)
			( gate "@baseboard_fab2_lib.baseboard_fab2(sch_1):page206_i123"
				( objectStatus "F1726" )
			)
			( gate "@baseboard_fab2_lib.baseboard_fab2(sch_1):page206_i124"
				( objectStatus "F1729" )
			)
			( gate "@baseboard_fab2_lib.baseboard_fab2(sch_1):page206_i125"
				( objectStatus "F1730" )
			)
			( gate "@baseboard_fab2_lib.baseboard_fab2(sch_1):page206_i126"
				( objectStatus "F1731" )
			)
			( gate "@baseboard_fab2_lib.baseboard_fab2(sch_1):page211_i91"
				( objectStatus "F1888" )
			)
			( gate "@baseboard_fab2_lib.baseboard_fab2(sch_1):page213_i94"
				( objectStatus "F1865" )
			)
			( gate "@baseboard_fab2_lib.baseboard_fab2(sch_1):page215_i341"
				( objectStatus "F1876" )
			)
			( gate "@baseboard_fab2_lib.baseboard_fab2(sch_1):page215_i332"
				( objectStatus "F1874" )
			)
			( gate "@baseboard_fab2_lib.baseboard_fab2(sch_1):page218_i57"
				( objectStatus "F1894" )
			)
			( gate "@baseboard_fab2_lib.baseboard_fab2(sch_1):page218_i50"
				( objectStatus "F1893" )
			)
			( gate "@baseboard_fab2_lib.baseboard_fab2(sch_1):page223_i87"
				( objectStatus "F1718" )
			)
			( gate "@baseboard_fab2_lib.baseboard_fab2(sch_1):page223_i88"
				( objectStatus "F1717" )
			)
			( gate "@baseboard_fab2_lib.baseboard_fab2(sch_1):page226_i87"
				( objectStatus "F1733" )
			)
			( gate "@baseboard_fab2_lib.baseboard_fab2(sch_1):page226_i88"
				( objectStatus "F1734" )
			)
			( gate "@baseboard_fab2_lib.baseboard_fab2(sch_1):page235_i224"
				( objectStatus "F1920" )
			)
			( gate "@baseboard_fab2_lib.baseboard_fab2(sch_1):page235_i225"
				( objectStatus "F1919" )
			)
			( gate "@baseboard_fab2_lib.baseboard_fab2(sch_1):page201_i154"
				( objectStatus "F1830" )
			)
			( gate "@baseboard_fab2_lib.baseboard_fab2(sch_1):page201_i150"
				( objectStatus "F1824" )
			)
			( gate "@baseboard_fab2_lib.baseboard_fab2(sch_1):page201_i139"
				( objectStatus "F1825" )
			)
			( gate "@baseboard_fab2_lib.baseboard_fab2(sch_1):page201_i147"
				( objectStatus "F1827" )
			)
			( gate "@baseboard_fab2_lib.baseboard_fab2(sch_1):page201_i148"
				( objectStatus "F1828" )
			)
			( gate "@baseboard_fab2_lib.baseboard_fab2(sch_1):page201_i149"
				( objectStatus "F1829" )
			)
			( gate "@baseboard_fab2_lib.baseboard_fab2(sch_1):page121_i67"
				( objectStatus "F1886" )
			)
			( gate "@baseboard_fab2_lib.baseboard_fab2(sch_1):page121_i66"
				( objectStatus "F1914" )
			)
			( gate "@baseboard_fab2_lib.baseboard_fab2(sch_1):page121_i65"
				( objectStatus "F1885" )
			)
			( gate "@baseboard_fab2_lib.baseboard_fab2(sch_1):page183_i52"
				( objectStatus "F1750" )
			)
			( gate "@baseboard_fab2_lib.baseboard_fab2(sch_1):page183_i53"
				( objectStatus "F1751" )
			)
			( gate "@baseboard_fab2_lib.baseboard_fab2(sch_1):page183_i49"
				( objectStatus "F1749" )
			)
			( gate "@baseboard_fab2_lib.baseboard_fab2(sch_1):page183_i48"
				( objectStatus "F1748" )
			)
			( gate "@baseboard_fab2_lib.baseboard_fab2(sch_1):page177_i6"
				( objectStatus "F1932" )
			)
			( gate "@baseboard_fab2_lib.baseboard_fab2(sch_1):page177_i3"
				( objectStatus "F1931" )
			)
			( gate "@baseboard_fab2_lib.baseboard_fab2(sch_1):page181_i255"
				( objectStatus "F1720" )
			)
			( gate "@baseboard_fab2_lib.baseboard_fab2(sch_1):page181_i254"
				( objectStatus "F1723" )
			)
			( gate "@baseboard_fab2_lib.baseboard_fab2(sch_1):page181_i256"
				( objectStatus "F1722" )
			)
			( gate "@baseboard_fab2_lib.baseboard_fab2(sch_1):page181_i261"
				( objectStatus "F1721" )
				( pin "B"
					( objectStatus "R9T1.2" )
				)
			)
			( gate "@baseboard_fab2_lib.baseboard_fab2(sch_1):page191_i184"
				( objectStatus "F1913" )
			)
			( gate "@baseboard_fab2_lib.baseboard_fab2(sch_1):page189_i63"
				( objectStatus "F1796" )
			)
			( gate "@baseboard_fab2_lib.baseboard_fab2(sch_1):page189_i65"
				( objectStatus "F1763" )
			)
			( gate "@baseboard_fab2_lib.baseboard_fab2(sch_1):page189_i64"
				( objectStatus "F1764" )
			)
			( gate "@baseboard_fab2_lib.baseboard_fab2(sch_1):page189_i66"
				( objectStatus "F1762" )
			)
			( gate "@baseboard_fab2_lib.baseboard_fab2(sch_1):page157_i379"
				( objectStatus "F1757" )
			)
			( gate "@baseboard_fab2_lib.baseboard_fab2(sch_1):page201_i131"
				( objectStatus "F1831" )
			)
			( gate "@baseboard_fab2_lib.baseboard_fab2(sch_1):page206_i119"
				( objectStatus "F1727" )
			)
			( gate "@baseboard_fab2_lib.baseboard_fab2(sch_1):page211_i87"
				( objectStatus "F1880" )
			)
			( gate "@baseboard_fab2_lib.baseboard_fab2(sch_1):page213_i90"
				( objectStatus "F1826" )
			)
			( gate "@baseboard_fab2_lib.baseboard_fab2(sch_1):page215_i343"
				( objectStatus "F1801" )
			)
			( gate "@baseboard_fab2_lib.baseboard_fab2(sch_1):page218_i59"
				( objectStatus "F1890" )
			)
			( gate "@baseboard_fab2_lib.baseboard_fab2(sch_1):page223_i84"
				( objectStatus "F1716" )
			)
			( gate "@baseboard_fab2_lib.baseboard_fab2(sch_1):page226_i84"
				( objectStatus "F1735" )
			)
			( gate "@baseboard_fab2_lib.baseboard_fab2(sch_1):page231_i220"
				( objectStatus "F1803" )
			)
			( gate "@baseboard_fab2_lib.baseboard_fab2(sch_1):page232_i307"
				( objectStatus "F1814" )
			)
			( gate "@baseboard_fab2_lib.baseboard_fab2(sch_1):page233_i275"
				( objectStatus "F1854" )
			)
			( gate "@baseboard_fab2_lib.baseboard_fab2(sch_1):page234_i220"
				( objectStatus "F1871" )
			)
			( gate "@baseboard_fab2_lib.baseboard_fab2(sch_1):page235_i221"
				( objectStatus "F1917" )
			)
			( gate "@baseboard_fab2_lib.baseboard_fab2(sch_1):page240_i176"
				( objectStatus "F1776" )
			)
			( gate "@baseboard_fab2_lib.baseboard_fab2(sch_1):page241_i91"
				( objectStatus "F1780" )
			)
			( gate "@baseboard_fab2_lib.baseboard_fab2(sch_1):page118_i120"
				( objectStatus "F1789" )
			)
			( gate "@baseboard_fab2_lib.baseboard_fab2(sch_1):page221_i32"
				( objectStatus "F1820" )
			)
			( gate "@baseboard_fab2_lib.baseboard_fab2(sch_1):page222_i34"
				( objectStatus "F1837" )
			)
			( gate "@baseboard_fab2_lib.baseboard_fab2(sch_1):page229_i39"
				( objectStatus "F1819" )
			)
			( gate "@baseboard_fab2_lib.baseboard_fab2(sch_1):page189_i18"
				( objectStatus "F1771" )
			)
			( gate "@baseboard_fab2_lib.baseboard_fab2(sch_1):page189_i23"
				( objectStatus "F1768" )
			)
			( gate "@baseboard_fab2_lib.baseboard_fab2(sch_1):page189_i26"
				( objectStatus "F1765" )
			)
			( gate "@baseboard_fab2_lib.baseboard_fab2(sch_1):page189_i38"
				( objectStatus "F1798" )
			)
			( gate "@baseboard_fab2_lib.baseboard_fab2(sch_1):page236_i92"
				( objectStatus "F1815" )
			)
			( gate "@baseboard_fab2_lib.baseboard_fab2(sch_1):page95_i108"
				( objectStatus "F1807" )
			)
			( gate "@baseboard_fab2_lib.baseboard_fab2(sch_1):page170_i51"
				( objectStatus "F1925" )
			)
			( gate "@baseboard_fab2_lib.baseboard_fab2(sch_1):page232_i299"
				( objectStatus "F1813" )
			)
			( gate "@baseboard_fab2_lib.baseboard_fab2(sch_1):page233_i271"
				( objectStatus "F1853" )
			)
			( gate "@baseboard_fab2_lib.baseboard_fab2(sch_1):page234_i214"
				( objectStatus "F1870" )
			)
			( gate "@baseboard_fab2_lib.baseboard_fab2(sch_1):page232_i240"
				( objectStatus "F1891" )
			)
			( gate "@baseboard_fab2_lib.baseboard_fab2(sch_1):page233_i199"
				( objectStatus "F1823" )
			)
			( gate "@baseboard_fab2_lib.baseboard_fab2(sch_1):page234_i155"
				( objectStatus "F1835" )
			)
			( gate "@baseboard_fab2_lib.baseboard_fab2(sch_1):page158_i91"
				( objectStatus "F1753" )
			)
			( gate "@baseboard_fab2_lib.baseboard_fab2(sch_1):page183_i24"
				( objectStatus "F1747" )
			)
			( gate "@baseboard_fab2_lib.baseboard_fab2(sch_1):page183_i25"
				( objectStatus "F1746" )
			)
			( gate "@baseboard_fab2_lib.baseboard_fab2(sch_1):page231_i168"
				( objectStatus "F1802" )
			)
			( gate "@baseboard_fab2_lib.baseboard_fab2(sch_1):page240_i144"
				( objectStatus "F1784" )
			)
			( gate "@baseboard_fab2_lib.baseboard_fab2(sch_1):page138_i171"
				( objectStatus "F1916" )
				( pin "A"
					( objectStatus "R2N20.1" )
				)
			)
			( gate "@baseboard_fab2_lib.baseboard_fab2(sch_1):page138_i175"
				( objectStatus "F1915" )
				( pin "A"
					( objectStatus "R2N21.1" )
				)
			)
			( gate "@baseboard_fab2_lib.baseboard_fab2(sch_1):page231_i154"
				( objectStatus "F1804" )
			)
			( gate "@baseboard_fab2_lib.baseboard_fab2(sch_1):page231_i170"
				( objectStatus "F1877" )
			)
			( gate "@baseboard_fab2_lib.baseboard_fab2(sch_1):page232_i150"
				( objectStatus "F1889" )
			)
			( gate "@baseboard_fab2_lib.baseboard_fab2(sch_1):page233_i157"
				( objectStatus "F1822" )
			)
			( gate "@baseboard_fab2_lib.baseboard_fab2(sch_1):page240_i127"
				( objectStatus "F1779" )
			)
			( gate "@baseboard_fab2_lib.baseboard_fab2(sch_1):page240_i140"
				( objectStatus "F1777" )
			)
			( gate "@baseboard_fab2_lib.baseboard_fab2(sch_1):page240_i146"
				( objectStatus "F1774" )
			)
			( gate "@baseboard_fab2_lib.baseboard_fab2(sch_1):page184_i92"
				( objectStatus "F1787" )
				( pin "A"
					( objectStatus "R8D35.1" )
				)
				( pin "B"
					( objectStatus "R8D35.2" )
				)
			)
			( gate "@baseboard_fab2_lib.baseboard_fab2(sch_1):page184_i99"
				( objectStatus "F1786" )
			)
			( gate "@baseboard_fab2_lib.baseboard_fab2(sch_1):page141_i75"
				( objectStatus "F1744" )
			)
			( gate "@baseboard_fab2_lib.baseboard_fab2(sch_1):page141_i76"
				( objectStatus "F1743" )
			)
			( gate "@baseboard_fab2_lib.baseboard_fab2(sch_1):page141_i77"
				( objectStatus "F1741" )
			)
			( gate "@baseboard_fab2_lib.baseboard_fab2(sch_1):page141_i78"
				( objectStatus "F1742" )
			)
			( gate "@baseboard_fab2_lib.baseboard_fab2(sch_1):page141_i79"
				( objectStatus "F1740" )
			)
			( gate "@baseboard_fab2_lib.baseboard_fab2(sch_1):page141_i80"
				( objectStatus "F1739" )
			)
			( gate "@baseboard_fab2_lib.baseboard_fab2(sch_1):page141_i81"
				( objectStatus "F1737" )
			)
			( gate "@baseboard_fab2_lib.baseboard_fab2(sch_1):page141_i82"
				( objectStatus "F1738" )
			)
			( gate "@baseboard_fab2_lib.baseboard_fab2(sch_1):page111_i74"
				( objectStatus "F1759" )
			)
			( gate "@baseboard_fab2_lib.baseboard_fab2(sch_1):page108_i173"
				( objectStatus "F1902" )
			)
			( gate "@baseboard_fab2_lib.baseboard_fab2(sch_1):page142_i32"
				( objectStatus "F1782" )
			)
			( gate "@baseboard_fab2_lib.baseboard_fab2(sch_1):page142_i30"
				( objectStatus "F1783" )
			)
			( gate "@baseboard_fab2_lib.baseboard_fab2(sch_1):page142_i33"
				( objectStatus "F1785" )
			)
			( gate "@baseboard_fab2_lib.baseboard_fab2(sch_1):page142_i31"
				( objectStatus "F1781" )
			)
			( gate "@baseboard_fab2_lib.baseboard_fab2(sch_1):page176_i31"
				( objectStatus "F1933" )
			)
			( gate "@baseboard_fab2_lib.baseboard_fab2(sch_1):page176_i16"
				( objectStatus "F1934" )
			)
			( gate "@baseboard_fab2_lib.baseboard_fab2(sch_1):page176_i58"
				( objectStatus "F1937" )
			)
			( gate "@baseboard_fab2_lib.baseboard_fab2(sch_1):page176_i59"
				( objectStatus "F1938" )
			)
			( gate "@baseboard_fab2_lib.baseboard_fab2(sch_1):page176_i60"
				( objectStatus "F1935" )
			)
			( gate "@baseboard_fab2_lib.baseboard_fab2(sch_1):page176_i61"
				( objectStatus "F1936" )
			)
			( gate "@baseboard_fab2_lib.baseboard_fab2(sch_1):page222_i38"
				( objectStatus "F1873" )
			)
			( gate "@baseboard_fab2_lib.baseboard_fab2(sch_1):page221_i38"
				( objectStatus "F1851" )
			)
			( gate "@baseboard_fab2_lib.baseboard_fab2(sch_1):page229_i35"
				( objectStatus "F1852" )
			)
			( gate "@baseboard_fab2_lib.baseboard_fab2(sch_1):page230_i38"
				( objectStatus "F1872" )
			)
			( gate "@baseboard_fab2_lib.baseboard_fab2(sch_1):page139_i201"
				( objectStatus "F1756" )
			)
			( gate "@baseboard_fab2_lib.baseboard_fab2(sch_1):page190_i116"
				( objectStatus "F1879" )
			)
			( gate "@baseboard_fab2_lib.baseboard_fab2(sch_1):page190_i117"
				( objectStatus "F1878" )
			)
			( gate "@baseboard_fab2_lib.baseboard_fab2(sch_1):page200_i71"
				( objectStatus "F1724" )
			)
			( gate "@baseboard_fab2_lib.baseboard_fab2(sch_1):page235_i159"
				( objectStatus "F1918" )
			)
			( gate "@baseboard_fab2_lib.baseboard_fab2(sch_1):page175_i63"
				( objectStatus "F1939" )
			)
			( gate "@baseboard_fab2_lib.baseboard_fab2(sch_1):page185_i115"
				( objectStatus "F1788" )
			)
			( gate "@baseboard_fab2_lib.baseboard_fab2(sch_1):page211_i24"
				( objectStatus "F1881" )
			)
			( gate "@baseboard_fab2_lib.baseboard_fab2(sch_1):page211_i61"
				( objectStatus "F1887" )
				( pin "A"
					( objectStatus "R3P1.1" )
				)
				( pin "B"
					( objectStatus "R3P1.2" )
				)
			)
			( gate "@baseboard_fab2_lib.baseboard_fab2(sch_1):page213_i16"
				( objectStatus "F1860" )
				( pin "A"
					( objectStatus "R4D56.1" )
				)
			)
			( gate "@baseboard_fab2_lib.baseboard_fab2(sch_1):page211_i16"
				( objectStatus "F1882" )
				( pin "A"
					( objectStatus "R3P11.1" )
				)
				( pin "B"
					( objectStatus "R3P11.2" )
				)
			)
			( gate "@baseboard_fab2_lib.baseboard_fab2(sch_1):page213_i37"
				( objectStatus "F1861" )
				( pin "B"
					( objectStatus "R4D54.2" )
				)
			)
			( gate "@baseboard_fab2_lib.baseboard_fab2(sch_1):page213_i25"
				( objectStatus "F1864" )
			)
			( gate "@baseboard_fab2_lib.baseboard_fab2(sch_1):page185_i105"
				( objectStatus "F1773" )
				( pin "A"
					( objectStatus "R8F18.1" )
				)
			)
			( gate "@baseboard_fab2_lib.baseboard_fab2(sch_1):page185_i106"
				( objectStatus "F1772" )
				( pin "A"
					( objectStatus "R8F21.1" )
				)
			)
			( gate "@baseboard_fab2_lib.baseboard_fab2(sch_1):page168_i6"
				( objectStatus "F1940" )
			)
			( gate "@baseboard_fab2_lib.baseboard_fab2(sch_1):page155_i53"
				( objectStatus "F1758" )
			)
			( gate "@baseboard_fab2_lib.baseboard_fab2(sch_1):page89_i2"
				( objectStatus "F1848" )
			)
			( gate "@baseboard_fab2_lib.baseboard_fab2(sch_1):page236_i59"
				( objectStatus "F1791" )
			)
			( gate "@baseboard_fab2_lib.baseboard_fab2(sch_1):page236_i56"
				( objectStatus "F1790" )
			)
			( gate "@baseboard_fab2_lib.baseboard_fab2(sch_1):page241_i78"
				( objectStatus "F1778" )
			)
			( gate "@baseboard_fab2_lib.baseboard_fab2(sch_1):page223_i30"
				( objectStatus "F1715" )
			)
			( gate "@baseboard_fab2_lib.baseboard_fab2(sch_1):page197_i110"
				( objectStatus "F1855" )
			)
			( gate "@baseboard_fab2_lib.baseboard_fab2(sch_1):page197_i113"
				( objectStatus "F1869" )
			)
			( gate "@baseboard_fab2_lib.baseboard_fab2(sch_1):page197_i126"
				( objectStatus "F1719" )
			)
			( gate "@baseboard_fab2_lib.baseboard_fab2(sch_1):page197_i137"
				( objectStatus "F1961" )
			)
			( gate "@baseboard_fab2_lib.baseboard_fab2(sch_1):page221_i28"
				( objectStatus "F1821" )
			)
			( gate "@baseboard_fab2_lib.baseboard_fab2(sch_1):page221_i18"
				( objectStatus "F1844" )
			)
			( gate "@baseboard_fab2_lib.baseboard_fab2(sch_1):page141_i56"
				( objectStatus "F1745" )
			)
			( gate "@baseboard_fab2_lib.baseboard_fab2(sch_1):page222_i30"
				( objectStatus "F1836" )
			)
			( gate "@baseboard_fab2_lib.baseboard_fab2(sch_1):page222_i15"
				( objectStatus "F1845" )
			)
			( gate "@baseboard_fab2_lib.baseboard_fab2(sch_1):page229_i18"
				( objectStatus "F1760" )
			)
			( gate "@baseboard_fab2_lib.baseboard_fab2(sch_1):page230_i13"
				( objectStatus "F1761" )
			)
			( gate "@baseboard_fab2_lib.baseboard_fab2(sch_1):page229_i32"
				( objectStatus "F1818" )
			)
			( gate "@baseboard_fab2_lib.baseboard_fab2(sch_1):page230_i30"
				( objectStatus "F1838" )
			)
			( gate "@baseboard_fab2_lib.baseboard_fab2(sch_1):page218_i34"
				( objectStatus "F1892" )
			)
			( gate "@baseboard_fab2_lib.baseboard_fab2(sch_1):page218_i15"
				( objectStatus "F1817" )
				( pin "A"
					( objectStatus "R7A11.1" )
				)
				( pin "B"
					( objectStatus "R7A11.2" )
				)
			)
			( gate "@baseboard_fab2_lib.baseboard_fab2(sch_1):page218_i25"
				( objectStatus "F1816" )
				( pin "A"
					( objectStatus "R7A12.1" )
				)
				( pin "B"
					( objectStatus "R7A12.2" )
				)
			)
			( gate "@baseboard_fab2_lib.baseboard_fab2(sch_1):page223_i16"
				( objectStatus "F1944" )
				( pin "A"
					( objectStatus "R1G9.1" )
				)
				( pin "B"
					( objectStatus "R1G9.2" )
				)
			)
			( gate "@baseboard_fab2_lib.baseboard_fab2(sch_1):page223_i23"
				( objectStatus "F1943" )
				( pin "A"
					( objectStatus "R1G10.1" )
				)
				( pin "B"
					( objectStatus "R1G10.2" )
				)
			)
			( gate "@baseboard_fab2_lib.baseboard_fab2(sch_1):page226_i30"
				( objectStatus "F1736" )
			)
			( gate "@baseboard_fab2_lib.baseboard_fab2(sch_1):page226_i16"
				( objectStatus "F1962" )
				( pin "A"
					( objectStatus "R1B11.1" )
				)
			)
			( gate "@baseboard_fab2_lib.baseboard_fab2(sch_1):page226_i23"
				( objectStatus "F1963" )
				( pin "A"
					( objectStatus "R1B10.1" )
				)
				( pin "B"
					( objectStatus "R1B10.2" )
				)
			)
			( gate "@baseboard_fab2_lib.baseboard_fab2(sch_1):page234_i29"
				( objectStatus "F1834" )
			)
			( gate "@baseboard_fab2_lib.baseboard_fab2(sch_1):page209_i11"
				( objectStatus "F1947" )
			)
			( gate "@baseboard_fab2_lib.baseboard_fab2(sch_1):page209_i10"
				( objectStatus "F1946" )
			)
			( gate "@baseboard_fab2_lib.baseboard_fab2(sch_1):page214_i99"
				( objectStatus "F1898" )
			)
			( gate "@baseboard_fab2_lib.baseboard_fab2(sch_1):page214_i104"
				( objectStatus "F1897" )
			)
			( gate "@baseboard_fab2_lib.baseboard_fab2(sch_1):page241_i37"
				( objectStatus "F1805" )
			)
			( gate "@baseboard_fab2_lib.baseboard_fab2(sch_1):page241_i58"
				( objectStatus "F1806" )
			)
			( gate "@baseboard_fab2_lib.baseboard_fab2(sch_1):page93_i15"
				( objectStatus "F1907" )
			)
			( gate "@baseboard_fab2_lib.baseboard_fab2(sch_1):page93_i23"
				( objectStatus "F1910" )
			)
			( gate "@baseboard_fab2_lib.baseboard_fab2(sch_1):page93_i16"
				( objectStatus "F1909" )
			)
			( gate "@baseboard_fab2_lib.baseboard_fab2(sch_1):page93_i13"
				( objectStatus "F1908" )
			)
			( gate "@baseboard_fab2_lib.baseboard_fab2(sch_1):page139_i110"
				( objectStatus "F1755" )
			)
			( gate "@baseboard_fab2_lib.baseboard_fab2(sch_1):page139_i195"
				( objectStatus "F1926" )
			)
			( gate "@baseboard_fab2_lib.baseboard_fab2(sch_1):page92_i97"
				( objectStatus "F1903" )
			)
			( gate "@baseboard_fab2_lib.baseboard_fab2(sch_1):page92_i98"
				( objectStatus "F1904" )
			)
			( gate "@baseboard_fab2_lib.baseboard_fab2(sch_1):page212_i71"
				( objectStatus "F1884" )
			)
			( gate "@baseboard_fab2_lib.baseboard_fab2(sch_1):page212_i66"
				( objectStatus "F1883" )
			)
			( gate "@baseboard_fab2_lib.baseboard_fab2(sch_1):page215_i313"
				( objectStatus "F1875" )
			)
			( gate "@baseboard_fab2_lib.baseboard_fab2(sch_1):page215_i302"
				( objectStatus "F1799" )
				( pin "A"
					( objectStatus "R7G4.1" )
				)
				( pin "B"
					( objectStatus "R7G4.2" )
				)
			)
			( gate "@baseboard_fab2_lib.baseboard_fab2(sch_1):page204_i61"
				( objectStatus "F1857" )
			)
			( gate "@baseboard_fab2_lib.baseboard_fab2(sch_1):page204_i62"
				( objectStatus "F1856" )
			)
			( gate "@baseboard_fab2_lib.baseboard_fab2(sch_1):page217_i67"
				( objectStatus "F1847" )
			)
			( gate "@baseboard_fab2_lib.baseboard_fab2(sch_1):page217_i71"
				( objectStatus "F1846" )
			)
			( gate "@baseboard_fab2_lib.baseboard_fab2(sch_1):page225_i67"
				( objectStatus "F1792" )
			)
			( gate "@baseboard_fab2_lib.baseboard_fab2(sch_1):page225_i71"
				( objectStatus "F1793" )
			)
			( gate "@baseboard_fab2_lib.baseboard_fab2(sch_1):page228_i67"
				( objectStatus "F1795" )
			)
			( gate "@baseboard_fab2_lib.baseboard_fab2(sch_1):page228_i71"
				( objectStatus "F1794" )
			)
			( gate "@baseboard_fab2_lib.baseboard_fab2(sch_1):page220_i67"
				( objectStatus "F1850" )
			)
			( gate "@baseboard_fab2_lib.baseboard_fab2(sch_1):page220_i71"
				( objectStatus "F1849" )
			)
			( gate "@baseboard_fab2_lib.baseboard_fab2(sch_1):page21_i154"
				( objectStatus "F1843" )
				( pin "A"
					( objectStatus "R6B4.1" )
				)
				( pin "B"
					( objectStatus "R6B4.2" )
				)
			)
			( gate "@baseboard_fab2_lib.baseboard_fab2(sch_1):page21_i153"
				( objectStatus "F1842" )
				( pin "A"
					( objectStatus "R6B5.1" )
				)
				( pin "B"
					( objectStatus "R6B5.2" )
				)
			)
			( gate "@baseboard_fab2_lib.baseboard_fab2(sch_1):page21_i151"
				( objectStatus "F1833" )
				( pin "A"
					( objectStatus "R6N11.1" )
				)
				( pin "B"
					( objectStatus "R6N11.2" )
				)
			)
			( gate "@baseboard_fab2_lib.baseboard_fab2(sch_1):page21_i150"
				( objectStatus "F1832" )
				( pin "A"
					( objectStatus "R6N12.1" )
				)
			)
			( gate "@baseboard_fab2_lib.baseboard_fab2(sch_1):page55_i25"
				( objectStatus "F1959" )
				( pin "A"
					( objectStatus "R1C3.1" )
				)
				( pin "B"
					( objectStatus "R1C3.2" )
				)
			)
			( gate "@baseboard_fab2_lib.baseboard_fab2(sch_1):page199_i27"
				( objectStatus "F1951" )
				( pin "B"
					( objectStatus "R1D24.2" )
				)
			)
			( gate "@baseboard_fab2_lib.baseboard_fab2(sch_1):page199_i28"
				( objectStatus "F1950" )
				( pin "B"
					( objectStatus "R1D25.2" )
				)
			)
			( gate "@baseboard_fab2_lib.baseboard_fab2(sch_1):page199_i36"
				( objectStatus "F1725" )
			)
			( gate "@baseboard_fab2_lib.baseboard_fab2(sch_1):page201_i40"
				( objectStatus "F1866" )
			)
			( gate "@baseboard_fab2_lib.baseboard_fab2(sch_1):page201_i98"
				( objectStatus "F1859" )
				( pin "A"
					( objectStatus "R4D66.1" )
				)
			)
			( gate "@baseboard_fab2_lib.baseboard_fab2(sch_1):page201_i26"
				( objectStatus "F1858" )
				( pin "A"
					( objectStatus "R4D67.1" )
				)
			)
			( gate "@baseboard_fab2_lib.baseboard_fab2(sch_1):page201_i28"
				( objectStatus "F1863" )
				( pin "A"
					( objectStatus "R4D50.1" )
				)
			)
			( gate "@baseboard_fab2_lib.baseboard_fab2(sch_1):page201_i31"
				( objectStatus "F1862" )
				( pin "A"
					( objectStatus "R4D53.1" )
				)
			)
			( gate "@baseboard_fab2_lib.baseboard_fab2(sch_1):page206_i46"
				( objectStatus "F1956" )
			)
			( gate "@baseboard_fab2_lib.baseboard_fab2(sch_1):page206_i38"
				( objectStatus "F1953" )
				( pin "A"
					( objectStatus "R1D2.1" )
				)
				( pin "B"
					( objectStatus "R1D2.2" )
				)
			)
			( gate "@baseboard_fab2_lib.baseboard_fab2(sch_1):page206_i27"
				( objectStatus "F1955" )
				( pin "A"
					( objectStatus "R1C23.1" )
				)
			)
			( gate "@baseboard_fab2_lib.baseboard_fab2(sch_1):page206_i37"
				( objectStatus "F1952" )
				( pin "A"
					( objectStatus "R1D3.1" )
				)
				( pin "B"
					( objectStatus "R1D3.2" )
				)
			)
			( gate "@baseboard_fab2_lib.baseboard_fab2(sch_1):page206_i28"
				( objectStatus "F1954" )
				( pin "A"
					( objectStatus "R1C25.1" )
				)
			)
			( gate "@baseboard_fab2_lib.baseboard_fab2(sch_1):page210_i31"
				( objectStatus "F1957" )
			)
			( gate "@baseboard_fab2_lib.baseboard_fab2(sch_1):page210_i32"
				( objectStatus "F1958" )
			)
			( gate "@baseboard_fab2_lib.baseboard_fab2(sch_1):page205_i26"
				( objectStatus "F1867" )
			)
			( gate "@baseboard_fab2_lib.baseboard_fab2(sch_1):page205_i30"
				( objectStatus "F1868" )
			)
			( gate "@baseboard_fab2_lib.baseboard_fab2(sch_1):page55_i24"
				( objectStatus "F1960" )
				( pin "A"
					( objectStatus "R1C2.1" )
				)
				( pin "B"
					( objectStatus "R1C2.2" )
				)
			)
			( gate "@baseboard_fab2_lib.baseboard_fab2(sch_1):page55_i29"
				( objectStatus "F1901" )
				( pin "A"
					( objectStatus "R3B3.1" )
				)
				( pin "B"
					( objectStatus "R3B3.2" )
				)
			)
			( gate "@baseboard_fab2_lib.baseboard_fab2(sch_1):page55_i28"
				( objectStatus "F1900" )
				( pin "A"
					( objectStatus "R3B5.1" )
				)
				( pin "B"
					( objectStatus "R3B5.2" )
				)
			)
			( gate "@baseboard_fab2_lib.baseboard_fab2(sch_1):page97_i33"
				( objectStatus "F1899" )
			)
			( gate "@baseboard_fab2_lib.baseboard_fab2(sch_1):page200_i44"
				( objectStatus "F1949" )
			)
			( gate "@baseboard_fab2_lib.baseboard_fab2(sch_1):page200_i43"
				( objectStatus "F1948" )
			)
			( gate "@baseboard_fab2_lib.baseboard_fab2(sch_1):page92_i68"
				( objectStatus "F1809" )
			)
			( gate "@baseboard_fab2_lib.baseboard_fab2(sch_1):page92_i67"
				( objectStatus "F1808" )
			)
			( gate "@baseboard_fab2_lib.baseboard_fab2(sch_1):page92_i93"
				( objectStatus "F1906" )
			)
			( gate "@baseboard_fab2_lib.baseboard_fab2(sch_1):page92_i92"
				( objectStatus "F1905" )
			)
			( gate "@baseboard_fab2_lib.baseboard_fab2(sch_1):page215_i307"
				( objectStatus "F1800" )
				( pin "A"
					( objectStatus "R7G2.1" )
				)
				( pin "B"
					( objectStatus "R7G2.2" )
				)
			)
			( gate "@baseboard_fab2_lib.baseboard_fab2(sch_1):page144_i405"
				( objectStatus "F1754" )
			)
			( gate "@baseboard_fab2_lib.baseboard_fab2(sch_1):page119_i215"
				( objectStatus "F1595" )
			)
			( gate "@baseboard_fab2_lib.baseboard_fab2(sch_1):page166_i11"
				( objectStatus "F1648" )
			)
			( gate "@baseboard_fab2_lib.baseboard_fab2(sch_1):page93_i131"
				( objectStatus "F1603" )
			)
			( gate "@baseboard_fab2_lib.baseboard_fab2(sch_1):page93_i133"
				( objectStatus "F1602" )
			)
			( gate "@baseboard_fab2_lib.baseboard_fab2(sch_1):page93_i135"
				( objectStatus "F1601" )
			)
			( gate "@baseboard_fab2_lib.baseboard_fab2(sch_1):page93_i137"
				( objectStatus "F1600" )
			)
			( gate "@baseboard_fab2_lib.baseboard_fab2(sch_1):page152_i95"
				( objectStatus "F1599" )
			)
			( gate "@baseboard_fab2_lib.baseboard_fab2(sch_1):page152_i98"
				( objectStatus "F1598" )
			)
			( gate "@baseboard_fab2_lib.baseboard_fab2(sch_1):page152_i100"
				( objectStatus "F1597" )
			)
			( gate "@baseboard_fab2_lib.baseboard_fab2(sch_1):page152_i102"
				( objectStatus "F1596" )
			)
			( gate "@baseboard_fab2_lib.baseboard_fab2(sch_1):page107_i466"
				( objectStatus "F1671" )
				( pin "A"
					( objectStatus "R2U14.1" )
				)
			)
			( gate "@baseboard_fab2_lib.baseboard_fab2(sch_1):page107_i465"
				( objectStatus "F1670" )
				( pin "A"
					( objectStatus "R2U15.1" )
				)
			)
			( gate "@baseboard_fab2_lib.baseboard_fab2(sch_1):page107_i467"
				( objectStatus "F1669" )
				( pin "A"
					( objectStatus "R2U16.1" )
				)
			)
			( gate "@baseboard_fab2_lib.baseboard_fab2(sch_1):page107_i464"
				( objectStatus "F1668" )
				( pin "A"
					( objectStatus "R2U17.1" )
				)
			)
			( gate "@baseboard_fab2_lib.baseboard_fab2(sch_1):page107_i468"
				( objectStatus "F1667" )
				( pin "A"
					( objectStatus "R2U18.1" )
				)
			)
			( gate "@baseboard_fab2_lib.baseboard_fab2(sch_1):page107_i463"
				( objectStatus "F1666" )
				( pin "A"
					( objectStatus "R2U19.1" )
				)
			)
			( gate "@baseboard_fab2_lib.baseboard_fab2(sch_1):page107_i469"
				( objectStatus "F1665" )
				( pin "A"
					( objectStatus "R2U20.1" )
				)
			)
			( gate "@baseboard_fab2_lib.baseboard_fab2(sch_1):page107_i462"
				( objectStatus "F1664" )
				( pin "A"
					( objectStatus "R2U21.1" )
				)
			)
			( gate "@baseboard_fab2_lib.baseboard_fab2(sch_1):page107_i470"
				( objectStatus "F1663" )
				( pin "A"
					( objectStatus "R2U22.1" )
				)
			)
			( gate "@baseboard_fab2_lib.baseboard_fab2(sch_1):page107_i461"
				( objectStatus "F1662" )
				( pin "A"
					( objectStatus "R2U23.1" )
				)
			)
			( gate "@baseboard_fab2_lib.baseboard_fab2(sch_1):page107_i471"
				( objectStatus "F1661" )
				( pin "A"
					( objectStatus "R2U24.1" )
				)
			)
			( gate "@baseboard_fab2_lib.baseboard_fab2(sch_1):page107_i460"
				( objectStatus "F1660" )
				( pin "A"
					( objectStatus "R2U25.1" )
				)
			)
			( gate "@baseboard_fab2_lib.baseboard_fab2(sch_1):page107_i472"
				( objectStatus "F1659" )
				( pin "A"
					( objectStatus "R2U26.1" )
				)
			)
			( gate "@baseboard_fab2_lib.baseboard_fab2(sch_1):page107_i459"
				( objectStatus "F1658" )
				( pin "A"
					( objectStatus "R2U27.1" )
				)
			)
			( gate "@baseboard_fab2_lib.baseboard_fab2(sch_1):page107_i473"
				( objectStatus "F1657" )
				( pin "A"
					( objectStatus "R2U28.1" )
				)
			)
			( gate "@baseboard_fab2_lib.baseboard_fab2(sch_1):page107_i458"
				( objectStatus "F1656" )
				( pin "A"
					( objectStatus "R2U29.1" )
				)
			)
			( gate "@baseboard_fab2_lib.baseboard_fab2(sch_1):page145_i257"
				( objectStatus "F1604" )
			)
			( gate "@baseboard_fab2_lib.baseboard_fab2(sch_1):page93_i88"
				( objectStatus "F1620" )
			)
			( gate "@baseboard_fab2_lib.baseboard_fab2(sch_1):page93_i108"
				( objectStatus "F1619" )
			)
			( gate "@baseboard_fab2_lib.baseboard_fab2(sch_1):page93_i89"
				( objectStatus "F1618" )
			)
			( gate "@baseboard_fab2_lib.baseboard_fab2(sch_1):page93_i107"
				( objectStatus "F1617" )
			)
			( gate "@baseboard_fab2_lib.baseboard_fab2(sch_1):page93_i93"
				( objectStatus "F1616" )
			)
			( gate "@baseboard_fab2_lib.baseboard_fab2(sch_1):page93_i109"
				( objectStatus "F1615" )
			)
			( gate "@baseboard_fab2_lib.baseboard_fab2(sch_1):page93_i110"
				( objectStatus "F1614" )
			)
			( gate "@baseboard_fab2_lib.baseboard_fab2(sch_1):page93_i94"
				( objectStatus "F1613" )
			)
			( gate "@baseboard_fab2_lib.baseboard_fab2(sch_1):page152_i51"
				( objectStatus "F1612" )
			)
			( gate "@baseboard_fab2_lib.baseboard_fab2(sch_1):page152_i68"
				( objectStatus "F1611" )
			)
			( gate "@baseboard_fab2_lib.baseboard_fab2(sch_1):page152_i50"
				( objectStatus "F1610" )
			)
			( gate "@baseboard_fab2_lib.baseboard_fab2(sch_1):page152_i67"
				( objectStatus "F1609" )
			)
			( gate "@baseboard_fab2_lib.baseboard_fab2(sch_1):page152_i47"
				( objectStatus "F1608" )
			)
			( gate "@baseboard_fab2_lib.baseboard_fab2(sch_1):page152_i69"
				( objectStatus "F1607" )
			)
			( gate "@baseboard_fab2_lib.baseboard_fab2(sch_1):page152_i66"
				( objectStatus "F1606" )
			)
			( gate "@baseboard_fab2_lib.baseboard_fab2(sch_1):page152_i70"
				( objectStatus "F1605" )
			)
			( gate "@baseboard_fab2_lib.baseboard_fab2(sch_1):page104_i94"
				( objectStatus "F1628" )
			)
			( gate "@baseboard_fab2_lib.baseboard_fab2(sch_1):page104_i97"
				( objectStatus "F1627" )
			)
			( gate "@baseboard_fab2_lib.baseboard_fab2(sch_1):page104_i78"
				( objectStatus "F1626" )
			)
			( gate "@baseboard_fab2_lib.baseboard_fab2(sch_1):page104_i79"
				( objectStatus "F1625" )
			)
			( gate "@baseboard_fab2_lib.baseboard_fab2(sch_1):page104_i84"
				( objectStatus "F1624" )
			)
			( gate "@baseboard_fab2_lib.baseboard_fab2(sch_1):page104_i88"
				( objectStatus "F1623" )
			)
			( gate "@baseboard_fab2_lib.baseboard_fab2(sch_1):page104_i95"
				( objectStatus "F1622" )
			)
			( gate "@baseboard_fab2_lib.baseboard_fab2(sch_1):page104_i98"
				( objectStatus "F1621" )
			)
			( gate "@baseboard_fab2_lib.baseboard_fab2(sch_1):page182_i110"
				( objectStatus "F1677" )
			)
			( gate "@baseboard_fab2_lib.baseboard_fab2(sch_1):page182_i97"
				( objectStatus "F1678" )
			)
			( gate "@baseboard_fab2_lib.baseboard_fab2(sch_1):page182_i101"
				( objectStatus "F1679" )
			)
			( gate "@baseboard_fab2_lib.baseboard_fab2(sch_1):page182_i104"
				( objectStatus "F1680" )
			)
			( gate "@baseboard_fab2_lib.baseboard_fab2(sch_1):page182_i107"
				( objectStatus "F1676" )
				( pin "B"
					( objectStatus "R1F9.2" )
				)
			)
			( gate "@baseboard_fab2_lib.baseboard_fab2(sch_1):page118_i125"
				( objectStatus "F1643" )
			)
			( gate "@baseboard_fab2_lib.baseboard_fab2(sch_1):page150_i114"
				( objectStatus "F1635" )
			)
			( gate "@baseboard_fab2_lib.baseboard_fab2(sch_1):page146_i127"
				( objectStatus "F1673" )
			)
			( gate "@baseboard_fab2_lib.baseboard_fab2(sch_1):page114_i142"
				( objectStatus "F1649" )
			)
			( gate "@baseboard_fab2_lib.baseboard_fab2(sch_1):page114_i141"
				( objectStatus "F1650" )
			)
			( gate "@baseboard_fab2_lib.baseboard_fab2(sch_1):page156_i279"
				( objectStatus "F1642" )
			)
			( gate "@baseboard_fab2_lib.baseboard_fab2(sch_1):page189_i9"
				( objectStatus "F1640" )
				( pin "B"
					( objectStatus "R8G9.2" )
				)
			)
			( gate "@baseboard_fab2_lib.baseboard_fab2(sch_1):page200_i198"
				( objectStatus "F1630" )
			)
			( gate "@baseboard_fab2_lib.baseboard_fab2(sch_1):page104_i41"
				( objectStatus "F1652" )
			)
			( gate "@baseboard_fab2_lib.baseboard_fab2(sch_1):page104_i51"
				( objectStatus "F1655" )
			)
			( gate "@baseboard_fab2_lib.baseboard_fab2(sch_1):page104_i37"
				( objectStatus "F1651" )
			)
			( gate "@baseboard_fab2_lib.baseboard_fab2(sch_1):page104_i53"
				( objectStatus "F1654" )
			)
			( gate "@baseboard_fab2_lib.baseboard_fab2(sch_1):page181_i249"
				( objectStatus "F1629" )
			)
			( gate "@baseboard_fab2_lib.baseboard_fab2(sch_1):page189_i13"
				( objectStatus "F1645" )
			)
			( gate "@baseboard_fab2_lib.baseboard_fab2(sch_1):page189_i19"
				( objectStatus "F1639" )
			)
			( gate "@baseboard_fab2_lib.baseboard_fab2(sch_1):page189_i22"
				( objectStatus "F1636" )
			)
			( gate "@baseboard_fab2_lib.baseboard_fab2(sch_1):page189_i36"
				( objectStatus "F1647" )
			)
			( gate "@baseboard_fab2_lib.baseboard_fab2(sch_1):page89_i23"
				( objectStatus "F1672" )
			)
			( gate "@baseboard_fab2_lib.baseboard_fab2(sch_1):page189_i8"
				( objectStatus "F1644" )
			)
			( gate "@baseboard_fab2_lib.baseboard_fab2(sch_1):page189_i21"
				( objectStatus "F1638" )
			)
			( gate "@baseboard_fab2_lib.baseboard_fab2(sch_1):page189_i24"
				( objectStatus "F1637" )
			)
			( gate "@baseboard_fab2_lib.baseboard_fab2(sch_1):page189_i27"
				( objectStatus "F1646" )
			)
			( gate "@baseboard_fab2_lib.baseboard_fab2(sch_1):page142_i18"
				( objectStatus "F1641" )
			)
			( gate "@baseboard_fab2_lib.baseboard_fab2(sch_1):page144_i516"
				( objectStatus "F1632" )
			)
			( gate "@baseboard_fab2_lib.baseboard_fab2(sch_1):page144_i517"
				( objectStatus "F1631" )
			)
			( gate "@baseboard_fab2_lib.baseboard_fab2(sch_1):page145_i183"
				( objectStatus "F1675" )
			)
			( gate "@baseboard_fab2_lib.baseboard_fab2(sch_1):page145_i184"
				( objectStatus "F1674" )
			)
			( gate "@baseboard_fab2_lib.baseboard_fab2(sch_1):page158_i100"
				( objectStatus "F1634" )
			)
			( gate "@baseboard_fab2_lib.baseboard_fab2(sch_1):page158_i99"
				( objectStatus "F1633" )
			)
			( gate "@baseboard_fab2_lib.baseboard_fab2(sch_1):page89_i1"
				( objectStatus "F1653" )
			)
			( gate "@baseboard_fab2_lib.baseboard_fab2(sch_1):page236_i41"
				( objectStatus "F1593" )
			)
			( gate "@baseboard_fab2_lib.baseboard_fab2(sch_1):page236_i14"
				( objectStatus "F1594" )
			)
			( gate "@baseboard_fab2_lib.baseboard_fab2(sch_1):page212_i32"
				( objectStatus "F1590" )
			)
			( gate "@baseboard_fab2_lib.baseboard_fab2(sch_1):page214_i71"
				( objectStatus "F1581" )
			)
			( gate "@baseboard_fab2_lib.baseboard_fab2(sch_1):page203_i38"
				( objectStatus "F1584" )
			)
			( gate "@baseboard_fab2_lib.baseboard_fab2(sch_1):page203_i50"
				( objectStatus "F1585" )
			)
			( gate "@baseboard_fab2_lib.baseboard_fab2(sch_1):page209_i24"
				( objectStatus "F1577" )
			)
			( gate "@baseboard_fab2_lib.baseboard_fab2(sch_1):page202_i39"
				( objectStatus "F1583" )
			)
			( gate "@baseboard_fab2_lib.baseboard_fab2(sch_1):page202_i33"
				( objectStatus "F1582" )
			)
			( gate "@baseboard_fab2_lib.baseboard_fab2(sch_1):page204_i33"
				( objectStatus "F1586" )
			)
			( gate "@baseboard_fab2_lib.baseboard_fab2(sch_1):page216_i52"
				( objectStatus "F1589" )
			)
			( gate "@baseboard_fab2_lib.baseboard_fab2(sch_1):page216_i76"
				( objectStatus "F1588" )
			)
			( gate "@baseboard_fab2_lib.baseboard_fab2(sch_1):page219_i52"
				( objectStatus "F1592" )
			)
			( gate "@baseboard_fab2_lib.baseboard_fab2(sch_1):page219_i76"
				( objectStatus "F1591" )
			)
			( gate "@baseboard_fab2_lib.baseboard_fab2(sch_1):page227_i52"
				( objectStatus "F1579" )
			)
			( gate "@baseboard_fab2_lib.baseboard_fab2(sch_1):page227_i76"
				( objectStatus "F1580" )
			)
			( gate "@baseboard_fab2_lib.baseboard_fab2(sch_1):page205_i19"
				( objectStatus "F1587" )
			)
			( gate "@baseboard_fab2_lib.baseboard_fab2(sch_1):page224_i52"
				( objectStatus "F1571" )
			)
			( gate "@baseboard_fab2_lib.baseboard_fab2(sch_1):page224_i76"
				( objectStatus "F1572" )
			)
			( gate "@baseboard_fab2_lib.baseboard_fab2(sch_1):page207_i39"
				( objectStatus "F1574" )
			)
			( gate "@baseboard_fab2_lib.baseboard_fab2(sch_1):page207_i26"
				( objectStatus "F1573" )
			)
			( gate "@baseboard_fab2_lib.baseboard_fab2(sch_1):page208_i36"
				( objectStatus "F1575" )
			)
			( gate "@baseboard_fab2_lib.baseboard_fab2(sch_1):page208_i49"
				( objectStatus "F1576" )
			)
			( gate "@baseboard_fab2_lib.baseboard_fab2(sch_1):page210_i20"
				( objectStatus "F1578" )
			)
			( gate "@baseboard_fab2_lib.baseboard_fab2(sch_1):page156_i333"
				( objectStatus "F1432" )
			)
			( gate "@baseboard_fab2_lib.baseboard_fab2(sch_1):page156_i337"
				( objectStatus "F1431" )
			)
			( gate "@baseboard_fab2_lib.baseboard_fab2(sch_1):page156_i302"
				( objectStatus "F1438" )
			)
			( gate "@baseboard_fab2_lib.baseboard_fab2(sch_1):page156_i303"
				( objectStatus "F1437" )
			)
			( gate "@baseboard_fab2_lib.baseboard_fab2(sch_1):page156_i304"
				( objectStatus "F1436" )
			)
			( gate "@baseboard_fab2_lib.baseboard_fab2(sch_1):page156_i313"
				( objectStatus "F1435" )
			)
			( gate "@baseboard_fab2_lib.baseboard_fab2(sch_1):page156_i312"
				( objectStatus "F1434" )
			)
			( gate "@baseboard_fab2_lib.baseboard_fab2(sch_1):page192_i59"
				( objectStatus "F1433" )
			)
			( gate "@baseboard_fab2_lib.baseboard_fab2(sch_1):page113_i204"
				( objectStatus "F1443" )
			)
			( gate "@baseboard_fab2_lib.baseboard_fab2(sch_1):page113_i202"
				( objectStatus "F1442" )
			)
			( gate "@baseboard_fab2_lib.baseboard_fab2(sch_1):page113_i203"
				( objectStatus "F1441" )
			)
			( gate "@baseboard_fab2_lib.baseboard_fab2(sch_1):page113_i205"
				( objectStatus "F1440" )
			)
			( gate "@baseboard_fab2_lib.baseboard_fab2(sch_1):page113_i179"
				( objectStatus "F1439" )
			)
			( gate "@baseboard_fab2_lib.baseboard_fab2(sch_1):page113_i168"
				( objectStatus "F1464" )
			)
			( gate "@baseboard_fab2_lib.baseboard_fab2(sch_1):page157_i326"
				( objectStatus "F1533" )
			)
			( gate "@baseboard_fab2_lib.baseboard_fab2(sch_1):page157_i327"
				( objectStatus "F1532" )
			)
			( gate "@baseboard_fab2_lib.baseboard_fab2(sch_1):page111_i89"
				( objectStatus "F1460" )
				( pin "A"
					( objectStatus "R8E2.1" )
				)
			)
			( gate "@baseboard_fab2_lib.baseboard_fab2(sch_1):page157_i368"
				( objectStatus "F1498" )
			)
			( gate "@baseboard_fab2_lib.baseboard_fab2(sch_1):page183_i12"
				( objectStatus "F1451" )
			)
			( gate "@baseboard_fab2_lib.baseboard_fab2(sch_1):page183_i11"
				( objectStatus "F1452" )
			)
			( gate "@baseboard_fab2_lib.baseboard_fab2(sch_1):page133_i332"
				( objectStatus "F1481" )
			)
			( gate "@baseboard_fab2_lib.baseboard_fab2(sch_1):page133_i331"
				( objectStatus "F1480" )
			)
			( gate "@baseboard_fab2_lib.baseboard_fab2(sch_1):page189_i44"
				( objectStatus "F1514" )
			)
			( gate "@baseboard_fab2_lib.baseboard_fab2(sch_1):page201_i132"
				( objectStatus "F1491" )
			)
			( gate "@baseboard_fab2_lib.baseboard_fab2(sch_1):page206_i120"
				( objectStatus "F1444" )
			)
			( gate "@baseboard_fab2_lib.baseboard_fab2(sch_1):page102_i80"
				( objectStatus "F1489" )
			)
			( gate "@baseboard_fab2_lib.baseboard_fab2(sch_1):page102_i81"
				( objectStatus "F1490" )
			)
			( gate "@baseboard_fab2_lib.baseboard_fab2(sch_1):page135_i99"
				( objectStatus "F1479" )
			)
			( gate "@baseboard_fab2_lib.baseboard_fab2(sch_1):page92_i75"
				( objectStatus "F1515" )
			)
			( gate "@baseboard_fab2_lib.baseboard_fab2(sch_1):page133_i315"
				( objectStatus "F1523" )
			)
			( gate "@baseboard_fab2_lib.baseboard_fab2(sch_1):page133_i316"
				( objectStatus "F1525" )
			)
			( gate "@baseboard_fab2_lib.baseboard_fab2(sch_1):page133_i317"
				( objectStatus "F1524" )
			)
			( gate "@baseboard_fab2_lib.baseboard_fab2(sch_1):page133_i318"
				( objectStatus "F1527" )
			)
			( gate "@baseboard_fab2_lib.baseboard_fab2(sch_1):page133_i321"
				( objectStatus "F1526" )
			)
			( gate "@baseboard_fab2_lib.baseboard_fab2(sch_1):page133_i322"
				( objectStatus "F1522" )
			)
			( gate "@baseboard_fab2_lib.baseboard_fab2(sch_1):page167_i70"
				( objectStatus "F1461" )
			)
			( gate "@baseboard_fab2_lib.baseboard_fab2(sch_1):page167_i34"
				( objectStatus "F1564" )
			)
			( gate "@baseboard_fab2_lib.baseboard_fab2(sch_1):page136_i155"
				( objectStatus "F1478" )
			)
			( gate "@baseboard_fab2_lib.baseboard_fab2(sch_1):page232_i210"
				( objectStatus "F1485" )
			)
			( gate "@baseboard_fab2_lib.baseboard_fab2(sch_1):page233_i185"
				( objectStatus "F1501" )
			)
			( gate "@baseboard_fab2_lib.baseboard_fab2(sch_1):page234_i143"
				( objectStatus "F1513" )
			)
			( gate "@baseboard_fab2_lib.baseboard_fab2(sch_1):page133_i286"
				( objectStatus "F1467" )
			)
			( gate "@baseboard_fab2_lib.baseboard_fab2(sch_1):page133_i280"
				( objectStatus "F1469" )
			)
			( gate "@baseboard_fab2_lib.baseboard_fab2(sch_1):page133_i282"
				( objectStatus "F1468" )
			)
			( gate "@baseboard_fab2_lib.baseboard_fab2(sch_1):page164_i32"
				( objectStatus "F1537" )
			)
			( gate "@baseboard_fab2_lib.baseboard_fab2(sch_1):page133_i284"
				( objectStatus "F1538" )
			)
			( gate "@baseboard_fab2_lib.baseboard_fab2(sch_1):page231_i143"
				( objectStatus "F1475" )
			)
			( gate "@baseboard_fab2_lib.baseboard_fab2(sch_1):page240_i117"
				( objectStatus "F1458" )
			)
			( gate "@baseboard_fab2_lib.baseboard_fab2(sch_1):page134_i24"
				( objectStatus "F1463" )
			)
			( gate "@baseboard_fab2_lib.baseboard_fab2(sch_1):page173_i266"
				( objectStatus "F1540" )
			)
			( gate "@baseboard_fab2_lib.baseboard_fab2(sch_1):page173_i264"
				( objectStatus "F1539" )
			)
			( gate "@baseboard_fab2_lib.baseboard_fab2(sch_1):page137_i69"
				( objectStatus "F1484" )
			)
			( gate "@baseboard_fab2_lib.baseboard_fab2(sch_1):page112_i62"
				( objectStatus "F1488" )
				( pin "A"
					( objectStatus "R6T5.1" )
				)
			)
			( gate "@baseboard_fab2_lib.baseboard_fab2(sch_1):page136_i102"
				( objectStatus "F1519" )
			)
			( gate "@baseboard_fab2_lib.baseboard_fab2(sch_1):page169_i83"
				( objectStatus "F1541" )
			)
			( gate "@baseboard_fab2_lib.baseboard_fab2(sch_1):page168_i11"
				( objectStatus "F1550" )
			)
			( gate "@baseboard_fab2_lib.baseboard_fab2(sch_1):page168_i22"
				( objectStatus "F1549" )
			)
			( gate "@baseboard_fab2_lib.baseboard_fab2(sch_1):page168_i10"
				( objectStatus "F1553" )
			)
			( gate "@baseboard_fab2_lib.baseboard_fab2(sch_1):page174_i5"
				( objectStatus "F1554" )
			)
			( gate "@baseboard_fab2_lib.baseboard_fab2(sch_1):page133_i258"
				( objectStatus "F1535" )
			)
			( gate "@baseboard_fab2_lib.baseboard_fab2(sch_1):page112_i94"
				( objectStatus "F1470" )
				( pin "A"
					( objectStatus "R8B2.1" )
				)
			)
			( gate "@baseboard_fab2_lib.baseboard_fab2(sch_1):page112_i85"
				( objectStatus "F1528" )
				( pin "A"
					( objectStatus "R3M10.1" )
				)
			)
			( gate "@baseboard_fab2_lib.baseboard_fab2(sch_1):page211_i64"
				( objectStatus "F1521" )
			)
			( gate "@baseboard_fab2_lib.baseboard_fab2(sch_1):page213_i63"
				( objectStatus "F1509" )
			)
			( gate "@baseboard_fab2_lib.baseboard_fab2(sch_1):page235_i216"
				( objectStatus "F1472" )
			)
			( gate "@baseboard_fab2_lib.baseboard_fab2(sch_1):page218_i17"
				( objectStatus "F1487" )
			)
			( gate "@baseboard_fab2_lib.baseboard_fab2(sch_1):page223_i79"
				( objectStatus "F1558" )
			)
			( gate "@baseboard_fab2_lib.baseboard_fab2(sch_1):page226_i79"
				( objectStatus "F1570" )
			)
			( gate "@baseboard_fab2_lib.baseboard_fab2(sch_1):page215_i303"
				( objectStatus "F1473" )
			)
			( gate "@baseboard_fab2_lib.baseboard_fab2(sch_1):page235_i149"
				( objectStatus "F1471" )
			)
			( gate "@baseboard_fab2_lib.baseboard_fab2(sch_1):page164_i22"
				( objectStatus "F1544" )
			)
			( gate "@baseboard_fab2_lib.baseboard_fab2(sch_1):page164_i7"
				( objectStatus "F1548" )
			)
			( gate "@baseboard_fab2_lib.baseboard_fab2(sch_1):page164_i20"
				( objectStatus "F1543" )
			)
			( gate "@baseboard_fab2_lib.baseboard_fab2(sch_1):page164_i6"
				( objectStatus "F1547" )
			)
			( gate "@baseboard_fab2_lib.baseboard_fab2(sch_1):page152_i2"
				( objectStatus "F1542" )
			)
			( gate "@baseboard_fab2_lib.baseboard_fab2(sch_1):page211_i56"
				( objectStatus "F1520" )
			)
			( gate "@baseboard_fab2_lib.baseboard_fab2(sch_1):page213_i15"
				( objectStatus "F1510" )
			)
			( gate "@baseboard_fab2_lib.baseboard_fab2(sch_1):page96_i71"
				( objectStatus "F1518" )
			)
			( gate "@baseboard_fab2_lib.baseboard_fab2(sch_1):page96_i69"
				( objectStatus "F1511" )
			)
			( gate "@baseboard_fab2_lib.baseboard_fab2(sch_1):page167_i35"
				( objectStatus "F1454" )
			)
			( gate "@baseboard_fab2_lib.baseboard_fab2(sch_1):page167_i50"
				( objectStatus "F1462" )
			)
			( gate "@baseboard_fab2_lib.baseboard_fab2(sch_1):page167_i10"
				( objectStatus "F1453" )
			)
			( gate "@baseboard_fab2_lib.baseboard_fab2(sch_1):page125_i40"
				( objectStatus "F1465" )
			)
			( gate "@baseboard_fab2_lib.baseboard_fab2(sch_1):page125_i15"
				( objectStatus "F1534" )
			)
			( gate "@baseboard_fab2_lib.baseboard_fab2(sch_1):page125_i70"
				( objectStatus "F1482" )
			)
			( gate "@baseboard_fab2_lib.baseboard_fab2(sch_1):page167_i38"
				( objectStatus "F1563" )
			)
			( gate "@baseboard_fab2_lib.baseboard_fab2(sch_1):page218_i16"
				( objectStatus "F1486" )
			)
			( gate "@baseboard_fab2_lib.baseboard_fab2(sch_1):page223_i17"
				( objectStatus "F1556" )
			)
			( gate "@baseboard_fab2_lib.baseboard_fab2(sch_1):page226_i17"
				( objectStatus "F1569" )
			)
			( gate "@baseboard_fab2_lib.baseboard_fab2(sch_1):page241_i11"
				( objectStatus "F1476" )
			)
			( gate "@baseboard_fab2_lib.baseboard_fab2(sch_1):page93_i127"
				( objectStatus "F1530" )
			)
			( gate "@baseboard_fab2_lib.baseboard_fab2(sch_1):page101_i48"
				( objectStatus "F1531" )
			)
			( gate "@baseboard_fab2_lib.baseboard_fab2(sch_1):page100_i19"
				( objectStatus "F1560" )
			)
			( gate "@baseboard_fab2_lib.baseboard_fab2(sch_1):page100_i35"
				( objectStatus "F1557" )
			)
			( gate "@baseboard_fab2_lib.baseboard_fab2(sch_1):page100_i22"
				( objectStatus "F1447" )
			)
			( gate "@baseboard_fab2_lib.baseboard_fab2(sch_1):page100_i38"
				( objectStatus "F1449" )
			)
			( gate "@baseboard_fab2_lib.baseboard_fab2(sch_1):page100_i20"
				( objectStatus "F1559" )
			)
			( gate "@baseboard_fab2_lib.baseboard_fab2(sch_1):page100_i36"
				( objectStatus "F1555" )
			)
			( gate "@baseboard_fab2_lib.baseboard_fab2(sch_1):page100_i24"
				( objectStatus "F1448" )
			)
			( gate "@baseboard_fab2_lib.baseboard_fab2(sch_1):page100_i40"
				( objectStatus "F1450" )
			)
			( gate "@baseboard_fab2_lib.baseboard_fab2(sch_1):page98_i54"
				( objectStatus "F1494" )
			)
			( gate "@baseboard_fab2_lib.baseboard_fab2(sch_1):page98_i38"
				( objectStatus "F1503" )
			)
			( gate "@baseboard_fab2_lib.baseboard_fab2(sch_1):page98_i46"
				( objectStatus "F1500" )
			)
			( gate "@baseboard_fab2_lib.baseboard_fab2(sch_1):page98_i62"
				( objectStatus "F1496" )
			)
			( gate "@baseboard_fab2_lib.baseboard_fab2(sch_1):page98_i56"
				( objectStatus "F1495" )
			)
			( gate "@baseboard_fab2_lib.baseboard_fab2(sch_1):page98_i40"
				( objectStatus "F1502" )
			)
			( gate "@baseboard_fab2_lib.baseboard_fab2(sch_1):page98_i48"
				( objectStatus "F1499" )
			)
			( gate "@baseboard_fab2_lib.baseboard_fab2(sch_1):page98_i64"
				( objectStatus "F1497" )
			)
			( gate "@baseboard_fab2_lib.baseboard_fab2(sch_1):page96_i36"
				( objectStatus "F1517" )
			)
			( gate "@baseboard_fab2_lib.baseboard_fab2(sch_1):page96_i55"
				( objectStatus "F1512" )
			)
			( gate "@baseboard_fab2_lib.baseboard_fab2(sch_1):page111_i57"
				( objectStatus "F1455" )
			)
			( gate "@baseboard_fab2_lib.baseboard_fab2(sch_1):page111_i60"
				( objectStatus "F1456" )
				( pin "A"
					( objectStatus "R9A15.1" )
				)
				( pin "B"
					( objectStatus "R9A15.2" )
				)
			)
			( gate "@baseboard_fab2_lib.baseboard_fab2(sch_1):page111_i37"
				( objectStatus "F1536" )
			)
			( gate "@baseboard_fab2_lib.baseboard_fab2(sch_1):page98_i36"
				( objectStatus "F1505" )
			)
			( gate "@baseboard_fab2_lib.baseboard_fab2(sch_1):page100_i11"
				( objectStatus "F1445" )
			)
			( gate "@baseboard_fab2_lib.baseboard_fab2(sch_1):page100_i6"
				( objectStatus "F1562" )
			)
			( gate "@baseboard_fab2_lib.baseboard_fab2(sch_1):page98_i9"
				( objectStatus "F1492" )
			)
			( gate "@baseboard_fab2_lib.baseboard_fab2(sch_1):page111_i6"
				( objectStatus "F1552" )
			)
			( gate "@baseboard_fab2_lib.baseboard_fab2(sch_1):page111_i11"
				( objectStatus "F1457" )
			)
			( gate "@baseboard_fab2_lib.baseboard_fab2(sch_1):page111_i13"
				( objectStatus "F1551" )
			)
			( gate "@baseboard_fab2_lib.baseboard_fab2(sch_1):page196_i46"
				( objectStatus "F1529" )
			)
			( gate "@baseboard_fab2_lib.baseboard_fab2(sch_1):page151_i60"
				( objectStatus "F1545" )
			)
			( gate "@baseboard_fab2_lib.baseboard_fab2(sch_1):page151_i61"
				( objectStatus "F1546" )
			)
			( gate "@baseboard_fab2_lib.baseboard_fab2(sch_1):page136_i148"
				( objectStatus "F1466" )
			)
			( gate "@baseboard_fab2_lib.baseboard_fab2(sch_1):page136_i139"
				( objectStatus "F1459" )
			)
			( gate "@baseboard_fab2_lib.baseboard_fab2(sch_1):page137_i15"
				( objectStatus "F1483" )
			)
			( gate "@baseboard_fab2_lib.baseboard_fab2(sch_1):page100_i2"
				( objectStatus "F1561" )
			)
			( gate "@baseboard_fab2_lib.baseboard_fab2(sch_1):page98_i4"
				( objectStatus "F1504" )
			)
			( gate "@baseboard_fab2_lib.baseboard_fab2(sch_1):page98_i12"
				( objectStatus "F1493" )
			)
			( gate "@baseboard_fab2_lib.baseboard_fab2(sch_1):page100_i4"
				( objectStatus "F1446" )
			)
			( gate "@baseboard_fab2_lib.baseboard_fab2(sch_1):page215_i301"
				( objectStatus "F1474" )
			)
			( gate "@baseboard_fab2_lib.baseboard_fab2(sch_1):page201_i27"
				( objectStatus "F1506" )
			)
			( gate "@baseboard_fab2_lib.baseboard_fab2(sch_1):page201_i25"
				( objectStatus "F1508" )
			)
			( gate "@baseboard_fab2_lib.baseboard_fab2(sch_1):page201_i111"
				( objectStatus "F1507" )
			)
			( gate "@baseboard_fab2_lib.baseboard_fab2(sch_1):page206_i36"
				( objectStatus "F1566" )
			)
			( gate "@baseboard_fab2_lib.baseboard_fab2(sch_1):page206_i35"
				( objectStatus "F1568" )
			)
			( gate "@baseboard_fab2_lib.baseboard_fab2(sch_1):page206_i6"
				( objectStatus "F1567" )
			)
			( gate "@baseboard_fab2_lib.baseboard_fab2(sch_1):page199_i65"
				( objectStatus "F1565" )
			)
			( gate "@baseboard_fab2_lib.baseboard_fab2(sch_1):page92_i54"
				( objectStatus "F1477" )
			)
			( gate "@baseboard_fab2_lib.baseboard_fab2(sch_1):page92_i46"
				( objectStatus "F1516" )
			)
			( gate "@baseboard_fab2_lib.baseboard_fab2(sch_1):page155_i186"
				( objectStatus "F1367" )
			)
			( gate "@baseboard_fab2_lib.baseboard_fab2(sch_1):page201_i109"
				( objectStatus "F1352" )
			)
			( gate "@baseboard_fab2_lib.baseboard_fab2(sch_1):page201_i110"
				( objectStatus "F1354" )
			)
			( gate "@baseboard_fab2_lib.baseboard_fab2(sch_1):page206_i79"
				( objectStatus "F1374" )
			)
			( gate "@baseboard_fab2_lib.baseboard_fab2(sch_1):page206_i77"
				( objectStatus "F1375" )
			)
			( gate "@baseboard_fab2_lib.baseboard_fab2(sch_1):page211_i81"
				( objectStatus "F1357" )
			)
			( gate "@baseboard_fab2_lib.baseboard_fab2(sch_1):page213_i84"
				( objectStatus "F1353" )
			)
			( gate "@baseboard_fab2_lib.baseboard_fab2(sch_1):page163_i2"
				( objectStatus "F1349" )
			)
			( gate "@baseboard_fab2_lib.baseboard_fab2(sch_1):page163_i3"
				( objectStatus "F1348" )
			)
			( gate "@baseboard_fab2_lib.baseboard_fab2(sch_1):page200_i154"
				( objectStatus "F1370" )
			)
			( gate "@baseboard_fab2_lib.baseboard_fab2(sch_1):page236_i93"
				( objectStatus "F1343" )
			)
			( gate "@baseboard_fab2_lib.baseboard_fab2(sch_1):page236_i94"
				( objectStatus "F1344" )
			)
			( gate "@baseboard_fab2_lib.baseboard_fab2(sch_1):page118_i66"
				( objectStatus "F1358" )
				( pin "A"
					( objectStatus "R3N9.1" )
				)
			)
			( gate "@baseboard_fab2_lib.baseboard_fab2(sch_1):page114_i110"
				( objectStatus "F1338" )
			)
			( gate "@baseboard_fab2_lib.baseboard_fab2(sch_1):page235_i210"
				( objectStatus "F1339" )
			)
			( gate "@baseboard_fab2_lib.baseboard_fab2(sch_1):page218_i60"
				( objectStatus "F1345" )
			)
			( gate "@baseboard_fab2_lib.baseboard_fab2(sch_1):page223_i32"
				( objectStatus "F1368" )
			)
			( gate "@baseboard_fab2_lib.baseboard_fab2(sch_1):page226_i32"
				( objectStatus "F1376" )
			)
			( gate "@baseboard_fab2_lib.baseboard_fab2(sch_1):page155_i65"
				( objectStatus "F1359" )
			)
			( gate "@baseboard_fab2_lib.baseboard_fab2(sch_1):page155_i66"
				( objectStatus "F1360" )
			)
			( gate "@baseboard_fab2_lib.baseboard_fab2(sch_1):page155_i67"
				( objectStatus "F1361" )
			)
			( gate "@baseboard_fab2_lib.baseboard_fab2(sch_1):page155_i68"
				( objectStatus "F1362" )
			)
			( gate "@baseboard_fab2_lib.baseboard_fab2(sch_1):page155_i73"
				( objectStatus "F1363" )
			)
			( gate "@baseboard_fab2_lib.baseboard_fab2(sch_1):page155_i74"
				( objectStatus "F1364" )
			)
			( gate "@baseboard_fab2_lib.baseboard_fab2(sch_1):page155_i75"
				( objectStatus "F1365" )
			)
			( gate "@baseboard_fab2_lib.baseboard_fab2(sch_1):page155_i76"
				( objectStatus "F1366" )
			)
			( gate "@baseboard_fab2_lib.baseboard_fab2(sch_1):page99_i88"
				( objectStatus "F1356" )
				( pin "A"
					( objectStatus "R3R7.1" )
				)
				( pin "B"
					( objectStatus "R3R7.2" )
				)
			)
			( gate "@baseboard_fab2_lib.baseboard_fab2(sch_1):page99_i92"
				( objectStatus "F1347" )
				( pin "A"
					( objectStatus "R6T3.1" )
				)
				( pin "B"
					( objectStatus "R6T3.2" )
				)
			)
			( gate "@baseboard_fab2_lib.baseboard_fab2(sch_1):page99_i83"
				( objectStatus "F1351" )
				( pin "A"
					( objectStatus "R4T3.1" )
				)
				( pin "B"
					( objectStatus "R4T3.2" )
				)
			)
			( gate "@baseboard_fab2_lib.baseboard_fab2(sch_1):page99_i98"
				( objectStatus "F1341" )
				( pin "A"
					( objectStatus "R7M3.1" )
				)
				( pin "B"
					( objectStatus "R7M3.2" )
				)
			)
			( gate "@baseboard_fab2_lib.baseboard_fab2(sch_1):page99_i112"
				( objectStatus "F1340" )
				( pin "B"
					( objectStatus "R7M8.2" )
				)
			)
			( gate "@baseboard_fab2_lib.baseboard_fab2(sch_1):page99_i110"
				( objectStatus "F1355" )
				( pin "A"
					( objectStatus "R3R14.1" )
				)
				( pin "B"
					( objectStatus "R3R14.2" )
				)
			)
			( gate "@baseboard_fab2_lib.baseboard_fab2(sch_1):page99_i111"
				( objectStatus "F1346" )
				( pin "A"
					( objectStatus "R6T4.1" )
				)
				( pin "B"
					( objectStatus "R6T4.2" )
				)
			)
			( gate "@baseboard_fab2_lib.baseboard_fab2(sch_1):page215_i344"
				( objectStatus "F1342" )
			)
			( gate "@baseboard_fab2_lib.baseboard_fab2(sch_1):page99_i20"
				( objectStatus "F1350" )
				( pin "A"
					( objectStatus "R4T4.1" )
				)
				( pin "B"
					( objectStatus "R4T4.2" )
				)
			)
			( gate "@baseboard_fab2_lib.baseboard_fab2(sch_1):page200_i48"
				( objectStatus "F1373" )
			)
			( gate "@baseboard_fab2_lib.baseboard_fab2(sch_1):page200_i47"
				( objectStatus "F1336" )
			)
			( gate "@baseboard_fab2_lib.baseboard_fab2(sch_1):page200_i51"
				( objectStatus "F1337" )
			)
			( gate "@baseboard_fab2_lib.baseboard_fab2(sch_1):page200_i52"
				( objectStatus "F1372" )
			)
			( gate "@baseboard_fab2_lib.baseboard_fab2(sch_1):page200_i60"
				( objectStatus "F1371" )
			)
			( gate "@baseboard_fab2_lib.baseboard_fab2(sch_1):page200_i58"
				( objectStatus "F1335" )
			)
			( gate "@baseboard_fab2_lib.baseboard_fab2(sch_1):page200_i56"
				( objectStatus "F1369" )
			)
			( gate "@baseboard_fab2_lib.baseboard_fab2(sch_1):page199_i26"
				( objectStatus "F1167" )
			)
			( gate "@baseboard_fab2_lib.baseboard_fab2(sch_1):page213_i27"
				( objectStatus "F1162" )
			)
			( gate "@baseboard_fab2_lib.baseboard_fab2(sch_1):page218_i7"
				( objectStatus "F1166" )
				( pin "B"
					( objectStatus "R3L11.2" )
				)
			)
			( gate "@baseboard_fab2_lib.baseboard_fab2(sch_1):page226_i8"
				( objectStatus "F1158" )
				( pin "B"
					( objectStatus "R9M7.2" )
				)
			)
			( gate "@baseboard_fab2_lib.baseboard_fab2(sch_1):page211_i17"
				( objectStatus "F1165" )
				( pin "B"
					( objectStatus "R3P13.2" )
				)
			)
			( gate "@baseboard_fab2_lib.baseboard_fab2(sch_1):page236_i57"
				( objectStatus "F1159" )
			)
			( gate "@baseboard_fab2_lib.baseboard_fab2(sch_1):page217_i74"
				( objectStatus "F1163" )
			)
			( gate "@baseboard_fab2_lib.baseboard_fab2(sch_1):page220_i74"
				( objectStatus "F1164" )
			)
			( gate "@baseboard_fab2_lib.baseboard_fab2(sch_1):page225_i74"
				( objectStatus "F1160" )
			)
			( gate "@baseboard_fab2_lib.baseboard_fab2(sch_1):page228_i74"
				( objectStatus "F1161" )
			)
			( gate "@baseboard_fab2_lib.baseboard_fab2(sch_1):page112_i55"
				( objectStatus "F1080" )
				( pin "B"
					( objectStatus "R6T7.2" )
				)
			)
			( gate "@baseboard_fab2_lib.baseboard_fab2(sch_1):page112_i56"
				( objectStatus "F1081" )
				( pin "B"
					( objectStatus "R6T6.2" )
				)
			)
			( gate "@baseboard_fab2_lib.baseboard_fab2(sch_1):page112_i60"
				( objectStatus "F1099" )
			)
			( gate "@baseboard_fab2_lib.baseboard_fab2(sch_1):page93_i104"
				( objectStatus "F1092" )
			)
			( gate "@baseboard_fab2_lib.baseboard_fab2(sch_1):page93_i80"
				( objectStatus "F1078" )
			)
			( gate "@baseboard_fab2_lib.baseboard_fab2(sch_1):page152_i62"
				( objectStatus "F1073" )
			)
			( gate "@baseboard_fab2_lib.baseboard_fab2(sch_1):page152_i57"
				( objectStatus "F1097" )
			)
			( gate "@baseboard_fab2_lib.baseboard_fab2(sch_1):page152_i61"
				( objectStatus "F1076" )
			)
			( gate "@baseboard_fab2_lib.baseboard_fab2(sch_1):page152_i56"
				( objectStatus "F1096" )
			)
			( gate "@baseboard_fab2_lib.baseboard_fab2(sch_1):page152_i53"
				( objectStatus "F1095" )
			)
			( gate "@baseboard_fab2_lib.baseboard_fab2(sch_1):page152_i54"
				( objectStatus "F1094" )
			)
			( gate "@baseboard_fab2_lib.baseboard_fab2(sch_1):page152_i58"
				( objectStatus "F1089" )
			)
			( gate "@baseboard_fab2_lib.baseboard_fab2(sch_1):page152_i59"
				( objectStatus "F1088" )
			)
			( gate "@baseboard_fab2_lib.baseboard_fab2(sch_1):page93_i106"
				( objectStatus "F1071" )
			)
			( gate "@baseboard_fab2_lib.baseboard_fab2(sch_1):page93_i79"
				( objectStatus "F1084" )
			)
			( gate "@baseboard_fab2_lib.baseboard_fab2(sch_1):page112_i59"
				( objectStatus "F1086" )
				( pin "B"
					( objectStatus "R4P24.2" )
				)
			)
			( gate "@baseboard_fab2_lib.baseboard_fab2(sch_1):page112_i58"
				( objectStatus "F1087" )
				( pin "B"
					( objectStatus "R4P23.2" )
				)
			)
			( gate "@baseboard_fab2_lib.baseboard_fab2(sch_1):page112_i80"
				( objectStatus "F1069" )
				( pin "B"
					( objectStatus "R8A14.2" )
				)
			)
			( gate "@baseboard_fab2_lib.baseboard_fab2(sch_1):page112_i79"
				( objectStatus "F1070" )
				( pin "B"
					( objectStatus "R8A13.2" )
				)
			)
			( gate "@baseboard_fab2_lib.baseboard_fab2(sch_1):page112_i78"
				( objectStatus "F1068" )
				( pin "B"
					( objectStatus "R9A11.2" )
				)
			)
			( gate "@baseboard_fab2_lib.baseboard_fab2(sch_1):page213_i46"
				( objectStatus "F1091" )
				( pin "B"
					( objectStatus "R4D51.2" )
				)
			)
			( gate "@baseboard_fab2_lib.baseboard_fab2(sch_1):page211_i29"
				( objectStatus "F1093" )
				( pin "A"
					( objectStatus "R3P15.1" )
				)
				( pin "B"
					( objectStatus "R3P15.2" )
				)
			)
			( gate "@baseboard_fab2_lib.baseboard_fab2(sch_1):page218_i48"
				( objectStatus "F1079" )
				( pin "B"
					( objectStatus "R7A17.2" )
				)
			)
			( gate "@baseboard_fab2_lib.baseboard_fab2(sch_1):page223_i53"
				( objectStatus "F1100" )
				( pin "B"
					( objectStatus "R1G7.2" )
				)
			)
			( gate "@baseboard_fab2_lib.baseboard_fab2(sch_1):page226_i53"
				( objectStatus "F1102" )
				( pin "A"
					( objectStatus "R1B8.1" )
				)
				( pin "B"
					( objectStatus "R1B8.2" )
				)
			)
			( gate "@baseboard_fab2_lib.baseboard_fab2(sch_1):page215_i331"
				( objectStatus "F1077" )
				( pin "B"
					( objectStatus "R7G24.2" )
				)
			)
			( gate "@baseboard_fab2_lib.baseboard_fab2(sch_1):page206_i54"
				( objectStatus "F1101" )
				( pin "A"
					( objectStatus "R1D9.1" )
				)
				( pin "B"
					( objectStatus "R1D9.2" )
				)
			)
			( gate "@baseboard_fab2_lib.baseboard_fab2(sch_1):page111_i56"
				( objectStatus "F1098" )
			)
			( gate "@baseboard_fab2_lib.baseboard_fab2(sch_1):page92_i101"
				( objectStatus "F1085" )
				( pin "B"
					( objectStatus "R4R2.2" )
				)
			)
			( gate "@baseboard_fab2_lib.baseboard_fab2(sch_1):page92_i100"
				( objectStatus "F1075" )
				( pin "B"
					( objectStatus "R7P18.2" )
				)
			)
			( gate "@baseboard_fab2_lib.baseboard_fab2(sch_1):page97_i44"
				( objectStatus "F1074" )
				( pin "B"
					( objectStatus "R7P20.2" )
				)
			)
			( gate "@baseboard_fab2_lib.baseboard_fab2(sch_1):page201_i56"
				( objectStatus "F1090" )
				( pin "A"
					( objectStatus "R4E6.1" )
				)
				( pin "B"
					( objectStatus "R4E6.2" )
				)
			)
			( gate "@baseboard_fab2_lib.baseboard_fab2(sch_1):page97_i42"
				( objectStatus "F1083" )
				( pin "B"
					( objectStatus "R4R4.2" )
				)
			)
			( gate "@baseboard_fab2_lib.baseboard_fab2(sch_1):page92_i64"
				( objectStatus "F1082" )
				( pin "B"
					( objectStatus "R6D9.2" )
				)
			)
			( gate "@baseboard_fab2_lib.baseboard_fab2(sch_1):page92_i65"
				( objectStatus "F1072" )
				( pin "B"
					( objectStatus "R7P27.2" )
				)
			)
			( gate "@baseboard_fab2_lib.baseboard_fab2(sch_1):page100_i25"
				( objectStatus "F1061" )
			)
			( gate "@baseboard_fab2_lib.baseboard_fab2(sch_1):page100_i41"
				( objectStatus "F1060" )
			)
			( gate "@baseboard_fab2_lib.baseboard_fab2(sch_1):page100_i29"
				( objectStatus "F1052" )
			)
			( gate "@baseboard_fab2_lib.baseboard_fab2(sch_1):page100_i45"
				( objectStatus "F1053" )
			)
			( gate "@baseboard_fab2_lib.baseboard_fab2(sch_1):page98_i58"
				( objectStatus "F1055" )
			)
			( gate "@baseboard_fab2_lib.baseboard_fab2(sch_1):page98_i42"
				( objectStatus "F1058" )
			)
			( gate "@baseboard_fab2_lib.baseboard_fab2(sch_1):page98_i50"
				( objectStatus "F1057" )
			)
			( gate "@baseboard_fab2_lib.baseboard_fab2(sch_1):page98_i66"
				( objectStatus "F1056" )
			)
			( gate "@baseboard_fab2_lib.baseboard_fab2(sch_1):page100_i7"
				( objectStatus "F1062" )
			)
			( gate "@baseboard_fab2_lib.baseboard_fab2(sch_1):page98_i5"
				( objectStatus "F1059" )
			)
			( gate "@baseboard_fab2_lib.baseboard_fab2(sch_1):page100_i13"
				( objectStatus "F1051" )
			)
			( gate "@baseboard_fab2_lib.baseboard_fab2(sch_1):page98_i14"
				( objectStatus "F1054" )
			)
			( gate "@baseboard_fab2_lib.baseboard_fab2(sch_1):page181_i199"
				( objectStatus "F1013" )
			)
			( gate "@baseboard_fab2_lib.baseboard_fab2(sch_1):page181_i200"
				( objectStatus "F1012" )
			)
			( gate "@baseboard_fab2_lib.baseboard_fab2(sch_1):page181_i201"
				( objectStatus "F1011" )
			)
			( gate "@baseboard_fab2_lib.baseboard_fab2(sch_1):page201_i19"
				( objectStatus "F1014" )
			)
			( gate "@baseboard_fab2_lib.baseboard_fab2(sch_1):page206_i7"
				( objectStatus "F1015" )
			)
			( gate "@baseboard_fab2_lib.baseboard_fab2(sch_1):page167_i84"
				( objectStatus "F928" )
			)
			( gate "@baseboard_fab2_lib.baseboard_fab2(sch_1):page167_i85"
				( objectStatus "F929" )
			)
			( gate "@baseboard_fab2_lib.baseboard_fab2(sch_1):page160_i4"
				( objectStatus "F976" )
				( pin "A"
					( objectStatus "R1T8.1" )
				)
			)
			( gate "@baseboard_fab2_lib.baseboard_fab2(sch_1):page160_i50"
				( objectStatus "F977" )
			)
			( gate "@baseboard_fab2_lib.baseboard_fab2(sch_1):page160_i51"
				( objectStatus "F924" )
				( pin "A"
					( objectStatus "R9F23.1" )
				)
			)
			( gate "@baseboard_fab2_lib.baseboard_fab2(sch_1):page160_i52"
				( objectStatus "F925" )
				( pin "A"
					( objectStatus "R9F22.1" )
				)
			)
			( gate "@baseboard_fab2_lib.baseboard_fab2(sch_1):page108_i330"
				( objectStatus "F961" )
				( pin "A"
					( objectStatus "R2U31.1" )
				)
			)
			( gate "@baseboard_fab2_lib.baseboard_fab2(sch_1):page108_i339"
				( objectStatus "F960" )
				( pin "A"
					( objectStatus "R2U32.1" )
				)
			)
			( gate "@baseboard_fab2_lib.baseboard_fab2(sch_1):page159_i224"
				( objectStatus "F923" )
			)
			( gate "@baseboard_fab2_lib.baseboard_fab2(sch_1):page159_i225"
				( objectStatus "F972" )
				( pin "A"
					( objectStatus "R1U20.1" )
				)
				( pin "B"
					( objectStatus "R1U20.2" )
				)
			)
			( gate "@baseboard_fab2_lib.baseboard_fab2(sch_1):page159_i226"
				( objectStatus "F973" )
				( pin "A"
					( objectStatus "R1U19.1" )
				)
				( pin "B"
					( objectStatus "R1U19.2" )
				)
			)
			( gate "@baseboard_fab2_lib.baseboard_fab2(sch_1):page159_i227"
				( objectStatus "F922" )
			)
			( gate "@baseboard_fab2_lib.baseboard_fab2(sch_1):page167_i58"
				( objectStatus "F920" )
				( pin "A"
					( objectStatus "R9G15.1" )
				)
			)
			( gate "@baseboard_fab2_lib.baseboard_fab2(sch_1):page167_i77"
				( objectStatus "F921" )
				( pin "A"
					( objectStatus "R9G14.1" )
				)
			)
			( gate "@baseboard_fab2_lib.baseboard_fab2(sch_1):page167_i78"
				( objectStatus "F970" )
			)
			( gate "@baseboard_fab2_lib.baseboard_fab2(sch_1):page167_i79"
				( objectStatus "F971" )
			)
			( gate "@baseboard_fab2_lib.baseboard_fab2(sch_1):page163_i20"
				( objectStatus "F917" )
				( pin "B"
					( objectStatus "R9M14.2" )
				)
			)
			( gate "@baseboard_fab2_lib.baseboard_fab2(sch_1):page163_i25"
				( objectStatus "F916" )
				( pin "A"
					( objectStatus "R9M15.1" )
				)
				( pin "B"
					( objectStatus "R9M15.2" )
				)
			)
			( gate "@baseboard_fab2_lib.baseboard_fab2(sch_1):page163_i21"
				( objectStatus "F918" )
				( pin "A"
					( objectStatus "R9M13.1" )
				)
				( pin "B"
					( objectStatus "R9M13.2" )
				)
			)
			( gate "@baseboard_fab2_lib.baseboard_fab2(sch_1):page163_i24"
				( objectStatus "F919" )
				( pin "B"
					( objectStatus "R9M12.2" )
				)
			)
			( gate "@baseboard_fab2_lib.baseboard_fab2(sch_1):page138_i116"
				( objectStatus "F968" )
				( pin "A"
					( objectStatus "R2T55.1" )
				)
			)
			( gate "@baseboard_fab2_lib.baseboard_fab2(sch_1):page138_i160"
				( objectStatus "F967" )
				( pin "A"
					( objectStatus "R2T56.1" )
				)
			)
			( gate "@baseboard_fab2_lib.baseboard_fab2(sch_1):page138_i169"
				( objectStatus "F937" )
				( pin "A"
					( objectStatus "R8C11.1" )
				)
			)
			( gate "@baseboard_fab2_lib.baseboard_fab2(sch_1):page138_i170"
				( objectStatus "F936" )
				( pin "A"
					( objectStatus "R8C12.1" )
				)
				( pin "B"
					( objectStatus "R8C12.2" )
				)
			)
			( gate "@baseboard_fab2_lib.baseboard_fab2(sch_1):page138_i167"
				( objectStatus "F934" )
			)
			( gate "@baseboard_fab2_lib.baseboard_fab2(sch_1):page138_i168"
				( objectStatus "F935" )
			)
			( gate "@baseboard_fab2_lib.baseboard_fab2(sch_1):page211_i46"
				( objectStatus "F956" )
				( pin "B"
					( objectStatus "R3P24.2" )
				)
			)
			( gate "@baseboard_fab2_lib.baseboard_fab2(sch_1):page215_i298"
				( objectStatus "F945" )
				( pin "A"
					( objectStatus "R7F25.1" )
				)
			)
			( gate "@baseboard_fab2_lib.baseboard_fab2(sch_1):page159_i219"
				( objectStatus "F969" )
				( pin "A"
					( objectStatus "R2T49.1" )
				)
				( pin "B"
					( objectStatus "R2T49.2" )
				)
			)
			( gate "@baseboard_fab2_lib.baseboard_fab2(sch_1):page159_i218"
				( objectStatus "F966" )
				( pin "A"
					( objectStatus "R2U1.1" )
				)
				( pin "B"
					( objectStatus "R2U1.2" )
				)
			)
			( gate "@baseboard_fab2_lib.baseboard_fab2(sch_1):page218_i24"
				( objectStatus "F947" )
				( pin "A"
					( objectStatus "R7B2.1" )
				)
			)
			( gate "@baseboard_fab2_lib.baseboard_fab2(sch_1):page218_i21"
				( objectStatus "F946" )
				( pin "A"
					( objectStatus "R7B3.1" )
				)
			)
			( gate "@baseboard_fab2_lib.baseboard_fab2(sch_1):page226_i22"
				( objectStatus "F980" )
				( pin "A"
					( objectStatus "R1B7.1" )
				)
			)
			( gate "@baseboard_fab2_lib.baseboard_fab2(sch_1):page226_i21"
				( objectStatus "F981" )
				( pin "A"
					( objectStatus "R1B6.1" )
				)
			)
			( gate "@baseboard_fab2_lib.baseboard_fab2(sch_1):page159_i221"
				( objectStatus "F962" )
				( pin "B"
					( objectStatus "R2U10.2" )
				)
			)
			( gate "@baseboard_fab2_lib.baseboard_fab2(sch_1):page159_i220"
				( objectStatus "F964" )
				( pin "A"
					( objectStatus "R2U7.1" )
				)
				( pin "B"
					( objectStatus "R2U7.2" )
				)
			)
			( gate "@baseboard_fab2_lib.baseboard_fab2(sch_1):page138_i174"
				( objectStatus "F938" )
				( pin "A"
					( objectStatus "R8B28.1" )
				)
			)
			( gate "@baseboard_fab2_lib.baseboard_fab2(sch_1):page138_i173"
				( objectStatus "F939" )
				( pin "A"
					( objectStatus "R8B27.1" )
				)
			)
			( gate "@baseboard_fab2_lib.baseboard_fab2(sch_1):page167_i8"
				( objectStatus "F978" )
				( pin "A"
					( objectStatus "R1M9.1" )
				)
			)
			( gate "@baseboard_fab2_lib.baseboard_fab2(sch_1):page167_i76"
				( objectStatus "F914" )
				( pin "A"
					( objectStatus "R9R8.1" )
				)
				( pin "B"
					( objectStatus "R9R8.2" )
				)
			)
			( gate "@baseboard_fab2_lib.baseboard_fab2(sch_1):page167_i74"
				( objectStatus "F979" )
				( pin "A"
					( objectStatus "R1M8.1" )
				)
			)
			( gate "@baseboard_fab2_lib.baseboard_fab2(sch_1):page167_i75"
				( objectStatus "F915" )
				( pin "A"
					( objectStatus "R9R7.1" )
				)
				( pin "B"
					( objectStatus "R9R7.2" )
				)
			)
			( gate "@baseboard_fab2_lib.baseboard_fab2(sch_1):page138_i165"
				( objectStatus "F963" )
				( pin "A"
					( objectStatus "R2U9.1" )
				)
				( pin "B"
					( objectStatus "R2U9.2" )
				)
			)
			( gate "@baseboard_fab2_lib.baseboard_fab2(sch_1):page138_i166"
				( objectStatus "F965" )
				( pin "A"
					( objectStatus "R2U6.1" )
				)
			)
			( gate "@baseboard_fab2_lib.baseboard_fab2(sch_1):page138_i162"
				( objectStatus "F931" )
				( pin "A"
					( objectStatus "R8D6.1" )
				)
				( pin "B"
					( objectStatus "R8D6.2" )
				)
			)
			( gate "@baseboard_fab2_lib.baseboard_fab2(sch_1):page138_i161"
				( objectStatus "F933" )
				( pin "A"
					( objectStatus "R8D3.1" )
				)
				( pin "B"
					( objectStatus "R8D3.2" )
				)
			)
			( gate "@baseboard_fab2_lib.baseboard_fab2(sch_1):page138_i163"
				( objectStatus "F930" )
				( pin "A"
					( objectStatus "R8D7.1" )
				)
			)
			( gate "@baseboard_fab2_lib.baseboard_fab2(sch_1):page138_i164"
				( objectStatus "F932" )
				( pin "A"
					( objectStatus "R8D4.1" )
				)
			)
			( gate "@baseboard_fab2_lib.baseboard_fab2(sch_1):page159_i233"
				( objectStatus "F974" )
				( pin "A"
					( objectStatus "R1U10.1" )
				)
			)
			( gate "@baseboard_fab2_lib.baseboard_fab2(sch_1):page159_i232"
				( objectStatus "F975" )
				( pin "A"
					( objectStatus "R1U9.1" )
				)
			)
			( gate "@baseboard_fab2_lib.baseboard_fab2(sch_1):page159_i231"
				( objectStatus "F959" )
			)
			( gate "@baseboard_fab2_lib.baseboard_fab2(sch_1):page159_i230"
				( objectStatus "F958" )
			)
			( gate "@baseboard_fab2_lib.baseboard_fab2(sch_1):page159_i228"
				( objectStatus "F926" )
				( pin "B"
					( objectStatus "R8G5.2" )
				)
			)
			( gate "@baseboard_fab2_lib.baseboard_fab2(sch_1):page159_i229"
				( objectStatus "F927" )
				( pin "B"
					( objectStatus "R8G4.2" )
				)
			)
			( gate "@baseboard_fab2_lib.baseboard_fab2(sch_1):page213_i38"
				( objectStatus "F952" )
				( pin "B"
					( objectStatus "R4D44.2" )
				)
			)
			( gate "@baseboard_fab2_lib.baseboard_fab2(sch_1):page215_i304"
				( objectStatus "F944" )
				( pin "A"
					( objectStatus "R7F26.1" )
				)
			)
			( gate "@baseboard_fab2_lib.baseboard_fab2(sch_1):page211_i47"
				( objectStatus "F957" )
				( pin "B"
					( objectStatus "R3P23.2" )
				)
			)
			( gate "@baseboard_fab2_lib.baseboard_fab2(sch_1):page213_i39"
				( objectStatus "F953" )
				( pin "B"
					( objectStatus "R4D43.2" )
				)
			)
			( gate "@baseboard_fab2_lib.baseboard_fab2(sch_1):page235_i172"
				( objectStatus "F941" )
				( pin "B"
					( objectStatus "R8A8.2" )
				)
			)
			( gate "@baseboard_fab2_lib.baseboard_fab2(sch_1):page235_i173"
				( objectStatus "F940" )
				( pin "B"
					( objectStatus "R8A9.2" )
				)
			)
			( gate "@baseboard_fab2_lib.baseboard_fab2(sch_1):page99_i34"
				( objectStatus "F954" )
				( pin "A"
					( objectStatus "R3R9.1" )
				)
				( pin "B"
					( objectStatus "R3R9.2" )
				)
			)
			( gate "@baseboard_fab2_lib.baseboard_fab2(sch_1):page99_i35"
				( objectStatus "F955" )
				( pin "A"
					( objectStatus "R3R8.1" )
				)
				( pin "B"
					( objectStatus "R3R8.2" )
				)
			)
			( gate "@baseboard_fab2_lib.baseboard_fab2(sch_1):page99_i43"
				( objectStatus "F948" )
				( pin "A"
					( objectStatus "R6U14.1" )
				)
				( pin "B"
					( objectStatus "R6U14.2" )
				)
			)
			( gate "@baseboard_fab2_lib.baseboard_fab2(sch_1):page99_i42"
				( objectStatus "F949" )
				( pin "A"
					( objectStatus "R6U13.1" )
				)
				( pin "B"
					( objectStatus "R6U13.2" )
				)
			)
			( gate "@baseboard_fab2_lib.baseboard_fab2(sch_1):page99_i10"
				( objectStatus "F950" )
				( pin "A"
					( objectStatus "R4T10.1" )
				)
				( pin "B"
					( objectStatus "R4T10.2" )
				)
			)
			( gate "@baseboard_fab2_lib.baseboard_fab2(sch_1):page99_i56"
				( objectStatus "F943" )
				( pin "A"
					( objectStatus "R7M4.1" )
				)
				( pin "B"
					( objectStatus "R7M4.2" )
				)
			)
			( gate "@baseboard_fab2_lib.baseboard_fab2(sch_1):page99_i55"
				( objectStatus "F942" )
				( pin "A"
					( objectStatus "R7M5.1" )
				)
				( pin "B"
					( objectStatus "R7M5.2" )
				)
			)
			( gate "@baseboard_fab2_lib.baseboard_fab2(sch_1):page99_i9"
				( objectStatus "F951" )
				( pin "A"
					( objectStatus "R4T9.1" )
				)
				( pin "B"
					( objectStatus "R4T9.2" )
				)
			)
			( gate "@baseboard_fab2_lib.baseboard_fab2(sch_1):page90_i31"
				( objectStatus "F832" )
			)
			( gate "@baseboard_fab2_lib.baseboard_fab2(sch_1):page90_i32"
				( objectStatus "F833" )
			)
			( gate "@baseboard_fab2_lib.baseboard_fab2(sch_1):page163_i7"
				( objectStatus "F825" )
			)
			( gate "@baseboard_fab2_lib.baseboard_fab2(sch_1):page163_i6"
				( objectStatus "F826" )
			)
			( gate "@baseboard_fab2_lib.baseboard_fab2(sch_1):page90_i70"
				( objectStatus "F827" )
			)
			( gate "@baseboard_fab2_lib.baseboard_fab2(sch_1):page90_i53"
				( objectStatus "F838" )
			)
			( gate "@baseboard_fab2_lib.baseboard_fab2(sch_1):page97_i72"
				( objectStatus "F837" )
			)
			( gate "@baseboard_fab2_lib.baseboard_fab2(sch_1):page97_i76"
				( objectStatus "F839" )
			)
			( gate "@baseboard_fab2_lib.baseboard_fab2(sch_1):page99_i65"
				( objectStatus "F840" )
				( pin "B"
					( objectStatus "R3R13.2" )
				)
			)
			( gate "@baseboard_fab2_lib.baseboard_fab2(sch_1):page99_i67"
				( objectStatus "F841" )
				( pin "B"
					( objectStatus "R3P60.2" )
				)
			)
			( gate "@baseboard_fab2_lib.baseboard_fab2(sch_1):page99_i72"
				( objectStatus "F830" )
				( pin "B"
					( objectStatus "R6T2.2" )
				)
			)
			( gate "@baseboard_fab2_lib.baseboard_fab2(sch_1):page99_i70"
				( objectStatus "F831" )
				( pin "B"
					( objectStatus "R6T1.2" )
				)
			)
			( gate "@baseboard_fab2_lib.baseboard_fab2(sch_1):page99_i19"
				( objectStatus "F836" )
				( pin "B"
					( objectStatus "R4T5.2" )
				)
			)
			( gate "@baseboard_fab2_lib.baseboard_fab2(sch_1):page90_i29"
				( objectStatus "F834" )
			)
			( gate "@baseboard_fab2_lib.baseboard_fab2(sch_1):page99_i79"
				( objectStatus "F829" )
				( pin "B"
					( objectStatus "R7M2.2" )
				)
			)
			( gate "@baseboard_fab2_lib.baseboard_fab2(sch_1):page99_i77"
				( objectStatus "F828" )
				( pin "B"
					( objectStatus "R7M7.2" )
				)
			)
			( gate "@baseboard_fab2_lib.baseboard_fab2(sch_1):page90_i59"
				( objectStatus "F842" )
			)
			( gate "@baseboard_fab2_lib.baseboard_fab2(sch_1):page151_i32"
				( objectStatus "F843" )
			)
			( gate "@baseboard_fab2_lib.baseboard_fab2(sch_1):page99_i17"
				( objectStatus "F835" )
				( pin "B"
					( objectStatus "R4T6.2" )
				)
			)
			( gate "@baseboard_fab2_lib.baseboard_fab2(sch_1):page90_i3"
				( objectStatus "F814" )
			)
			( gate "@baseboard_fab2_lib.baseboard_fab2(sch_1):page90_i11"
				( objectStatus "F824" )
			)
			( gate "@baseboard_fab2_lib.baseboard_fab2(sch_1):page90_i76"
				( objectStatus "F809" )
			)
			( gate "@baseboard_fab2_lib.baseboard_fab2(sch_1):page90_i66"
				( objectStatus "F818" )
			)
			( gate "@baseboard_fab2_lib.baseboard_fab2(sch_1):page90_i52"
				( objectStatus "F811" )
			)
			( gate "@baseboard_fab2_lib.baseboard_fab2(sch_1):page90_i68"
				( objectStatus "F815" )
			)
			( gate "@baseboard_fab2_lib.baseboard_fab2(sch_1):page90_i49"
				( objectStatus "F813" )
			)
			( gate "@baseboard_fab2_lib.baseboard_fab2(sch_1):page90_i33"
				( objectStatus "F812" )
			)
			( gate "@baseboard_fab2_lib.baseboard_fab2(sch_1):page90_i28"
				( objectStatus "F817" )
			)
			( gate "@baseboard_fab2_lib.baseboard_fab2(sch_1):page90_i12"
				( objectStatus "F823" )
			)
			( gate "@baseboard_fab2_lib.baseboard_fab2(sch_1):page90_i25"
				( objectStatus "F819" )
			)
			( gate "@baseboard_fab2_lib.baseboard_fab2(sch_1):page90_i24"
				( objectStatus "F822" )
			)
			( gate "@baseboard_fab2_lib.baseboard_fab2(sch_1):page90_i17"
				( objectStatus "F820" )
			)
			( gate "@baseboard_fab2_lib.baseboard_fab2(sch_1):page90_i4"
				( objectStatus "F816" )
			)
			( gate "@baseboard_fab2_lib.baseboard_fab2(sch_1):page90_i60"
				( objectStatus "F821" )
			)
			( gate "@baseboard_fab2_lib.baseboard_fab2(sch_1):page90_i48"
				( objectStatus "F810" )
			)
			( gate "@baseboard_fab2_lib.baseboard_fab2(sch_1):page157_i388"
				( objectStatus "F667" )
			)
			( gate "@baseboard_fab2_lib.baseboard_fab2(sch_1):page102_i82"
				( objectStatus "F713" )
			)
			( gate "@baseboard_fab2_lib.baseboard_fab2(sch_1):page102_i87"
				( objectStatus "F712" )
			)
			( gate "@baseboard_fab2_lib.baseboard_fab2(sch_1):page156_i289"
				( objectStatus "F733" )
			)
			( gate "@baseboard_fab2_lib.baseboard_fab2(sch_1):page157_i386"
				( objectStatus "F692" )
			)
			( gate "@baseboard_fab2_lib.baseboard_fab2(sch_1):page170_i74"
				( objectStatus "F738" )
			)
			( gate "@baseboard_fab2_lib.baseboard_fab2(sch_1):page190_i338"
				( objectStatus "F737" )
			)
			( gate "@baseboard_fab2_lib.baseboard_fab2(sch_1):page151_i70"
				( objectStatus "F672" )
			)
			( gate "@baseboard_fab2_lib.baseboard_fab2(sch_1):page165_i81"
				( objectStatus "F746" )
			)
			( gate "@baseboard_fab2_lib.baseboard_fab2(sch_1):page199_i110"
				( objectStatus "F754" )
			)
			( gate "@baseboard_fab2_lib.baseboard_fab2(sch_1):page199_i109"
				( objectStatus "F755" )
			)
			( gate "@baseboard_fab2_lib.baseboard_fab2(sch_1):page201_i128"
				( objectStatus "F708" )
			)
			( gate "@baseboard_fab2_lib.baseboard_fab2(sch_1):page201_i127"
				( objectStatus "F711" )
			)
			( gate "@baseboard_fab2_lib.baseboard_fab2(sch_1):page206_i117"
				( objectStatus "F668" )
			)
			( gate "@baseboard_fab2_lib.baseboard_fab2(sch_1):page206_i116"
				( objectStatus "F756" )
			)
			( gate "@baseboard_fab2_lib.baseboard_fab2(sch_1):page221_i54"
				( objectStatus "F709" )
			)
			( gate "@baseboard_fab2_lib.baseboard_fab2(sch_1):page222_i51"
				( objectStatus "F714" )
			)
			( gate "@baseboard_fab2_lib.baseboard_fab2(sch_1):page223_i82"
				( objectStatus "F752" )
			)
			( gate "@baseboard_fab2_lib.baseboard_fab2(sch_1):page226_i82"
				( objectStatus "F757" )
			)
			( gate "@baseboard_fab2_lib.baseboard_fab2(sch_1):page229_i51"
				( objectStatus "F710" )
			)
			( gate "@baseboard_fab2_lib.baseboard_fab2(sch_1):page230_i51"
				( objectStatus "F715" )
			)
			( gate "@baseboard_fab2_lib.baseboard_fab2(sch_1):page215_i297"
				( objectStatus "F696" )
			)
			( gate "@baseboard_fab2_lib.baseboard_fab2(sch_1):page218_i12"
				( objectStatus "F707" )
			)
			( gate "@baseboard_fab2_lib.baseboard_fab2(sch_1):page199_i108"
				( objectStatus "F753" )
			)
			( gate "@baseboard_fab2_lib.baseboard_fab2(sch_1):page111_i68"
				( objectStatus "F750" )
			)
			( gate "@baseboard_fab2_lib.baseboard_fab2(sch_1):page145_i187"
				( objectStatus "F670" )
			)
			( gate "@baseboard_fab2_lib.baseboard_fab2(sch_1):page145_i188"
				( objectStatus "F669" )
			)
			( gate "@baseboard_fab2_lib.baseboard_fab2(sch_1):page136_i126"
				( objectStatus "F686" )
			)
			( gate "@baseboard_fab2_lib.baseboard_fab2(sch_1):page156_i214"
				( objectStatus "F685" )
			)
			( gate "@baseboard_fab2_lib.baseboard_fab2(sch_1):page153_i109"
				( objectStatus "F698" )
				( pin "A"
					( objectStatus "R7F3.1" )
				)
				( pin "B"
					( objectStatus "R7F3.2" )
				)
			)
			( gate "@baseboard_fab2_lib.baseboard_fab2(sch_1):page153_i157"
				( objectStatus "F719" )
			)
			( gate "@baseboard_fab2_lib.baseboard_fab2(sch_1):page153_i181"
				( objectStatus "F695" )
				( pin "B"
					( objectStatus "R7F29.2" )
				)
			)
			( gate "@baseboard_fab2_lib.baseboard_fab2(sch_1):page153_i184"
				( objectStatus "F717" )
				( pin "A"
					( objectStatus "R3T10.1" )
				)
				( pin "B"
					( objectStatus "R3T10.2" )
				)
			)
			( gate "@baseboard_fab2_lib.baseboard_fab2(sch_1):page153_i108"
				( objectStatus "F694" )
			)
			( gate "@baseboard_fab2_lib.baseboard_fab2(sch_1):page153_i156"
				( objectStatus "F716" )
			)
			( gate "@baseboard_fab2_lib.baseboard_fab2(sch_1):page184_i88"
				( objectStatus "F690" )
				( pin "A"
					( objectStatus "R8E9.1" )
				)
				( pin "B"
					( objectStatus "R8E9.2" )
				)
			)
			( gate "@baseboard_fab2_lib.baseboard_fab2(sch_1):page184_i95"
				( objectStatus "F689" )
				( pin "A"
					( objectStatus "R8E10.1" )
				)
				( pin "B"
					( objectStatus "R8E10.2" )
				)
			)
			( gate "@baseboard_fab2_lib.baseboard_fab2(sch_1):page184_i93"
				( objectStatus "F688" )
				( pin "A"
					( objectStatus "R8E13.1" )
				)
				( pin "B"
					( objectStatus "R8E13.2" )
				)
			)
			( gate "@baseboard_fab2_lib.baseboard_fab2(sch_1):page121_i68"
				( objectStatus "F693" )
			)
			( gate "@baseboard_fab2_lib.baseboard_fab2(sch_1):page121_i69"
				( objectStatus "F706" )
			)
			( gate "@baseboard_fab2_lib.baseboard_fab2(sch_1):page139_i235"
				( objectStatus "F674" )
			)
			( gate "@baseboard_fab2_lib.baseboard_fab2(sch_1):page101_i130"
				( objectStatus "F729" )
			)
			( gate "@baseboard_fab2_lib.baseboard_fab2(sch_1):page101_i133"
				( objectStatus "F680" )
			)
			( gate "@baseboard_fab2_lib.baseboard_fab2(sch_1):page144_i554"
				( objectStatus "F724" )
			)
			( gate "@baseboard_fab2_lib.baseboard_fab2(sch_1):page144_i553"
				( objectStatus "F728" )
			)
			( gate "@baseboard_fab2_lib.baseboard_fab2(sch_1):page144_i555"
				( objectStatus "F726" )
			)
			( gate "@baseboard_fab2_lib.baseboard_fab2(sch_1):page101_i131"
				( objectStatus "F749" )
			)
			( gate "@baseboard_fab2_lib.baseboard_fab2(sch_1):page101_i132"
				( objectStatus "F704" )
			)
			( gate "@baseboard_fab2_lib.baseboard_fab2(sch_1):page144_i527"
				( objectStatus "F727" )
			)
			( gate "@baseboard_fab2_lib.baseboard_fab2(sch_1):page157_i358"
				( objectStatus "F736" )
			)
			( gate "@baseboard_fab2_lib.baseboard_fab2(sch_1):page119_i172"
				( objectStatus "F742" )
			)
			( gate "@baseboard_fab2_lib.baseboard_fab2(sch_1):page119_i173"
				( objectStatus "F740" )
			)
			( gate "@baseboard_fab2_lib.baseboard_fab2(sch_1):page119_i174"
				( objectStatus "F741" )
			)
			( gate "@baseboard_fab2_lib.baseboard_fab2(sch_1):page120_i218"
				( objectStatus "F743" )
			)
			( gate "@baseboard_fab2_lib.baseboard_fab2(sch_1):page120_i219"
				( objectStatus "F739" )
			)
			( gate "@baseboard_fab2_lib.baseboard_fab2(sch_1):page119_i189"
				( objectStatus "F735" )
			)
			( gate "@baseboard_fab2_lib.baseboard_fab2(sch_1):page92_i61"
				( objectStatus "F720" )
			)
			( gate "@baseboard_fab2_lib.baseboard_fab2(sch_1):page92_i70"
				( objectStatus "F702" )
			)
			( gate "@baseboard_fab2_lib.baseboard_fab2(sch_1):page93_i62"
				( objectStatus "F703" )
			)
			( gate "@baseboard_fab2_lib.baseboard_fab2(sch_1):page92_i14"
				( objectStatus "F723" )
			)
			( gate "@baseboard_fab2_lib.baseboard_fab2(sch_1):page92_i13"
				( objectStatus "F722" )
			)
			( gate "@baseboard_fab2_lib.baseboard_fab2(sch_1):page92_i12"
				( objectStatus "F721" )
			)
			( gate "@baseboard_fab2_lib.baseboard_fab2(sch_1):page92_i24"
				( objectStatus "F699" )
			)
			( gate "@baseboard_fab2_lib.baseboard_fab2(sch_1):page92_i29"
				( objectStatus "F700" )
			)
			( gate "@baseboard_fab2_lib.baseboard_fab2(sch_1):page92_i30"
				( objectStatus "F701" )
			)
			( gate "@baseboard_fab2_lib.baseboard_fab2(sch_1):page93_i42"
				( objectStatus "F732" )
			)
			( gate "@baseboard_fab2_lib.baseboard_fab2(sch_1):page93_i40"
				( objectStatus "F731" )
			)
			( gate "@baseboard_fab2_lib.baseboard_fab2(sch_1):page93_i39"
				( objectStatus "F730" )
			)
			( gate "@baseboard_fab2_lib.baseboard_fab2(sch_1):page146_i108"
				( objectStatus "F671" )
				( pin "A"
					( objectStatus "R9F41.1" )
				)
				( pin "B"
					( objectStatus "R9F41.2" )
				)
			)
			( gate "@baseboard_fab2_lib.baseboard_fab2(sch_1):page146_i109"
				( objectStatus "F673" )
				( pin "A"
					( objectStatus "R9F21.1" )
				)
				( pin "B"
					( objectStatus "R9F21.2" )
				)
			)
			( gate "@baseboard_fab2_lib.baseboard_fab2(sch_1):page144_i521"
				( objectStatus "F725" )
			)
			( gate "@baseboard_fab2_lib.baseboard_fab2(sch_1):page144_i520"
				( objectStatus "F734" )
			)
			( gate "@baseboard_fab2_lib.baseboard_fab2(sch_1):page152_i6"
				( objectStatus "F744" )
			)
			( gate "@baseboard_fab2_lib.baseboard_fab2(sch_1):page152_i14"
				( objectStatus "F745" )
			)
			( gate "@baseboard_fab2_lib.baseboard_fab2(sch_1):page152_i15"
				( objectStatus "F747" )
			)
			( gate "@baseboard_fab2_lib.baseboard_fab2(sch_1):page152_i16"
				( objectStatus "F748" )
			)
			( gate "@baseboard_fab2_lib.baseboard_fab2(sch_1):page142_i2"
				( objectStatus "F687" )
			)
			( gate "@baseboard_fab2_lib.baseboard_fab2(sch_1):page175_i13"
				( objectStatus "F751" )
			)
			( gate "@baseboard_fab2_lib.baseboard_fab2(sch_1):page153_i167"
				( objectStatus "F684" )
				( pin "A"
					( objectStatus "R8F7.1" )
				)
				( pin "B"
					( objectStatus "R8F7.2" )
				)
			)
			( gate "@baseboard_fab2_lib.baseboard_fab2(sch_1):page181_i218"
				( objectStatus "F691" )
			)
			( gate "@baseboard_fab2_lib.baseboard_fab2(sch_1):page153_i155"
				( objectStatus "F718" )
				( pin "A"
					( objectStatus "R3T2.1" )
				)
				( pin "B"
					( objectStatus "R3T2.2" )
				)
			)
			( gate "@baseboard_fab2_lib.baseboard_fab2(sch_1):page162_i13"
				( objectStatus "F682" )
				( pin "A"
					( objectStatus "R8F12.1" )
				)
				( pin "B"
					( objectStatus "R8F12.2" )
				)
			)
			( gate "@baseboard_fab2_lib.baseboard_fab2(sch_1):page101_i20"
				( objectStatus "F681" )
			)
			( gate "@baseboard_fab2_lib.baseboard_fab2(sch_1):page140_i17"
				( objectStatus "F677" )
			)
			( gate "@baseboard_fab2_lib.baseboard_fab2(sch_1):page139_i129"
				( objectStatus "F678" )
			)
			( gate "@baseboard_fab2_lib.baseboard_fab2(sch_1):page139_i128"
				( objectStatus "F675" )
			)
			( gate "@baseboard_fab2_lib.baseboard_fab2(sch_1):page139_i130"
				( objectStatus "F676" )
			)
			( gate "@baseboard_fab2_lib.baseboard_fab2(sch_1):page153_i166"
				( objectStatus "F683" )
				( pin "A"
					( objectStatus "R8F8.1" )
				)
				( pin "B"
					( objectStatus "R8F8.2" )
				)
			)
			( gate "@baseboard_fab2_lib.baseboard_fab2(sch_1):page121_i33"
				( objectStatus "F705" )
			)
			( gate "@baseboard_fab2_lib.baseboard_fab2(sch_1):page134_i14"
				( objectStatus "F679" )
			)
			( gate "@baseboard_fab2_lib.baseboard_fab2(sch_1):page153_i98"
				( objectStatus "F697" )
				( pin "A"
					( objectStatus "R7F4.1" )
				)
				( pin "B"
					( objectStatus "R7F4.2" )
				)
			)
			( gate "@baseboard_fab2_lib.baseboard_fab2(sch_1):page191_i193"
				( objectStatus "F529" )
			)
			( gate "@baseboard_fab2_lib.baseboard_fab2(sch_1):page161_i70"
				( objectStatus "F650" )
			)
			( gate "@baseboard_fab2_lib.baseboard_fab2(sch_1):page161_i45"
				( objectStatus "F645" )
			)
			( gate "@baseboard_fab2_lib.baseboard_fab2(sch_1):page135_i104"
				( objectStatus "F557" )
			)
			( gate "@baseboard_fab2_lib.baseboard_fab2(sch_1):page108_i343"
				( objectStatus "F531" )
			)
			( gate "@baseboard_fab2_lib.baseboard_fab2(sch_1):page119_i213"
				( objectStatus "F530" )
			)
			( gate "@baseboard_fab2_lib.baseboard_fab2(sch_1):page166_i28"
				( objectStatus "F600" )
			)
			( gate "@baseboard_fab2_lib.baseboard_fab2(sch_1):page133_i243"
				( objectStatus "F599" )
			)
			( gate "@baseboard_fab2_lib.baseboard_fab2(sch_1):page133_i341"
				( objectStatus "F590" )
			)
			( gate "@baseboard_fab2_lib.baseboard_fab2(sch_1):page133_i301"
				( objectStatus "F573" )
			)
			( gate "@baseboard_fab2_lib.baseboard_fab2(sch_1):page156_i340"
				( objectStatus "F532" )
			)
			( gate "@baseboard_fab2_lib.baseboard_fab2(sch_1):page156_i294"
				( objectStatus "F535" )
			)
			( gate "@baseboard_fab2_lib.baseboard_fab2(sch_1):page133_i356"
				( objectStatus "F534" )
			)
			( gate "@baseboard_fab2_lib.baseboard_fab2(sch_1):page133_i357"
				( objectStatus "F533" )
			)
			( gate "@baseboard_fab2_lib.baseboard_fab2(sch_1):page133_i349"
				( objectStatus "F537" )
			)
			( gate "@baseboard_fab2_lib.baseboard_fab2(sch_1):page133_i352"
				( objectStatus "F536" )
			)
			( gate "@baseboard_fab2_lib.baseboard_fab2(sch_1):page196_i115"
				( objectStatus "F538" )
			)
			( gate "@baseboard_fab2_lib.baseboard_fab2(sch_1):page192_i48"
				( objectStatus "F629" )
			)
			( gate "@baseboard_fab2_lib.baseboard_fab2(sch_1):page192_i49"
				( objectStatus "F614" )
			)
			( gate "@baseboard_fab2_lib.baseboard_fab2(sch_1):page102_i93"
				( objectStatus "F604" )
			)
			( gate "@baseboard_fab2_lib.baseboard_fab2(sch_1):page102_i94"
				( objectStatus "F601" )
			)
			( gate "@baseboard_fab2_lib.baseboard_fab2(sch_1):page154_i127"
				( objectStatus "F625" )
			)
			( gate "@baseboard_fab2_lib.baseboard_fab2(sch_1):page21_i258"
				( objectStatus "F607" )
			)
			( gate "@baseboard_fab2_lib.baseboard_fab2(sch_1):page55_i181"
				( objectStatus "F602" )
			)
			( gate "@baseboard_fab2_lib.baseboard_fab2(sch_1):page170_i71"
				( objectStatus "F571" )
			)
			( gate "@baseboard_fab2_lib.baseboard_fab2(sch_1):page170_i73"
				( objectStatus "F641" )
			)
			( gate "@baseboard_fab2_lib.baseboard_fab2(sch_1):page157_i385"
				( objectStatus "F564" )
			)
			( gate "@baseboard_fab2_lib.baseboard_fab2(sch_1):page161_i135"
				( objectStatus "F540" )
			)
			( gate "@baseboard_fab2_lib.baseboard_fab2(sch_1):page161_i126"
				( objectStatus "F649" )
			)
			( gate "@baseboard_fab2_lib.baseboard_fab2(sch_1):page133_i333"
				( objectStatus "F574" )
			)
			( gate "@baseboard_fab2_lib.baseboard_fab2(sch_1):page177_i82"
				( objectStatus "F543" )
			)
			( gate "@baseboard_fab2_lib.baseboard_fab2(sch_1):page177_i76"
				( objectStatus "F547" )
			)
			( gate "@baseboard_fab2_lib.baseboard_fab2(sch_1):page196_i59"
				( objectStatus "F613" )
			)
			( gate "@baseboard_fab2_lib.baseboard_fab2(sch_1):page157_i382"
				( objectStatus "F644" )
			)
			( gate "@baseboard_fab2_lib.baseboard_fab2(sch_1):page200_i204"
				( objectStatus "F648" )
			)
			( gate "@baseboard_fab2_lib.baseboard_fab2(sch_1):page150_i66"
				( objectStatus "F640" )
			)
			( gate "@baseboard_fab2_lib.baseboard_fab2(sch_1):page157_i335"
				( objectStatus "F572" )
			)
			( gate "@baseboard_fab2_lib.baseboard_fab2(sch_1):page134_i27"
				( objectStatus "F597" )
			)
			( gate "@baseboard_fab2_lib.baseboard_fab2(sch_1):page189_i56"
				( objectStatus "F558" )
			)
			( gate "@baseboard_fab2_lib.baseboard_fab2(sch_1):page102_i91"
				( objectStatus "F615" )
			)
			( gate "@baseboard_fab2_lib.baseboard_fab2(sch_1):page136_i133"
				( objectStatus "F568" )
			)
			( gate "@baseboard_fab2_lib.baseboard_fab2(sch_1):page156_i267"
				( objectStatus "F559" )
			)
			( gate "@baseboard_fab2_lib.baseboard_fab2(sch_1):page156_i265"
				( objectStatus "F621" )
			)
			( gate "@baseboard_fab2_lib.baseboard_fab2(sch_1):page157_i367"
				( objectStatus "F620" )
			)
			( gate "@baseboard_fab2_lib.baseboard_fab2(sch_1):page157_i361"
				( objectStatus "F567" )
			)
			( gate "@baseboard_fab2_lib.baseboard_fab2(sch_1):page126_i12"
				( objectStatus "F647" )
			)
			( gate "@baseboard_fab2_lib.baseboard_fab2(sch_1):page170_i61"
				( objectStatus "F628" )
			)
			( gate "@baseboard_fab2_lib.baseboard_fab2(sch_1):page170_i65"
				( objectStatus "F553" )
			)
			( gate "@baseboard_fab2_lib.baseboard_fab2(sch_1):page119_i186"
				( objectStatus "F555" )
			)
			( gate "@baseboard_fab2_lib.baseboard_fab2(sch_1):page119_i183"
				( objectStatus "F556" )
			)
			( gate "@baseboard_fab2_lib.baseboard_fab2(sch_1):page147_i140"
				( objectStatus "F581" )
			)
			( gate "@baseboard_fab2_lib.baseboard_fab2(sch_1):page157_i348"
				( objectStatus "F635" )
			)
			( gate "@baseboard_fab2_lib.baseboard_fab2(sch_1):page170_i54"
				( objectStatus "F626" )
			)
			( gate "@baseboard_fab2_lib.baseboard_fab2(sch_1):page170_i56"
				( objectStatus "F631" )
			)
			( gate "@baseboard_fab2_lib.baseboard_fab2(sch_1):page133_i326"
				( objectStatus "F579" )
			)
			( gate "@baseboard_fab2_lib.baseboard_fab2(sch_1):page133_i327"
				( objectStatus "F576" )
			)
			( gate "@baseboard_fab2_lib.baseboard_fab2(sch_1):page126_i20"
				( objectStatus "F575" )
			)
			( gate "@baseboard_fab2_lib.baseboard_fab2(sch_1):page156_i206"
				( objectStatus "F623" )
			)
			( gate "@baseboard_fab2_lib.baseboard_fab2(sch_1):page156_i207"
				( objectStatus "F622" )
			)
			( gate "@baseboard_fab2_lib.baseboard_fab2(sch_1):page102_i53"
				( objectStatus "F608" )
			)
			( gate "@baseboard_fab2_lib.baseboard_fab2(sch_1):page133_i309"
				( objectStatus "F634" )
			)
			( gate "@baseboard_fab2_lib.baseboard_fab2(sch_1):page161_i51"
				( objectStatus "F646" )
			)
			( gate "@baseboard_fab2_lib.baseboard_fab2(sch_1):page161_i65"
				( objectStatus "F592" )
				( pin "B"
					( objectStatus "R7F33.2" )
				)
			)
			( gate "@baseboard_fab2_lib.baseboard_fab2(sch_1):page133_i306"
				( objectStatus "F598" )
			)
			( gate "@baseboard_fab2_lib.baseboard_fab2(sch_1):page133_i303"
				( objectStatus "F577" )
			)
			( gate "@baseboard_fab2_lib.baseboard_fab2(sch_1):page133_i304"
				( objectStatus "F578" )
			)
			( gate "@baseboard_fab2_lib.baseboard_fab2(sch_1):page133_i307"
				( objectStatus "F580" )
			)
			( gate "@baseboard_fab2_lib.baseboard_fab2(sch_1):page170_i2"
				( objectStatus "F632" )
			)
			( gate "@baseboard_fab2_lib.baseboard_fab2(sch_1):page157_i346"
				( objectStatus "F636" )
			)
			( gate "@baseboard_fab2_lib.baseboard_fab2(sch_1):page147_i137"
				( objectStatus "F554" )
			)
			( gate "@baseboard_fab2_lib.baseboard_fab2(sch_1):page157_i342"
				( objectStatus "F617" )
			)
			( gate "@baseboard_fab2_lib.baseboard_fab2(sch_1):page157_i344"
				( objectStatus "F618" )
			)
			( gate "@baseboard_fab2_lib.baseboard_fab2(sch_1):page170_i52"
				( objectStatus "F630" )
			)
			( gate "@baseboard_fab2_lib.baseboard_fab2(sch_1):page191_i172"
				( objectStatus "F627" )
			)
			( gate "@baseboard_fab2_lib.baseboard_fab2(sch_1):page181_i177"
				( objectStatus "F539" )
			)
			( gate "@baseboard_fab2_lib.baseboard_fab2(sch_1):page95_i106"
				( objectStatus "F596" )
			)
			( gate "@baseboard_fab2_lib.baseboard_fab2(sch_1):page150_i51"
				( objectStatus "F546" )
			)
			( gate "@baseboard_fab2_lib.baseboard_fab2(sch_1):page125_i76"
				( objectStatus "F619" )
			)
			( gate "@baseboard_fab2_lib.baseboard_fab2(sch_1):page183_i4"
				( objectStatus "F544" )
			)
			( gate "@baseboard_fab2_lib.baseboard_fab2(sch_1):page183_i30"
				( objectStatus "F542" )
			)
			( gate "@baseboard_fab2_lib.baseboard_fab2(sch_1):page89_i26"
				( objectStatus "F570" )
			)
			( gate "@baseboard_fab2_lib.baseboard_fab2(sch_1):page89_i27"
				( objectStatus "F569" )
			)
			( gate "@baseboard_fab2_lib.baseboard_fab2(sch_1):page91_i24"
				( objectStatus "F589" )
			)
			( gate "@baseboard_fab2_lib.baseboard_fab2(sch_1):page91_i22"
				( objectStatus "F588" )
			)
			( gate "@baseboard_fab2_lib.baseboard_fab2(sch_1):page91_i21"
				( objectStatus "F582" )
			)
			( gate "@baseboard_fab2_lib.baseboard_fab2(sch_1):page91_i20"
				( objectStatus "F583" )
			)
			( gate "@baseboard_fab2_lib.baseboard_fab2(sch_1):page91_i18"
				( objectStatus "F584" )
			)
			( gate "@baseboard_fab2_lib.baseboard_fab2(sch_1):page91_i17"
				( objectStatus "F585" )
			)
			( gate "@baseboard_fab2_lib.baseboard_fab2(sch_1):page91_i16"
				( objectStatus "F586" )
			)
			( gate "@baseboard_fab2_lib.baseboard_fab2(sch_1):page91_i14"
				( objectStatus "F587" )
			)
			( gate "@baseboard_fab2_lib.baseboard_fab2(sch_1):page150_i47"
				( objectStatus "F551" )
			)
			( gate "@baseboard_fab2_lib.baseboard_fab2(sch_1):page150_i52"
				( objectStatus "F552" )
			)
			( gate "@baseboard_fab2_lib.baseboard_fab2(sch_1):page150_i54"
				( objectStatus "F639" )
			)
			( gate "@baseboard_fab2_lib.baseboard_fab2(sch_1):page150_i56"
				( objectStatus "F549" )
			)
			( gate "@baseboard_fab2_lib.baseboard_fab2(sch_1):page150_i65"
				( objectStatus "F545" )
			)
			( gate "@baseboard_fab2_lib.baseboard_fab2(sch_1):page95_i62"
				( objectStatus "F595" )
			)
			( gate "@baseboard_fab2_lib.baseboard_fab2(sch_1):page95_i72"
				( objectStatus "F594" )
			)
			( gate "@baseboard_fab2_lib.baseboard_fab2(sch_1):page118_i71"
				( objectStatus "F616" )
			)
			( gate "@baseboard_fab2_lib.baseboard_fab2(sch_1):page150_i111"
				( objectStatus "F550" )
			)
			( gate "@baseboard_fab2_lib.baseboard_fab2(sch_1):page154_i105"
				( objectStatus "F624" )
			)
			( gate "@baseboard_fab2_lib.baseboard_fab2(sch_1):page142_i3"
				( objectStatus "F565" )
			)
			( gate "@baseboard_fab2_lib.baseboard_fab2(sch_1):page156_i215"
				( objectStatus "F566" )
			)
			( gate "@baseboard_fab2_lib.baseboard_fab2(sch_1):page102_i45"
				( objectStatus "F609" )
			)
			( gate "@baseboard_fab2_lib.baseboard_fab2(sch_1):page175_i5"
				( objectStatus "F643" )
			)
			( gate "@baseboard_fab2_lib.baseboard_fab2(sch_1):page165_i56"
				( objectStatus "F637" )
			)
			( gate "@baseboard_fab2_lib.baseboard_fab2(sch_1):page165_i55"
				( objectStatus "F638" )
			)
			( gate "@baseboard_fab2_lib.baseboard_fab2(sch_1):page165_i69"
				( objectStatus "F541" )
			)
			( gate "@baseboard_fab2_lib.baseboard_fab2(sch_1):page94_i94"
				( objectStatus "F605" )
			)
			( gate "@baseboard_fab2_lib.baseboard_fab2(sch_1):page94_i91"
				( objectStatus "F606" )
			)
			( gate "@baseboard_fab2_lib.baseboard_fab2(sch_1):page157_i316"
				( objectStatus "F561" )
			)
			( gate "@baseboard_fab2_lib.baseboard_fab2(sch_1):page153_i152"
				( objectStatus "F610" )
				( pin "B"
					( objectStatus "R3T5.2" )
				)
			)
			( gate "@baseboard_fab2_lib.baseboard_fab2(sch_1):page162_i9"
				( objectStatus "F562" )
			)
			( gate "@baseboard_fab2_lib.baseboard_fab2(sch_1):page162_i23"
				( objectStatus "F563" )
				( pin "B"
					( objectStatus "R8F13.2" )
				)
			)
			( gate "@baseboard_fab2_lib.baseboard_fab2(sch_1):page162_i22"
				( objectStatus "F560" )
			)
			( gate "@baseboard_fab2_lib.baseboard_fab2(sch_1):page153_i94"
				( objectStatus "F593" )
				( pin "B"
					( objectStatus "R7F5.2" )
				)
			)
			( gate "@baseboard_fab2_lib.baseboard_fab2(sch_1):page111_i66"
				( objectStatus "F642" )
			)
			( gate "@baseboard_fab2_lib.baseboard_fab2(sch_1):page151_i71"
				( objectStatus "F548" )
			)
			( gate "@baseboard_fab2_lib.baseboard_fab2(sch_1):page94_i51"
				( objectStatus "F591" )
			)
			( gate "@baseboard_fab2_lib.baseboard_fab2(sch_1):page94_i66"
				( objectStatus "F612" )
			)
			( gate "@baseboard_fab2_lib.baseboard_fab2(sch_1):page94_i79"
				( objectStatus "F611" )
			)
			( gate "@baseboard_fab2_lib.baseboard_fab2(sch_1):page94_i82"
				( objectStatus "F603" )
			)
			( gate "@baseboard_fab2_lib.baseboard_fab2(sch_1):page157_i97"
				( objectStatus "F633" )
			)
			( gate "@baseboard_fab2_lib.baseboard_fab2(sch_1):page93_i67"
				( objectStatus "F304" )
			)
			( gate "@baseboard_fab2_lib.baseboard_fab2(sch_1):page93_i68"
				( objectStatus "F303" )
			)
			( gate "@baseboard_fab2_lib.baseboard_fab2(sch_1):page154_i62"
				( objectStatus "F305" )
				( pin "A"
					( objectStatus "R2T9.1" )
				)
				( pin "B"
					( objectStatus "R2T9.2" )
				)
			)
			( gate "@baseboard_fab2_lib.baseboard_fab2(sch_1):page92_i9"
				( objectStatus "F301" )
			)
			( gate "@baseboard_fab2_lib.baseboard_fab2(sch_1):page92_i96"
				( objectStatus "F302" )
			)
			( gate "@baseboard_fab2_lib.baseboard_fab2(sch_1):page92_i19"
				( objectStatus "F300" )
			)
			( gate "@baseboard_fab2_lib.baseboard_fab2(sch_1):page151_i1"
				( objectStatus "F2056" )
			)
			( gate "@baseboard_fab2_lib.baseboard_fab2(sch_1):page158_i86"
				( objectStatus "F1173" )
			)
			( gate "@baseboard_fab2_lib.baseboard_fab2(sch_1):page186_i222"
				( objectStatus "F1174" )
			)
			( gate "@baseboard_fab2_lib.baseboard_fab2(sch_1):page187_i18"
				( objectStatus "F1208" )
			)
			( gate "@baseboard_fab2_lib.baseboard_fab2(sch_1):page196_i106"
				( objectStatus "F1168" )
			)
			( gate "@baseboard_fab2_lib.baseboard_fab2(sch_1):page112_i76"
				( objectStatus "F1213" )
				( pin "B"
					( objectStatus "R1L39.2" )
				)
			)
			( gate "@baseboard_fab2_lib.baseboard_fab2(sch_1):page112_i51"
				( objectStatus "F1211" )
			)
			( gate "@baseboard_fab2_lib.baseboard_fab2(sch_1):page161_i134"
				( objectStatus "F1170" )
			)
			( gate "@baseboard_fab2_lib.baseboard_fab2(sch_1):page161_i124"
				( objectStatus "F1219" )
			)
			( gate "@baseboard_fab2_lib.baseboard_fab2(sch_1):page236_i90"
				( objectStatus "F1182" )
			)
			( gate "@baseboard_fab2_lib.baseboard_fab2(sch_1):page112_i54"
				( objectStatus "F1210" )
			)
			( gate "@baseboard_fab2_lib.baseboard_fab2(sch_1):page215_i295"
				( objectStatus "F1197" )
				( pin "B"
					( objectStatus "R3U2.2" )
				)
			)
			( gate "@baseboard_fab2_lib.baseboard_fab2(sch_1):page112_i57"
				( objectStatus "F1190" )
				( pin "B"
					( objectStatus "R4P12.2" )
				)
			)
			( gate "@baseboard_fab2_lib.baseboard_fab2(sch_1):page112_i53"
				( objectStatus "F1189" )
				( pin "B"
					( objectStatus "R4P15.2" )
				)
			)
			( gate "@baseboard_fab2_lib.baseboard_fab2(sch_1):page223_i8"
				( objectStatus "F1169" )
				( pin "B"
					( objectStatus "R9U3.2" )
				)
			)
			( gate "@baseboard_fab2_lib.baseboard_fab2(sch_1):page196_i65"
				( objectStatus "F1176" )
			)
			( gate "@baseboard_fab2_lib.baseboard_fab2(sch_1):page112_i77"
				( objectStatus "F1212" )
				( pin "B"
					( objectStatus "R1L41.2" )
				)
			)
			( gate "@baseboard_fab2_lib.baseboard_fab2(sch_1):page175_i35"
				( objectStatus "F1175" )
			)
			( gate "@baseboard_fab2_lib.baseboard_fab2(sch_1):page152_i26"
				( objectStatus "F1209" )
			)
			( gate "@baseboard_fab2_lib.baseboard_fab2(sch_1):page161_i43"
				( objectStatus "F1214" )
				( pin "B"
					( objectStatus "R1F2.2" )
				)
			)
			( gate "@baseboard_fab2_lib.baseboard_fab2(sch_1):page161_i67"
				( objectStatus "F1220" )
				( pin "B"
					( objectStatus "R1B22.2" )
				)
			)
			( gate "@baseboard_fab2_lib.baseboard_fab2(sch_1):page214_i101"
				( objectStatus "F1204" )
			)
			( gate "@baseboard_fab2_lib.baseboard_fab2(sch_1):page212_i74"
				( objectStatus "F1199" )
			)
			( gate "@baseboard_fab2_lib.baseboard_fab2(sch_1):page214_i105"
				( objectStatus "F1203" )
			)
			( gate "@baseboard_fab2_lib.baseboard_fab2(sch_1):page212_i68"
				( objectStatus "F1200" )
			)
			( gate "@baseboard_fab2_lib.baseboard_fab2(sch_1):page209_i15"
				( objectStatus "F1216" )
			)
			( gate "@baseboard_fab2_lib.baseboard_fab2(sch_1):page209_i9"
				( objectStatus "F1215" )
			)
			( gate "@baseboard_fab2_lib.baseboard_fab2(sch_1):page93_i98"
				( objectStatus "F1207" )
			)
			( gate "@baseboard_fab2_lib.baseboard_fab2(sch_1):page116_i181"
				( objectStatus "F1201" )
			)
			( gate "@baseboard_fab2_lib.baseboard_fab2(sch_1):page121_i35"
				( objectStatus "F1177" )
			)
			( gate "@baseboard_fab2_lib.baseboard_fab2(sch_1):page120_i148"
				( objectStatus "F1178" )
			)
			( gate "@baseboard_fab2_lib.baseboard_fab2(sch_1):page112_i50"
				( objectStatus "F1179" )
				( pin "B"
					( objectStatus "R7P30.2" )
				)
			)
			( gate "@baseboard_fab2_lib.baseboard_fab2(sch_1):page112_i49"
				( objectStatus "F1185" )
				( pin "B"
					( objectStatus "R6P46.2" )
				)
			)
			( gate "@baseboard_fab2_lib.baseboard_fab2(sch_1):page112_i121"
				( objectStatus "F1184" )
				( pin "B"
					( objectStatus "R6T8.2" )
				)
			)
			( gate "@baseboard_fab2_lib.baseboard_fab2(sch_1):page112_i120"
				( objectStatus "F1183" )
				( pin "B"
					( objectStatus "R6T9.2" )
				)
			)
			( gate "@baseboard_fab2_lib.baseboard_fab2(sch_1):page205_i24"
				( objectStatus "F1195" )
			)
			( gate "@baseboard_fab2_lib.baseboard_fab2(sch_1):page204_i60"
				( objectStatus "F1193" )
			)
			( gate "@baseboard_fab2_lib.baseboard_fab2(sch_1):page204_i64"
				( objectStatus "F1192" )
			)
			( gate "@baseboard_fab2_lib.baseboard_fab2(sch_1):page21_i159"
				( objectStatus "F1188" )
				( pin "B"
					( objectStatus "R6B2.2" )
				)
			)
			( gate "@baseboard_fab2_lib.baseboard_fab2(sch_1):page21_i163"
				( objectStatus "F1186" )
				( pin "A"
					( objectStatus "R6N2.1" )
				)
			)
			( gate "@baseboard_fab2_lib.baseboard_fab2(sch_1):page55_i7"
				( objectStatus "F1172" )
				( pin "B"
					( objectStatus "R9N2.2" )
				)
			)
			( gate "@baseboard_fab2_lib.baseboard_fab2(sch_1):page55_i21"
				( objectStatus "F1206" )
				( pin "A"
					( objectStatus "R3B4.1" )
				)
			)
			( gate "@baseboard_fab2_lib.baseboard_fab2(sch_1):page201_i20"
				( objectStatus "F1194" )
			)
			( gate "@baseboard_fab2_lib.baseboard_fab2(sch_1):page206_i4"
				( objectStatus "F1171" )
				( pin "B"
					( objectStatus "R9P1.2" )
				)
			)
			( gate "@baseboard_fab2_lib.baseboard_fab2(sch_1):page210_i29"
				( objectStatus "F1217" )
			)
			( gate "@baseboard_fab2_lib.baseboard_fab2(sch_1):page210_i33"
				( objectStatus "F1218" )
			)
			( gate "@baseboard_fab2_lib.baseboard_fab2(sch_1):page205_i29"
				( objectStatus "F1196" )
			)
			( gate "@baseboard_fab2_lib.baseboard_fab2(sch_1):page116_i108"
				( objectStatus "F1202" )
			)
			( gate "@baseboard_fab2_lib.baseboard_fab2(sch_1):page92_i38"
				( objectStatus "F1198" )
			)
			( gate "@baseboard_fab2_lib.baseboard_fab2(sch_1):page92_i48"
				( objectStatus "F1181" )
			)
			( gate "@baseboard_fab2_lib.baseboard_fab2(sch_1):page21_i182"
				( objectStatus "F1191" )
			)
			( gate "@baseboard_fab2_lib.baseboard_fab2(sch_1):page21_i179"
				( objectStatus "F1187" )
			)
			( gate "@baseboard_fab2_lib.baseboard_fab2(sch_1):page55_i115"
				( objectStatus "F1180" )
			)
			( gate "@baseboard_fab2_lib.baseboard_fab2(sch_1):page55_i118"
				( objectStatus "F1205" )
			)
			( gate "@baseboard_fab2_lib.baseboard_fab2(sch_1):page90_i72"
				( objectStatus "F446" )
			)
			( gate "@baseboard_fab2_lib.baseboard_fab2(sch_1):page90_i74"
				( objectStatus "F420" )
			)
			( gate "@baseboard_fab2_lib.baseboard_fab2(sch_1):page113_i134"
				( objectStatus "F445" )
			)
			( gate "@baseboard_fab2_lib.baseboard_fab2(sch_1):page113_i180"
				( objectStatus "F428" )
			)
			( gate "@baseboard_fab2_lib.baseboard_fab2(sch_1):page113_i195"
				( objectStatus "F427" )
			)
			( gate "@baseboard_fab2_lib.baseboard_fab2(sch_1):page113_i188"
				( objectStatus "F426" )
			)
			( gate "@baseboard_fab2_lib.baseboard_fab2(sch_1):page156_i288"
				( objectStatus "F461" )
			)
			( gate "@baseboard_fab2_lib.baseboard_fab2(sch_1):page196_i68"
				( objectStatus "F465" )
			)
			( gate "@baseboard_fab2_lib.baseboard_fab2(sch_1):page90_i79"
				( objectStatus "F442" )
			)
			( gate "@baseboard_fab2_lib.baseboard_fab2(sch_1):page90_i80"
				( objectStatus "F441" )
			)
			( gate "@baseboard_fab2_lib.baseboard_fab2(sch_1):page90_i81"
				( objectStatus "F436" )
			)
			( gate "@baseboard_fab2_lib.baseboard_fab2(sch_1):page90_i85"
				( objectStatus "F414" )
			)
			( gate "@baseboard_fab2_lib.baseboard_fab2(sch_1):page90_i86"
				( objectStatus "F413" )
			)
			( gate "@baseboard_fab2_lib.baseboard_fab2(sch_1):page90_i88"
				( objectStatus "F457" )
			)
			( gate "@baseboard_fab2_lib.baseboard_fab2(sch_1):page22_i190"
				( objectStatus "F440" )
			)
			( gate "@baseboard_fab2_lib.baseboard_fab2(sch_1):page22_i188"
				( objectStatus "F439" )
			)
			( gate "@baseboard_fab2_lib.baseboard_fab2(sch_1):page56_i173"
				( objectStatus "F412" )
			)
			( gate "@baseboard_fab2_lib.baseboard_fab2(sch_1):page56_i174"
				( objectStatus "F411" )
			)
			( gate "@baseboard_fab2_lib.baseboard_fab2(sch_1):page178_i1"
				( objectStatus "F415" )
			)
			( gate "@baseboard_fab2_lib.baseboard_fab2(sch_1):page178_i8"
				( objectStatus "F416" )
			)
			( gate "@baseboard_fab2_lib.baseboard_fab2(sch_1):page178_i11"
				( objectStatus "F452" )
			)
			( gate "@baseboard_fab2_lib.baseboard_fab2(sch_1):page178_i22"
				( objectStatus "F463" )
			)
			( gate "@baseboard_fab2_lib.baseboard_fab2(sch_1):page178_i21"
				( objectStatus "F417" )
			)
			( gate "@baseboard_fab2_lib.baseboard_fab2(sch_1):page178_i23"
				( objectStatus "F462" )
			)
			( gate "@baseboard_fab2_lib.baseboard_fab2(sch_1):page218_i47"
				( objectStatus "F453" )
				( pin "B"
					( objectStatus "R3L13.2" )
				)
			)
			( gate "@baseboard_fab2_lib.baseboard_fab2(sch_1):page226_i50"
				( objectStatus "F408" )
				( pin "B"
					( objectStatus "R9M6.2" )
				)
			)
			( gate "@baseboard_fab2_lib.baseboard_fab2(sch_1):page201_i52"
				( objectStatus "F450" )
				( pin "B"
					( objectStatus "R4E9.2" )
				)
			)
			( gate "@baseboard_fab2_lib.baseboard_fab2(sch_1):page206_i53"
				( objectStatus "F406" )
				( pin "B"
					( objectStatus "R9P2.2" )
				)
			)
			( gate "@baseboard_fab2_lib.baseboard_fab2(sch_1):page21_i244"
				( objectStatus "F444" )
				( pin "A"
					( objectStatus "R4P18.1" )
				)
			)
			( gate "@baseboard_fab2_lib.baseboard_fab2(sch_1):page55_i170"
				( objectStatus "F419" )
				( pin "A"
					( objectStatus "R7P25.1" )
				)
			)
			( gate "@baseboard_fab2_lib.baseboard_fab2(sch_1):page21_i219"
				( objectStatus "F443" )
			)
			( gate "@baseboard_fab2_lib.baseboard_fab2(sch_1):page55_i156"
				( objectStatus "F418" )
			)
			( gate "@baseboard_fab2_lib.baseboard_fab2(sch_1):page55_i155"
				( objectStatus "F458" )
			)
			( gate "@baseboard_fab2_lib.baseboard_fab2(sch_1):page152_i25"
				( objectStatus "F464" )
			)
			( gate "@baseboard_fab2_lib.baseboard_fab2(sch_1):page89_i3"
				( objectStatus "F430" )
			)
			( gate "@baseboard_fab2_lib.baseboard_fab2(sch_1):page89_i4"
				( objectStatus "F432" )
			)
			( gate "@baseboard_fab2_lib.baseboard_fab2(sch_1):page89_i5"
				( objectStatus "F429" )
			)
			( gate "@baseboard_fab2_lib.baseboard_fab2(sch_1):page89_i6"
				( objectStatus "F431" )
			)
			( gate "@baseboard_fab2_lib.baseboard_fab2(sch_1):page167_i6"
				( objectStatus "F410" )
			)
			( gate "@baseboard_fab2_lib.baseboard_fab2(sch_1):page167_i5"
				( objectStatus "F409" )
			)
			( gate "@baseboard_fab2_lib.baseboard_fab2(sch_1):page167_i25"
				( objectStatus "F405" )
			)
			( gate "@baseboard_fab2_lib.baseboard_fab2(sch_1):page167_i26"
				( objectStatus "F404" )
			)
			( gate "@baseboard_fab2_lib.baseboard_fab2(sch_1):page93_i97"
				( objectStatus "F460" )
			)
			( gate "@baseboard_fab2_lib.baseboard_fab2(sch_1):page96_i25"
				( objectStatus "F454" )
			)
			( gate "@baseboard_fab2_lib.baseboard_fab2(sch_1):page96_i26"
				( objectStatus "F456" )
			)
			( gate "@baseboard_fab2_lib.baseboard_fab2(sch_1):page96_i2"
				( objectStatus "F433" )
			)
			( gate "@baseboard_fab2_lib.baseboard_fab2(sch_1):page96_i3"
				( objectStatus "F435" )
			)
			( gate "@baseboard_fab2_lib.baseboard_fab2(sch_1):page21_i161"
				( objectStatus "F438" )
				( pin "B"
					( objectStatus "R6B1.2" )
				)
			)
			( gate "@baseboard_fab2_lib.baseboard_fab2(sch_1):page21_i164"
				( objectStatus "F425" )
				( pin "A"
					( objectStatus "R6N1.1" )
				)
			)
			( gate "@baseboard_fab2_lib.baseboard_fab2(sch_1):page55_i4"
				( objectStatus "F407" )
				( pin "B"
					( objectStatus "R9N1.2" )
				)
			)
			( gate "@baseboard_fab2_lib.baseboard_fab2(sch_1):page55_i19"
				( objectStatus "F459" )
				( pin "A"
					( objectStatus "R3B2.1" )
				)
			)
			( gate "@baseboard_fab2_lib.baseboard_fab2(sch_1):page92_i39"
				( objectStatus "F451" )
			)
			( gate "@baseboard_fab2_lib.baseboard_fab2(sch_1):page92_i51"
				( objectStatus "F424" )
			)
			( gate "@baseboard_fab2_lib.baseboard_fab2(sch_1):page21_i204"
				( objectStatus "F437" )
			)
			( gate "@baseboard_fab2_lib.baseboard_fab2(sch_1):page21_i188"
				( objectStatus "F449" )
			)
			( gate "@baseboard_fab2_lib.baseboard_fab2(sch_1):page21_i186"
				( objectStatus "F448" )
			)
			( gate "@baseboard_fab2_lib.baseboard_fab2(sch_1):page21_i184"
				( objectStatus "F434" )
			)
			( gate "@baseboard_fab2_lib.baseboard_fab2(sch_1):page21_i189"
				( objectStatus "F447" )
			)
			( gate "@baseboard_fab2_lib.baseboard_fab2(sch_1):page55_i123"
				( objectStatus "F423" )
			)
			( gate "@baseboard_fab2_lib.baseboard_fab2(sch_1):page55_i124"
				( objectStatus "F422" )
			)
			( gate "@baseboard_fab2_lib.baseboard_fab2(sch_1):page55_i125"
				( objectStatus "F455" )
			)
			( gate "@baseboard_fab2_lib.baseboard_fab2(sch_1):page55_i126"
				( objectStatus "F421" )
			)
			( gate "@baseboard_fab2_lib.baseboard_fab2(sch_1):page199_i10"
				( objectStatus "F4197" )
				( pin "SCL"
					( objectStatus "EU1D2.16" )
				)
				( pin "SDA"
					( objectStatus "EU1D2.15" )
				)
			)
			( gate "@baseboard_fab2_lib.baseboard_fab2(sch_1):page143_i281"
				( objectStatus "F4192" )
				( pin "MA(0)"
					( attribute "PIN_DELAY" "209.00 MIL"
						( Units "uTimeLength" "mil" 1.000000)
						( Origin gBackEnd )
					)
					( objectStatus "U9F4.AB14" )
				)
				( pin "MA(10)"
					( attribute "PIN_DELAY" "164.00 MIL"
						( Units "uTimeLength" "mil" 1.000000)
						( Origin gBackEnd )
					)
					( objectStatus "U9F4.Y15" )
				)
				( pin "MA(11)"
					( attribute "PIN_DELAY" "208.00 MIL"
						( Units "uTimeLength" "mil" 1.000000)
						( Origin gBackEnd )
					)
					( objectStatus "U9F4.AA16" )
				)
				( pin "MA(12)"
					( attribute "PIN_DELAY" "115.00 MIL"
						( Units "uTimeLength" "mil" 1.000000)
						( Origin gBackEnd )
					)
					( objectStatus "U9F4.W17" )
				)
				( pin "MA(13)"
					( attribute "PIN_DELAY" "190.00 MIL"
						( Units "uTimeLength" "mil" 1.000000)
						( Origin gBackEnd )
					)
					( objectStatus "U9F4.Y17" )
				)
				( pin "MA(14)"
					( attribute "PIN_DELAY" "216.00 MIL"
						( Units "uTimeLength" "mil" 1.000000)
						( Origin gBackEnd )
					)
					( objectStatus "U9F4.AB17" )
				)
				( pin "MA(1)"
					( attribute "PIN_DELAY" "138.00 MIL"
						( Units "uTimeLength" "mil" 1.000000)
						( Origin gBackEnd )
					)
					( objectStatus "U9F4.W15" )
				)
				( pin "MA(2)"
					( attribute "PIN_DELAY" "107.00 MIL"
						( Units "uTimeLength" "mil" 1.000000)
						( Origin gBackEnd )
					)
					( objectStatus "U9F4.V15" )
				)
				( pin "MA(3)"
					( attribute "PIN_DELAY" "168.00 MIL"
						( Units "uTimeLength" "mil" 1.000000)
						( Origin gBackEnd )
					)
					( objectStatus "U9F4.Y16" )
				)
				( pin "MA(4)"
					( attribute "PIN_DELAY" "240.00 MIL"
						( Units "uTimeLength" "mil" 1.000000)
						( Origin gBackEnd )
					)
					( objectStatus "U9F4.AB15" )
				)
				( pin "MA(5)"
					( attribute "PIN_DELAY" "149.00 MIL"
						( Units "uTimeLength" "mil" 1.000000)
						( Origin gBackEnd )
					)
					( objectStatus "U9F4.W16" )
				)
				( pin "MA(6)"
					( attribute "PIN_DELAY" "201.00 MIL"
						( Units "uTimeLength" "mil" 1.000000)
						( Origin gBackEnd )
					)
					( objectStatus "U9F4.AA15" )
				)
				( pin "MA(7)"
					( attribute "PIN_DELAY" "224.00 MIL"
						( Units "uTimeLength" "mil" 1.000000)
						( Origin gBackEnd )
					)
					( objectStatus "U9F4.AB18" )
				)
				( pin "MA(8)"
					( attribute "PIN_DELAY" "224.00 MIL"
						( Units "uTimeLength" "mil" 1.000000)
						( Origin gBackEnd )
					)
					( objectStatus "U9F4.AB16" )
				)
				( pin "MA(9)"
					( attribute "PIN_DELAY" "182.00 MIL"
						( Units "uTimeLength" "mil" 1.000000)
						( Origin gBackEnd )
					)
					( objectStatus "U9F4.AA17" )
				)
				( pin "MBA(0)"
					( attribute "PIN_DELAY" "130.00 MIL"
						( Units "uTimeLength" "mil" 1.000000)
						( Origin gBackEnd )
					)
					( objectStatus "U9F4.W14" )
				)
				( pin "MBA(1)"
					( attribute "PIN_DELAY" "190.00 MIL"
						( Units "uTimeLength" "mil" 1.000000)
						( Origin gBackEnd )
					)
					( objectStatus "U9F4.AA14" )
				)
				( pin "MBA(2)"
					( attribute "PIN_DELAY" "159.00 MIL"
						( Units "uTimeLength" "mil" 1.000000)
						( Origin gBackEnd )
					)
					( objectStatus "U9F4.Y14" )
				)
				( pin "MCAS_N"
					( attribute "PIN_DELAY" "206.00 MIL"
						( Units "uTimeLength" "mil" 1.000000)
						( Origin gBackEnd )
					)
					( objectStatus "U9F4.AB13" )
				)
				( pin "MCKE"
					( attribute "PIN_DELAY" "170.00 MIL"
						( Units "uTimeLength" "mil" 1.000000)
						( Origin gBackEnd )
					)
					( objectStatus "U9F4.Y12" )
				)
				( pin "MCKN"
					( attribute "PIN_DELAY" "201.00 MIL"
						( Units "uTimeLength" "mil" 1.000000)
						( Origin gBackEnd )
					)
					( objectStatus "U9F4.AA12" )
				)
				( pin "MCKP"
					( attribute "PIN_DELAY" "201.00 MIL"
						( Units "uTimeLength" "mil" 1.000000)
						( Origin gBackEnd )
					)
					( objectStatus "U9F4.AB12" )
				)
				( pin "MCS_N"
					( attribute "PIN_DELAY" "171.00 MIL"
						( Units "uTimeLength" "mil" 1.000000)
						( Origin gBackEnd )
					)
					( objectStatus "U9F4.AA13" )
				)
				( pin "MDM(0)"
					( attribute "PIN_DELAY" "119.00 MIL"
						( Units "uTimeLength" "mil" 1.000000)
						( Origin gBackEnd )
					)
					( objectStatus "U9F4.W10" )
				)
				( pin "MDM(1)"
					( attribute "PIN_DELAY" "135.00 MIL"
						( Units "uTimeLength" "mil" 1.000000)
						( Origin gBackEnd )
					)
					( objectStatus "U9F4.V8" )
				)
				( pin "MDQ(0)"
					( attribute "PIN_DELAY" "187.00 MIL"
						( Units "uTimeLength" "mil" 1.000000)
						( Origin gBackEnd )
					)
					( objectStatus "U9F4.W12" )
				)
				( pin "MDQ(10)"
					( attribute "PIN_DELAY" "188.00 MIL"
						( Units "uTimeLength" "mil" 1.000000)
						( Origin gBackEnd )
					)
					( objectStatus "U9F4.AA9" )
				)
				( pin "MDQ(11)"
					( attribute "PIN_DELAY" "156.00 MIL"
						( Units "uTimeLength" "mil" 1.000000)
						( Origin gBackEnd )
					)
					( objectStatus "U9F4.Y9" )
				)
				( pin "MDQ(12)"
					( attribute "PIN_DELAY" "126.00 MIL"
						( Units "uTimeLength" "mil" 1.000000)
						( Origin gBackEnd )
					)
					( objectStatus "U9F4.W9" )
				)
				( pin "MDQ(13)"
					( attribute "PIN_DELAY" "100.00 MIL"
						( Units "uTimeLength" "mil" 1.000000)
						( Origin gBackEnd )
					)
					( objectStatus "U9F4.V9" )
				)
				( pin "MDQ(14)"
					( attribute "PIN_DELAY" "135.00 MIL"
						( Units "uTimeLength" "mil" 1.000000)
						( Origin gBackEnd )
					)
					( objectStatus "U9F4.Y8" )
				)
				( pin "MDQ(15)"
					( attribute "PIN_DELAY" "111.00 MIL"
						( Units "uTimeLength" "mil" 1.000000)
						( Origin gBackEnd )
					)
					( objectStatus "U9F4.W8" )
				)
				( pin "MDQ(1)"
					( attribute "PIN_DELAY" "98.00 MIL"
						( Units "uTimeLength" "mil" 1.000000)
						( Origin gBackEnd )
					)
					( objectStatus "U9F4.V12" )
				)
				( pin "MDQ(2)"
					( attribute "PIN_DELAY" "228.00 MIL"
						( Units "uTimeLength" "mil" 1.000000)
						( Origin gBackEnd )
					)
					( objectStatus "U9F4.AB11" )
				)
				( pin "MDQ(3)"
					( attribute "PIN_DELAY" "184.00 MIL"
						( Units "uTimeLength" "mil" 1.000000)
						( Origin gBackEnd )
					)
					( objectStatus "U9F4.AA11" )
				)
				( pin "MDQ(4)"
					( attribute "PIN_DELAY" "153.00 MIL"
						( Units "uTimeLength" "mil" 1.000000)
						( Origin gBackEnd )
					)
					( objectStatus "U9F4.Y11" )
				)
				( pin "MDQ(5)"
					( attribute "PIN_DELAY" "121.00 MIL"
						( Units "uTimeLength" "mil" 1.000000)
						( Origin gBackEnd )
					)
					( objectStatus "U9F4.W11" )
				)
				( pin "MDQ(6)"
					( attribute "PIN_DELAY" "95.00 MIL"
						( Units "uTimeLength" "mil" 1.000000)
						( Origin gBackEnd )
					)
					( objectStatus "U9F4.V11" )
				)
				( pin "MDQ(7)"
					( attribute "PIN_DELAY" "152.00 MIL"
						( Units "uTimeLength" "mil" 1.000000)
						( Origin gBackEnd )
					)
					( objectStatus "U9F4.Y10" )
				)
				( pin "MDQ(8)"
					( attribute "PIN_DELAY" "102.00 MIL"
						( Units "uTimeLength" "mil" 1.000000)
						( Origin gBackEnd )
					)
					( objectStatus "U9F4.V10" )
				)
				( pin "MDQ(9)"
					( attribute "PIN_DELAY" "229.00 MIL"
						( Units "uTimeLength" "mil" 1.000000)
						( Origin gBackEnd )
					)
					( objectStatus "U9F4.AB9" )
				)
				( pin "MDQS0"
					( attribute "PIN_DELAY" "187.00 MIL"
						( Units "uTimeLength" "mil" 1.000000)
						( Origin gBackEnd )
					)
					( objectStatus "U9F4.AB10" )
				)
				( pin "MDQS0_N"
					( attribute "PIN_DELAY" "190.00 MIL"
						( Units "uTimeLength" "mil" 1.000000)
						( Origin gBackEnd )
					)
					( objectStatus "U9F4.AA10" )
				)
				( pin "MDQS1"
					( attribute "PIN_DELAY" "208.00 MIL"
						( Units "uTimeLength" "mil" 1.000000)
						( Origin gBackEnd )
					)
					( objectStatus "U9F4.AA8" )
				)
				( pin "MDQS1_N"
					( attribute "PIN_DELAY" "211.00 MIL"
						( Units "uTimeLength" "mil" 1.000000)
						( Origin gBackEnd )
					)
					( objectStatus "U9F4.AB8" )
				)
				( pin "MODT"
					( attribute "PIN_DELAY" "98.00 MIL"
						( Units "uTimeLength" "mil" 1.000000)
						( Origin gBackEnd )
					)
					( objectStatus "U9F4.V14" )
				)
				( pin "MRAS_N"
					( attribute "PIN_DELAY" "93.00 MIL"
						( Units "uTimeLength" "mil" 1.000000)
						( Origin gBackEnd )
					)
					( objectStatus "U9F4.W13" )
				)
				( pin "MVREF"
					( attribute "PIN_DELAY" "193.00 MIL"
						( Units "uTimeLength" "mil" 1.000000)
						( Origin gBackEnd )
					)
					( objectStatus "U9F4.V13" )
				)
				( pin "MWE_N"
					( attribute "PIN_DELAY" "152.00 MIL"
						( Units "uTimeLength" "mil" 1.000000)
						( Origin gBackEnd )
					)
					( objectStatus "U9F4.Y13" )
				)
			)
			( gate "@baseboard_fab2_lib.baseboard_fab2(sch_1):page144_i347"
				( objectStatus "F4191" )
				( pin "DN_USB11_DN_USB11_HDN2"
					( objectStatus "U9F4.K3" )
				)
				( pin "DN_USB2_DN_USB2_HDN"
					( objectStatus "U9F4.AB20" )
				)
				( pin "DP_USB11_DP_USB11_HDP2"
					( objectStatus "U9F4.K4" )
				)
				( pin "DP_USB2_DP_USB2_HDP"
					( objectStatus "U9F4.AB21" )
				)
				( pin "GPIOA4_TIMER5_SCL9"
					( objectStatus "U9F4.C5" )
				)
				( pin "GPIOA5_TIMER6_SDA9"
					( objectStatus "U9F4.B4" )
				)
				( pin "GPIOI4_SPICS0_N_VBCS_N"
					( objectStatus "U9F4.B22" )
				)
				( pin "GPIOI5_SPICK_VBCK"
					( objectStatus "U9F4.G19" )
				)
				( pin "GPIOI6_SPIDO_VBDO"
					( objectStatus "U9F4.C18" )
				)
				( pin "GPIOI7_SPIDI_VBDI"
					( objectStatus "U9F4.E20" )
				)
				( pin "GPIOK0_SCL5"
					( objectStatus "U9F4.E3" )
				)
				( pin "GPIOK1_SDA5"
					( objectStatus "U9F4.D2" )
				)
				( pin "GPIOK2_SCL6"
					( objectStatus "U9F4.C1" )
				)
				( pin "GPIOK3_SDA6"
					( objectStatus "U9F4.F4" )
				)
				( pin "GPIOK4_SCL7"
					( objectStatus "U9F4.E2" )
				)
				( pin "GPIOK5_SDA7"
					( objectStatus "U9F4.D1" )
				)
				( pin "GPIOK6_SCL8"
					( objectStatus "U9F4.G5" )
				)
				( pin "GPIOK7_SDA8"
					( objectStatus "U9F4.F3" )
				)
				( pin "GPIOQ0_SCL3"
					( objectStatus "U9F4.D3" )
				)
				( pin "GPIOQ1_SDA3"
					( objectStatus "U9F4.C2" )
				)
				( pin "SCL(1)"
					( objectStatus "U9F4.K21" )
				)
				( pin "SCL(2)"
					( objectStatus "U9F4.J19" )
				)
				( pin "SDA(1)"
					( objectStatus "U9F4.K22" )
				)
				( pin "SDA(2)"
					( objectStatus "U9F4.J18" )
				)
			)
			( gate "@baseboard_fab2_lib.baseboard_fab2(sch_1):page145_i100"
				( objectStatus "F4190" )
			)
			( gate "@baseboard_fab2_lib.baseboard_fab2(sch_1):page146_i1"
				( objectStatus "F4189" )
				( pin "ROMCS0_N"
					( objectStatus "U9F4.R19" )
				)
				( pin "ROMD0"
					( objectStatus "U9F4.T22" )
				)
				( pin "ROMD1"
					( objectStatus "U9F4.T21" )
				)
				( pin "ROMD2"
					( objectStatus "U9F4.T20" )
				)
			)
			( gate "@baseboard_fab2_lib.baseboard_fab2(sch_1):page147_i1"
				( objectStatus "F4188" )
				( pin "RGMII1RXCK_RMII1RCLK_GPIOU4"
					( objectStatus "U9F4.E11" )
				)
				( pin "RGMII2RXCK_RMII2RCLK_GPIOV2"
					( objectStatus "U9F4.C9" )
				)
				( pin "RGMII2RXD0_RMII2RXD0_GPIOV4"
					( objectStatus "U9F4.A9" )
				)
				( pin "RGMII2RXD1_RMII2RXD1_GPIOV5"
					( objectStatus "U9F4.E8" )
				)
				( pin "RGMII2RXD2_RMII2CRSDV_GPIOV6"
					( objectStatus "U9F4.D8" )
				)
				( pin "RGMII2TXCK_RMII2TXEN_GPIOT6"
					( objectStatus "U9F4.D9" )
				)
				( pin "RGMII2TXD0_RMII2TXD0_GPIOU0"
					( objectStatus "U9F4.A10" )
				)
				( pin "RGMII2TXD1_RMII2TXD1_GPIOU1"
					( objectStatus "U9F4.B10" )
				)
			)
			( gate "@baseboard_fab2_lib.baseboard_fab2(sch_1):page148_i11"
				( objectStatus "F4187" )
			)
			( gate "@baseboard_fab2_lib.baseboard_fab2(sch_1):page196_i47"
				( objectStatus "TF-4025" )
			)
			( gate "@baseboard_fab2_lib.baseboard_fab2(sch_1):page209_i35"
				( objectStatus "F4184" )
			)
			( gate "@baseboard_fab2_lib.baseboard_fab2(sch_1):page209_i37"
				( objectStatus "F4182" )
			)
			( gate "@baseboard_fab2_lib.baseboard_fab2(sch_1):page209_i38"
				( objectStatus "F4183" )
			)
			( gate "@baseboard_fab2_lib.baseboard_fab2(sch_1):page204_i50"
				( objectStatus "F4179" )
			)
			( gate "@baseboard_fab2_lib.baseboard_fab2(sch_1):page204_i48"
				( objectStatus "F4180" )
			)
			( gate "@baseboard_fab2_lib.baseboard_fab2(sch_1):page204_i67"
				( objectStatus "F4181" )
			)
			( gate "@baseboard_fab2_lib.baseboard_fab2(sch_1):page217_i175"
				( objectStatus "F4177" )
			)
			( gate "@baseboard_fab2_lib.baseboard_fab2(sch_1):page220_i175"
				( objectStatus "F4178" )
			)
			( gate "@baseboard_fab2_lib.baseboard_fab2(sch_1):page228_i175"
				( objectStatus "F4185" )
			)
			( gate "@baseboard_fab2_lib.baseboard_fab2(sch_1):page194_i29"
				( objectStatus "F4162" )
			)
			( gate "@baseboard_fab2_lib.baseboard_fab2(sch_1):page193_i62"
				( objectStatus "F4149" )
			)
			( gate "@baseboard_fab2_lib.baseboard_fab2(sch_1):page194_i31"
				( objectStatus "F4170" )
			)
			( gate "@baseboard_fab2_lib.baseboard_fab2(sch_1):page193_i61"
				( objectStatus "F4164" )
			)
			( gate "@baseboard_fab2_lib.baseboard_fab2(sch_1):page194_i101"
				( objectStatus "F4174" )
			)
			( gate "@baseboard_fab2_lib.baseboard_fab2(sch_1):page193_i29"
				( objectStatus "F4166" )
			)
			( gate "@baseboard_fab2_lib.baseboard_fab2(sch_1):page203_i34"
				( objectStatus "F4158" )
			)
			( gate "@baseboard_fab2_lib.baseboard_fab2(sch_1):page203_i32"
				( objectStatus "F4157" )
			)
			( gate "@baseboard_fab2_lib.baseboard_fab2(sch_1):page203_i30"
				( objectStatus "F4155" )
			)
			( gate "@baseboard_fab2_lib.baseboard_fab2(sch_1):page203_i29"
				( objectStatus "F4156" )
			)
			( gate "@baseboard_fab2_lib.baseboard_fab2(sch_1):page203_i28"
				( objectStatus "F4154" )
			)
			( gate "@baseboard_fab2_lib.baseboard_fab2(sch_1):page203_i18"
				( objectStatus "F4151" )
			)
			( gate "@baseboard_fab2_lib.baseboard_fab2(sch_1):page203_i16"
				( objectStatus "F4153" )
			)
			( gate "@baseboard_fab2_lib.baseboard_fab2(sch_1):page212_i18"
				( objectStatus "F4172" )
			)
			( gate "@baseboard_fab2_lib.baseboard_fab2(sch_1):page212_i17"
				( objectStatus "F4173" )
			)
			( gate "@baseboard_fab2_lib.baseboard_fab2(sch_1):page212_i16"
				( objectStatus "F4171" )
			)
			( gate "@baseboard_fab2_lib.baseboard_fab2(sch_1):page214_i24"
				( objectStatus "F4152" )
			)
			( gate "@baseboard_fab2_lib.baseboard_fab2(sch_1):page214_i21"
				( objectStatus "F4150" )
			)
			( gate "@baseboard_fab2_lib.baseboard_fab2(sch_1):page214_i20"
				( objectStatus "F4165" )
			)
			( gate "@baseboard_fab2_lib.baseboard_fab2(sch_1):page205_i14"
				( objectStatus "F4159" )
			)
			( gate "@baseboard_fab2_lib.baseboard_fab2(sch_1):page205_i12"
				( objectStatus "F4160" )
			)
			( gate "@baseboard_fab2_lib.baseboard_fab2(sch_1):page217_i75"
				( objectStatus "F4148" )
			)
			( gate "@baseboard_fab2_lib.baseboard_fab2(sch_1):page217_i76"
				( objectStatus "F4169" )
			)
			( gate "@baseboard_fab2_lib.baseboard_fab2(sch_1):page217_i77"
				( objectStatus "F4168" )
			)
			( gate "@baseboard_fab2_lib.baseboard_fab2(sch_1):page217_i78"
				( objectStatus "F4167" )
			)
			( gate "@baseboard_fab2_lib.baseboard_fab2(sch_1):page220_i75"
				( objectStatus "F4176" )
			)
			( gate "@baseboard_fab2_lib.baseboard_fab2(sch_1):page220_i76"
				( objectStatus "F4175" )
			)
			( gate "@baseboard_fab2_lib.baseboard_fab2(sch_1):page220_i77"
				( objectStatus "F4161" )
			)
			( gate "@baseboard_fab2_lib.baseboard_fab2(sch_1):page220_i78"
				( objectStatus "F4163" )
			)
			( gate "@baseboard_fab2_lib.baseboard_fab2(sch_1):page225_i75"
				( objectStatus "F4134" )
			)
			( gate "@baseboard_fab2_lib.baseboard_fab2(sch_1):page225_i76"
				( objectStatus "F4133" )
			)
			( gate "@baseboard_fab2_lib.baseboard_fab2(sch_1):page225_i77"
				( objectStatus "F4131" )
			)
			( gate "@baseboard_fab2_lib.baseboard_fab2(sch_1):page225_i78"
				( objectStatus "F4132" )
			)
			( gate "@baseboard_fab2_lib.baseboard_fab2(sch_1):page228_i75"
				( objectStatus "F4145" )
			)
			( gate "@baseboard_fab2_lib.baseboard_fab2(sch_1):page228_i76"
				( objectStatus "F4144" )
			)
			( gate "@baseboard_fab2_lib.baseboard_fab2(sch_1):page228_i77"
				( objectStatus "F4146" )
			)
			( gate "@baseboard_fab2_lib.baseboard_fab2(sch_1):page228_i78"
				( objectStatus "F4147" )
			)
			( gate "@baseboard_fab2_lib.baseboard_fab2(sch_1):page208_i30"
				( objectStatus "F4138" )
			)
			( gate "@baseboard_fab2_lib.baseboard_fab2(sch_1):page208_i28"
				( objectStatus "F4137" )
			)
			( gate "@baseboard_fab2_lib.baseboard_fab2(sch_1):page208_i26"
				( objectStatus "F4136" )
			)
			( gate "@baseboard_fab2_lib.baseboard_fab2(sch_1):page208_i25"
				( objectStatus "F4135" )
			)
			( gate "@baseboard_fab2_lib.baseboard_fab2(sch_1):page208_i24"
				( objectStatus "F4141" )
			)
			( gate "@baseboard_fab2_lib.baseboard_fab2(sch_1):page208_i14"
				( objectStatus "F4140" )
			)
			( gate "@baseboard_fab2_lib.baseboard_fab2(sch_1):page208_i12"
				( objectStatus "F4139" )
			)
			( gate "@baseboard_fab2_lib.baseboard_fab2(sch_1):page210_i14"
				( objectStatus "F4142" )
			)
			( gate "@baseboard_fab2_lib.baseboard_fab2(sch_1):page210_i12"
				( objectStatus "F4143" )
			)
			( gate "@baseboard_fab2_lib.baseboard_fab2(sch_1):page236_i76"
				( objectStatus "F4095" )
			)
			( gate "@baseboard_fab2_lib.baseboard_fab2(sch_1):page236_i71"
				( objectStatus "F4096" )
			)
			( gate "@baseboard_fab2_lib.baseboard_fab2(sch_1):page236_i73"
				( objectStatus "F4094" )
			)
			( gate "@baseboard_fab2_lib.baseboard_fab2(sch_1):page236_i74"
				( objectStatus "F4093" )
			)
			( gate "@baseboard_fab2_lib.baseboard_fab2(sch_1):page236_i75"
				( objectStatus "F4092" )
			)
			( gate "@baseboard_fab2_lib.baseboard_fab2(sch_1):page236_i77"
				( objectStatus "F4097" )
			)
			( gate "@baseboard_fab2_lib.baseboard_fab2(sch_1):page236_i78"
				( objectStatus "F4091" )
			)
			( gate "@baseboard_fab2_lib.baseboard_fab2(sch_1):page236_i79"
				( objectStatus "F4098" )
			)
			( gate "@baseboard_fab2_lib.baseboard_fab2(sch_1):page196_i102"
				( objectStatus "F3682" )
			)
			( gate "@baseboard_fab2_lib.baseboard_fab2(sch_1):page177_i20"
				( objectStatus "F3736" )
			)
			( gate "@baseboard_fab2_lib.baseboard_fab2(sch_1):page157_i353"
				( objectStatus "F3688" )
			)
			( gate "@baseboard_fab2_lib.baseboard_fab2(sch_1):page113_i117"
				( objectStatus "F3689" )
			)
			( gate "@baseboard_fab2_lib.baseboard_fab2(sch_1):page186_i335"
				( objectStatus "F3734" )
			)
			( gate "@baseboard_fab2_lib.baseboard_fab2(sch_1):page215_i309"
				( objectStatus "F3616" )
			)
			( gate "@baseboard_fab2_lib.baseboard_fab2(sch_1):page215_i325"
				( objectStatus "F3617" )
			)
			( gate "@baseboard_fab2_lib.baseboard_fab2(sch_1):page201_i37"
				( objectStatus "F3636" )
			)
			( gate "@baseboard_fab2_lib.baseboard_fab2(sch_1):page201_i30"
				( objectStatus "F3634" )
			)
			( gate "@baseboard_fab2_lib.baseboard_fab2(sch_1):page206_i41"
				( objectStatus "F3750" )
			)
			( gate "@baseboard_fab2_lib.baseboard_fab2(sch_1):page218_i29"
				( objectStatus "F3621" )
			)
			( gate "@baseboard_fab2_lib.baseboard_fab2(sch_1):page218_i22"
				( objectStatus "F3620" )
			)
			( gate "@baseboard_fab2_lib.baseboard_fab2(sch_1):page223_i25"
				( objectStatus "F3740" )
			)
			( gate "@baseboard_fab2_lib.baseboard_fab2(sch_1):page223_i41"
				( objectStatus "F3741" )
			)
			( gate "@baseboard_fab2_lib.baseboard_fab2(sch_1):page226_i25"
				( objectStatus "F3752" )
			)
			( gate "@baseboard_fab2_lib.baseboard_fab2(sch_1):page226_i41"
				( objectStatus "F3753" )
			)
			( gate "@baseboard_fab2_lib.baseboard_fab2(sch_1):page206_i29"
				( objectStatus "F3749" )
			)
			( gate "@baseboard_fab2_lib.baseboard_fab2(sch_1):page186_i334"
				( objectStatus "F3735" )
			)
			( gate "@baseboard_fab2_lib.baseboard_fab2(sch_1):page211_i11"
				( objectStatus "F3646" )
			)
			( gate "@baseboard_fab2_lib.baseboard_fab2(sch_1):page213_i9"
				( objectStatus "F3632" )
			)
			( gate "@baseboard_fab2_lib.baseboard_fab2(sch_1):page211_i20"
				( objectStatus "F3647" )
			)
			( gate "@baseboard_fab2_lib.baseboard_fab2(sch_1):page213_i17"
				( objectStatus "F3631" )
			)
			( gate "@baseboard_fab2_lib.baseboard_fab2(sch_1):page235_i143"
				( objectStatus "F3612" )
			)
			( gate "@baseboard_fab2_lib.baseboard_fab2(sch_1):page102_i30"
				( objectStatus "F3633" )
			)
			( gate "@baseboard_fab2_lib.baseboard_fab2(sch_1):page102_i19"
				( objectStatus "F3635" )
			)
			( gate "@baseboard_fab2_lib.baseboard_fab2(sch_1):page235_i151"
				( objectStatus "F3718" )
			)
			( gate "@baseboard_fab2_lib.baseboard_fab2(sch_1):page127_i63"
				( objectStatus "F3707" )
			)
			( gate "@baseboard_fab2_lib.baseboard_fab2(sch_1):page127_i31"
				( objectStatus "F3678" )
			)
			( gate "@baseboard_fab2_lib.baseboard_fab2(sch_1):page127_i33"
				( objectStatus "F3677" )
			)
			( gate "@baseboard_fab2_lib.baseboard_fab2(sch_1):page127_i42"
				( objectStatus "F3717" )
			)
			( gate "@baseboard_fab2_lib.baseboard_fab2(sch_1):page127_i35"
				( objectStatus "F3674" )
			)
			( gate "@baseboard_fab2_lib.baseboard_fab2(sch_1):page127_i53"
				( objectStatus "F3673" )
			)
			( gate "@baseboard_fab2_lib.baseboard_fab2(sch_1):page127_i48"
				( objectStatus "F3715" )
			)
			( gate "@baseboard_fab2_lib.baseboard_fab2(sch_1):page175_i11"
				( objectStatus "F3737" )
			)
			( gate "@baseboard_fab2_lib.baseboard_fab2(sch_1):page175_i19"
				( objectStatus "F3738" )
			)
			( gate "@baseboard_fab2_lib.baseboard_fab2(sch_1):page162_i30"
				( objectStatus "F3611" )
			)
			( gate "@baseboard_fab2_lib.baseboard_fab2(sch_1):page205_i18"
				( objectStatus "F3640" )
			)
			( gate "@baseboard_fab2_lib.baseboard_fab2(sch_1):page236_i38"
				( objectStatus "F3613" )
			)
			( gate "@baseboard_fab2_lib.baseboard_fab2(sch_1):page236_i17"
				( objectStatus "F3679" )
			)
			( gate "@baseboard_fab2_lib.baseboard_fab2(sch_1):page194_i86"
				( objectStatus "F3644" )
			)
			( gate "@baseboard_fab2_lib.baseboard_fab2(sch_1):page194_i99"
				( objectStatus "F3645" )
			)
			( gate "@baseboard_fab2_lib.baseboard_fab2(sch_1):page193_i31"
				( objectStatus "F3680" )
			)
			( gate "@baseboard_fab2_lib.baseboard_fab2(sch_1):page193_i38"
				( objectStatus "F3681" )
			)
			( gate "@baseboard_fab2_lib.baseboard_fab2(sch_1):page194_i9"
				( objectStatus "F3625" )
			)
			( gate "@baseboard_fab2_lib.baseboard_fab2(sch_1):page194_i16"
				( objectStatus "F3626" )
			)
			( gate "@baseboard_fab2_lib.baseboard_fab2(sch_1):page193_i68"
				( objectStatus "F3628" )
			)
			( gate "@baseboard_fab2_lib.baseboard_fab2(sch_1):page193_i70"
				( objectStatus "F3627" )
			)
			( gate "@baseboard_fab2_lib.baseboard_fab2(sch_1):page153_i130"
				( objectStatus "F3618" )
			)
			( gate "@baseboard_fab2_lib.baseboard_fab2(sch_1):page153_i138"
				( objectStatus "F3642" )
			)
			( gate "@baseboard_fab2_lib.baseboard_fab2(sch_1):page212_i34"
				( objectStatus "F3648" )
			)
			( gate "@baseboard_fab2_lib.baseboard_fab2(sch_1):page214_i74"
				( objectStatus "F3624" )
			)
			( gate "@baseboard_fab2_lib.baseboard_fab2(sch_1):page203_i41"
				( objectStatus "F3637" )
			)
			( gate "@baseboard_fab2_lib.baseboard_fab2(sch_1):page203_i49"
				( objectStatus "F3638" )
			)
			( gate "@baseboard_fab2_lib.baseboard_fab2(sch_1):page151_i62"
				( objectStatus "F3724" )
			)
			( gate "@baseboard_fab2_lib.baseboard_fab2(sch_1):page132_i48"
				( objectStatus "F3662" )
			)
			( gate "@baseboard_fab2_lib.baseboard_fab2(sch_1):page132_i51"
				( objectStatus "F3654" )
			)
			( gate "@baseboard_fab2_lib.baseboard_fab2(sch_1):page132_i46"
				( objectStatus "F3663" )
			)
			( gate "@baseboard_fab2_lib.baseboard_fab2(sch_1):page132_i49"
				( objectStatus "F3659" )
			)
			( gate "@baseboard_fab2_lib.baseboard_fab2(sch_1):page132_i43"
				( objectStatus "F3665" )
			)
			( gate "@baseboard_fab2_lib.baseboard_fab2(sch_1):page132_i45"
				( objectStatus "F3657" )
			)
			( gate "@baseboard_fab2_lib.baseboard_fab2(sch_1):page132_i42"
				( objectStatus "F3656" )
			)
			( gate "@baseboard_fab2_lib.baseboard_fab2(sch_1):page132_i44"
				( objectStatus "F3661" )
			)
			( gate "@baseboard_fab2_lib.baseboard_fab2(sch_1):page132_i32"
				( objectStatus "F3664" )
			)
			( gate "@baseboard_fab2_lib.baseboard_fab2(sch_1):page132_i36"
				( objectStatus "F3658" )
			)
			( gate "@baseboard_fab2_lib.baseboard_fab2(sch_1):page132_i31"
				( objectStatus "F3655" )
			)
			( gate "@baseboard_fab2_lib.baseboard_fab2(sch_1):page132_i35"
				( objectStatus "F3660" )
			)
			( gate "@baseboard_fab2_lib.baseboard_fab2(sch_1):page132_i30"
				( objectStatus "F3699" )
			)
			( gate "@baseboard_fab2_lib.baseboard_fab2(sch_1):page132_i34"
				( objectStatus "F3666" )
			)
			( gate "@baseboard_fab2_lib.baseboard_fab2(sch_1):page132_i27"
				( objectStatus "F3705" )
			)
			( gate "@baseboard_fab2_lib.baseboard_fab2(sch_1):page132_i29"
				( objectStatus "F3698" )
			)
			( gate "@baseboard_fab2_lib.baseboard_fab2(sch_1):page132_i26"
				( objectStatus "F3700" )
			)
			( gate "@baseboard_fab2_lib.baseboard_fab2(sch_1):page132_i28"
				( objectStatus "F3704" )
			)
			( gate "@baseboard_fab2_lib.baseboard_fab2(sch_1):page130_i49"
				( objectStatus "F3653" )
			)
			( gate "@baseboard_fab2_lib.baseboard_fab2(sch_1):page130_i37"
				( objectStatus "F3713" )
			)
			( gate "@baseboard_fab2_lib.baseboard_fab2(sch_1):page130_i34"
				( objectStatus "F3691" )
			)
			( gate "@baseboard_fab2_lib.baseboard_fab2(sch_1):page130_i29"
				( objectStatus "F3694" )
			)
			( gate "@baseboard_fab2_lib.baseboard_fab2(sch_1):page130_i47"
				( objectStatus "F3696" )
			)
			( gate "@baseboard_fab2_lib.baseboard_fab2(sch_1):page131_i41"
				( objectStatus "F3706" )
			)
			( gate "@baseboard_fab2_lib.baseboard_fab2(sch_1):page131_i40"
				( objectStatus "F3697" )
			)
			( gate "@baseboard_fab2_lib.baseboard_fab2(sch_1):page131_i39"
				( objectStatus "F3710" )
			)
			( gate "@baseboard_fab2_lib.baseboard_fab2(sch_1):page131_i29"
				( objectStatus "F3712" )
			)
			( gate "@baseboard_fab2_lib.baseboard_fab2(sch_1):page130_i12"
				( objectStatus "F3692" )
			)
			( gate "@baseboard_fab2_lib.baseboard_fab2(sch_1):page131_i28"
				( objectStatus "F3709" )
			)
			( gate "@baseboard_fab2_lib.baseboard_fab2(sch_1):page130_i7"
				( objectStatus "F3693" )
			)
			( gate "@baseboard_fab2_lib.baseboard_fab2(sch_1):page131_i47"
				( objectStatus "F3701" )
			)
			( gate "@baseboard_fab2_lib.baseboard_fab2(sch_1):page131_i43"
				( objectStatus "F3702" )
			)
			( gate "@baseboard_fab2_lib.baseboard_fab2(sch_1):page131_i42"
				( objectStatus "F3667" )
			)
			( gate "@baseboard_fab2_lib.baseboard_fab2(sch_1):page131_i32"
				( objectStatus "F3670" )
			)
			( gate "@baseboard_fab2_lib.baseboard_fab2(sch_1):page131_i31"
				( objectStatus "F3711" )
			)
			( gate "@baseboard_fab2_lib.baseboard_fab2(sch_1):page131_i27"
				( objectStatus "F3708" )
			)
			( gate "@baseboard_fab2_lib.baseboard_fab2(sch_1):page130_i53"
				( objectStatus "F3652" )
			)
			( gate "@baseboard_fab2_lib.baseboard_fab2(sch_1):page130_i42"
				( objectStatus "F3651" )
			)
			( gate "@baseboard_fab2_lib.baseboard_fab2(sch_1):page130_i52"
				( objectStatus "F3695" )
			)
			( gate "@baseboard_fab2_lib.baseboard_fab2(sch_1):page130_i4"
				( objectStatus "F3690" )
			)
			( gate "@baseboard_fab2_lib.baseboard_fab2(sch_1):page130_i50"
				( objectStatus "F3650" )
			)
			( gate "@baseboard_fab2_lib.baseboard_fab2(sch_1):page149_i141"
				( objectStatus "F3719" )
			)
			( gate "@baseboard_fab2_lib.baseboard_fab2(sch_1):page209_i21"
				( objectStatus "F3748" )
			)
			( gate "@baseboard_fab2_lib.baseboard_fab2(sch_1):page93_i72"
				( objectStatus "F3684" )
			)
			( gate "@baseboard_fab2_lib.baseboard_fab2(sch_1):page101_i116"
				( objectStatus "F3686" )
			)
			( gate "@baseboard_fab2_lib.baseboard_fab2(sch_1):page101_i106"
				( objectStatus "F3687" )
			)
			( gate "@baseboard_fab2_lib.baseboard_fab2(sch_1):page101_i97"
				( objectStatus "F3683" )
			)
			( gate "@baseboard_fab2_lib.baseboard_fab2(sch_1):page101_i89"
				( objectStatus "F3685" )
			)
			( gate "@baseboard_fab2_lib.baseboard_fab2(sch_1):page127_i9"
				( objectStatus "F3676" )
			)
			( gate "@baseboard_fab2_lib.baseboard_fab2(sch_1):page127_i18"
				( objectStatus "F3675" )
			)
			( gate "@baseboard_fab2_lib.baseboard_fab2(sch_1):page127_i27"
				( objectStatus "F3672" )
			)
			( gate "@baseboard_fab2_lib.baseboard_fab2(sch_1):page96_i73"
				( objectStatus "F3643" )
			)
			( gate "@baseboard_fab2_lib.baseboard_fab2(sch_1):page96_i75"
				( objectStatus "F3641" )
			)
			( gate "@baseboard_fab2_lib.baseboard_fab2(sch_1):page149_i77"
				( objectStatus "F3730" )
			)
			( gate "@baseboard_fab2_lib.baseboard_fab2(sch_1):page149_i89"
				( objectStatus "F3728" )
			)
			( gate "@baseboard_fab2_lib.baseboard_fab2(sch_1):page149_i78"
				( objectStatus "F3722" )
			)
			( gate "@baseboard_fab2_lib.baseboard_fab2(sch_1):page149_i90"
				( objectStatus "F3723" )
			)
			( gate "@baseboard_fab2_lib.baseboard_fab2(sch_1):page149_i79"
				( objectStatus "F3721" )
			)
			( gate "@baseboard_fab2_lib.baseboard_fab2(sch_1):page149_i91"
				( objectStatus "F3726" )
			)
			( gate "@baseboard_fab2_lib.baseboard_fab2(sch_1):page149_i92"
				( objectStatus "F3729" )
			)
			( gate "@baseboard_fab2_lib.baseboard_fab2(sch_1):page149_i93"
				( objectStatus "F3727" )
			)
			( gate "@baseboard_fab2_lib.baseboard_fab2(sch_1):page149_i94"
				( objectStatus "F3725" )
			)
			( gate "@baseboard_fab2_lib.baseboard_fab2(sch_1):page149_i106"
				( objectStatus "F3608" )
			)
			( gate "@baseboard_fab2_lib.baseboard_fab2(sch_1):page149_i121"
				( objectStatus "F3732" )
			)
			( gate "@baseboard_fab2_lib.baseboard_fab2(sch_1):page148_i28"
				( objectStatus "F3731" )
			)
			( gate "@baseboard_fab2_lib.baseboard_fab2(sch_1):page112_i47"
				( objectStatus "F3609" )
			)
			( gate "@baseboard_fab2_lib.baseboard_fab2(sch_1):page127_i57"
				( objectStatus "F3671" )
			)
			( gate "@baseboard_fab2_lib.baseboard_fab2(sch_1):page127_i65"
				( objectStatus "F3703" )
			)
			( gate "@baseboard_fab2_lib.baseboard_fab2(sch_1):page127_i44"
				( objectStatus "F3716" )
			)
			( gate "@baseboard_fab2_lib.baseboard_fab2(sch_1):page127_i50"
				( objectStatus "F3714" )
			)
			( gate "@baseboard_fab2_lib.baseboard_fab2(sch_1):page202_i25"
				( objectStatus "F3630" )
			)
			( gate "@baseboard_fab2_lib.baseboard_fab2(sch_1):page202_i19"
				( objectStatus "F3629" )
			)
			( gate "@baseboard_fab2_lib.baseboard_fab2(sch_1):page204_i19"
				( objectStatus "F3639" )
			)
			( gate "@baseboard_fab2_lib.baseboard_fab2(sch_1):page111_i30"
				( objectStatus "F3739" )
			)
			( gate "@baseboard_fab2_lib.baseboard_fab2(sch_1):page111_i25"
				( objectStatus "F3610" )
			)
			( gate "@baseboard_fab2_lib.baseboard_fab2(sch_1):page131_i45"
				( objectStatus "F3668" )
			)
			( gate "@baseboard_fab2_lib.baseboard_fab2(sch_1):page131_i44"
				( objectStatus "F3669" )
			)
			( gate "@baseboard_fab2_lib.baseboard_fab2(sch_1):page137_i20"
				( objectStatus "F3649" )
			)
			( gate "@baseboard_fab2_lib.baseboard_fab2(sch_1):page137_i14"
				( objectStatus "F3619" )
			)
			( gate "@baseboard_fab2_lib.baseboard_fab2(sch_1):page149_i8"
				( objectStatus "F3733" )
			)
			( gate "@baseboard_fab2_lib.baseboard_fab2(sch_1):page149_i19"
				( objectStatus "F3720" )
			)
			( gate "@baseboard_fab2_lib.baseboard_fab2(sch_1):page216_i53"
				( objectStatus "F3615" )
			)
			( gate "@baseboard_fab2_lib.baseboard_fab2(sch_1):page216_i73"
				( objectStatus "F3614" )
			)
			( gate "@baseboard_fab2_lib.baseboard_fab2(sch_1):page219_i53"
				( objectStatus "F3623" )
			)
			( gate "@baseboard_fab2_lib.baseboard_fab2(sch_1):page219_i73"
				( objectStatus "F3622" )
			)
			( gate "@baseboard_fab2_lib.baseboard_fab2(sch_1):page227_i53"
				( objectStatus "F3755" )
			)
			( gate "@baseboard_fab2_lib.baseboard_fab2(sch_1):page227_i73"
				( objectStatus "F3754" )
			)
			( gate "@baseboard_fab2_lib.baseboard_fab2(sch_1):page224_i53"
				( objectStatus "F3742" )
			)
			( gate "@baseboard_fab2_lib.baseboard_fab2(sch_1):page224_i73"
				( objectStatus "F3743" )
			)
			( gate "@baseboard_fab2_lib.baseboard_fab2(sch_1):page207_i37"
				( objectStatus "F3745" )
			)
			( gate "@baseboard_fab2_lib.baseboard_fab2(sch_1):page207_i29"
				( objectStatus "F3744" )
			)
			( gate "@baseboard_fab2_lib.baseboard_fab2(sch_1):page208_i39"
				( objectStatus "F3746" )
			)
			( gate "@baseboard_fab2_lib.baseboard_fab2(sch_1):page208_i47"
				( objectStatus "F3747" )
			)
			( gate "@baseboard_fab2_lib.baseboard_fab2(sch_1):page210_i23"
				( objectStatus "F3751" )
			)
			( gate "@baseboard_fab2_lib.baseboard_fab2(sch_1):page113_i267"
				( objectStatus "F3492" )
			)
			( gate "@baseboard_fab2_lib.baseboard_fab2(sch_1):page113_i266"
				( objectStatus "F3494" )
			)
			( gate "@baseboard_fab2_lib.baseboard_fab2(sch_1):page113_i265"
				( objectStatus "F3493" )
			)
			( gate "@baseboard_fab2_lib.baseboard_fab2(sch_1):page161_i137"
				( objectStatus "F3498" )
			)
			( gate "@baseboard_fab2_lib.baseboard_fab2(sch_1):page161_i128"
				( objectStatus "F3599" )
			)
			( gate "@baseboard_fab2_lib.baseboard_fab2(sch_1):page113_i116"
				( objectStatus "F3533" )
			)
			( gate "@baseboard_fab2_lib.baseboard_fab2(sch_1):page113_i119"
				( objectStatus "F3532" )
			)
			( gate "@baseboard_fab2_lib.baseboard_fab2(sch_1):page112_i131"
				( objectStatus "F3506" )
			)
			( gate "@baseboard_fab2_lib.baseboard_fab2(sch_1):page174_i29"
				( objectStatus "F3552" )
				( pin "A"
					( objectStatus "C2L31.1" )
				)
				( pin "B"
					( objectStatus "C2L31.2" )
				)
			)
			( gate "@baseboard_fab2_lib.baseboard_fab2(sch_1):page174_i32"
				( objectStatus "F3554" )
				( pin "A"
					( objectStatus "C2L29.1" )
				)
				( pin "B"
					( objectStatus "C2L29.2" )
				)
			)
			( gate "@baseboard_fab2_lib.baseboard_fab2(sch_1):page174_i39"
				( objectStatus "F3548" )
				( pin "A"
					( objectStatus "C2L36.1" )
				)
				( pin "B"
					( objectStatus "C2L36.2" )
				)
			)
			( gate "@baseboard_fab2_lib.baseboard_fab2(sch_1):page174_i41"
				( objectStatus "F3550" )
				( pin "A"
					( objectStatus "C2L34.1" )
				)
				( pin "B"
					( objectStatus "C2L34.2" )
				)
			)
			( gate "@baseboard_fab2_lib.baseboard_fab2(sch_1):page174_i28"
				( objectStatus "F3553" )
				( pin "A"
					( objectStatus "C2L30.1" )
				)
				( pin "B"
					( objectStatus "C2L30.2" )
				)
			)
			( gate "@baseboard_fab2_lib.baseboard_fab2(sch_1):page174_i30"
				( objectStatus "F3555" )
				( pin "A"
					( objectStatus "C2L28.1" )
				)
				( pin "B"
					( objectStatus "C2L28.2" )
				)
			)
			( gate "@baseboard_fab2_lib.baseboard_fab2(sch_1):page174_i31"
				( objectStatus "F3549" )
				( pin "A"
					( objectStatus "C2L35.1" )
				)
				( pin "B"
					( objectStatus "C2L35.2" )
				)
			)
			( gate "@baseboard_fab2_lib.baseboard_fab2(sch_1):page174_i40"
				( objectStatus "F3551" )
				( pin "A"
					( objectStatus "C2L33.1" )
				)
				( pin "B"
					( objectStatus "C2L33.2" )
				)
			)
			( gate "@baseboard_fab2_lib.baseboard_fab2(sch_1):page174_i19"
				( objectStatus "F3587" )
				( pin "A"
					( objectStatus "C1L12.1" )
				)
				( pin "B"
					( objectStatus "C1L12.2" )
				)
			)
			( gate "@baseboard_fab2_lib.baseboard_fab2(sch_1):page174_i20"
				( objectStatus "F3585" )
				( pin "A"
					( objectStatus "C1L14.1" )
				)
				( pin "B"
					( objectStatus "C1L14.2" )
				)
			)
			( gate "@baseboard_fab2_lib.baseboard_fab2(sch_1):page174_i9"
				( objectStatus "F3591" )
				( pin "A"
					( objectStatus "C1L2.1" )
				)
				( pin "B"
					( objectStatus "C1L2.2" )
				)
			)
			( gate "@baseboard_fab2_lib.baseboard_fab2(sch_1):page174_i13"
				( objectStatus "F3589" )
				( pin "A"
					( objectStatus "C1L6.1" )
				)
				( pin "B"
					( objectStatus "C1L6.2" )
				)
			)
			( gate "@baseboard_fab2_lib.baseboard_fab2(sch_1):page174_i14"
				( objectStatus "F3586" )
				( pin "A"
					( objectStatus "C1L13.1" )
				)
				( pin "B"
					( objectStatus "C1L13.2" )
				)
			)
			( gate "@baseboard_fab2_lib.baseboard_fab2(sch_1):page174_i18"
				( objectStatus "F3584" )
				( pin "A"
					( objectStatus "C1L15.1" )
				)
				( pin "B"
					( objectStatus "C1L15.2" )
				)
			)
			( gate "@baseboard_fab2_lib.baseboard_fab2(sch_1):page174_i8"
				( objectStatus "F3590" )
				( pin "A"
					( objectStatus "C1L3.1" )
				)
				( pin "B"
					( objectStatus "C1L3.2" )
				)
			)
			( gate "@baseboard_fab2_lib.baseboard_fab2(sch_1):page174_i12"
				( objectStatus "F3588" )
				( pin "A"
					( objectStatus "C1L7.1" )
				)
				( pin "B"
					( objectStatus "C1L7.2" )
				)
			)
			( gate "@baseboard_fab2_lib.baseboard_fab2(sch_1):page173_i208"
				( objectStatus "F3568" )
				( pin "A"
					( objectStatus "C2L14.1" )
				)
				( pin "B"
					( objectStatus "C2L14.2" )
				)
			)
			( gate "@baseboard_fab2_lib.baseboard_fab2(sch_1):page173_i209"
				( objectStatus "F3575" )
				( pin "A"
					( objectStatus "C2L5.1" )
				)
				( pin "B"
					( objectStatus "C2L5.2" )
				)
			)
			( gate "@baseboard_fab2_lib.baseboard_fab2(sch_1):page173_i197"
				( objectStatus "F3564" )
				( pin "A"
					( objectStatus "C2L18.1" )
				)
				( pin "B"
					( objectStatus "C2L18.2" )
				)
			)
			( gate "@baseboard_fab2_lib.baseboard_fab2(sch_1):page173_i207"
				( objectStatus "F3572" )
				( pin "A"
					( objectStatus "C2L9.1" )
				)
				( pin "B"
					( objectStatus "C2L9.2" )
				)
			)
			( gate "@baseboard_fab2_lib.baseboard_fab2(sch_1):page173_i195"
				( objectStatus "F3562" )
				( pin "A"
					( objectStatus "C2L20.1" )
				)
				( pin "B"
					( objectStatus "C2L20.2" )
				)
			)
			( gate "@baseboard_fab2_lib.baseboard_fab2(sch_1):page173_i196"
				( objectStatus "F3570" )
				( pin "A"
					( objectStatus "C2L12.1" )
				)
				( pin "B"
					( objectStatus "C2L12.2" )
				)
			)
			( gate "@baseboard_fab2_lib.baseboard_fab2(sch_1):page173_i205"
				( objectStatus "F3566" )
				( pin "A"
					( objectStatus "C2L16.1" )
				)
				( pin "B"
					( objectStatus "C2L16.2" )
				)
			)
			( gate "@baseboard_fab2_lib.baseboard_fab2(sch_1):page173_i206"
				( objectStatus "F3573" )
				( pin "A"
					( objectStatus "C2L7.1" )
				)
				( pin "B"
					( objectStatus "C2L7.2" )
				)
			)
			( gate "@baseboard_fab2_lib.baseboard_fab2(sch_1):page173_i239"
				( objectStatus "F3539" )
				( pin "A"
					( objectStatus "C2L47.1" )
				)
				( pin "B"
					( objectStatus "C2L47.2" )
				)
			)
			( gate "@baseboard_fab2_lib.baseboard_fab2(sch_1):page173_i240"
				( objectStatus "F3556" )
				( pin "A"
					( objectStatus "C2L27.1" )
				)
				( pin "B"
					( objectStatus "C2L27.2" )
				)
			)
			( gate "@baseboard_fab2_lib.baseboard_fab2(sch_1):page173_i257"
				( objectStatus "F3538" )
				( pin "A"
					( objectStatus "C2L48.1" )
				)
				( pin "B"
					( objectStatus "C2L48.2" )
				)
			)
			( gate "@baseboard_fab2_lib.baseboard_fab2(sch_1):page173_i258"
				( objectStatus "F3558" )
				( pin "A"
					( objectStatus "C2L24.1" )
				)
				( pin "B"
					( objectStatus "C2L24.2" )
				)
			)
			( gate "@baseboard_fab2_lib.baseboard_fab2(sch_1):page173_i238"
				( objectStatus "F3547" )
				( pin "A"
					( objectStatus "C2L37.1" )
				)
				( pin "B"
					( objectStatus "C2L37.2" )
				)
			)
			( gate "@baseboard_fab2_lib.baseboard_fab2(sch_1):page173_i255"
				( objectStatus "F3557" )
				( pin "A"
					( objectStatus "C2L26.1" )
				)
				( pin "B"
					( objectStatus "C2L26.2" )
				)
			)
			( gate "@baseboard_fab2_lib.baseboard_fab2(sch_1):page173_i256"
				( objectStatus "F3546" )
				( pin "A"
					( objectStatus "C2L38.1" )
				)
				( pin "B"
					( objectStatus "C2L38.2" )
				)
			)
			( gate "@baseboard_fab2_lib.baseboard_fab2(sch_1):page173_i259"
				( objectStatus "F3561" )
				( pin "A"
					( objectStatus "C2L21.1" )
				)
				( pin "B"
					( objectStatus "C2L21.2" )
				)
			)
			( gate "@baseboard_fab2_lib.baseboard_fab2(sch_1):page192_i1"
				( objectStatus "F3531" )
			)
			( gate "@baseboard_fab2_lib.baseboard_fab2(sch_1):page43_i272"
				( objectStatus "F3522" )
			)
			( gate "@baseboard_fab2_lib.baseboard_fab2(sch_1):page45_i179"
				( objectStatus "F3520" )
			)
			( gate "@baseboard_fab2_lib.baseboard_fab2(sch_1):page79_i178"
				( objectStatus "F3496" )
			)
			( gate "@baseboard_fab2_lib.baseboard_fab2(sch_1):page77_i181"
				( objectStatus "F3596" )
			)
			( gate "@baseboard_fab2_lib.baseboard_fab2(sch_1):page47_i188"
				( objectStatus "F3518" )
			)
			( gate "@baseboard_fab2_lib.baseboard_fab2(sch_1):page48_i176"
				( objectStatus "F3509" )
			)
			( gate "@baseboard_fab2_lib.baseboard_fab2(sch_1):page49_i179"
				( objectStatus "F3524" )
			)
			( gate "@baseboard_fab2_lib.baseboard_fab2(sch_1):page51_i175"
				( objectStatus "F3515" )
			)
			( gate "@baseboard_fab2_lib.baseboard_fab2(sch_1):page88_i177"
				( objectStatus "F3504" )
			)
			( gate "@baseboard_fab2_lib.baseboard_fab2(sch_1):page87_i178"
				( objectStatus "F3603" )
			)
			( gate "@baseboard_fab2_lib.baseboard_fab2(sch_1):page53_i178"
				( objectStatus "F3517" )
			)
			( gate "@baseboard_fab2_lib.baseboard_fab2(sch_1):page83_i176"
				( objectStatus "F3601" )
			)
			( gate "@baseboard_fab2_lib.baseboard_fab2(sch_1):page54_i179"
				( objectStatus "F3526" )
			)
			( gate "@baseboard_fab2_lib.baseboard_fab2(sch_1):page82_i180"
				( objectStatus "F3592" )
			)
			( gate "@baseboard_fab2_lib.baseboard_fab2(sch_1):page84_i4"
				( objectStatus "F3500" )
			)
			( gate "@baseboard_fab2_lib.baseboard_fab2(sch_1):page86_i182"
				( objectStatus "F3602" )
			)
			( gate "@baseboard_fab2_lib.baseboard_fab2(sch_1):page78_i2"
				( objectStatus "F3497" )
			)
			( gate "@baseboard_fab2_lib.baseboard_fab2(sch_1):page80_i3"
				( objectStatus "F3594" )
			)
			( gate "@baseboard_fab2_lib.baseboard_fab2(sch_1):page52_i3"
				( objectStatus "F3525" )
			)
			( gate "@baseboard_fab2_lib.baseboard_fab2(sch_1):page44_i2"
				( objectStatus "F3511" )
			)
			( gate "@baseboard_fab2_lib.baseboard_fab2(sch_1):page46_i5"
				( objectStatus "F3510" )
			)
			( gate "@baseboard_fab2_lib.baseboard_fab2(sch_1):page50_i177"
				( objectStatus "F3513" )
			)
			( gate "@baseboard_fab2_lib.baseboard_fab2(sch_1):page81_i178"
				( objectStatus "F3495" )
			)
			( gate "@baseboard_fab2_lib.baseboard_fab2(sch_1):page85_i181"
				( objectStatus "F3502" )
			)
			( gate "@baseboard_fab2_lib.baseboard_fab2(sch_1):page162_i28"
				( objectStatus "F3507" )
			)
			( gate "@baseboard_fab2_lib.baseboard_fab2(sch_1):page153_i131"
				( objectStatus "F3508" )
			)
			( gate "@baseboard_fab2_lib.baseboard_fab2(sch_1):page153_i136"
				( objectStatus "F3527" )
			)
			( gate "@baseboard_fab2_lib.baseboard_fab2(sch_1):page173_i174"
				( objectStatus "F3565" )
				( pin "A"
					( objectStatus "C2L17.1" )
				)
				( pin "B"
					( objectStatus "C2L17.2" )
				)
			)
			( gate "@baseboard_fab2_lib.baseboard_fab2(sch_1):page173_i166"
				( objectStatus "F3574" )
				( pin "A"
					( objectStatus "C2L6.1" )
				)
				( pin "B"
					( objectStatus "C2L6.2" )
				)
			)
			( gate "@baseboard_fab2_lib.baseboard_fab2(sch_1):page173_i165"
				( objectStatus "F3569" )
				( pin "A"
					( objectStatus "C2L13.1" )
				)
				( pin "B"
					( objectStatus "C2L13.2" )
				)
			)
			( gate "@baseboard_fab2_lib.baseboard_fab2(sch_1):page173_i194"
				( objectStatus "F3577" )
				( pin "A"
					( objectStatus "C2L3.1" )
				)
				( pin "B"
					( objectStatus "C2L3.2" )
				)
			)
			( gate "@baseboard_fab2_lib.baseboard_fab2(sch_1):page173_i172"
				( objectStatus "F3563" )
				( pin "A"
					( objectStatus "C2L19.1" )
				)
				( pin "B"
					( objectStatus "C2L19.2" )
				)
			)
			( gate "@baseboard_fab2_lib.baseboard_fab2(sch_1):page173_i173"
				( objectStatus "F3571" )
				( pin "A"
					( objectStatus "C2L10.1" )
				)
				( pin "B"
					( objectStatus "C2L10.2" )
				)
			)
			( gate "@baseboard_fab2_lib.baseboard_fab2(sch_1):page173_i191"
				( objectStatus "F3567" )
				( pin "A"
					( objectStatus "C2L15.1" )
				)
				( pin "B"
					( objectStatus "C2L15.2" )
				)
			)
			( gate "@baseboard_fab2_lib.baseboard_fab2(sch_1):page173_i192"
				( objectStatus "F3576" )
				( pin "A"
					( objectStatus "C2L4.1" )
				)
				( pin "B"
					( objectStatus "C2L4.2" )
				)
			)
			( gate "@baseboard_fab2_lib.baseboard_fab2(sch_1):page173_i242"
				( objectStatus "F3543" )
				( pin "A"
					( objectStatus "C2L41.1" )
				)
				( pin "B"
					( objectStatus "C2L41.2" )
				)
			)
			( gate "@baseboard_fab2_lib.baseboard_fab2(sch_1):page173_i241"
				( objectStatus "F3559" )
				( pin "A"
					( objectStatus "C2L23.1" )
				)
				( pin "B"
					( objectStatus "C2L23.2" )
				)
			)
			( gate "@baseboard_fab2_lib.baseboard_fab2(sch_1):page173_i221"
				( objectStatus "F3545" )
				( pin "A"
					( objectStatus "C2L39.1" )
				)
				( pin "B"
					( objectStatus "C2L39.2" )
				)
			)
			( gate "@baseboard_fab2_lib.baseboard_fab2(sch_1):page173_i222"
				( objectStatus "F3541" )
				( pin "A"
					( objectStatus "C2L43.1" )
				)
				( pin "B"
					( objectStatus "C2L43.2" )
				)
			)
			( gate "@baseboard_fab2_lib.baseboard_fab2(sch_1):page173_i233"
				( objectStatus "F3542" )
				( pin "A"
					( objectStatus "C2L42.1" )
				)
				( pin "B"
					( objectStatus "C2L42.2" )
				)
			)
			( gate "@baseboard_fab2_lib.baseboard_fab2(sch_1):page173_i234"
				( objectStatus "F3560" )
				( pin "A"
					( objectStatus "C2L22.1" )
				)
				( pin "B"
					( objectStatus "C2L22.2" )
				)
			)
			( gate "@baseboard_fab2_lib.baseboard_fab2(sch_1):page173_i220"
				( objectStatus "F3544" )
				( pin "A"
					( objectStatus "C2L40.1" )
				)
				( pin "B"
					( objectStatus "C2L40.2" )
				)
			)
			( gate "@baseboard_fab2_lib.baseboard_fab2(sch_1):page173_i228"
				( objectStatus "F3540" )
				( pin "A"
					( objectStatus "C2L44.1" )
				)
				( pin "B"
					( objectStatus "C2L44.2" )
				)
			)
			( gate "@baseboard_fab2_lib.baseboard_fab2(sch_1):page161_i46"
				( objectStatus "F3598" )
			)
			( gate "@baseboard_fab2_lib.baseboard_fab2(sch_1):page161_i68"
				( objectStatus "F3600" )
			)
			( gate "@baseboard_fab2_lib.baseboard_fab2(sch_1):page101_i104"
				( objectStatus "F3530" )
			)
			( gate "@baseboard_fab2_lib.baseboard_fab2(sch_1):page101_i99"
				( objectStatus "F3528" )
			)
			( gate "@baseboard_fab2_lib.baseboard_fab2(sch_1):page101_i90"
				( objectStatus "F3529" )
			)
			( gate "@baseboard_fab2_lib.baseboard_fab2(sch_1):page100_i26"
				( objectStatus "F3595" )
			)
			( gate "@baseboard_fab2_lib.baseboard_fab2(sch_1):page100_i42"
				( objectStatus "F3593" )
			)
			( gate "@baseboard_fab2_lib.baseboard_fab2(sch_1):page100_i30"
				( objectStatus "F3501" )
			)
			( gate "@baseboard_fab2_lib.baseboard_fab2(sch_1):page100_i46"
				( objectStatus "F3503" )
			)
			( gate "@baseboard_fab2_lib.baseboard_fab2(sch_1):page98_i59"
				( objectStatus "F3514" )
			)
			( gate "@baseboard_fab2_lib.baseboard_fab2(sch_1):page98_i43"
				( objectStatus "F3521" )
			)
			( gate "@baseboard_fab2_lib.baseboard_fab2(sch_1):page98_i51"
				( objectStatus "F3519" )
			)
			( gate "@baseboard_fab2_lib.baseboard_fab2(sch_1):page98_i67"
				( objectStatus "F3516" )
			)
			( gate "@baseboard_fab2_lib.baseboard_fab2(sch_1):page151_i64"
				( objectStatus "F3579" )
			)
			( gate "@baseboard_fab2_lib.baseboard_fab2(sch_1):page151_i63"
				( objectStatus "F3578" )
			)
			( gate "@baseboard_fab2_lib.baseboard_fab2(sch_1):page149_i80"
				( objectStatus "F3581" )
			)
			( gate "@baseboard_fab2_lib.baseboard_fab2(sch_1):page149_i81"
				( objectStatus "F3583" )
			)
			( gate "@baseboard_fab2_lib.baseboard_fab2(sch_1):page149_i82"
				( objectStatus "F3582" )
			)
			( gate "@baseboard_fab2_lib.baseboard_fab2(sch_1):page149_i83"
				( objectStatus "F3580" )
			)
			( gate "@baseboard_fab2_lib.baseboard_fab2(sch_1):page98_i33"
				( objectStatus "F3512" )
			)
			( gate "@baseboard_fab2_lib.baseboard_fab2(sch_1):page98_i7"
				( objectStatus "F3523" )
			)
			( gate "@baseboard_fab2_lib.baseboard_fab2(sch_1):page112_i42"
				( objectStatus "F3505" )
			)
			( gate "@baseboard_fab2_lib.baseboard_fab2(sch_1):page172_i6"
				( objectStatus "F3534" )
				( pin "A"
					( objectStatus "C2L52.1" )
				)
				( pin "B"
					( objectStatus "C2L52.2" )
				)
			)
			( gate "@baseboard_fab2_lib.baseboard_fab2(sch_1):page172_i5"
				( objectStatus "F3537" )
			)
			( gate "@baseboard_fab2_lib.baseboard_fab2(sch_1):page172_i8"
				( objectStatus "F3535" )
				( pin "A"
					( objectStatus "C2L51.1" )
				)
				( pin "B"
					( objectStatus "C2L51.2" )
				)
			)
			( gate "@baseboard_fab2_lib.baseboard_fab2(sch_1):page172_i7"
				( objectStatus "F3536" )
			)
			( gate "@baseboard_fab2_lib.baseboard_fab2(sch_1):page100_i8"
				( objectStatus "F3597" )
			)
			( gate "@baseboard_fab2_lib.baseboard_fab2(sch_1):page100_i15"
				( objectStatus "F3499" )
			)
			( gate "@baseboard_fab2_lib.baseboard_fab2(sch_1):page209_i30"
				( objectStatus "F3489" )
			)
			( gate "@baseboard_fab2_lib.baseboard_fab2(sch_1):page149_i151"
				( objectStatus "F3487" )
			)
			( gate "@baseboard_fab2_lib.baseboard_fab2(sch_1):page204_i51"
				( objectStatus "F3482" )
			)
			( gate "@baseboard_fab2_lib.baseboard_fab2(sch_1):page149_i160"
				( objectStatus "F3481" )
			)
			( gate "@baseboard_fab2_lib.baseboard_fab2(sch_1):page145_i202"
				( objectStatus "F3480" )
			)
			( gate "@baseboard_fab2_lib.baseboard_fab2(sch_1):page145_i201"
				( objectStatus "F3479" )
			)
			( gate "@baseboard_fab2_lib.baseboard_fab2(sch_1):page116_i182"
				( objectStatus "F3485" )
			)
			( gate "@baseboard_fab2_lib.baseboard_fab2(sch_1):page116_i183"
				( objectStatus "F3486" )
			)
			( gate "@baseboard_fab2_lib.baseboard_fab2(sch_1):page214_i96"
				( objectStatus "F3484" )
			)
			( gate "@baseboard_fab2_lib.baseboard_fab2(sch_1):page212_i60"
				( objectStatus "F3483" )
			)
			( gate "@baseboard_fab2_lib.baseboard_fab2(sch_1):page199_i67"
				( objectStatus "F3478" )
			)
			( gate "@baseboard_fab2_lib.baseboard_fab2(sch_1):page200_i36"
				( objectStatus "F3476" )
			)
			( gate "@baseboard_fab2_lib.baseboard_fab2(sch_1):page200_i40"
				( objectStatus "F3477" )
			)
			( gate "@baseboard_fab2_lib.baseboard_fab2(sch_1):page200_i42"
				( objectStatus "F3488" )
			)
			( gate "@baseboard_fab2_lib.baseboard_fab2(sch_1):page113_i248"
				( objectStatus "F3216" )
			)
			( gate "@baseboard_fab2_lib.baseboard_fab2(sch_1):page113_i250"
				( objectStatus "F3215" )
			)
			( gate "@baseboard_fab2_lib.baseboard_fab2(sch_1):page145_i258"
				( objectStatus "F3213" )
			)
			( gate "@baseboard_fab2_lib.baseboard_fab2(sch_1):page113_i246"
				( objectStatus "F3214" )
			)
			( gate "@baseboard_fab2_lib.baseboard_fab2(sch_1):page188_i64"
				( objectStatus "F3224" )
				( pin "B"
					( objectStatus "C8C8.2" )
				)
			)
			( gate "@baseboard_fab2_lib.baseboard_fab2(sch_1):page188_i68"
				( objectStatus "F3223" )
				( pin "B"
					( objectStatus "C8C9.2" )
				)
			)
			( gate "@baseboard_fab2_lib.baseboard_fab2(sch_1):page188_i72"
				( objectStatus "F3222" )
				( pin "B"
					( objectStatus "C8C11.2" )
				)
			)
			( gate "@baseboard_fab2_lib.baseboard_fab2(sch_1):page188_i73"
				( objectStatus "F3221" )
				( pin "B"
					( objectStatus "C8C10.2" )
				)
			)
			( gate "@baseboard_fab2_lib.baseboard_fab2(sch_1):page188_i80"
				( objectStatus "F3220" )
				( pin "B"
					( objectStatus "C8C12.2" )
				)
			)
			( gate "@baseboard_fab2_lib.baseboard_fab2(sch_1):page188_i81"
				( objectStatus "F3219" )
				( pin "B"
					( objectStatus "C8C13.2" )
				)
			)
			( gate "@baseboard_fab2_lib.baseboard_fab2(sch_1):page188_i82"
				( objectStatus "F3218" )
				( pin "B"
					( objectStatus "C8C15.2" )
				)
			)
			( gate "@baseboard_fab2_lib.baseboard_fab2(sch_1):page188_i86"
				( objectStatus "F3217" )
				( pin "B"
					( objectStatus "C8C14.2" )
				)
			)
			( gate "@baseboard_fab2_lib.baseboard_fab2(sch_1):page188_i23"
				( objectStatus "F3326" )
			)
			( gate "@baseboard_fab2_lib.baseboard_fab2(sch_1):page188_i21"
				( objectStatus "F3307" )
			)
			( gate "@baseboard_fab2_lib.baseboard_fab2(sch_1):page188_i2"
				( objectStatus "F3306" )
			)
			( gate "@baseboard_fab2_lib.baseboard_fab2(sch_1):page188_i57"
				( objectStatus "F3294" )
			)
			( gate "@baseboard_fab2_lib.baseboard_fab2(sch_1):page188_i56"
				( objectStatus "F3273" )
			)
			( gate "@baseboard_fab2_lib.baseboard_fab2(sch_1):page188_i55"
				( objectStatus "F3258" )
			)
			( gate "@baseboard_fab2_lib.baseboard_fab2(sch_1):page188_i53"
				( objectStatus "F3228" )
			)
			( gate "@baseboard_fab2_lib.baseboard_fab2(sch_1):page188_i40"
				( objectStatus "F3227" )
			)
			( gate "@baseboard_fab2_lib.baseboard_fab2(sch_1):page188_i25"
				( objectStatus "F3226" )
			)
			( gate "@baseboard_fab2_lib.baseboard_fab2(sch_1):page188_i3"
				( objectStatus "F3225" )
			)
			( gate "@baseboard_fab2_lib.baseboard_fab2(sch_1):page118_i136"
				( objectStatus "F3287" )
			)
			( gate "@baseboard_fab2_lib.baseboard_fab2(sch_1):page199_i121"
				( objectStatus "F3462" )
			)
			( gate "@baseboard_fab2_lib.baseboard_fab2(sch_1):page223_i92"
				( objectStatus "F3229" )
			)
			( gate "@baseboard_fab2_lib.baseboard_fab2(sch_1):page218_i77"
				( objectStatus "F3324" )
			)
			( gate "@baseboard_fab2_lib.baseboard_fab2(sch_1):page215_i360"
				( objectStatus "F3310" )
			)
			( gate "@baseboard_fab2_lib.baseboard_fab2(sch_1):page226_i92"
				( objectStatus "F3471" )
			)
			( gate "@baseboard_fab2_lib.baseboard_fab2(sch_1):page95_i115"
				( objectStatus "F3282" )
			)
			( gate "@baseboard_fab2_lib.baseboard_fab2(sch_1):page155_i184"
				( objectStatus "F3247" )
			)
			( gate "@baseboard_fab2_lib.baseboard_fab2(sch_1):page151_i90"
				( objectStatus "F3246" )
			)
			( gate "@baseboard_fab2_lib.baseboard_fab2(sch_1):page156_i275"
				( objectStatus "F3260" )
			)
			( gate "@baseboard_fab2_lib.baseboard_fab2(sch_1):page156_i273"
				( objectStatus "F3355" )
			)
			( gate "@baseboard_fab2_lib.baseboard_fab2(sch_1):page111_i87"
				( objectStatus "F3445" )
			)
			( gate "@baseboard_fab2_lib.baseboard_fab2(sch_1):page181_i253"
				( objectStatus "F3265" )
			)
			( gate "@baseboard_fab2_lib.baseboard_fab2(sch_1):page154_i132"
				( objectStatus "F3367" )
			)
			( gate "@baseboard_fab2_lib.baseboard_fab2(sch_1):page154_i135"
				( objectStatus "F3368" )
			)
			( gate "@baseboard_fab2_lib.baseboard_fab2(sch_1):page157_i376"
				( objectStatus "F3267" )
			)
			( gate "@baseboard_fab2_lib.baseboard_fab2(sch_1):page157_i370"
				( objectStatus "F3371" )
			)
			( gate "@baseboard_fab2_lib.baseboard_fab2(sch_1):page102_i79"
				( objectStatus "F3299" )
			)
			( gate "@baseboard_fab2_lib.baseboard_fab2(sch_1):page101_i109"
				( objectStatus "F3356" )
			)
			( gate "@baseboard_fab2_lib.baseboard_fab2(sch_1):page200_i201"
				( objectStatus "F3235" )
			)
			( gate "@baseboard_fab2_lib.baseboard_fab2(sch_1):page136_i128"
				( objectStatus "F3262" )
			)
			( gate "@baseboard_fab2_lib.baseboard_fab2(sch_1):page199_i107"
				( objectStatus "F3461" )
			)
			( gate "@baseboard_fab2_lib.baseboard_fab2(sch_1):page200_i187"
				( objectStatus "F3465" )
			)
			( gate "@baseboard_fab2_lib.baseboard_fab2(sch_1):page200_i185"
				( objectStatus "F3236" )
			)
			( gate "@baseboard_fab2_lib.baseboard_fab2(sch_1):page199_i105"
				( objectStatus "F3234" )
			)
			( gate "@baseboard_fab2_lib.baseboard_fab2(sch_1):page232_i252"
				( objectStatus "F3289" )
			)
			( gate "@baseboard_fab2_lib.baseboard_fab2(sch_1):page231_i205"
				( objectStatus "F3278" )
			)
			( gate "@baseboard_fab2_lib.baseboard_fab2(sch_1):page233_i242"
				( objectStatus "F3295" )
			)
			( gate "@baseboard_fab2_lib.baseboard_fab2(sch_1):page234_i199"
				( objectStatus "F3325" )
			)
			( gate "@baseboard_fab2_lib.baseboard_fab2(sch_1):page113_i147"
				( objectStatus "F3386" )
			)
			( gate "@baseboard_fab2_lib.baseboard_fab2(sch_1):page170_i49"
				( objectStatus "F3427" )
			)
			( gate "@baseboard_fab2_lib.baseboard_fab2(sch_1):page170_i8"
				( objectStatus "F3385" )
			)
			( gate "@baseboard_fab2_lib.baseboard_fab2(sch_1):page170_i33"
				( objectStatus "F3266" )
			)
			( gate "@baseboard_fab2_lib.baseboard_fab2(sch_1):page170_i30"
				( objectStatus "F3428" )
			)
			( gate "@baseboard_fab2_lib.baseboard_fab2(sch_1):page185_i120"
				( objectStatus "F3359" )
			)
			( gate "@baseboard_fab2_lib.baseboard_fab2(sch_1):page185_i129"
				( objectStatus "F3362" )
			)
			( gate "@baseboard_fab2_lib.baseboard_fab2(sch_1):page185_i135"
				( objectStatus "F3369" )
			)
			( gate "@baseboard_fab2_lib.baseboard_fab2(sch_1):page185_i123"
				( objectStatus "F3360" )
			)
			( gate "@baseboard_fab2_lib.baseboard_fab2(sch_1):page185_i127"
				( objectStatus "F3366" )
			)
			( gate "@baseboard_fab2_lib.baseboard_fab2(sch_1):page185_i132"
				( objectStatus "F3370" )
			)
			( gate "@baseboard_fab2_lib.baseboard_fab2(sch_1):page185_i124"
				( objectStatus "F3363" )
			)
			( gate "@baseboard_fab2_lib.baseboard_fab2(sch_1):page185_i126"
				( objectStatus "F3365" )
			)
			( gate "@baseboard_fab2_lib.baseboard_fab2(sch_1):page185_i131"
				( objectStatus "F3372" )
			)
			( gate "@baseboard_fab2_lib.baseboard_fab2(sch_1):page183_i7"
				( objectStatus "F3244" )
			)
			( gate "@baseboard_fab2_lib.baseboard_fab2(sch_1):page108_i318"
				( objectStatus "F3350" )
			)
			( gate "@baseboard_fab2_lib.baseboard_fab2(sch_1):page108_i315"
				( objectStatus "F3349" )
			)
			( gate "@baseboard_fab2_lib.baseboard_fab2(sch_1):page239_i71"
				( objectStatus "F3248" )
			)
			( gate "@baseboard_fab2_lib.baseboard_fab2(sch_1):page155_i127"
				( objectStatus "F3257" )
			)
			( gate "@baseboard_fab2_lib.baseboard_fab2(sch_1):page170_i40"
				( objectStatus "F3264" )
			)
			( gate "@baseboard_fab2_lib.baseboard_fab2(sch_1):page104_i34"
				( objectStatus "F3342" )
			)
			( gate "@baseboard_fab2_lib.baseboard_fab2(sch_1):page104_i25"
				( objectStatus "F3305" )
			)
			( gate "@baseboard_fab2_lib.baseboard_fab2(sch_1):page192_i20"
				( objectStatus "F3379" )
			)
			( gate "@baseboard_fab2_lib.baseboard_fab2(sch_1):page192_i19"
				( objectStatus "F3376" )
			)
			( gate "@baseboard_fab2_lib.baseboard_fab2(sch_1):page192_i12"
				( objectStatus "F3334" )
			)
			( gate "@baseboard_fab2_lib.baseboard_fab2(sch_1):page192_i17"
				( objectStatus "F3330" )
			)
			( gate "@baseboard_fab2_lib.baseboard_fab2(sch_1):page192_i11"
				( objectStatus "F3331" )
			)
			( gate "@baseboard_fab2_lib.baseboard_fab2(sch_1):page192_i18"
				( objectStatus "F3380" )
			)
			( gate "@baseboard_fab2_lib.baseboard_fab2(sch_1):page192_i15"
				( objectStatus "F3374" )
			)
			( gate "@baseboard_fab2_lib.baseboard_fab2(sch_1):page192_i7"
				( objectStatus "F3327" )
			)
			( gate "@baseboard_fab2_lib.baseboard_fab2(sch_1):page192_i8"
				( objectStatus "F3378" )
			)
			( gate "@baseboard_fab2_lib.baseboard_fab2(sch_1):page192_i6"
				( objectStatus "F3336" )
			)
			( gate "@baseboard_fab2_lib.baseboard_fab2(sch_1):page192_i3"
				( objectStatus "F3381" )
			)
			( gate "@baseboard_fab2_lib.baseboard_fab2(sch_1):page192_i16"
				( objectStatus "F3382" )
			)
			( gate "@baseboard_fab2_lib.baseboard_fab2(sch_1):page192_i9"
				( objectStatus "F3384" )
			)
			( gate "@baseboard_fab2_lib.baseboard_fab2(sch_1):page192_i4"
				( objectStatus "F3329" )
			)
			( gate "@baseboard_fab2_lib.baseboard_fab2(sch_1):page192_i10"
				( objectStatus "F3328" )
			)
			( gate "@baseboard_fab2_lib.baseboard_fab2(sch_1):page192_i21"
				( objectStatus "F3375" )
			)
			( gate "@baseboard_fab2_lib.baseboard_fab2(sch_1):page192_i28"
				( objectStatus "F3377" )
			)
			( gate "@baseboard_fab2_lib.baseboard_fab2(sch_1):page192_i22"
				( objectStatus "F3383" )
			)
			( gate "@baseboard_fab2_lib.baseboard_fab2(sch_1):page192_i23"
				( objectStatus "F3335" )
			)
			( gate "@baseboard_fab2_lib.baseboard_fab2(sch_1):page192_i25"
				( objectStatus "F3333" )
			)
			( gate "@baseboard_fab2_lib.baseboard_fab2(sch_1):page102_i28"
				( objectStatus "F3319" )
			)
			( gate "@baseboard_fab2_lib.baseboard_fab2(sch_1):page102_i18"
				( objectStatus "F3318" )
			)
			( gate "@baseboard_fab2_lib.baseboard_fab2(sch_1):page102_i11"
				( objectStatus "F3302" )
			)
			( gate "@baseboard_fab2_lib.baseboard_fab2(sch_1):page102_i12"
				( objectStatus "F3300" )
			)
			( gate "@baseboard_fab2_lib.baseboard_fab2(sch_1):page102_i13"
				( objectStatus "F3298" )
			)
			( gate "@baseboard_fab2_lib.baseboard_fab2(sch_1):page102_i14"
				( objectStatus "F3301" )
			)
			( gate "@baseboard_fab2_lib.baseboard_fab2(sch_1):page102_i15"
				( objectStatus "F3296" )
			)
			( gate "@baseboard_fab2_lib.baseboard_fab2(sch_1):page102_i16"
				( objectStatus "F3297" )
			)
			( gate "@baseboard_fab2_lib.baseboard_fab2(sch_1):page175_i40"
				( objectStatus "F3255" )
			)
			( gate "@baseboard_fab2_lib.baseboard_fab2(sch_1):page175_i38"
				( objectStatus "F3446" )
			)
			( gate "@baseboard_fab2_lib.baseboard_fab2(sch_1):page175_i37"
				( objectStatus "F3444" )
			)
			( gate "@baseboard_fab2_lib.baseboard_fab2(sch_1):page175_i64"
				( objectStatus "F3448" )
			)
			( gate "@baseboard_fab2_lib.baseboard_fab2(sch_1):page198_i67"
				( objectStatus "F3238" )
			)
			( gate "@baseboard_fab2_lib.baseboard_fab2(sch_1):page198_i76"
				( objectStatus "F3237" )
			)
			( gate "@baseboard_fab2_lib.baseboard_fab2(sch_1):page198_i64"
				( objectStatus "F3470" )
			)
			( gate "@baseboard_fab2_lib.baseboard_fab2(sch_1):page235_i169"
				( objectStatus "F3389" )
			)
			( gate "@baseboard_fab2_lib.baseboard_fab2(sch_1):page154_i14"
				( objectStatus "F3261" )
			)
			( gate "@baseboard_fab2_lib.baseboard_fab2(sch_1):page158_i70"
				( objectStatus "F3421" )
			)
			( gate "@baseboard_fab2_lib.baseboard_fab2(sch_1):page161_i113"
				( objectStatus "F3453" )
			)
			( gate "@baseboard_fab2_lib.baseboard_fab2(sch_1):page185_i117"
				( objectStatus "F3268" )
			)
			( gate "@baseboard_fab2_lib.baseboard_fab2(sch_1):page95_i92"
				( objectStatus "F3283" )
			)
			( gate "@baseboard_fab2_lib.baseboard_fab2(sch_1):page235_i145"
				( objectStatus "F3272" )
			)
			( gate "@baseboard_fab2_lib.baseboard_fab2(sch_1):page236_i35"
				( objectStatus "F3341" )
			)
			( gate "@baseboard_fab2_lib.baseboard_fab2(sch_1):page236_i20"
				( objectStatus "F3340" )
			)
			( gate "@baseboard_fab2_lib.baseboard_fab2(sch_1):page154_i94"
				( objectStatus "F3373" )
			)
			( gate "@baseboard_fab2_lib.baseboard_fab2(sch_1):page142_i20"
				( objectStatus "F3263" )
			)
			( gate "@baseboard_fab2_lib.baseboard_fab2(sch_1):page152_i27"
				( objectStatus "F3390" )
			)
			( gate "@baseboard_fab2_lib.baseboard_fab2(sch_1):page211_i13"
				( objectStatus "F3338" )
			)
			( gate "@baseboard_fab2_lib.baseboard_fab2(sch_1):page212_i38"
				( objectStatus "F3288" )
			)
			( gate "@baseboard_fab2_lib.baseboard_fab2(sch_1):page213_i11"
				( objectStatus "F3316" )
			)
			( gate "@baseboard_fab2_lib.baseboard_fab2(sch_1):page214_i77"
				( objectStatus "F3312" )
			)
			( gate "@baseboard_fab2_lib.baseboard_fab2(sch_1):page211_i22"
				( objectStatus "F3337" )
			)
			( gate "@baseboard_fab2_lib.baseboard_fab2(sch_1):page213_i35"
				( objectStatus "F3314" )
			)
			( gate "@baseboard_fab2_lib.baseboard_fab2(sch_1):page161_i90"
				( objectStatus "F3346" )
			)
			( gate "@baseboard_fab2_lib.baseboard_fab2(sch_1):page161_i93"
				( objectStatus "F3345" )
			)
			( gate "@baseboard_fab2_lib.baseboard_fab2(sch_1):page165_i61"
				( objectStatus "F3240" )
			)
			( gate "@baseboard_fab2_lib.baseboard_fab2(sch_1):page203_i46"
				( objectStatus "F3315" )
			)
			( gate "@baseboard_fab2_lib.baseboard_fab2(sch_1):page203_i52"
				( objectStatus "F3321" )
			)
			( gate "@baseboard_fab2_lib.baseboard_fab2(sch_1):page151_i86"
				( objectStatus "F3396" )
			)
			( gate "@baseboard_fab2_lib.baseboard_fab2(sch_1):page151_i84"
				( objectStatus "F3393" )
			)
			( gate "@baseboard_fab2_lib.baseboard_fab2(sch_1):page151_i83"
				( objectStatus "F3401" )
			)
			( gate "@baseboard_fab2_lib.baseboard_fab2(sch_1):page151_i82"
				( objectStatus "F3402" )
			)
			( gate "@baseboard_fab2_lib.baseboard_fab2(sch_1):page151_i81"
				( objectStatus "F3391" )
			)
			( gate "@baseboard_fab2_lib.baseboard_fab2(sch_1):page151_i80"
				( objectStatus "F3412" )
			)
			( gate "@baseboard_fab2_lib.baseboard_fab2(sch_1):page151_i76"
				( objectStatus "F3409" )
			)
			( gate "@baseboard_fab2_lib.baseboard_fab2(sch_1):page151_i79"
				( objectStatus "F3394" )
			)
			( gate "@baseboard_fab2_lib.baseboard_fab2(sch_1):page151_i78"
				( objectStatus "F3392" )
			)
			( gate "@baseboard_fab2_lib.baseboard_fab2(sch_1):page151_i58"
				( objectStatus "F3405" )
			)
			( gate "@baseboard_fab2_lib.baseboard_fab2(sch_1):page161_i4"
				( objectStatus "F3454" )
			)
			( gate "@baseboard_fab2_lib.baseboard_fab2(sch_1):page161_i26"
				( objectStatus "F3239" )
			)
			( gate "@baseboard_fab2_lib.baseboard_fab2(sch_1):page198_i52"
				( objectStatus "F3281" )
			)
			( gate "@baseboard_fab2_lib.baseboard_fab2(sch_1):page198_i49"
				( objectStatus "F3279" )
			)
			( gate "@baseboard_fab2_lib.baseboard_fab2(sch_1):page198_i43"
				( objectStatus "F3354" )
			)
			( gate "@baseboard_fab2_lib.baseboard_fab2(sch_1):page198_i46"
				( objectStatus "F3353" )
			)
			( gate "@baseboard_fab2_lib.baseboard_fab2(sch_1):page198_i37"
				( objectStatus "F3271" )
			)
			( gate "@baseboard_fab2_lib.baseboard_fab2(sch_1):page198_i41"
				( objectStatus "F3270" )
			)
			( gate "@baseboard_fab2_lib.baseboard_fab2(sch_1):page198_i24"
				( objectStatus "F3259" )
			)
			( gate "@baseboard_fab2_lib.baseboard_fab2(sch_1):page198_i28"
				( objectStatus "F3280" )
			)
			( gate "@baseboard_fab2_lib.baseboard_fab2(sch_1):page198_i26"
				( objectStatus "F3269" )
			)
			( gate "@baseboard_fab2_lib.baseboard_fab2(sch_1):page130_i16"
				( objectStatus "F3339" )
			)
			( gate "@baseboard_fab2_lib.baseboard_fab2(sch_1):page149_i147"
				( objectStatus "F3417" )
			)
			( gate "@baseboard_fab2_lib.baseboard_fab2(sch_1):page158_i97"
				( objectStatus "F3420" )
			)
			( gate "@baseboard_fab2_lib.baseboard_fab2(sch_1):page176_i108"
				( objectStatus "F3252" )
			)
			( gate "@baseboard_fab2_lib.baseboard_fab2(sch_1):page141_i47"
				( objectStatus "F3242" )
			)
			( gate "@baseboard_fab2_lib.baseboard_fab2(sch_1):page141_i46"
				( objectStatus "F3243" )
			)
			( gate "@baseboard_fab2_lib.baseboard_fab2(sch_1):page141_i33"
				( objectStatus "F3241" )
			)
			( gate "@baseboard_fab2_lib.baseboard_fab2(sch_1):page167_i39"
				( objectStatus "F3251" )
			)
			( gate "@baseboard_fab2_lib.baseboard_fab2(sch_1):page167_i41"
				( objectStatus "F3230" )
			)
			( gate "@baseboard_fab2_lib.baseboard_fab2(sch_1):page167_i42"
				( objectStatus "F3231" )
			)
			( gate "@baseboard_fab2_lib.baseboard_fab2(sch_1):page218_i31"
				( objectStatus "F3291" )
			)
			( gate "@baseboard_fab2_lib.baseboard_fab2(sch_1):page218_i23"
				( objectStatus "F3290" )
			)
			( gate "@baseboard_fab2_lib.baseboard_fab2(sch_1):page223_i27"
				( objectStatus "F3449" )
			)
			( gate "@baseboard_fab2_lib.baseboard_fab2(sch_1):page223_i44"
				( objectStatus "F3450" )
			)
			( gate "@baseboard_fab2_lib.baseboard_fab2(sch_1):page226_i27"
				( objectStatus "F3472" )
			)
			( gate "@baseboard_fab2_lib.baseboard_fab2(sch_1):page226_i44"
				( objectStatus "F3473" )
			)
			( gate "@baseboard_fab2_lib.baseboard_fab2(sch_1):page139_i90"
				( objectStatus "F3387" )
			)
			( gate "@baseboard_fab2_lib.baseboard_fab2(sch_1):page139_i89"
				( objectStatus "F3388" )
			)
			( gate "@baseboard_fab2_lib.baseboard_fab2(sch_1):page139_i88"
				( objectStatus "F3250" )
			)
			( gate "@baseboard_fab2_lib.baseboard_fab2(sch_1):page139_i87"
				( objectStatus "F3249" )
			)
			( gate "@baseboard_fab2_lib.baseboard_fab2(sch_1):page209_i17"
				( objectStatus "F3466" )
			)
			( gate "@baseboard_fab2_lib.baseboard_fab2(sch_1):page93_i95"
				( objectStatus "F3357" )
			)
			( gate "@baseboard_fab2_lib.baseboard_fab2(sch_1):page101_i112"
				( objectStatus "F3364" )
			)
			( gate "@baseboard_fab2_lib.baseboard_fab2(sch_1):page101_i111"
				( objectStatus "F3361" )
			)
			( gate "@baseboard_fab2_lib.baseboard_fab2(sch_1):page101_i110"
				( objectStatus "F3358" )
			)
			( gate "@baseboard_fab2_lib.baseboard_fab2(sch_1):page140_i3"
				( objectStatus "F3430" )
			)
			( gate "@baseboard_fab2_lib.baseboard_fab2(sch_1):page139_i143"
				( objectStatus "F3433" )
			)
			( gate "@baseboard_fab2_lib.baseboard_fab2(sch_1):page139_i144"
				( objectStatus "F3424" )
			)
			( gate "@baseboard_fab2_lib.baseboard_fab2(sch_1):page139_i145"
				( objectStatus "F3437" )
			)
			( gate "@baseboard_fab2_lib.baseboard_fab2(sch_1):page139_i146"
				( objectStatus "F3432" )
			)
			( gate "@baseboard_fab2_lib.baseboard_fab2(sch_1):page139_i152"
				( objectStatus "F3425" )
			)
			( gate "@baseboard_fab2_lib.baseboard_fab2(sch_1):page139_i151"
				( objectStatus "F3434" )
			)
			( gate "@baseboard_fab2_lib.baseboard_fab2(sch_1):page139_i150"
				( objectStatus "F3426" )
			)
			( gate "@baseboard_fab2_lib.baseboard_fab2(sch_1):page139_i149"
				( objectStatus "F3429" )
			)
			( gate "@baseboard_fab2_lib.baseboard_fab2(sch_1):page139_i160"
				( objectStatus "F3436" )
			)
			( gate "@baseboard_fab2_lib.baseboard_fab2(sch_1):page139_i159"
				( objectStatus "F3431" )
			)
			( gate "@baseboard_fab2_lib.baseboard_fab2(sch_1):page139_i158"
				( objectStatus "F3423" )
			)
			( gate "@baseboard_fab2_lib.baseboard_fab2(sch_1):page139_i157"
				( objectStatus "F3435" )
			)
			( gate "@baseboard_fab2_lib.baseboard_fab2(sch_1):page176_i63"
				( objectStatus "F3442" )
			)
			( gate "@baseboard_fab2_lib.baseboard_fab2(sch_1):page176_i64"
				( objectStatus "F3443" )
			)
			( gate "@baseboard_fab2_lib.baseboard_fab2(sch_1):page186_i270"
				( objectStatus "F3441" )
			)
			( gate "@baseboard_fab2_lib.baseboard_fab2(sch_1):page149_i105"
				( objectStatus "F3245" )
			)
			( gate "@baseboard_fab2_lib.baseboard_fab2(sch_1):page99_i41"
				( objectStatus "F3308" )
			)
			( gate "@baseboard_fab2_lib.baseboard_fab2(sch_1):page99_i47"
				( objectStatus "F3344" )
			)
			( gate "@baseboard_fab2_lib.baseboard_fab2(sch_1):page99_i53"
				( objectStatus "F3343" )
			)
			( gate "@baseboard_fab2_lib.baseboard_fab2(sch_1):page111_i59"
				( objectStatus "F3254" )
			)
			( gate "@baseboard_fab2_lib.baseboard_fab2(sch_1):page111_i10"
				( objectStatus "F3256" )
			)
			( gate "@baseboard_fab2_lib.baseboard_fab2(sch_1):page111_i12"
				( objectStatus "F3253" )
			)
			( gate "@baseboard_fab2_lib.baseboard_fab2(sch_1):page111_i14"
				( objectStatus "F3447" )
			)
			( gate "@baseboard_fab2_lib.baseboard_fab2(sch_1):page108_i5"
				( objectStatus "F3351" )
			)
			( gate "@baseboard_fab2_lib.baseboard_fab2(sch_1):page108_i1"
				( objectStatus "F3352" )
			)
			( gate "@baseboard_fab2_lib.baseboard_fab2(sch_1):page108_i7"
				( objectStatus "F3347" )
			)
			( gate "@baseboard_fab2_lib.baseboard_fab2(sch_1):page108_i2"
				( objectStatus "F3348" )
			)
			( gate "@baseboard_fab2_lib.baseboard_fab2(sch_1):page149_i1"
				( objectStatus "F3403" )
			)
			( gate "@baseboard_fab2_lib.baseboard_fab2(sch_1):page149_i4"
				( objectStatus "F3400" )
			)
			( gate "@baseboard_fab2_lib.baseboard_fab2(sch_1):page149_i5"
				( objectStatus "F3414" )
			)
			( gate "@baseboard_fab2_lib.baseboard_fab2(sch_1):page149_i6"
				( objectStatus "F3413" )
			)
			( gate "@baseboard_fab2_lib.baseboard_fab2(sch_1):page149_i20"
				( objectStatus "F3408" )
			)
			( gate "@baseboard_fab2_lib.baseboard_fab2(sch_1):page149_i21"
				( objectStatus "F3407" )
			)
			( gate "@baseboard_fab2_lib.baseboard_fab2(sch_1):page149_i18"
				( objectStatus "F3399" )
			)
			( gate "@baseboard_fab2_lib.baseboard_fab2(sch_1):page149_i24"
				( objectStatus "F3406" )
			)
			( gate "@baseboard_fab2_lib.baseboard_fab2(sch_1):page149_i25"
				( objectStatus "F3395" )
			)
			( gate "@baseboard_fab2_lib.baseboard_fab2(sch_1):page149_i23"
				( objectStatus "F3397" )
			)
			( gate "@baseboard_fab2_lib.baseboard_fab2(sch_1):page149_i43"
				( objectStatus "F3418" )
			)
			( gate "@baseboard_fab2_lib.baseboard_fab2(sch_1):page149_i41"
				( objectStatus "F3404" )
			)
			( gate "@baseboard_fab2_lib.baseboard_fab2(sch_1):page149_i44"
				( objectStatus "F3422" )
			)
			( gate "@baseboard_fab2_lib.baseboard_fab2(sch_1):page149_i42"
				( objectStatus "F3416" )
			)
			( gate "@baseboard_fab2_lib.baseboard_fab2(sch_1):page149_i49"
				( objectStatus "F3419" )
			)
			( gate "@baseboard_fab2_lib.baseboard_fab2(sch_1):page149_i46"
				( objectStatus "F3415" )
			)
			( gate "@baseboard_fab2_lib.baseboard_fab2(sch_1):page202_i46"
				( objectStatus "F3313" )
			)
			( gate "@baseboard_fab2_lib.baseboard_fab2(sch_1):page202_i35"
				( objectStatus "F3311" )
			)
			( gate "@baseboard_fab2_lib.baseboard_fab2(sch_1):page216_i51"
				( objectStatus "F3275" )
			)
			( gate "@baseboard_fab2_lib.baseboard_fab2(sch_1):page216_i78"
				( objectStatus "F3274" )
			)
			( gate "@baseboard_fab2_lib.baseboard_fab2(sch_1):page205_i31"
				( objectStatus "F3323" )
			)
			( gate "@baseboard_fab2_lib.baseboard_fab2(sch_1):page215_i311"
				( objectStatus "F3276" )
			)
			( gate "@baseboard_fab2_lib.baseboard_fab2(sch_1):page215_i327"
				( objectStatus "F3277" )
			)
			( gate "@baseboard_fab2_lib.baseboard_fab2(sch_1):page219_i51"
				( objectStatus "F3293" )
			)
			( gate "@baseboard_fab2_lib.baseboard_fab2(sch_1):page219_i78"
				( objectStatus "F3292" )
			)
			( gate "@baseboard_fab2_lib.baseboard_fab2(sch_1):page227_i51"
				( objectStatus "F3475" )
			)
			( gate "@baseboard_fab2_lib.baseboard_fab2(sch_1):page227_i78"
				( objectStatus "F3474" )
			)
			( gate "@baseboard_fab2_lib.baseboard_fab2(sch_1):page224_i51"
				( objectStatus "F3451" )
			)
			( gate "@baseboard_fab2_lib.baseboard_fab2(sch_1):page224_i78"
				( objectStatus "F3452" )
			)
			( gate "@baseboard_fab2_lib.baseboard_fab2(sch_1):page201_i39"
				( objectStatus "F3320" )
			)
			( gate "@baseboard_fab2_lib.baseboard_fab2(sch_1):page201_i32"
				( objectStatus "F3317" )
			)
			( gate "@baseboard_fab2_lib.baseboard_fab2(sch_1):page206_i42"
				( objectStatus "F3469" )
			)
			( gate "@baseboard_fab2_lib.baseboard_fab2(sch_1):page206_i31"
				( objectStatus "F3468" )
			)
			( gate "@baseboard_fab2_lib.baseboard_fab2(sch_1):page186_i10"
				( objectStatus "F3438" )
			)
			( gate "@baseboard_fab2_lib.baseboard_fab2(sch_1):page186_i7"
				( objectStatus "F3439" )
			)
			( gate "@baseboard_fab2_lib.baseboard_fab2(sch_1):page186_i8"
				( objectStatus "F3440" )
			)
			( gate "@baseboard_fab2_lib.baseboard_fab2(sch_1):page199_i7"
				( objectStatus "F3460" )
			)
			( gate "@baseboard_fab2_lib.baseboard_fab2(sch_1):page207_i33"
				( objectStatus "F3457" )
			)
			( gate "@baseboard_fab2_lib.baseboard_fab2(sch_1):page207_i41"
				( objectStatus "F3458" )
			)
			( gate "@baseboard_fab2_lib.baseboard_fab2(sch_1):page208_i44"
				( objectStatus "F3459" )
			)
			( gate "@baseboard_fab2_lib.baseboard_fab2(sch_1):page208_i51"
				( objectStatus "F3463" )
			)
			( gate "@baseboard_fab2_lib.baseboard_fab2(sch_1):page210_i27"
				( objectStatus "F3467" )
			)
			( gate "@baseboard_fab2_lib.baseboard_fab2(sch_1):page99_i7"
				( objectStatus "F3303" )
			)
			( gate "@baseboard_fab2_lib.baseboard_fab2(sch_1):page99_i32"
				( objectStatus "F3284" )
			)
			( gate "@baseboard_fab2_lib.baseboard_fab2(sch_1):page99_i2"
				( objectStatus "F3304" )
			)
			( gate "@baseboard_fab2_lib.baseboard_fab2(sch_1):page99_i23"
				( objectStatus "F3285" )
			)
			( gate "@baseboard_fab2_lib.baseboard_fab2(sch_1):page99_i27"
				( objectStatus "F3309" )
			)
			( gate "@baseboard_fab2_lib.baseboard_fab2(sch_1):page199_i53"
				( objectStatus "F3464" )
			)
			( gate "@baseboard_fab2_lib.baseboard_fab2(sch_1):page204_i35"
				( objectStatus "F3322" )
			)
			( gate "@baseboard_fab2_lib.baseboard_fab2(sch_1):page195_i36"
				( objectStatus "F3232" )
			)
			( gate "@baseboard_fab2_lib.baseboard_fab2(sch_1):page195_i37"
				( objectStatus "F3233" )
			)
			( gate "@baseboard_fab2_lib.baseboard_fab2(sch_1):page195_i38"
				( objectStatus "F3455" )
			)
			( gate "@baseboard_fab2_lib.baseboard_fab2(sch_1):page195_i39"
				( objectStatus "F3456" )
			)
			( gate "@baseboard_fab2_lib.baseboard_fab2(sch_1):page149_i17"
				( objectStatus "F3398" )
			)
			( gate "@baseboard_fab2_lib.baseboard_fab2(sch_1):page149_i22"
				( objectStatus "F3410" )
			)
			( gate "@baseboard_fab2_lib.baseboard_fab2(sch_1):page92_i37"
				( objectStatus "F3332" )
			)
			( gate "@baseboard_fab2_lib.baseboard_fab2(sch_1):page92_i52"
				( objectStatus "F3286" )
			)
			( gate "@baseboard_fab2_lib.baseboard_fab2(sch_1):page143_i336"
				( objectStatus "F3411" )
			)
			( gate "@baseboard_fab2_lib.baseboard_fab2(sch_1):page169_i108"
				( objectStatus "F3212" )
			)
			( gate "@baseboard_fab2_lib.baseboard_fab2(sch_1):page234_i212"
				( objectStatus "F3208" )
			)
			( gate "@baseboard_fab2_lib.baseboard_fab2(sch_1):page233_i273"
				( objectStatus "F3207" )
			)
			( gate "@baseboard_fab2_lib.baseboard_fab2(sch_1):page232_i301"
				( objectStatus "F3206" )
			)
			( gate "@baseboard_fab2_lib.baseboard_fab2(sch_1):page231_i199"
				( objectStatus "F3205" )
			)
			( gate "@baseboard_fab2_lib.baseboard_fab2(sch_1):page149_i142"
				( objectStatus "F3209" )
			)
			( gate "@baseboard_fab2_lib.baseboard_fab2(sch_1):page148_i26"
				( objectStatus "F3210" )
			)
			( gate "@baseboard_fab2_lib.baseboard_fab2(sch_1):page149_i119"
				( objectStatus "F3211" )
			)
			( gate "@baseboard_fab2_lib.baseboard_fab2(sch_1):page149_i104"
				( objectStatus "F3204" )
			)
			( gate "@baseboard_fab2_lib.baseboard_fab2(sch_1):page232_i185"
				( objectStatus "F3197" )
			)
			( gate "@baseboard_fab2_lib.baseboard_fab2(sch_1):page233_i183"
				( objectStatus "F3200" )
			)
			( gate "@baseboard_fab2_lib.baseboard_fab2(sch_1):page234_i129"
				( objectStatus "F3201" )
			)
			( gate "@baseboard_fab2_lib.baseboard_fab2(sch_1):page231_i140"
				( objectStatus "F3196" )
			)
			( gate "@baseboard_fab2_lib.baseboard_fab2(sch_1):page240_i113"
				( objectStatus "F3193" )
			)
			( gate "@baseboard_fab2_lib.baseboard_fab2(sch_1):page237_i55"
				( objectStatus "F3195" )
			)
			( gate "@baseboard_fab2_lib.baseboard_fab2(sch_1):page221_i39"
				( objectStatus "F3198" )
			)
			( gate "@baseboard_fab2_lib.baseboard_fab2(sch_1):page222_i40"
				( objectStatus "F3203" )
			)
			( gate "@baseboard_fab2_lib.baseboard_fab2(sch_1):page229_i36"
				( objectStatus "F3199" )
			)
			( gate "@baseboard_fab2_lib.baseboard_fab2(sch_1):page230_i39"
				( objectStatus "F3202" )
			)
			( gate "@baseboard_fab2_lib.baseboard_fab2(sch_1):page241_i41"
				( objectStatus "F3194" )
			)
			( gate "@baseboard_fab2_lib.baseboard_fab2(sch_1):page238_i5"
				( objectStatus "F3191" )
			)
			( gate "@baseboard_fab2_lib.baseboard_fab2(sch_1):page239_i30"
				( objectStatus "F3192" )
			)
			( gate "@baseboard_fab2_lib.baseboard_fab2(sch_1):page201_i125"
				( objectStatus "F3176" )
			)
			( gate "@baseboard_fab2_lib.baseboard_fab2(sch_1):page206_i114"
				( objectStatus "F3187" )
			)
			( gate "@baseboard_fab2_lib.baseboard_fab2(sch_1):page211_i71"
				( objectStatus "F3183" )
			)
			( gate "@baseboard_fab2_lib.baseboard_fab2(sch_1):page213_i73"
				( objectStatus "F3178" )
			)
			( gate "@baseboard_fab2_lib.baseboard_fab2(sch_1):page235_i218"
				( objectStatus "F3164" )
			)
			( gate "@baseboard_fab2_lib.baseboard_fab2(sch_1):page215_i305"
				( objectStatus "F3167" )
			)
			( gate "@baseboard_fab2_lib.baseboard_fab2(sch_1):page218_i26"
				( objectStatus "F3171" )
			)
			( gate "@baseboard_fab2_lib.baseboard_fab2(sch_1):page223_i80"
				( objectStatus "F3186" )
			)
			( gate "@baseboard_fab2_lib.baseboard_fab2(sch_1):page226_i80"
				( objectStatus "F3190" )
			)
			( gate "@baseboard_fab2_lib.baseboard_fab2(sch_1):page232_i209"
				( objectStatus "F3170" )
			)
			( gate "@baseboard_fab2_lib.baseboard_fab2(sch_1):page233_i201"
				( objectStatus "F3175" )
			)
			( gate "@baseboard_fab2_lib.baseboard_fab2(sch_1):page234_i139"
				( objectStatus "F3180" )
			)
			( gate "@baseboard_fab2_lib.baseboard_fab2(sch_1):page231_i142"
				( objectStatus "F3168" )
			)
			( gate "@baseboard_fab2_lib.baseboard_fab2(sch_1):page240_i116"
				( objectStatus "F3162" )
			)
			( gate "@baseboard_fab2_lib.baseboard_fab2(sch_1):page221_i15"
				( objectStatus "F3173" )
			)
			( gate "@baseboard_fab2_lib.baseboard_fab2(sch_1):page222_i12"
				( objectStatus "F3181" )
			)
			( gate "@baseboard_fab2_lib.baseboard_fab2(sch_1):page229_i15"
				( objectStatus "F3174" )
			)
			( gate "@baseboard_fab2_lib.baseboard_fab2(sch_1):page230_i16"
				( objectStatus "F3182" )
			)
			( gate "@baseboard_fab2_lib.baseboard_fab2(sch_1):page237_i5"
				( objectStatus "F3163" )
			)
			( gate "@baseboard_fab2_lib.baseboard_fab2(sch_1):page235_i167"
				( objectStatus "F3165" )
			)
			( gate "@baseboard_fab2_lib.baseboard_fab2(sch_1):page211_i33"
				( objectStatus "F3184" )
			)
			( gate "@baseboard_fab2_lib.baseboard_fab2(sch_1):page213_i33"
				( objectStatus "F3177" )
			)
			( gate "@baseboard_fab2_lib.baseboard_fab2(sch_1):page218_i55"
				( objectStatus "F3172" )
			)
			( gate "@baseboard_fab2_lib.baseboard_fab2(sch_1):page223_i59"
				( objectStatus "F3185" )
			)
			( gate "@baseboard_fab2_lib.baseboard_fab2(sch_1):page226_i59"
				( objectStatus "F3189" )
			)
			( gate "@baseboard_fab2_lib.baseboard_fab2(sch_1):page241_i14"
				( objectStatus "F3169" )
			)
			( gate "@baseboard_fab2_lib.baseboard_fab2(sch_1):page238_i19"
				( objectStatus "F3161" )
			)
			( gate "@baseboard_fab2_lib.baseboard_fab2(sch_1):page239_i4"
				( objectStatus "F3160" )
			)
			( gate "@baseboard_fab2_lib.baseboard_fab2(sch_1):page215_i339"
				( objectStatus "F3166" )
			)
			( gate "@baseboard_fab2_lib.baseboard_fab2(sch_1):page201_i60"
				( objectStatus "F3179" )
			)
			( gate "@baseboard_fab2_lib.baseboard_fab2(sch_1):page206_i73"
				( objectStatus "F3188" )
			)
			( gate "@baseboard_fab2_lib.baseboard_fab2(sch_1):page114_i56"
				( objectStatus "F3155" )
			)
			( gate "@baseboard_fab2_lib.baseboard_fab2(sch_1):page114_i46"
				( objectStatus "F3154" )
			)
			( gate "@baseboard_fab2_lib.baseboard_fab2(sch_1):page139_i112"
				( objectStatus "F3152" )
			)
			( gate "@baseboard_fab2_lib.baseboard_fab2(sch_1):page139_i111"
				( objectStatus "F3153" )
			)
			( gate "@baseboard_fab2_lib.baseboard_fab2(sch_1):page232_i306"
				( objectStatus "F3146" )
			)
			( gate "@baseboard_fab2_lib.baseboard_fab2(sch_1):page234_i218"
				( objectStatus "F3151" )
			)
			( gate "@baseboard_fab2_lib.baseboard_fab2(sch_1):page234_i211"
				( objectStatus "F3150" )
			)
			( gate "@baseboard_fab2_lib.baseboard_fab2(sch_1):page233_i274"
				( objectStatus "F3149" )
			)
			( gate "@baseboard_fab2_lib.baseboard_fab2(sch_1):page233_i267"
				( objectStatus "F3148" )
			)
			( gate "@baseboard_fab2_lib.baseboard_fab2(sch_1):page232_i302"
				( objectStatus "F3147" )
			)
			( gate "@baseboard_fab2_lib.baseboard_fab2(sch_1):page231_i200"
				( objectStatus "F3145" )
			)
			( gate "@baseboard_fab2_lib.baseboard_fab2(sch_1):page231_i219"
				( objectStatus "F3144" )
			)
			( gate "@baseboard_fab2_lib.baseboard_fab2(sch_1):page241_i57"
				( objectStatus "F3143" )
			)
			( gate "@baseboard_fab2_lib.baseboard_fab2(sch_1):page235_i153"
				( objectStatus "F3134" )
			)
			( gate "@baseboard_fab2_lib.baseboard_fab2(sch_1):page235_i209"
				( objectStatus "F3123" )
			)
			( gate "@baseboard_fab2_lib.baseboard_fab2(sch_1):page211_i83"
				( objectStatus "F3133" )
			)
			( gate "@baseboard_fab2_lib.baseboard_fab2(sch_1):page213_i83"
				( objectStatus "F3129" )
			)
			( gate "@baseboard_fab2_lib.baseboard_fab2(sch_1):page218_i39"
				( objectStatus "F3126" )
			)
			( gate "@baseboard_fab2_lib.baseboard_fab2(sch_1):page218_i61"
				( objectStatus "F3127" )
			)
			( gate "@baseboard_fab2_lib.baseboard_fab2(sch_1):page223_i36"
				( objectStatus "F3135" )
			)
			( gate "@baseboard_fab2_lib.baseboard_fab2(sch_1):page223_i39"
				( objectStatus "F3136" )
			)
			( gate "@baseboard_fab2_lib.baseboard_fab2(sch_1):page226_i36"
				( objectStatus "F3142" )
			)
			( gate "@baseboard_fab2_lib.baseboard_fab2(sch_1):page226_i39"
				( objectStatus "F3141" )
			)
			( gate "@baseboard_fab2_lib.baseboard_fab2(sch_1):page215_i342"
				( objectStatus "F3124" )
			)
			( gate "@baseboard_fab2_lib.baseboard_fab2(sch_1):page215_i320"
				( objectStatus "F3125" )
			)
			( gate "@baseboard_fab2_lib.baseboard_fab2(sch_1):page201_i70"
				( objectStatus "F3128" )
				( pin "A"
					( objectStatus "C4D45.1" )
				)
				( pin "B"
					( objectStatus "C4D45.2" )
				)
			)
			( gate "@baseboard_fab2_lib.baseboard_fab2(sch_1):page201_i68"
				( objectStatus "F3131" )
			)
			( gate "@baseboard_fab2_lib.baseboard_fab2(sch_1):page201_i66"
				( objectStatus "F3132" )
			)
			( gate "@baseboard_fab2_lib.baseboard_fab2(sch_1):page201_i64"
				( objectStatus "F3130" )
			)
			( gate "@baseboard_fab2_lib.baseboard_fab2(sch_1):page206_i78"
				( objectStatus "F3137" )
			)
			( gate "@baseboard_fab2_lib.baseboard_fab2(sch_1):page206_i71"
				( objectStatus "F3139" )
			)
			( gate "@baseboard_fab2_lib.baseboard_fab2(sch_1):page206_i69"
				( objectStatus "F3140" )
			)
			( gate "@baseboard_fab2_lib.baseboard_fab2(sch_1):page206_i68"
				( objectStatus "F3138" )
			)
			( gate "@baseboard_fab2_lib.baseboard_fab2(sch_1):page101_i53"
				( objectStatus "F3121" )
			)
			( gate "@baseboard_fab2_lib.baseboard_fab2(sch_1):page101_i49"
				( objectStatus "F3122" )
			)
			( gate "@baseboard_fab2_lib.baseboard_fab2(sch_1):page241_i53"
				( objectStatus "F3120" )
			)
			( gate "@baseboard_fab2_lib.baseboard_fab2(sch_1):page232_i220"
				( objectStatus "F3115" )
			)
			( gate "@baseboard_fab2_lib.baseboard_fab2(sch_1):page233_i209"
				( objectStatus "F3116" )
			)
			( gate "@baseboard_fab2_lib.baseboard_fab2(sch_1):page234_i163"
				( objectStatus "F3117" )
			)
			( gate "@baseboard_fab2_lib.baseboard_fab2(sch_1):page231_i175"
				( objectStatus "F3114" )
			)
			( gate "@baseboard_fab2_lib.baseboard_fab2(sch_1):page240_i163"
				( objectStatus "F3113" )
			)
			( gate "@baseboard_fab2_lib.baseboard_fab2(sch_1):page169_i153"
				( objectStatus "F3108" )
			)
			( gate "@baseboard_fab2_lib.baseboard_fab2(sch_1):page169_i139"
				( objectStatus "F3110" )
			)
			( gate "@baseboard_fab2_lib.baseboard_fab2(sch_1):page169_i146"
				( objectStatus "F3111" )
			)
			( gate "@baseboard_fab2_lib.baseboard_fab2(sch_1):page169_i56"
				( objectStatus "F3112" )
			)
			( gate "@baseboard_fab2_lib.baseboard_fab2(sch_1):page169_i68"
				( objectStatus "F3106" )
			)
			( gate "@baseboard_fab2_lib.baseboard_fab2(sch_1):page169_i80"
				( objectStatus "F3109" )
			)
			( gate "@baseboard_fab2_lib.baseboard_fab2(sch_1):page169_i86"
				( objectStatus "F3107" )
			)
			( gate "@baseboard_fab2_lib.baseboard_fab2(sch_1):page141_i60"
				( objectStatus "F3097" )
			)
			( gate "@baseboard_fab2_lib.baseboard_fab2(sch_1):page141_i58"
				( objectStatus "F3096" )
			)
			( gate "@baseboard_fab2_lib.baseboard_fab2(sch_1):page141_i59"
				( objectStatus "F3094" )
			)
			( gate "@baseboard_fab2_lib.baseboard_fab2(sch_1):page141_i36"
				( objectStatus "F3095" )
			)
			( gate "@baseboard_fab2_lib.baseboard_fab2(sch_1):page149_i85"
				( objectStatus "F3093" )
			)
			( gate "@baseboard_fab2_lib.baseboard_fab2(sch_1):page237_i29"
				( objectStatus "F3075" )
			)
			( gate "@baseboard_fab2_lib.baseboard_fab2(sch_1):page130_i25"
				( objectStatus "F3082" )
			)
			( gate "@baseboard_fab2_lib.baseboard_fab2(sch_1):page130_i22"
				( objectStatus "F3071" )
			)
			( gate "@baseboard_fab2_lib.baseboard_fab2(sch_1):page130_i24"
				( objectStatus "F3078" )
			)
			( gate "@baseboard_fab2_lib.baseboard_fab2(sch_1):page130_i21"
				( objectStatus "F3072" )
			)
			( gate "@baseboard_fab2_lib.baseboard_fab2(sch_1):page130_i20"
				( objectStatus "F3073" )
			)
			( gate "@baseboard_fab2_lib.baseboard_fab2(sch_1):page130_i19"
				( objectStatus "F3074" )
			)
			( gate "@baseboard_fab2_lib.baseboard_fab2(sch_1):page130_i2"
				( objectStatus "F3076" )
			)
			( gate "@baseboard_fab2_lib.baseboard_fab2(sch_1):page130_i15"
				( objectStatus "F3080" )
			)
			( gate "@baseboard_fab2_lib.baseboard_fab2(sch_1):page130_i9"
				( objectStatus "F3079" )
			)
			( gate "@baseboard_fab2_lib.baseboard_fab2(sch_1):page130_i8"
				( objectStatus "F3077" )
			)
			( gate "@baseboard_fab2_lib.baseboard_fab2(sch_1):page130_i28"
				( objectStatus "F3081" )
			)
			( gate "@baseboard_fab2_lib.baseboard_fab2(sch_1):page238_i7"
				( objectStatus "F3069" )
			)
			( gate "@baseboard_fab2_lib.baseboard_fab2(sch_1):page238_i23"
				( objectStatus "F3070" )
			)
			( gate "@baseboard_fab2_lib.baseboard_fab2(sch_1):page239_i22"
				( objectStatus "F3084" )
			)
			( gate "@baseboard_fab2_lib.baseboard_fab2(sch_1):page239_i12"
				( objectStatus "F3083" )
			)
			( gate "@baseboard_fab2_lib.baseboard_fab2(sch_1):page139_i136"
				( objectStatus "F3087" )
			)
			( gate "@baseboard_fab2_lib.baseboard_fab2(sch_1):page139_i135"
				( objectStatus "F3086" )
			)
			( gate "@baseboard_fab2_lib.baseboard_fab2(sch_1):page139_i134"
				( objectStatus "F3085" )
			)
			( gate "@baseboard_fab2_lib.baseboard_fab2(sch_1):page139_i142"
				( objectStatus "F3090" )
			)
			( gate "@baseboard_fab2_lib.baseboard_fab2(sch_1):page139_i153"
				( objectStatus "F3088" )
			)
			( gate "@baseboard_fab2_lib.baseboard_fab2(sch_1):page139_i161"
				( objectStatus "F3089" )
			)
			( gate "@baseboard_fab2_lib.baseboard_fab2(sch_1):page240_i109"
				( objectStatus "F2746" )
			)
			( gate "@baseboard_fab2_lib.baseboard_fab2(sch_1):page231_i202"
				( objectStatus "F2744" )
			)
			( gate "@baseboard_fab2_lib.baseboard_fab2(sch_1):page232_i253"
				( objectStatus "F2745" )
			)
			( gate "@baseboard_fab2_lib.baseboard_fab2(sch_1):page233_i187"
				( objectStatus "F2740" )
			)
			( gate "@baseboard_fab2_lib.baseboard_fab2(sch_1):page234_i144"
				( objectStatus "F2741" )
			)
			( gate "@baseboard_fab2_lib.baseboard_fab2(sch_1):page221_i49"
				( objectStatus "F2738" )
			)
			( gate "@baseboard_fab2_lib.baseboard_fab2(sch_1):page222_i46"
				( objectStatus "F2742" )
			)
			( gate "@baseboard_fab2_lib.baseboard_fab2(sch_1):page229_i46"
				( objectStatus "F2739" )
			)
			( gate "@baseboard_fab2_lib.baseboard_fab2(sch_1):page230_i46"
				( objectStatus "F2743" )
			)
			( gate "@baseboard_fab2_lib.baseboard_fab2(sch_1):page148_i25"
				( objectStatus "F2747" )
			)
			( gate "@baseboard_fab2_lib.baseboard_fab2(sch_1):page199_i24"
				( objectStatus "F2685" )
			)
			( gate "@baseboard_fab2_lib.baseboard_fab2(sch_1):page232_i241"
				( objectStatus "F2684" )
			)
			( gate "@baseboard_fab2_lib.baseboard_fab2(sch_1):page233_i224"
				( objectStatus "F2682" )
			)
			( gate "@baseboard_fab2_lib.baseboard_fab2(sch_1):page234_i182"
				( objectStatus "F2683" )
			)
			( gate "@baseboard_fab2_lib.baseboard_fab2(sch_1):page231_i159"
				( objectStatus "F2681" )
			)
			( gate "@baseboard_fab2_lib.baseboard_fab2(sch_1):page240_i129"
				( objectStatus "F2678" )
			)
			( gate "@baseboard_fab2_lib.baseboard_fab2(sch_1):page237_i31"
				( objectStatus "F2680" )
			)
			( gate "@baseboard_fab2_lib.baseboard_fab2(sch_1):page241_i12"
				( objectStatus "F2679" )
			)
			( gate "@baseboard_fab2_lib.baseboard_fab2(sch_1):page231_i149"
				( objectStatus "F2613" )
			)
			( gate "@baseboard_fab2_lib.baseboard_fab2(sch_1):page232_i129"
				( objectStatus "F2644" )
			)
			( gate "@baseboard_fab2_lib.baseboard_fab2(sch_1):page233_i136"
				( objectStatus "F2592" )
			)
			( gate "@baseboard_fab2_lib.baseboard_fab2(sch_1):page231_i122"
				( objectStatus "F2612" )
			)
			( gate "@baseboard_fab2_lib.baseboard_fab2(sch_1):page231_i124"
				( objectStatus "F2637" )
			)
			( gate "@baseboard_fab2_lib.baseboard_fab2(sch_1):page231_i125"
				( objectStatus "F2638" )
			)
			( gate "@baseboard_fab2_lib.baseboard_fab2(sch_1):page231_i126"
				( objectStatus "F2611" )
			)
			( gate "@baseboard_fab2_lib.baseboard_fab2(sch_1):page231_i128"
				( objectStatus "F2610" )
			)
			( gate "@baseboard_fab2_lib.baseboard_fab2(sch_1):page231_i129"
				( objectStatus "F2635" )
			)
			( gate "@baseboard_fab2_lib.baseboard_fab2(sch_1):page231_i130"
				( objectStatus "F2636" )
			)
			( gate "@baseboard_fab2_lib.baseboard_fab2(sch_1):page231_i131"
				( objectStatus "F2609" )
			)
			( gate "@baseboard_fab2_lib.baseboard_fab2(sch_1):page231_i145"
				( objectStatus "F2608" )
			)
			( gate "@baseboard_fab2_lib.baseboard_fab2(sch_1):page231_i146"
				( objectStatus "F2633" )
			)
			( gate "@baseboard_fab2_lib.baseboard_fab2(sch_1):page231_i148"
				( objectStatus "F2634" )
			)
			( gate "@baseboard_fab2_lib.baseboard_fab2(sch_1):page232_i102"
				( objectStatus "F2643" )
			)
			( gate "@baseboard_fab2_lib.baseboard_fab2(sch_1):page232_i104"
				( objectStatus "F2619" )
			)
			( gate "@baseboard_fab2_lib.baseboard_fab2(sch_1):page232_i105"
				( objectStatus "F2620" )
			)
			( gate "@baseboard_fab2_lib.baseboard_fab2(sch_1):page232_i106"
				( objectStatus "F2642" )
			)
			( gate "@baseboard_fab2_lib.baseboard_fab2(sch_1):page232_i108"
				( objectStatus "F2641" )
			)
			( gate "@baseboard_fab2_lib.baseboard_fab2(sch_1):page232_i109"
				( objectStatus "F2617" )
			)
			( gate "@baseboard_fab2_lib.baseboard_fab2(sch_1):page232_i110"
				( objectStatus "F2618" )
			)
			( gate "@baseboard_fab2_lib.baseboard_fab2(sch_1):page232_i111"
				( objectStatus "F2640" )
			)
			( gate "@baseboard_fab2_lib.baseboard_fab2(sch_1):page232_i125"
				( objectStatus "F2639" )
			)
			( gate "@baseboard_fab2_lib.baseboard_fab2(sch_1):page232_i126"
				( objectStatus "F2615" )
			)
			( gate "@baseboard_fab2_lib.baseboard_fab2(sch_1):page232_i128"
				( objectStatus "F2616" )
			)
			( gate "@baseboard_fab2_lib.baseboard_fab2(sch_1):page233_i109"
				( objectStatus "F2591" )
			)
			( gate "@baseboard_fab2_lib.baseboard_fab2(sch_1):page233_i111"
				( objectStatus "F2590" )
			)
			( gate "@baseboard_fab2_lib.baseboard_fab2(sch_1):page233_i112"
				( objectStatus "F2594" )
			)
			( gate "@baseboard_fab2_lib.baseboard_fab2(sch_1):page233_i113"
				( objectStatus "F2593" )
			)
			( gate "@baseboard_fab2_lib.baseboard_fab2(sch_1):page233_i115"
				( objectStatus "F2589" )
			)
			( gate "@baseboard_fab2_lib.baseboard_fab2(sch_1):page233_i116"
				( objectStatus "F2655" )
			)
			( gate "@baseboard_fab2_lib.baseboard_fab2(sch_1):page233_i117"
				( objectStatus "F2654" )
			)
			( gate "@baseboard_fab2_lib.baseboard_fab2(sch_1):page233_i118"
				( objectStatus "F2653" )
			)
			( gate "@baseboard_fab2_lib.baseboard_fab2(sch_1):page233_i132"
				( objectStatus "F2651" )
			)
			( gate "@baseboard_fab2_lib.baseboard_fab2(sch_1):page233_i133"
				( objectStatus "F2652" )
			)
			( gate "@baseboard_fab2_lib.baseboard_fab2(sch_1):page233_i135"
				( objectStatus "F2650" )
			)
			( gate "@baseboard_fab2_lib.baseboard_fab2(sch_1):page234_i97"
				( objectStatus "F2662" )
			)
			( gate "@baseboard_fab2_lib.baseboard_fab2(sch_1):page234_i95"
				( objectStatus "F2660" )
			)
			( gate "@baseboard_fab2_lib.baseboard_fab2(sch_1):page234_i94"
				( objectStatus "F2658" )
			)
			( gate "@baseboard_fab2_lib.baseboard_fab2(sch_1):page234_i93"
				( objectStatus "F2661" )
			)
			( gate "@baseboard_fab2_lib.baseboard_fab2(sch_1):page234_i92"
				( objectStatus "F2596" )
			)
			( gate "@baseboard_fab2_lib.baseboard_fab2(sch_1):page234_i91"
				( objectStatus "F2595" )
			)
			( gate "@baseboard_fab2_lib.baseboard_fab2(sch_1):page234_i90"
				( objectStatus "F2598" )
			)
			( gate "@baseboard_fab2_lib.baseboard_fab2(sch_1):page234_i89"
				( objectStatus "F2597" )
			)
			( gate "@baseboard_fab2_lib.baseboard_fab2(sch_1):page234_i88"
				( objectStatus "F2600" )
			)
			( gate "@baseboard_fab2_lib.baseboard_fab2(sch_1):page234_i87"
				( objectStatus "F2599" )
			)
			( gate "@baseboard_fab2_lib.baseboard_fab2(sch_1):page234_i86"
				( objectStatus "F2659" )
			)
			( gate "@baseboard_fab2_lib.baseboard_fab2(sch_1):page234_i84"
				( objectStatus "F2657" )
			)
			( gate "@baseboard_fab2_lib.baseboard_fab2(sch_1):page127_i54"
				( objectStatus "F2646" )
			)
			( gate "@baseboard_fab2_lib.baseboard_fab2(sch_1):page127_i64"
				( objectStatus "F2663" )
			)
			( gate "@baseboard_fab2_lib.baseboard_fab2(sch_1):page127_i43"
				( objectStatus "F2665" )
			)
			( gate "@baseboard_fab2_lib.baseboard_fab2(sch_1):page127_i49"
				( objectStatus "F2664" )
			)
			( gate "@baseboard_fab2_lib.baseboard_fab2(sch_1):page127_i3"
				( objectStatus "F2649" )
			)
			( gate "@baseboard_fab2_lib.baseboard_fab2(sch_1):page127_i10"
				( objectStatus "F2648" )
			)
			( gate "@baseboard_fab2_lib.baseboard_fab2(sch_1):page127_i19"
				( objectStatus "F2647" )
			)
			( gate "@baseboard_fab2_lib.baseboard_fab2(sch_1):page221_i26"
				( objectStatus "F2602" )
			)
			( gate "@baseboard_fab2_lib.baseboard_fab2(sch_1):page221_i22"
				( objectStatus "F2601" )
			)
			( gate "@baseboard_fab2_lib.baseboard_fab2(sch_1):page222_i26"
				( objectStatus "F2606" )
			)
			( gate "@baseboard_fab2_lib.baseboard_fab2(sch_1):page229_i29"
				( objectStatus "F2604" )
			)
			( gate "@baseboard_fab2_lib.baseboard_fab2(sch_1):page230_i26"
				( objectStatus "F2605" )
			)
			( gate "@baseboard_fab2_lib.baseboard_fab2(sch_1):page222_i24"
				( objectStatus "F2607" )
			)
			( gate "@baseboard_fab2_lib.baseboard_fab2(sch_1):page229_i25"
				( objectStatus "F2603" )
			)
			( gate "@baseboard_fab2_lib.baseboard_fab2(sch_1):page230_i25"
				( objectStatus "F2645" )
			)
			( gate "@baseboard_fab2_lib.baseboard_fab2(sch_1):page217_i190"
				( objectStatus "F2624" )
			)
			( gate "@baseboard_fab2_lib.baseboard_fab2(sch_1):page217_i189"
				( objectStatus "F2623" )
			)
			( gate "@baseboard_fab2_lib.baseboard_fab2(sch_1):page217_i188"
				( objectStatus "F2622" )
			)
			( gate "@baseboard_fab2_lib.baseboard_fab2(sch_1):page217_i186"
				( objectStatus "F2621" )
			)
			( gate "@baseboard_fab2_lib.baseboard_fab2(sch_1):page220_i180"
				( objectStatus "F2629" )
			)
			( gate "@baseboard_fab2_lib.baseboard_fab2(sch_1):page220_i182"
				( objectStatus "F2632" )
			)
			( gate "@baseboard_fab2_lib.baseboard_fab2(sch_1):page220_i183"
				( objectStatus "F2631" )
			)
			( gate "@baseboard_fab2_lib.baseboard_fab2(sch_1):page220_i184"
				( objectStatus "F2630" )
			)
			( gate "@baseboard_fab2_lib.baseboard_fab2(sch_1):page225_i179"
				( objectStatus "F2667" )
			)
			( gate "@baseboard_fab2_lib.baseboard_fab2(sch_1):page225_i180"
				( objectStatus "F2669" )
			)
			( gate "@baseboard_fab2_lib.baseboard_fab2(sch_1):page225_i181"
				( objectStatus "F2666" )
			)
			( gate "@baseboard_fab2_lib.baseboard_fab2(sch_1):page225_i183"
				( objectStatus "F2668" )
			)
			( gate "@baseboard_fab2_lib.baseboard_fab2(sch_1):page228_i186"
				( objectStatus "F2674" )
			)
			( gate "@baseboard_fab2_lib.baseboard_fab2(sch_1):page228_i187"
				( objectStatus "F2677" )
			)
			( gate "@baseboard_fab2_lib.baseboard_fab2(sch_1):page228_i188"
				( objectStatus "F2676" )
			)
			( gate "@baseboard_fab2_lib.baseboard_fab2(sch_1):page228_i190"
				( objectStatus "F2675" )
			)
			( gate "@baseboard_fab2_lib.baseboard_fab2(sch_1):page42_i108"
				( objectStatus "F2628" )
			)
			( gate "@baseboard_fab2_lib.baseboard_fab2(sch_1):page42_i94"
				( objectStatus "F2626" )
			)
			( gate "@baseboard_fab2_lib.baseboard_fab2(sch_1):page42_i93"
				( objectStatus "F2627" )
			)
			( gate "@baseboard_fab2_lib.baseboard_fab2(sch_1):page42_i91"
				( objectStatus "F2625" )
			)
			( gate "@baseboard_fab2_lib.baseboard_fab2(sch_1):page76_i43"
				( objectStatus "F2672" )
			)
			( gate "@baseboard_fab2_lib.baseboard_fab2(sch_1):page76_i42"
				( objectStatus "F2670" )
			)
			( gate "@baseboard_fab2_lib.baseboard_fab2(sch_1):page76_i37"
				( objectStatus "F2671" )
			)
			( gate "@baseboard_fab2_lib.baseboard_fab2(sch_1):page76_i33"
				( objectStatus "F2673" )
			)
			( gate "@baseboard_fab2_lib.baseboard_fab2(sch_1):page72_i25"
				( objectStatus "F2656" )
			)
			( gate "@baseboard_fab2_lib.baseboard_fab2(sch_1):page38_i19"
				( objectStatus "F2614" )
			)
			( gate "@baseboard_fab2_lib.baseboard_fab2(sch_1):page172_i39"
				( objectStatus "F2483" )
			)
			( gate "@baseboard_fab2_lib.baseboard_fab2(sch_1):page172_i36"
				( objectStatus "F2482" )
			)
			( gate "@baseboard_fab2_lib.baseboard_fab2(sch_1):page101_i113"
				( objectStatus "F2548" )
			)
			( gate "@baseboard_fab2_lib.baseboard_fab2(sch_1):page231_i209"
				( objectStatus "F2486" )
			)
			( gate "@baseboard_fab2_lib.baseboard_fab2(sch_1):page231_i210"
				( objectStatus "F2527" )
			)
			( gate "@baseboard_fab2_lib.baseboard_fab2(sch_1):page231_i211"
				( objectStatus "F2525" )
			)
			( gate "@baseboard_fab2_lib.baseboard_fab2(sch_1):page231_i215"
				( objectStatus "F2526" )
			)
			( gate "@baseboard_fab2_lib.baseboard_fab2(sch_1):page232_i259"
				( objectStatus "F2533" )
			)
			( gate "@baseboard_fab2_lib.baseboard_fab2(sch_1):page232_i260"
				( objectStatus "F2532" )
			)
			( gate "@baseboard_fab2_lib.baseboard_fab2(sch_1):page232_i261"
				( objectStatus "F2531" )
			)
			( gate "@baseboard_fab2_lib.baseboard_fab2(sch_1):page232_i262"
				( objectStatus "F2489" )
			)
			( gate "@baseboard_fab2_lib.baseboard_fab2(sch_1):page233_i248"
				( objectStatus "F2492" )
			)
			( gate "@baseboard_fab2_lib.baseboard_fab2(sch_1):page233_i253"
				( objectStatus "F2517" )
			)
			( gate "@baseboard_fab2_lib.baseboard_fab2(sch_1):page233_i254"
				( objectStatus "F2491" )
			)
			( gate "@baseboard_fab2_lib.baseboard_fab2(sch_1):page233_i255"
				( objectStatus "F2490" )
			)
			( gate "@baseboard_fab2_lib.baseboard_fab2(sch_1):page234_i202"
				( objectStatus "F2516" )
			)
			( gate "@baseboard_fab2_lib.baseboard_fab2(sch_1):page234_i203"
				( objectStatus "F2515" )
			)
			( gate "@baseboard_fab2_lib.baseboard_fab2(sch_1):page234_i204"
				( objectStatus "F2514" )
			)
			( gate "@baseboard_fab2_lib.baseboard_fab2(sch_1):page234_i205"
				( objectStatus "F2518" )
			)
			( gate "@baseboard_fab2_lib.baseboard_fab2(sch_1):page198_i61"
				( objectStatus "F2556" )
			)
			( gate "@baseboard_fab2_lib.baseboard_fab2(sch_1):page198_i74"
				( objectStatus "F2474" )
			)
			( gate "@baseboard_fab2_lib.baseboard_fab2(sch_1):page236_i31"
				( objectStatus "F2543" )
			)
			( gate "@baseboard_fab2_lib.baseboard_fab2(sch_1):page236_i24"
				( objectStatus "F2539" )
			)
			( gate "@baseboard_fab2_lib.baseboard_fab2(sch_1):page236_i29"
				( objectStatus "F2541" )
			)
			( gate "@baseboard_fab2_lib.baseboard_fab2(sch_1):page236_i26"
				( objectStatus "F2542" )
			)
			( gate "@baseboard_fab2_lib.baseboard_fab2(sch_1):page236_i32"
				( objectStatus "F2540" )
			)
			( gate "@baseboard_fab2_lib.baseboard_fab2(sch_1):page236_i23"
				( objectStatus "F2538" )
			)
			( gate "@baseboard_fab2_lib.baseboard_fab2(sch_1):page212_i43"
				( objectStatus "F2529" )
			)
			( gate "@baseboard_fab2_lib.baseboard_fab2(sch_1):page212_i40"
				( objectStatus "F2528" )
			)
			( gate "@baseboard_fab2_lib.baseboard_fab2(sch_1):page214_i83"
				( objectStatus "F2497" )
			)
			( gate "@baseboard_fab2_lib.baseboard_fab2(sch_1):page214_i81"
				( objectStatus "F2496" )
			)
			( gate "@baseboard_fab2_lib.baseboard_fab2(sch_1):page214_i80"
				( objectStatus "F2493" )
			)
			( gate "@baseboard_fab2_lib.baseboard_fab2(sch_1):page203_i1"
				( objectStatus "F2500" )
			)
			( gate "@baseboard_fab2_lib.baseboard_fab2(sch_1):page203_i2"
				( objectStatus "F2498" )
			)
			( gate "@baseboard_fab2_lib.baseboard_fab2(sch_1):page203_i54"
				( objectStatus "F2503" )
			)
			( gate "@baseboard_fab2_lib.baseboard_fab2(sch_1):page203_i59"
				( objectStatus "F2507" )
			)
			( gate "@baseboard_fab2_lib.baseboard_fab2(sch_1):page203_i58"
				( objectStatus "F2505" )
			)
			( gate "@baseboard_fab2_lib.baseboard_fab2(sch_1):page203_i57"
				( objectStatus "F2502" )
			)
			( gate "@baseboard_fab2_lib.baseboard_fab2(sch_1):page161_i3"
				( objectStatus "F2553" )
			)
			( gate "@baseboard_fab2_lib.baseboard_fab2(sch_1):page161_i27"
				( objectStatus "F2475" )
			)
			( gate "@baseboard_fab2_lib.baseboard_fab2(sch_1):page198_i53"
				( objectStatus "F2488" )
			)
			( gate "@baseboard_fab2_lib.baseboard_fab2(sch_1):page198_i50"
				( objectStatus "F2487" )
			)
			( gate "@baseboard_fab2_lib.baseboard_fab2(sch_1):page198_i44"
				( objectStatus "F2547" )
			)
			( gate "@baseboard_fab2_lib.baseboard_fab2(sch_1):page198_i47"
				( objectStatus "F2546" )
			)
			( gate "@baseboard_fab2_lib.baseboard_fab2(sch_1):page198_i38"
				( objectStatus "F2484" )
			)
			( gate "@baseboard_fab2_lib.baseboard_fab2(sch_1):page198_i40"
				( objectStatus "F2485" )
			)
			( gate "@baseboard_fab2_lib.baseboard_fab2(sch_1):page195_i31"
				( objectStatus "F2458" )
			)
			( gate "@baseboard_fab2_lib.baseboard_fab2(sch_1):page195_i32"
				( objectStatus "F2555" )
			)
			( gate "@baseboard_fab2_lib.baseboard_fab2(sch_1):page212_i41"
				( objectStatus "F2530" )
			)
			( gate "@baseboard_fab2_lib.baseboard_fab2(sch_1):page209_i5"
				( objectStatus "F2462" )
			)
			( gate "@baseboard_fab2_lib.baseboard_fab2(sch_1):page209_i7"
				( objectStatus "F2463" )
			)
			( gate "@baseboard_fab2_lib.baseboard_fab2(sch_1):page209_i8"
				( objectStatus "F2464" )
			)
			( gate "@baseboard_fab2_lib.baseboard_fab2(sch_1):page186_i3"
				( objectStatus "F2551" )
			)
			( gate "@baseboard_fab2_lib.baseboard_fab2(sch_1):page186_i6"
				( objectStatus "F2552" )
			)
			( gate "@baseboard_fab2_lib.baseboard_fab2(sch_1):page149_i88"
				( objectStatus "F2549" )
			)
			( gate "@baseboard_fab2_lib.baseboard_fab2(sch_1):page149_i84"
				( objectStatus "F2550" )
			)
			( gate "@baseboard_fab2_lib.baseboard_fab2(sch_1):page202_i38"
				( objectStatus "F2506" )
			)
			( gate "@baseboard_fab2_lib.baseboard_fab2(sch_1):page204_i38"
				( objectStatus "F2504" )
			)
			( gate "@baseboard_fab2_lib.baseboard_fab2(sch_1):page202_i51"
				( objectStatus "F2510" )
			)
			( gate "@baseboard_fab2_lib.baseboard_fab2(sch_1):page202_i42"
				( objectStatus "F2494" )
			)
			( gate "@baseboard_fab2_lib.baseboard_fab2(sch_1):page202_i49"
				( objectStatus "F2501" )
			)
			( gate "@baseboard_fab2_lib.baseboard_fab2(sch_1):page202_i48"
				( objectStatus "F2499" )
			)
			( gate "@baseboard_fab2_lib.baseboard_fab2(sch_1):page202_i37"
				( objectStatus "F2495" )
			)
			( gate "@baseboard_fab2_lib.baseboard_fab2(sch_1):page216_i45"
				( objectStatus "F2524" )
			)
			( gate "@baseboard_fab2_lib.baseboard_fab2(sch_1):page216_i84"
				( objectStatus "F2521" )
			)
			( gate "@baseboard_fab2_lib.baseboard_fab2(sch_1):page216_i46"
				( objectStatus "F2523" )
			)
			( gate "@baseboard_fab2_lib.baseboard_fab2(sch_1):page216_i81"
				( objectStatus "F2520" )
			)
			( gate "@baseboard_fab2_lib.baseboard_fab2(sch_1):page216_i47"
				( objectStatus "F2522" )
			)
			( gate "@baseboard_fab2_lib.baseboard_fab2(sch_1):page216_i80"
				( objectStatus "F2519" )
			)
			( gate "@baseboard_fab2_lib.baseboard_fab2(sch_1):page205_i35"
				( objectStatus "F2511" )
			)
			( gate "@baseboard_fab2_lib.baseboard_fab2(sch_1):page205_i34"
				( objectStatus "F2512" )
			)
			( gate "@baseboard_fab2_lib.baseboard_fab2(sch_1):page205_i33"
				( objectStatus "F2513" )
			)
			( gate "@baseboard_fab2_lib.baseboard_fab2(sch_1):page219_i45"
				( objectStatus "F2545" )
			)
			( gate "@baseboard_fab2_lib.baseboard_fab2(sch_1):page219_i84"
				( objectStatus "F2536" )
			)
			( gate "@baseboard_fab2_lib.baseboard_fab2(sch_1):page219_i46"
				( objectStatus "F2544" )
			)
			( gate "@baseboard_fab2_lib.baseboard_fab2(sch_1):page219_i81"
				( objectStatus "F2535" )
			)
			( gate "@baseboard_fab2_lib.baseboard_fab2(sch_1):page219_i47"
				( objectStatus "F2537" )
			)
			( gate "@baseboard_fab2_lib.baseboard_fab2(sch_1):page219_i80"
				( objectStatus "F2534" )
			)
			( gate "@baseboard_fab2_lib.baseboard_fab2(sch_1):page227_i45"
				( objectStatus "F2478" )
			)
			( gate "@baseboard_fab2_lib.baseboard_fab2(sch_1):page227_i84"
				( objectStatus "F2476" )
			)
			( gate "@baseboard_fab2_lib.baseboard_fab2(sch_1):page227_i46"
				( objectStatus "F2479" )
			)
			( gate "@baseboard_fab2_lib.baseboard_fab2(sch_1):page227_i81"
				( objectStatus "F2477" )
			)
			( gate "@baseboard_fab2_lib.baseboard_fab2(sch_1):page227_i47"
				( objectStatus "F2480" )
			)
			( gate "@baseboard_fab2_lib.baseboard_fab2(sch_1):page227_i80"
				( objectStatus "F2481" )
			)
			( gate "@baseboard_fab2_lib.baseboard_fab2(sch_1):page224_i45"
				( objectStatus "F2449" )
			)
			( gate "@baseboard_fab2_lib.baseboard_fab2(sch_1):page224_i84"
				( objectStatus "F2452" )
			)
			( gate "@baseboard_fab2_lib.baseboard_fab2(sch_1):page224_i46"
				( objectStatus "F2450" )
			)
			( gate "@baseboard_fab2_lib.baseboard_fab2(sch_1):page224_i81"
				( objectStatus "F2453" )
			)
			( gate "@baseboard_fab2_lib.baseboard_fab2(sch_1):page224_i47"
				( objectStatus "F2454" )
			)
			( gate "@baseboard_fab2_lib.baseboard_fab2(sch_1):page224_i80"
				( objectStatus "F2451" )
			)
			( gate "@baseboard_fab2_lib.baseboard_fab2(sch_1):page207_i54"
				( objectStatus "F2459" )
			)
			( gate "@baseboard_fab2_lib.baseboard_fab2(sch_1):page207_i48"
				( objectStatus "F2455" )
			)
			( gate "@baseboard_fab2_lib.baseboard_fab2(sch_1):page207_i51"
				( objectStatus "F2460" )
			)
			( gate "@baseboard_fab2_lib.baseboard_fab2(sch_1):page207_i44"
				( objectStatus "F2456" )
			)
			( gate "@baseboard_fab2_lib.baseboard_fab2(sch_1):page207_i50"
				( objectStatus "F2461" )
			)
			( gate "@baseboard_fab2_lib.baseboard_fab2(sch_1):page207_i43"
				( objectStatus "F2457" )
			)
			( gate "@baseboard_fab2_lib.baseboard_fab2(sch_1):page208_i55"
				( objectStatus "F2465" )
			)
			( gate "@baseboard_fab2_lib.baseboard_fab2(sch_1):page208_i60"
				( objectStatus "F2468" )
			)
			( gate "@baseboard_fab2_lib.baseboard_fab2(sch_1):page208_i54"
				( objectStatus "F2466" )
			)
			( gate "@baseboard_fab2_lib.baseboard_fab2(sch_1):page208_i59"
				( objectStatus "F2469" )
			)
			( gate "@baseboard_fab2_lib.baseboard_fab2(sch_1):page208_i53"
				( objectStatus "F2467" )
			)
			( gate "@baseboard_fab2_lib.baseboard_fab2(sch_1):page208_i58"
				( objectStatus "F2470" )
			)
			( gate "@baseboard_fab2_lib.baseboard_fab2(sch_1):page210_i38"
				( objectStatus "F2471" )
			)
			( gate "@baseboard_fab2_lib.baseboard_fab2(sch_1):page210_i36"
				( objectStatus "F2472" )
			)
			( gate "@baseboard_fab2_lib.baseboard_fab2(sch_1):page210_i35"
				( objectStatus "F2473" )
			)
			( gate "@baseboard_fab2_lib.baseboard_fab2(sch_1):page204_i42"
				( objectStatus "F2508" )
			)
			( gate "@baseboard_fab2_lib.baseboard_fab2(sch_1):page204_i37"
				( objectStatus "F2509" )
			)
			( gate "@baseboard_fab2_lib.baseboard_fab2(sch_1):page195_i35"
				( objectStatus "F2554" )
			)
			( gate "@baseboard_fab2_lib.baseboard_fab2(sch_1):page102_i10"
				( objectStatus "F2444" )
			)
			( gate "@baseboard_fab2_lib.baseboard_fab2(sch_1):page165_i67"
				( objectStatus "F2445" )
			)
			( gate "@baseboard_fab2_lib.baseboard_fab2(sch_1):page197_i65"
				( objectStatus "F2439" )
			)
			( gate "@baseboard_fab2_lib.baseboard_fab2(sch_1):page197_i54"
				( objectStatus "F2440" )
			)
			( gate "@baseboard_fab2_lib.baseboard_fab2(sch_1):page197_i52"
				( objectStatus "F2438" )
			)
			( gate "@baseboard_fab2_lib.baseboard_fab2(sch_1):page197_i67"
				( objectStatus "F2442" )
			)
			( gate "@baseboard_fab2_lib.baseboard_fab2(sch_1):page197_i62"
				( objectStatus "F2443" )
			)
			( gate "@baseboard_fab2_lib.baseboard_fab2(sch_1):page197_i59"
				( objectStatus "F2441" )
			)
			( gate "@baseboard_fab2_lib.baseboard_fab2(sch_1):page197_i76"
				( objectStatus "F2436" )
			)
			( gate "@baseboard_fab2_lib.baseboard_fab2(sch_1):page197_i73"
				( objectStatus "F2435" )
			)
			( gate "@baseboard_fab2_lib.baseboard_fab2(sch_1):page197_i70"
				( objectStatus "F2437" )
			)
			( gate "@baseboard_fab2_lib.baseboard_fab2(sch_1):page197_i85"
				( objectStatus "F2447" )
			)
			( gate "@baseboard_fab2_lib.baseboard_fab2(sch_1):page197_i82"
				( objectStatus "F2446" )
			)
			( gate "@baseboard_fab2_lib.baseboard_fab2(sch_1):page197_i79"
				( objectStatus "F2448" )
			)
			( gate "@baseboard_fab2_lib.baseboard_fab2(sch_1):page240_i158"
				( objectStatus "F2430" )
			)
			( gate "@baseboard_fab2_lib.baseboard_fab2(sch_1):page240_i160"
				( objectStatus "F2431" )
			)
			( gate "@baseboard_fab2_lib.baseboard_fab2(sch_1):page240_i174"
				( objectStatus "F2429" )
			)
			( gate "@baseboard_fab2_lib.baseboard_fab2(sch_1):page241_i3"
				( objectStatus "F2427" )
			)
			( gate "@baseboard_fab2_lib.baseboard_fab2(sch_1):page241_i2"
				( objectStatus "F2426" )
			)
			( gate "@baseboard_fab2_lib.baseboard_fab2(sch_1):page237_i13"
				( objectStatus "F2428" )
			)
			( gate "@baseboard_fab2_lib.baseboard_fab2(sch_1):page237_i12"
				( objectStatus "F2432" )
			)
			( gate "@baseboard_fab2_lib.baseboard_fab2(sch_1):page149_i74"
				( objectStatus "F2433" )
			)
			( gate "@baseboard_fab2_lib.baseboard_fab2(sch_1):page149_i75"
				( objectStatus "F2434" )
			)
			( gate "@baseboard_fab2_lib.baseboard_fab2(sch_1):page76_i52"
				( objectStatus "F2363" )
			)
			( gate "@baseboard_fab2_lib.baseboard_fab2(sch_1):page76_i51"
				( objectStatus "F2350" )
			)
			( gate "@baseboard_fab2_lib.baseboard_fab2(sch_1):page76_i29"
				( objectStatus "F2351" )
			)
			( gate "@baseboard_fab2_lib.baseboard_fab2(sch_1):page42_i184"
				( objectStatus "F2395" )
			)
			( gate "@baseboard_fab2_lib.baseboard_fab2(sch_1):page42_i61"
				( objectStatus "F2374" )
			)
			( gate "@baseboard_fab2_lib.baseboard_fab2(sch_1):page42_i60"
				( objectStatus "F2375" )
			)
			( gate "@baseboard_fab2_lib.baseboard_fab2(sch_1):page42_i59"
				( objectStatus "F2376" )
			)
			( gate "@baseboard_fab2_lib.baseboard_fab2(sch_1):page42_i57"
				( objectStatus "F2378" )
			)
			( gate "@baseboard_fab2_lib.baseboard_fab2(sch_1):page42_i40"
				( objectStatus "F2377" )
			)
			( gate "@baseboard_fab2_lib.baseboard_fab2(sch_1):page42_i44"
				( objectStatus "F2389" )
			)
			( gate "@baseboard_fab2_lib.baseboard_fab2(sch_1):page42_i56"
				( objectStatus "F2390" )
			)
			( gate "@baseboard_fab2_lib.baseboard_fab2(sch_1):page42_i38"
				( objectStatus "F2407" )
			)
			( gate "@baseboard_fab2_lib.baseboard_fab2(sch_1):page42_i42"
				( objectStatus "F2408" )
			)
			( gate "@baseboard_fab2_lib.baseboard_fab2(sch_1):page42_i27"
				( objectStatus "F2409" )
			)
			( gate "@baseboard_fab2_lib.baseboard_fab2(sch_1):page42_i190"
				( objectStatus "F2399" )
			)
			( gate "@baseboard_fab2_lib.baseboard_fab2(sch_1):page42_i189"
				( objectStatus "F2410" )
			)
			( gate "@baseboard_fab2_lib.baseboard_fab2(sch_1):page42_i188"
				( objectStatus "F2400" )
			)
			( gate "@baseboard_fab2_lib.baseboard_fab2(sch_1):page42_i187"
				( objectStatus "F2401" )
			)
			( gate "@baseboard_fab2_lib.baseboard_fab2(sch_1):page42_i14"
				( objectStatus "F2415" )
			)
			( gate "@baseboard_fab2_lib.baseboard_fab2(sch_1):page42_i2"
				( objectStatus "F2398" )
			)
			( gate "@baseboard_fab2_lib.baseboard_fab2(sch_1):page42_i55"
				( objectStatus "F2394" )
			)
			( gate "@baseboard_fab2_lib.baseboard_fab2(sch_1):page42_i28"
				( objectStatus "F2393" )
			)
			( gate "@baseboard_fab2_lib.baseboard_fab2(sch_1):page42_i33"
				( objectStatus "F2392" )
			)
			( gate "@baseboard_fab2_lib.baseboard_fab2(sch_1):page42_i37"
				( objectStatus "F2391" )
			)
			( gate "@baseboard_fab2_lib.baseboard_fab2(sch_1):page42_i13"
				( objectStatus "F2397" )
			)
			( gate "@baseboard_fab2_lib.baseboard_fab2(sch_1):page42_i9"
				( objectStatus "F2413" )
			)
			( gate "@baseboard_fab2_lib.baseboard_fab2(sch_1):page42_i8"
				( objectStatus "F2416" )
			)
			( gate "@baseboard_fab2_lib.baseboard_fab2(sch_1):page42_i6"
				( objectStatus "F2406" )
			)
			( gate "@baseboard_fab2_lib.baseboard_fab2(sch_1):page42_i4"
				( objectStatus "F2405" )
			)
			( gate "@baseboard_fab2_lib.baseboard_fab2(sch_1):page42_i3"
				( objectStatus "F2388" )
			)
			( gate "@baseboard_fab2_lib.baseboard_fab2(sch_1):page76_i139"
				( objectStatus "F2338" )
			)
			( gate "@baseboard_fab2_lib.baseboard_fab2(sch_1):page76_i214"
				( objectStatus "F2340" )
			)
			( gate "@baseboard_fab2_lib.baseboard_fab2(sch_1):page76_i125"
				( objectStatus "F2320" )
			)
			( gate "@baseboard_fab2_lib.baseboard_fab2(sch_1):page76_i137"
				( objectStatus "F2321" )
			)
			( gate "@baseboard_fab2_lib.baseboard_fab2(sch_1):page76_i141"
				( objectStatus "F2322" )
			)
			( gate "@baseboard_fab2_lib.baseboard_fab2(sch_1):page76_i118"
				( objectStatus "F2323" )
			)
			( gate "@baseboard_fab2_lib.baseboard_fab2(sch_1):page76_i132"
				( objectStatus "F2336" )
			)
			( gate "@baseboard_fab2_lib.baseboard_fab2(sch_1):page76_i136"
				( objectStatus "F2324" )
			)
			( gate "@baseboard_fab2_lib.baseboard_fab2(sch_1):page76_i212"
				( objectStatus "F2334" )
			)
			( gate "@baseboard_fab2_lib.baseboard_fab2(sch_1):page76_i131"
				( objectStatus "F2318" )
			)
			( gate "@baseboard_fab2_lib.baseboard_fab2(sch_1):page76_i135"
				( objectStatus "F2328" )
			)
			( gate "@baseboard_fab2_lib.baseboard_fab2(sch_1):page76_i213"
				( objectStatus "F2341" )
			)
			( gate "@baseboard_fab2_lib.baseboard_fab2(sch_1):page76_i129"
				( objectStatus "F2333" )
			)
			( gate "@baseboard_fab2_lib.baseboard_fab2(sch_1):page76_i133"
				( objectStatus "F2332" )
			)
			( gate "@baseboard_fab2_lib.baseboard_fab2(sch_1):page76_i92"
				( objectStatus "F2331" )
			)
			( gate "@baseboard_fab2_lib.baseboard_fab2(sch_1):page76_i103"
				( objectStatus "F2330" )
			)
			( gate "@baseboard_fab2_lib.baseboard_fab2(sch_1):page76_i107"
				( objectStatus "F2337" )
			)
			( gate "@baseboard_fab2_lib.baseboard_fab2(sch_1):page76_i89"
				( objectStatus "F2329" )
			)
			( gate "@baseboard_fab2_lib.baseboard_fab2(sch_1):page76_i101"
				( objectStatus "F2343" )
			)
			( gate "@baseboard_fab2_lib.baseboard_fab2(sch_1):page76_i106"
				( objectStatus "F2317" )
			)
			( gate "@baseboard_fab2_lib.baseboard_fab2(sch_1):page76_i88"
				( objectStatus "F2342" )
			)
			( gate "@baseboard_fab2_lib.baseboard_fab2(sch_1):page76_i100"
				( objectStatus "F2364" )
			)
			( gate "@baseboard_fab2_lib.baseboard_fab2(sch_1):page76_i105"
				( objectStatus "F2365" )
			)
			( gate "@baseboard_fab2_lib.baseboard_fab2(sch_1):page76_i217"
				( objectStatus "F2325" )
			)
			( gate "@baseboard_fab2_lib.baseboard_fab2(sch_1):page76_i215"
				( objectStatus "F2349" )
			)
			( gate "@baseboard_fab2_lib.baseboard_fab2(sch_1):page76_i218"
				( objectStatus "F2348" )
			)
			( gate "@baseboard_fab2_lib.baseboard_fab2(sch_1):page76_i216"
				( objectStatus "F2319" )
			)
			( gate "@baseboard_fab2_lib.baseboard_fab2(sch_1):page76_i211"
				( objectStatus "F2335" )
			)
			( gate "@baseboard_fab2_lib.baseboard_fab2(sch_1):page76_i49"
				( objectStatus "F2353" )
			)
			( gate "@baseboard_fab2_lib.baseboard_fab2(sch_1):page76_i48"
				( objectStatus "F2326" )
			)
			( gate "@baseboard_fab2_lib.baseboard_fab2(sch_1):page76_i45"
				( objectStatus "F2352" )
			)
			( gate "@baseboard_fab2_lib.baseboard_fab2(sch_1):page76_i28"
				( objectStatus "F2327" )
			)
			( gate "@baseboard_fab2_lib.baseboard_fab2(sch_1):page76_i27"
				( objectStatus "F2359" )
			)
			( gate "@baseboard_fab2_lib.baseboard_fab2(sch_1):page76_i26"
				( objectStatus "F2356" )
			)
			( gate "@baseboard_fab2_lib.baseboard_fab2(sch_1):page76_i25"
				( objectStatus "F2354" )
			)
			( gate "@baseboard_fab2_lib.baseboard_fab2(sch_1):page76_i23"
				( objectStatus "F2360" )
			)
			( gate "@baseboard_fab2_lib.baseboard_fab2(sch_1):page76_i181"
				( objectStatus "F2357" )
			)
			( gate "@baseboard_fab2_lib.baseboard_fab2(sch_1):page76_i182"
				( objectStatus "F2361" )
			)
			( gate "@baseboard_fab2_lib.baseboard_fab2(sch_1):page76_i183"
				( objectStatus "F2355" )
			)
			( gate "@baseboard_fab2_lib.baseboard_fab2(sch_1):page76_i184"
				( objectStatus "F2358" )
			)
			( gate "@baseboard_fab2_lib.baseboard_fab2(sch_1):page76_i195"
				( objectStatus "F2362" )
			)
			( gate "@baseboard_fab2_lib.baseboard_fab2(sch_1):page42_i149"
				( objectStatus "F2387" )
			)
			( gate "@baseboard_fab2_lib.baseboard_fab2(sch_1):page42_i148"
				( objectStatus "F2386" )
			)
			( gate "@baseboard_fab2_lib.baseboard_fab2(sch_1):page42_i162"
				( objectStatus "F2385" )
			)
			( gate "@baseboard_fab2_lib.baseboard_fab2(sch_1):page42_i163"
				( objectStatus "F2417" )
			)
			( gate "@baseboard_fab2_lib.baseboard_fab2(sch_1):page42_i172"
				( objectStatus "F2414" )
			)
			( gate "@baseboard_fab2_lib.baseboard_fab2(sch_1):page42_i63"
				( objectStatus "F2379" )
			)
			( gate "@baseboard_fab2_lib.baseboard_fab2(sch_1):page42_i65"
				( objectStatus "F2380" )
			)
			( gate "@baseboard_fab2_lib.baseboard_fab2(sch_1):page42_i51"
				( objectStatus "F2381" )
			)
			( gate "@baseboard_fab2_lib.baseboard_fab2(sch_1):page42_i54"
				( objectStatus "F2382" )
			)
			( gate "@baseboard_fab2_lib.baseboard_fab2(sch_1):page42_i50"
				( objectStatus "F2383" )
			)
			( gate "@baseboard_fab2_lib.baseboard_fab2(sch_1):page42_i53"
				( objectStatus "F2384" )
			)
			( gate "@baseboard_fab2_lib.baseboard_fab2(sch_1):page42_i185"
				( objectStatus "F2396" )
			)
			( gate "@baseboard_fab2_lib.baseboard_fab2(sch_1):page42_i186"
				( objectStatus "F2403" )
			)
			( gate "@baseboard_fab2_lib.baseboard_fab2(sch_1):page42_i41"
				( objectStatus "F2402" )
			)
			( gate "@baseboard_fab2_lib.baseboard_fab2(sch_1):page42_i183"
				( objectStatus "F2404" )
			)
			( gate "@baseboard_fab2_lib.baseboard_fab2(sch_1):page42_i17"
				( objectStatus "F2411" )
			)
			( gate "@baseboard_fab2_lib.baseboard_fab2(sch_1):page42_i12"
				( objectStatus "F2412" )
			)
			( gate "@baseboard_fab2_lib.baseboard_fab2(sch_1):page42_i10"
				( objectStatus "F2418" )
			)
			( gate "@baseboard_fab2_lib.baseboard_fab2(sch_1):page76_i127"
				( objectStatus "F2339" )
			)
			( gate "@baseboard_fab2_lib.baseboard_fab2(sch_1):page237_i77"
				( objectStatus "F2347" )
			)
			( gate "@baseboard_fab2_lib.baseboard_fab2(sch_1):page237_i79"
				( objectStatus "F2425" )
			)
			( gate "@baseboard_fab2_lib.baseboard_fab2(sch_1):page232_i236"
				( objectStatus "F2373" )
			)
			( gate "@baseboard_fab2_lib.baseboard_fab2(sch_1):page232_i238"
				( objectStatus "F2366" )
			)
			( gate "@baseboard_fab2_lib.baseboard_fab2(sch_1):page233_i221"
				( objectStatus "F2371" )
			)
			( gate "@baseboard_fab2_lib.baseboard_fab2(sch_1):page233_i223"
				( objectStatus "F2372" )
			)
			( gate "@baseboard_fab2_lib.baseboard_fab2(sch_1):page234_i177"
				( objectStatus "F2419" )
			)
			( gate "@baseboard_fab2_lib.baseboard_fab2(sch_1):page234_i180"
				( objectStatus "F2420" )
			)
			( gate "@baseboard_fab2_lib.baseboard_fab2(sch_1):page231_i184"
				( objectStatus "F2422" )
			)
			( gate "@baseboard_fab2_lib.baseboard_fab2(sch_1):page231_i186"
				( objectStatus "F2421" )
			)
			( gate "@baseboard_fab2_lib.baseboard_fab2(sch_1):page132_i40"
				( objectStatus "F2370" )
			)
			( gate "@baseboard_fab2_lib.baseboard_fab2(sch_1):page132_i38"
				( objectStatus "F2369" )
			)
			( gate "@baseboard_fab2_lib.baseboard_fab2(sch_1):page132_i24"
				( objectStatus "F2367" )
			)
			( gate "@baseboard_fab2_lib.baseboard_fab2(sch_1):page132_i23"
				( objectStatus "F2368" )
			)
			( gate "@baseboard_fab2_lib.baseboard_fab2(sch_1):page131_i24"
				( objectStatus "F2345" )
			)
			( gate "@baseboard_fab2_lib.baseboard_fab2(sch_1):page131_i22"
				( objectStatus "F2344" )
			)
			( gate "@baseboard_fab2_lib.baseboard_fab2(sch_1):page131_i37"
				( objectStatus "F2346" )
			)
			( gate "@baseboard_fab2_lib.baseboard_fab2(sch_1):page131_i35"
				( objectStatus "F2424" )
			)
			( gate "@baseboard_fab2_lib.baseboard_fab2(sch_1):page131_i34"
				( objectStatus "F2423" )
			)
			( gate "@baseboard_fab2_lib.baseboard_fab2(sch_1):page236_i9"
				( objectStatus "F2298" )
			)
			( gate "@baseboard_fab2_lib.baseboard_fab2(sch_1):page236_i46"
				( objectStatus "F2296" )
			)
			( gate "@baseboard_fab2_lib.baseboard_fab2(sch_1):page217_i184"
				( objectStatus "F2302" )
			)
			( gate "@baseboard_fab2_lib.baseboard_fab2(sch_1):page217_i193"
				( objectStatus "F2303" )
			)
			( gate "@baseboard_fab2_lib.baseboard_fab2(sch_1):page220_i177"
				( objectStatus "F2307" )
			)
			( gate "@baseboard_fab2_lib.baseboard_fab2(sch_1):page220_i179"
				( objectStatus "F2308" )
			)
			( gate "@baseboard_fab2_lib.baseboard_fab2(sch_1):page225_i184"
				( objectStatus "F2290" )
			)
			( gate "@baseboard_fab2_lib.baseboard_fab2(sch_1):page225_i178"
				( objectStatus "F2289" )
			)
			( gate "@baseboard_fab2_lib.baseboard_fab2(sch_1):page228_i183"
				( objectStatus "F2294" )
			)
			( gate "@baseboard_fab2_lib.baseboard_fab2(sch_1):page228_i185"
				( objectStatus "F2295" )
			)
			( gate "@baseboard_fab2_lib.baseboard_fab2(sch_1):page221_i20"
				( objectStatus "F2309" )
			)
			( gate "@baseboard_fab2_lib.baseboard_fab2(sch_1):page229_i17"
				( objectStatus "F2310" )
			)
			( gate "@baseboard_fab2_lib.baseboard_fab2(sch_1):page222_i16"
				( objectStatus "F2312" )
			)
			( gate "@baseboard_fab2_lib.baseboard_fab2(sch_1):page230_i18"
				( objectStatus "F2311" )
			)
			( gate "@baseboard_fab2_lib.baseboard_fab2(sch_1):page238_i30"
				( objectStatus "F2288" )
			)
			( gate "@baseboard_fab2_lib.baseboard_fab2(sch_1):page239_i7"
				( objectStatus "F2287" )
			)
			( gate "@baseboard_fab2_lib.baseboard_fab2(sch_1):page216_i6"
				( objectStatus "F2299" )
			)
			( gate "@baseboard_fab2_lib.baseboard_fab2(sch_1):page216_i68"
				( objectStatus "F2297" )
			)
			( gate "@baseboard_fab2_lib.baseboard_fab2(sch_1):page42_i25"
				( objectStatus "F2306" )
			)
			( gate "@baseboard_fab2_lib.baseboard_fab2(sch_1):page224_i6"
				( objectStatus "F2314" )
			)
			( gate "@baseboard_fab2_lib.baseboard_fab2(sch_1):page219_i87"
				( objectStatus "F2301" )
			)
			( gate "@baseboard_fab2_lib.baseboard_fab2(sch_1):page219_i68"
				( objectStatus "F2300" )
			)
			( gate "@baseboard_fab2_lib.baseboard_fab2(sch_1):page227_i68"
				( objectStatus "F2316" )
			)
			( gate "@baseboard_fab2_lib.baseboard_fab2(sch_1):page224_i68"
				( objectStatus "F2313" )
			)
			( gate "@baseboard_fab2_lib.baseboard_fab2(sch_1):page227_i6"
				( objectStatus "F2315" )
			)
			( gate "@baseboard_fab2_lib.baseboard_fab2(sch_1):page42_i19"
				( objectStatus "F2305" )
			)
			( gate "@baseboard_fab2_lib.baseboard_fab2(sch_1):page42_i18"
				( objectStatus "F2304" )
			)
			( gate "@baseboard_fab2_lib.baseboard_fab2(sch_1):page76_i58"
				( objectStatus "F2293" )
			)
			( gate "@baseboard_fab2_lib.baseboard_fab2(sch_1):page76_i55"
				( objectStatus "F2292" )
			)
			( gate "@baseboard_fab2_lib.baseboard_fab2(sch_1):page76_i50"
				( objectStatus "F2291" )
			)
			( gate "@baseboard_fab2_lib.baseboard_fab2(sch_1):page232_i202"
				( objectStatus "F2267" )
			)
			( gate "@baseboard_fab2_lib.baseboard_fab2(sch_1):page233_i189"
				( objectStatus "F2268" )
			)
			( gate "@baseboard_fab2_lib.baseboard_fab2(sch_1):page234_i130"
				( objectStatus "F2269" )
			)
			( gate "@baseboard_fab2_lib.baseboard_fab2(sch_1):page231_i151"
				( objectStatus "F2264" )
			)
			( gate "@baseboard_fab2_lib.baseboard_fab2(sch_1):page240_i134"
				( objectStatus "F2262" )
			)
			( gate "@baseboard_fab2_lib.baseboard_fab2(sch_1):page240_i135"
				( objectStatus "F2263" )
			)
			( gate "@baseboard_fab2_lib.baseboard_fab2(sch_1):page225_i192"
				( objectStatus "F2270" )
			)
			( gate "@baseboard_fab2_lib.baseboard_fab2(sch_1):page225_i193"
				( objectStatus "F2271" )
			)
			( gate "@baseboard_fab2_lib.baseboard_fab2(sch_1):page225_i194"
				( objectStatus "F2273" )
			)
			( gate "@baseboard_fab2_lib.baseboard_fab2(sch_1):page225_i195"
				( objectStatus "F2272" )
			)
			( gate "@baseboard_fab2_lib.baseboard_fab2(sch_1):page241_i47"
				( objectStatus "F2266" )
			)
			( gate "@baseboard_fab2_lib.baseboard_fab2(sch_1):page241_i45"
				( objectStatus "F2265" )
			)
			( gate "@baseboard_fab2_lib.baseboard_fab2(sch_1):page176_i30"
				( objectStatus "F2261" )
				( pin "B1"
					( objectStatus "L1M2.3" )
				)
				( pin "B2"
					( objectStatus "L1M2.4" )
				)
			)
			( gate "@baseboard_fab2_lib.baseboard_fab2(sch_1):page196_i53"
				( objectStatus "F2225" )
			)
			( gate "@baseboard_fab2_lib.baseboard_fab2(sch_1):page176_i98"
				( objectStatus "F2223" )
			)
			( gate "@baseboard_fab2_lib.baseboard_fab2(sch_1):page176_i52"
				( objectStatus "F2224" )
				( pin "AC2"
					( objectStatus "CR1M1.4" )
				)
				( pin "AC3"
					( objectStatus "CR1M1.5" )
				)
			)
			( gate "@baseboard_fab2_lib.baseboard_fab2(sch_1):page232_i200"
				( objectStatus "F2196" )
			)
			( gate "@baseboard_fab2_lib.baseboard_fab2(sch_1):page233_i198"
				( objectStatus "F2197" )
			)
			( gate "@baseboard_fab2_lib.baseboard_fab2(sch_1):page234_i154"
				( objectStatus "F2198" )
			)
			( gate "@baseboard_fab2_lib.baseboard_fab2(sch_1):page231_i162"
				( objectStatus "F2194" )
			)
			( gate "@baseboard_fab2_lib.baseboard_fab2(sch_1):page240_i132"
				( objectStatus "F2193" )
			)
			( gate "@baseboard_fab2_lib.baseboard_fab2(sch_1):page241_i82"
				( objectStatus "F2195" )
			)
			( gate "@baseboard_fab2_lib.baseboard_fab2(sch_1):page169_i155"
				( objectStatus "F2191" )
			)
			( gate "@baseboard_fab2_lib.baseboard_fab2(sch_1):page169_i57"
				( objectStatus "F2192" )
			)
			( gate "@baseboard_fab2_lib.baseboard_fab2(sch_1):page156_i291"
				( objectStatus "F2164" )
			)
			( gate "@baseboard_fab2_lib.baseboard_fab2(sch_1):page156_i290"
				( objectStatus "F2163" )
			)
			( gate "@baseboard_fab2_lib.baseboard_fab2(sch_1):page169_i162"
				( objectStatus "F2146" )
			)
			( gate "@baseboard_fab2_lib.baseboard_fab2(sch_1):page169_i157"
				( objectStatus "F2145" )
			)
			( gate "@baseboard_fab2_lib.baseboard_fab2(sch_1):page155_i188"
				( objectStatus "F2176" )
			)
			( gate "@baseboard_fab2_lib.baseboard_fab2(sch_1):page155_i187"
				( objectStatus "F2175" )
			)
			( gate "@baseboard_fab2_lib.baseboard_fab2(sch_1):page177_i80"
				( objectStatus "F2148" )
			)
			( gate "@baseboard_fab2_lib.baseboard_fab2(sch_1):page177_i79"
				( objectStatus "F2147" )
			)
			( gate "@baseboard_fab2_lib.baseboard_fab2(sch_1):page119_i175"
				( objectStatus "F2152" )
			)
			( gate "@baseboard_fab2_lib.baseboard_fab2(sch_1):page119_i180"
				( objectStatus "F2151" )
			)
			( gate "@baseboard_fab2_lib.baseboard_fab2(sch_1):page147_i135"
				( objectStatus "F2150" )
			)
			( gate "@baseboard_fab2_lib.baseboard_fab2(sch_1):page147_i55"
				( objectStatus "F2149" )
			)
			( gate "@baseboard_fab2_lib.baseboard_fab2(sch_1):page95_i111"
				( objectStatus "F2156" )
			)
			( gate "@baseboard_fab2_lib.baseboard_fab2(sch_1):page95_i59"
				( objectStatus "F2155" )
			)
			( gate "@baseboard_fab2_lib.baseboard_fab2(sch_1):page95_i112"
				( objectStatus "F2154" )
			)
			( gate "@baseboard_fab2_lib.baseboard_fab2(sch_1):page95_i69"
				( objectStatus "F2153" )
			)
			( gate "@baseboard_fab2_lib.baseboard_fab2(sch_1):page95_i32"
				( objectStatus "F2168" )
			)
			( gate "@baseboard_fab2_lib.baseboard_fab2(sch_1):page95_i33"
				( objectStatus "F2167" )
			)
			( gate "@baseboard_fab2_lib.baseboard_fab2(sch_1):page94_i98"
				( objectStatus "F2166" )
			)
			( gate "@baseboard_fab2_lib.baseboard_fab2(sch_1):page94_i102"
				( objectStatus "F2165" )
			)
			( gate "@baseboard_fab2_lib.baseboard_fab2(sch_1):page95_i28"
				( objectStatus "F2174" )
			)
			( gate "@baseboard_fab2_lib.baseboard_fab2(sch_1):page95_i113"
				( objectStatus "F2173" )
			)
			( gate "@baseboard_fab2_lib.baseboard_fab2(sch_1):page94_i49"
				( objectStatus "F2172" )
			)
			( gate "@baseboard_fab2_lib.baseboard_fab2(sch_1):page94_i89"
				( objectStatus "F2171" )
			)
			( gate "@baseboard_fab2_lib.baseboard_fab2(sch_1):page94_i60"
				( objectStatus "F2162" )
			)
			( gate "@baseboard_fab2_lib.baseboard_fab2(sch_1):page94_i64"
				( objectStatus "F2161" )
			)
			( gate "@baseboard_fab2_lib.baseboard_fab2(sch_1):page94_i69"
				( objectStatus "F2160" )
			)
			( gate "@baseboard_fab2_lib.baseboard_fab2(sch_1):page94_i75"
				( objectStatus "F2159" )
			)
			( gate "@baseboard_fab2_lib.baseboard_fab2(sch_1):page94_i84"
				( objectStatus "F2170" )
			)
			( gate "@baseboard_fab2_lib.baseboard_fab2(sch_1):page94_i77"
				( objectStatus "F2169" )
			)
			( gate "@baseboard_fab2_lib.baseboard_fab2(sch_1):page95_i52"
				( objectStatus "F2158" )
			)
			( gate "@baseboard_fab2_lib.baseboard_fab2(sch_1):page95_i51"
				( objectStatus "F2157" )
			)
			( gate "@baseboard_fab2_lib.baseboard_fab2(sch_1):page126_i13"
				( objectStatus "F2135" )
			)
			( gate "@baseboard_fab2_lib.baseboard_fab2(sch_1):page200_i203"
				( objectStatus "F2138" )
			)
			( gate "@baseboard_fab2_lib.baseboard_fab2(sch_1):page136_i134"
				( objectStatus "F2134" )
			)
			( gate "@baseboard_fab2_lib.baseboard_fab2(sch_1):page170_i58"
				( objectStatus "F2137" )
			)
			( gate "@baseboard_fab2_lib.baseboard_fab2(sch_1):page170_i67"
				( objectStatus "F2132" )
			)
			( gate "@baseboard_fab2_lib.baseboard_fab2(sch_1):page157_i340"
				( objectStatus "F2136" )
			)
			( gate "@baseboard_fab2_lib.baseboard_fab2(sch_1):page175_i49"
				( objectStatus "F2131" )
			)
			( gate "@baseboard_fab2_lib.baseboard_fab2(sch_1):page154_i126"
				( objectStatus "F2133" )
			)
			( gate "@baseboard_fab2_lib.baseboard_fab2(sch_1):page152_i1"
				( objectStatus "F2120" )
			)
			( gate "@baseboard_fab2_lib.baseboard_fab2(sch_1):page93_i30"
				( objectStatus "F2125" )
			)
			( gate "@baseboard_fab2_lib.baseboard_fab2(sch_1):page96_i42"
				( objectStatus "F2124" )
			)
			( gate "@baseboard_fab2_lib.baseboard_fab2(sch_1):page96_i46"
				( objectStatus "F2122" )
			)
			( gate "@baseboard_fab2_lib.baseboard_fab2(sch_1):page92_i1"
				( objectStatus "F2123" )
				( pin "B2"
					( objectStatus "U3P2.5" )
				)
			)
			( gate "@baseboard_fab2_lib.baseboard_fab2(sch_1):page92_i32"
				( objectStatus "F2121" )
				( pin "B0"
					( objectStatus "U7D2.2" )
				)
				( pin "B1"
					( objectStatus "U7D2.3" )
				)
			)
			( gate "@baseboard_fab2_lib.baseboard_fab2(sch_1):page177_i31"
				( objectStatus "F2033" )
			)
			( gate "@baseboard_fab2_lib.baseboard_fab2(sch_1):page119_i179"
				( objectStatus "F2034" )
			)
			( gate "@baseboard_fab2_lib.baseboard_fab2(sch_1):page147_i56"
				( objectStatus "F2032" )
			)
			( gate "@baseboard_fab2_lib.baseboard_fab2(sch_1):page200_i54"
				( objectStatus "F2019" )
			)
			( gate "@baseboard_fab2_lib.baseboard_fab2(sch_1):page200_i57"
				( objectStatus "F2018" )
			)
			( gate "@baseboard_fab2_lib.baseboard_fab2(sch_1):page200_i59"
				( objectStatus "F2020" )
			)
			( gate "@baseboard_fab2_lib.baseboard_fab2(sch_1):page157_i352"
				( objectStatus "F897" )
			)
			( gate "@baseboard_fab2_lib.baseboard_fab2(sch_1):page93_i63"
				( objectStatus "F895" )
			)
			( gate "@baseboard_fab2_lib.baseboard_fab2(sch_1):page93_i87"
				( objectStatus "F894" )
			)
			( gate "@baseboard_fab2_lib.baseboard_fab2(sch_1):page175_i4"
				( objectStatus "F899" )
			)
			( gate "@baseboard_fab2_lib.baseboard_fab2(sch_1):page175_i22"
				( objectStatus "F900" )
			)
			( gate "@baseboard_fab2_lib.baseboard_fab2(sch_1):page154_i101"
				( objectStatus "F896" )
				( pin "A"
					( objectStatus "R2T13.1" )
				)
				( pin "B"
					( objectStatus "R2T13.2" )
				)
			)
			( gate "@baseboard_fab2_lib.baseboard_fab2(sch_1):page187_i153"
				( objectStatus "F890" )
			)
			( gate "@baseboard_fab2_lib.baseboard_fab2(sch_1):page187_i150"
				( objectStatus "F891" )
			)
			( gate "@baseboard_fab2_lib.baseboard_fab2(sch_1):page187_i145"
				( objectStatus "F892" )
			)
			( gate "@baseboard_fab2_lib.baseboard_fab2(sch_1):page92_i94"
				( objectStatus "F893" )
			)
			( gate "@baseboard_fab2_lib.baseboard_fab2(sch_1):page186_i220"
				( objectStatus "F898" )
			)
			( gate "@baseboard_fab2_lib.baseboard_fab2(sch_1):page209_i39"
				( objectStatus "F250" )
			)
			( gate "@baseboard_fab2_lib.baseboard_fab2(sch_1):page204_i45"
				( objectStatus "F249" )
			)
			( gate "@baseboard_fab2_lib.baseboard_fab2(sch_1):page200_i50"
				( objectStatus "F248" )
			)
			( gate "@baseboard_fab2_lib.baseboard_fab2(sch_1):page200_i49"
				( objectStatus "F247" )
			)
			( pin "@baseboard_fab2_lib.baseboard_fab2(sch_1):spi_switch_clk:\T.1\"
				( objectStatus "SPI_SWITCH_CLK.T.1" )
			)
			( pin "@baseboard_fab2_lib.baseboard_fab2(sch_1):spi_pch_clk:\T.1\"
				( objectStatus "SPI_PCH_CLK.T.1" )
			)
			( pin "@baseboard_fab2_lib.baseboard_fab2(sch_1):spi_switch_miso:\T.1\"
				( objectStatus "SPI_SWITCH_MISO.T.1" )
			)
			( pin "@baseboard_fab2_lib.baseboard_fab2(sch_1):h_cpu_msmi_g_n:\<user>\"
				( objectStatus "H_CPU_MSMI_G_N.T.1" )
			)
			( pin "@baseboard_fab2_lib.baseboard_fab2(sch_1):h_cpu_caterr_g_n:\<user>\"
				( objectStatus "H_CPU_CATERR_G_N.T.1" )
			)
			( differentialPair "@crescent_city_bb_fab1_lib.crescent_city_bb_fab1(sch_1):\DP_ISENSE_TMP421_1_DX\"
				( memberType ( signal ) )
				( physicalCSetRef "@sapphirecity_baseboard_lib.sapphirecity_baseboard(sch_1):\10-5-10_DIFF\" )
				( member ( electricalNetRef "@crescent_city_bb_fab1_lib.crescent_city_bb_fab1(sch_1):isense_tmp421_1_dxn") )
				( member ( electricalNetRef "@crescent_city_bb_fab1_lib.crescent_city_bb_fab1(sch_1):isense_tmp421_1_dxp") )
				( objectStatus "DP_ISENSE_TMP421_1_DX" )
			)
			( differentialPair "@crescent_city_bb_fab1_lib.crescent_city_bb_fab1(sch_1):\DP_ISENSE_TMP421_2_DX\"
				( memberType ( signal ) )
				( physicalCSetRef "@sapphirecity_baseboard_lib.sapphirecity_baseboard(sch_1):\10-5-10_DIFF\" )
				( member ( electricalNetRef "@crescent_city_bb_fab1_lib.crescent_city_bb_fab1(sch_1):isense_tmp421_2_dxn") )
				( member ( electricalNetRef "@crescent_city_bb_fab1_lib.crescent_city_bb_fab1(sch_1):isense_tmp421_2_dxp") )
				( objectStatus "DP_ISENSE_TMP421_2_DX" )
			)
			( differentialPair "@baseboard_fab2_lib.baseboard_fab2(sch_1):\DP_KR_P0_OCP_TX\"
				( memberType ( signal ) )
				( electricalCSetRef "@baseboard_fab2_lib.baseboard_fab2(sch_1):\KR_OCP_TX\" )
				( member ( signalRef "@baseboard_fab2_lib.baseboard_fab2(sch_1):kr_p0_ocp_tx_dn") )
				( member ( signalRef "@baseboard_fab2_lib.baseboard_fab2(sch_1):kr_p0_ocp_tx_dp") )
				( objectStatus "DP_KR_P0_OCP_TX" )
			)
			( differentialPair "@baseboard_fab2_lib.baseboard_fab2(sch_1):\DP_KR_P1_OCP_TX\"
				( memberType ( signal ) )
				( electricalCSetRef "@baseboard_fab2_lib.baseboard_fab2(sch_1):\KR_OCP_TX\" )
				( member ( signalRef "@baseboard_fab2_lib.baseboard_fab2(sch_1):kr_p1_ocp_tx_dn") )
				( member ( signalRef "@baseboard_fab2_lib.baseboard_fab2(sch_1):kr_p1_ocp_tx_dp") )
				( objectStatus "DP_KR_P1_OCP_TX" )
			)
			( differentialPair "@baseboard_fab2_lib.baseboard_fab2(sch_1):\DP_KR_P2_OCP_TX\"
				( memberType ( signal ) )
				( electricalCSetRef "@baseboard_fab2_lib.baseboard_fab2(sch_1):\KR_OCP_TX\" )
				( member ( signalRef "@baseboard_fab2_lib.baseboard_fab2(sch_1):kr_p2_ocp_tx_dn") )
				( member ( signalRef "@baseboard_fab2_lib.baseboard_fab2(sch_1):kr_p2_ocp_tx_dp") )
				( objectStatus "DP_KR_P2_OCP_TX" )
			)
			( differentialPair "@baseboard_fab2_lib.baseboard_fab2(sch_1):\DP_KR_P3_OCP_TX\"
				( memberType ( signal ) )
				( electricalCSetRef "@baseboard_fab2_lib.baseboard_fab2(sch_1):\KR_OCP_TX\" )
				( member ( signalRef "@baseboard_fab2_lib.baseboard_fab2(sch_1):kr_p3_ocp_tx_dn") )
				( member ( signalRef "@baseboard_fab2_lib.baseboard_fab2(sch_1):kr_p3_ocp_tx_dp") )
				( objectStatus "DP_KR_P3_OCP_TX" )
			)
			( differentialPair "@baseboard_fab2_lib.baseboard_fab2(sch_1):\DP_KR_P0_OCP_RX\"
				( memberType ( signal ) )
				( electricalCSetRef "@baseboard_fab2_lib.baseboard_fab2(sch_1):\DP_KR_P0_OCP_RX\" )
				( member ( electricalNetRef "@baseboard_fab2_lib.baseboard_fab2(sch_1):kr_p0_ocp_rx_c_dn") )
				( member ( electricalNetRef "@baseboard_fab2_lib.baseboard_fab2(sch_1):kr_p0_ocp_rx_c_dp") )
				( objectStatus "DP_KR_P0_OCP_RX" )
			)
			( differentialPair "@baseboard_fab2_lib.baseboard_fab2(sch_1):\DP_KR_P1_OCP_RX\"
				( memberType ( signal ) )
				( electricalCSetRef "@baseboard_fab2_lib.baseboard_fab2(sch_1):\DP_KR_P0_OCP_RX\" )
				( member ( electricalNetRef "@baseboard_fab2_lib.baseboard_fab2(sch_1):kr_p1_ocp_rx_c_dn") )
				( member ( electricalNetRef "@baseboard_fab2_lib.baseboard_fab2(sch_1):kr_p1_ocp_rx_c_dp") )
				( objectStatus "DP_KR_P1_OCP_RX" )
			)
			( differentialPair "@baseboard_fab2_lib.baseboard_fab2(sch_1):\DP_KR_P2_OCP_RX\"
				( memberType ( signal ) )
				( electricalCSetRef "@baseboard_fab2_lib.baseboard_fab2(sch_1):\DP_KR_P0_OCP_RX\" )
				( member ( electricalNetRef "@baseboard_fab2_lib.baseboard_fab2(sch_1):kr_p2_ocp_rx_c_dn") )
				( member ( electricalNetRef "@baseboard_fab2_lib.baseboard_fab2(sch_1):kr_p2_ocp_rx_c_dp") )
				( objectStatus "DP_KR_P2_OCP_RX" )
			)
			( differentialPair "@baseboard_fab2_lib.baseboard_fab2(sch_1):\DP_KR_P3_OCP_RX\"
				( memberType ( signal ) )
				( electricalCSetRef "@baseboard_fab2_lib.baseboard_fab2(sch_1):\DP_KR_P0_OCP_RX\" )
				( member ( electricalNetRef "@baseboard_fab2_lib.baseboard_fab2(sch_1):kr_p3_ocp_rx_c_dn") )
				( member ( electricalNetRef "@baseboard_fab2_lib.baseboard_fab2(sch_1):kr_p3_ocp_rx_c_dp") )
				( objectStatus "DP_KR_P3_OCP_RX" )
			)
			( differentialPair "@baseboard_fab2_lib.baseboard_fab2(sch_1):\DP_ISENSE_PVCCIN_CPU1_PH1\"
				( memberType ( signal ) )
				( physicalCSetRef "@baseboard_fab2_lib.baseboard_fab2(sch_1):\5-5-5_DIFF\" )
				( member ( signalRef "@baseboard_fab2_lib.baseboard_fab2(sch_1):isense_pvccin_cpu1_ph1_imon") )
				( member ( signalRef "@baseboard_fab2_lib.baseboard_fab2(sch_1):vr_pvccin_cpu1_airef1") )
				( objectStatus "DP_ISENSE_PVCCIN_CPU1_PH1" )
			)
			( differentialPair "@baseboard_fab2_lib.baseboard_fab2(sch_1):\DP_ISENSE_PVCCIN_CPU1_PH2\"
				( memberType ( signal ) )
				( physicalCSetRef "@baseboard_fab2_lib.baseboard_fab2(sch_1):\5-5-5_DIFF\" )
				( member ( signalRef "@baseboard_fab2_lib.baseboard_fab2(sch_1):isense_pvccin_cpu1_ph2_imon") )
				( member ( signalRef "@baseboard_fab2_lib.baseboard_fab2(sch_1):vr_pvccin_cpu1_airef2") )
				( objectStatus "DP_ISENSE_PVCCIN_CPU1_PH2" )
			)
			( differentialPair "@baseboard_fab2_lib.baseboard_fab2(sch_1):\DP_ISENSE_PVCCIN_CPU1_PH4\"
				( memberType ( signal ) )
				( physicalCSetRef "@baseboard_fab2_lib.baseboard_fab2(sch_1):\5-5-5_DIFF\" )
				( member ( signalRef "@baseboard_fab2_lib.baseboard_fab2(sch_1):isense_pvccin_cpu1_ph4_imon") )
				( member ( signalRef "@baseboard_fab2_lib.baseboard_fab2(sch_1):vr_pvccin_cpu1_airef4") )
				( objectStatus "DP_ISENSE_PVCCIN_CPU1_PH4" )
			)
			( differentialPair "@baseboard_fab2_lib.baseboard_fab2(sch_1):\DP_ISENSE_PVCCIN_CPU1_PH5\"
				( memberType ( signal ) )
				( physicalCSetRef "@baseboard_fab2_lib.baseboard_fab2(sch_1):\5-5-5_DIFF\" )
				( member ( signalRef "@baseboard_fab2_lib.baseboard_fab2(sch_1):isense_pvccin_cpu1_ph5_imon") )
				( member ( signalRef "@baseboard_fab2_lib.baseboard_fab2(sch_1):vr_pvccin_cpu1_airef5") )
				( objectStatus "DP_ISENSE_PVCCIN_CPU1_PH5" )
			)
			( differentialPair "@baseboard_fab2_lib.baseboard_fab2(sch_1):\DP_ISENSE_PVSA_CPU1_PH\"
				( memberType ( signal ) )
				( member ( signalRef "@baseboard_fab2_lib.baseboard_fab2(sch_1):isense_pvsa_cpu1_imon") )
				( member ( signalRef "@baseboard_fab2_lib.baseboard_fab2(sch_1):vr_pvsa_cpu1_biref1") )
				( objectStatus "DP_ISENSE_PVSA_CPU1_PH" )
			)
			( differentialPair "@baseboard_fab2_lib.baseboard_fab2(sch_1):\DP_ISENSE_PVCCIN_CPU1_PH3\"
				( memberType ( signal ) )
				( physicalCSetRef "@baseboard_fab2_lib.baseboard_fab2(sch_1):\5-5-5_DIFF\" )
				( member ( signalRef "@baseboard_fab2_lib.baseboard_fab2(sch_1):isense_pvccin_cpu1_ph3_imon") )
				( member ( signalRef "@baseboard_fab2_lib.baseboard_fab2(sch_1):vr_pvccin_cpu1_airef3") )
				( objectStatus "DP_ISENSE_PVCCIN_CPU1_PH3" )
			)
			( differentialPair "@baseboard_fab2_lib.baseboard_fab2(sch_1):\DIFFPAIR0\"
				( memberType ( signal ) )
				( member ( signalRef "@baseboard_fab2_lib.baseboard_fab2(sch_1):isense_pvddq_ghj_ph2_imon") )
				( member ( signalRef "@baseboard_fab2_lib.baseboard_fab2(sch_1):vr_pvddq_ghj_airef2") )
				( objectStatus "DP_ISENSE_PVDDQ_GHJ_PH2_IMON" )
			)
			( differentialPair "@baseboard_fab2_lib.baseboard_fab2(sch_1):\DIFFPAIR1\"
				( memberType ( signal ) )
				( member ( signalRef "@baseboard_fab2_lib.baseboard_fab2(sch_1):isense_pvddq_ghj_ph1_imon") )
				( member ( signalRef "@baseboard_fab2_lib.baseboard_fab2(sch_1):vr_pvddq_ghj_airef1") )
				( objectStatus "DP_ISENSE_PVDDQ_GHJ_PH1_IMON" )
			)
			( differentialPair "@baseboard_fab2_lib.baseboard_fab2(sch_1):\DIFFPAIR2\"
				( memberType ( signal ) )
				( physicalCSetRef "@baseboard_fab2_lib.baseboard_fab2(sch_1):\5-5-5_DIFF\" )
				( member ( signalRef "@baseboard_fab2_lib.baseboard_fab2(sch_1):isense_pvddq_klm_ph2_imon") )
				( member ( signalRef "@baseboard_fab2_lib.baseboard_fab2(sch_1):vr_pvddq_klm_airef2") )
				( objectStatus "DP_ISENSE_PVDDQ_KLM_PH2_IMON" )
			)
			( differentialPair "@baseboard_fab2_lib.baseboard_fab2(sch_1):\DIFFPAIR3\"
				( memberType ( signal ) )
				( physicalCSetRef "@baseboard_fab2_lib.baseboard_fab2(sch_1):\5-5-5_DIFF\" )
				( member ( signalRef "@baseboard_fab2_lib.baseboard_fab2(sch_1):isense_pvddq_klm_ph1_imon") )
				( member ( signalRef "@baseboard_fab2_lib.baseboard_fab2(sch_1):vr_pvddq_klm_airef1") )
				( objectStatus "DP_ISENSE_PVDDQ_KLM_PH1_IMON" )
			)
			( differentialPair "@baseboard_fab2_lib.baseboard_fab2(sch_1):\DIFFPAIR4\"
				( memberType ( signal ) )
				( physicalCSetRef "@baseboard_fab2_lib.baseboard_fab2(sch_1):\5-5-5_DIFF\" )
				( member ( signalRef "@baseboard_fab2_lib.baseboard_fab2(sch_1):isense_pvddq_def_ph2_imon") )
				( member ( signalRef "@baseboard_fab2_lib.baseboard_fab2(sch_1):vr_pvddq_def_airef2") )
				( objectStatus "DP_ISENSE_PVDDQ_DEF_PH2_IMON" )
			)
			( differentialPair "@baseboard_fab2_lib.baseboard_fab2(sch_1):\DIFFPAIR5\"
				( memberType ( signal ) )
				( physicalCSetRef "@baseboard_fab2_lib.baseboard_fab2(sch_1):\5-5-5_DIFF\" )
				( member ( signalRef "@baseboard_fab2_lib.baseboard_fab2(sch_1):isense_pvddq_def_ph1_imon") )
				( member ( signalRef "@baseboard_fab2_lib.baseboard_fab2(sch_1):vr_pvddq_def_airef1") )
				( objectStatus "DP_ISENSE_PVDDQ_DEF_PH1_IMON" )
			)
			( differentialPair "@baseboard_fab2_lib.baseboard_fab2(sch_1):\DIFFPAIR6\"
				( memberType ( signal ) )
				( physicalCSetRef "@baseboard_fab2_lib.baseboard_fab2(sch_1):\5-5-5_DIFF\" )
				( member ( signalRef "@baseboard_fab2_lib.baseboard_fab2(sch_1):isense_pvnn_pch_ph1_imon") )
				( member ( signalRef "@baseboard_fab2_lib.baseboard_fab2(sch_1):vr_pvnn_pch_airef1") )
				( objectStatus "DP_ISENSE_PVNN_PCH_PH1_IMON" )
			)
			( differentialPair "@baseboard_fab2_lib.baseboard_fab2(sch_1):\DIFFPAIR7\"
				( memberType ( signal ) )
				( physicalCSetRef "@baseboard_fab2_lib.baseboard_fab2(sch_1):\5-5-5_DIFF\" )
				( member ( signalRef "@baseboard_fab2_lib.baseboard_fab2(sch_1):isense_p1v05_pch_stby_ph1_imon") )
				( member ( signalRef "@baseboard_fab2_lib.baseboard_fab2(sch_1):vr_p1v05_pch_biref1") )
				( objectStatus "DP_ISENSE_P1V05_PCH_STBY_PH1_IMON" )
			)
			( differentialPair "@baseboard_fab2_lib.baseboard_fab2(sch_1):\DIFFPAIR8\"
				( memberType ( signal ) )
				( physicalCSetRef "@baseboard_fab2_lib.baseboard_fab2(sch_1):\5-5-5_DIFF\" )
				( member ( signalRef "@baseboard_fab2_lib.baseboard_fab2(sch_1):isense_pvddq_abc_ph2_imon") )
				( member ( signalRef "@baseboard_fab2_lib.baseboard_fab2(sch_1):vr_pvddq_abc_airef2") )
				( objectStatus "DP_ISENSE_PVDDQ_ABC_PH2_IMON" )
			)
			( differentialPair "@baseboard_fab2_lib.baseboard_fab2(sch_1):\DIFFPAIR9\"
				( memberType ( signal ) )
				( physicalCSetRef "@baseboard_fab2_lib.baseboard_fab2(sch_1):\5-5-5_DIFF\" )
				( member ( signalRef "@baseboard_fab2_lib.baseboard_fab2(sch_1):isense_pvddq_abc_ph1_imon") )
				( member ( signalRef "@baseboard_fab2_lib.baseboard_fab2(sch_1):vr_pvddq_abc_airef1") )
				( objectStatus "DP_ISENSE_PVDDQ_ABC_PH1_IMON" )
			)
			( differentialPair "@baseboard_fab2_lib.baseboard_fab2(sch_1):\DIFFPAIR10\"
				( memberType ( signal ) )
				( physicalCSetRef "@baseboard_fab2_lib.baseboard_fab2(sch_1):\5-5-5_DIFF\" )
				( member ( signalRef "@baseboard_fab2_lib.baseboard_fab2(sch_1):isense_pvccin_cpu0_ph1_imon") )
				( member ( signalRef "@baseboard_fab2_lib.baseboard_fab2(sch_1):vr_pvccin_cpu0_airef1") )
				( objectStatus "DP_ISENSE_PVCCIN_CPU0_PH1_IMON" )
			)
			( differentialPair "@baseboard_fab2_lib.baseboard_fab2(sch_1):\DIFFPAIR11\"
				( memberType ( signal ) )
				( physicalCSetRef "@baseboard_fab2_lib.baseboard_fab2(sch_1):\5-5-5_DIFF\" )
				( member ( signalRef "@baseboard_fab2_lib.baseboard_fab2(sch_1):isense_pvccin_cpu0_ph2_imon") )
				( member ( signalRef "@baseboard_fab2_lib.baseboard_fab2(sch_1):vr_pvccin_cpu0_airef2") )
				( objectStatus "DP_ISENSE_PVCCIN_CPU0_PH2_IMON" )
			)
			( differentialPair "@baseboard_fab2_lib.baseboard_fab2(sch_1):\DIFFPAIR12\"
				( memberType ( signal ) )
				( physicalCSetRef "@baseboard_fab2_lib.baseboard_fab2(sch_1):\5-5-5_DIFF\" )
				( member ( signalRef "@baseboard_fab2_lib.baseboard_fab2(sch_1):isense_pvccin_cpu0_ph3_imon") )
				( member ( signalRef "@baseboard_fab2_lib.baseboard_fab2(sch_1):vr_pvccin_cpu0_airef3") )
				( objectStatus "DP_ISENSE_PVCCIN_CPU0_PH3_IMON" )
			)
			( differentialPair "@baseboard_fab2_lib.baseboard_fab2(sch_1):\DIFFPAIR13\"
				( memberType ( signal ) )
				( physicalCSetRef "@baseboard_fab2_lib.baseboard_fab2(sch_1):\5-5-5_DIFF\" )
				( member ( signalRef "@baseboard_fab2_lib.baseboard_fab2(sch_1):isense_pvccin_cpu0_ph4_imon") )
				( member ( signalRef "@baseboard_fab2_lib.baseboard_fab2(sch_1):vr_pvccin_cpu0_airef4") )
				( objectStatus "DP_ISENSE_PVCCIN_CPU0_PH4_IMON" )
			)
			( differentialPair "@baseboard_fab2_lib.baseboard_fab2(sch_1):\DIFFPAIR14\"
				( memberType ( signal ) )
				( physicalCSetRef "@baseboard_fab2_lib.baseboard_fab2(sch_1):\5-5-5_DIFF\" )
				( member ( signalRef "@baseboard_fab2_lib.baseboard_fab2(sch_1):isense_pvccin_cpu0_ph5_imon") )
				( member ( signalRef "@baseboard_fab2_lib.baseboard_fab2(sch_1):vr_pvccin_cpu0_airef5") )
				( objectStatus "DP_ISENSE_PVCCIN_CPU0_PH5_IMON" )
			)
			( differentialPair "@baseboard_fab2_lib.baseboard_fab2(sch_1):\DIFFPAIR15\"
				( memberType ( signal ) )
				( physicalCSetRef "@baseboard_fab2_lib.baseboard_fab2(sch_1):\5-5-5_DIFF\" )
				( member ( signalRef "@baseboard_fab2_lib.baseboard_fab2(sch_1):isense_pvsa_cpu0_imon") )
				( member ( signalRef "@baseboard_fab2_lib.baseboard_fab2(sch_1):vr_pvsa_cpu0_biref1") )
				( objectStatus "DP_ISENSE_PVSA_CPU0_IMON" )
			)
			( differentialPair "@baseboard_fab2_lib.baseboard_fab2(sch_1):\DIFFPAIR16\"
				( memberType ( signal ) )
				( physicalCSetRef "@baseboard_fab2_lib.baseboard_fab2(sch_1):\5-5-5_DIFF\" )
				( member ( signalRef "@baseboard_fab2_lib.baseboard_fab2(sch_1):isense_pvccio_cpu1_ph1_imon") )
				( member ( signalRef "@baseboard_fab2_lib.baseboard_fab2(sch_1):vr_pvccio_cpu1_airef1") )
				( objectStatus "DP_ISENSE_PVCCIO_CPU1_PH1_IMON" )
			)
			( differentialPair "@baseboard_fab2_lib.baseboard_fab2(sch_1):\DIFFPAIR17\"
				( memberType ( signal ) )
				( member ( signalRef "@baseboard_fab2_lib.baseboard_fab2(sch_1):isense_pvccio_cpu0_ph1_imon") )
				( member ( signalRef "@baseboard_fab2_lib.baseboard_fab2(sch_1):vr_pvccio_cpu0_airef1") )
				( objectStatus "DP_ISENSE_PVCCIO_CPU0_PH1_IMON" )
			)
			( differentialPair "@crescent_city_bb_fab1_lib.crescent_city_bb_fab1(sch_1):\CLK_100M_AIRMAX8_PE1\"
				( memberType ( signal ) )
				( attribute "DIFFP_PHASE_TOL" "10 mil"
					( Units "uPhaseTol" "ns" 1.000000)
					( Origin gBackEnd )
				)
				( member ( signalRef "@baseboard_fab2_lib.baseboard_fab2(sch_1):clk_100m_airmax8_pe1_dn") )
				( member ( signalRef "@baseboard_fab2_lib.baseboard_fab2(sch_1):clk_100m_airmax8_pe1_dp") )
				( objectStatus "DP_CLK_100M_AIRMAX8_PE1" )
			)
			( differentialPair "@crescent_city_bb_fab1_lib.crescent_city_bb_fab1(sch_1):\DP_CLK_100M_BMC_PE\"
				( memberType ( signal ) )
				( attribute "DIFFP_UNCOUPLED_LENGTH" "955.00"
					( Origin gBackEnd )
				)
				( attribute "DIFFP_PHASE_TOL" "10 mil"
					( Units "uPhaseTol" "ns" 1.000000)
					( Origin gBackEnd )
				)
				( member ( electricalNetRef "@crescent_city_bb_fab1_lib.crescent_city_bb_fab1(sch_1):clk_100m_bmc_pe_r_dn") )
				( member ( electricalNetRef "@crescent_city_bb_fab1_lib.crescent_city_bb_fab1(sch_1):clk_100m_bmc_pe_r_dp") )
				( objectStatus "DP_CLK_100M_BMC_PE" )
			)
			( differentialPair "@sapphirecity_baseboard_lib.sapphirecity_baseboard(sch_1):\CLK_100M_CPU0_BCLK0\"
				( memberType ( signal ) )
				( attribute "DIFFP_GATHER_CONTROL" "IGNORE"
					( Origin gBackEnd )
				)
				( attribute "DIFFP_UNCOUPLED_LENGTH" "10.00"
					( Origin gBackEnd )
				)
				( attribute "DIFFP_PHASE_TOL" "10 mil"
					( Units "uPhaseTol" "ns" 1.000000)
					( Origin gBackEnd )
				)
				( member ( electricalNetRef "@crescent_city_bb_fab1_lib.crescent_city_bb_fab1(sch_1):clk_100m_cpu0_bclk0_dn") )
				( member ( electricalNetRef "@crescent_city_bb_fab1_lib.crescent_city_bb_fab1(sch_1):clk_100m_cpu0_bclk0_dp") )
				( objectStatus "DP_CLK_100M_CPU0_BCLK0" )
			)
			( differentialPair "@sapphirecity_baseboard_lib.sapphirecity_baseboard(sch_1):\CLK_100M_CPU0_BCLK1\"
				( memberType ( signal ) )
				( attribute "DIFFP_GATHER_CONTROL" "IGNORE"
					( Origin gBackEnd )
				)
				( attribute "DIFFP_UNCOUPLED_LENGTH" "10.00"
					( Origin gBackEnd )
				)
				( attribute "DIFFP_PHASE_TOL" "10 mil"
					( Units "uPhaseTol" "ns" 1.000000)
					( Origin gBackEnd )
				)
				( member ( electricalNetRef "@crescent_city_bb_fab1_lib.crescent_city_bb_fab1(sch_1):clk_100m_cpu0_bclk1_dn") )
				( member ( electricalNetRef "@crescent_city_bb_fab1_lib.crescent_city_bb_fab1(sch_1):clk_100m_cpu0_bclk1_dp") )
				( objectStatus "DP_CLK_100M_CPU0_BCLK1" )
			)
			( differentialPair "@sapphirecity_baseboard_lib.sapphirecity_baseboard(sch_1):\CLK_100M_CPU0_BCLK2\"
				( memberType ( signal ) )
				( attribute "DIFFP_GATHER_CONTROL" "IGNORE"
					( Origin gBackEnd )
				)
				( attribute "DIFFP_UNCOUPLED_LENGTH" "10.00"
					( Origin gBackEnd )
				)
				( attribute "DIFFP_PHASE_TOL" "10 mil"
					( Units "uPhaseTol" "ns" 1.000000)
					( Origin gBackEnd )
				)
				( member ( electricalNetRef "@crescent_city_bb_fab1_lib.crescent_city_bb_fab1(sch_1):clk_100m_cpu0_bclk2_dn") )
				( member ( electricalNetRef "@crescent_city_bb_fab1_lib.crescent_city_bb_fab1(sch_1):clk_100m_cpu0_bclk2_dp") )
				( objectStatus "DP_CLK_100M_CPU0_BCLK2" )
			)
			( differentialPair "@crescent_city_bb_fab1_lib.crescent_city_bb_fab1(sch_1):\CLK_100M_CPU0_MCP_CLK1_R_D\"
				( memberType ( signal ) )
				( attribute "DIFFP_GATHER_CONTROL" "IGNORE"
					( Origin gBackEnd )
				)
				( attribute "DIFFP_UNCOUPLED_LENGTH" "10.00"
					( Origin gBackEnd )
				)
				( attribute "DIFFP_PHASE_TOL" "10 mil"
					( Units "uPhaseTol" "ns" 1.000000)
					( Origin gBackEnd )
				)
				( member ( electricalNetRef "@crescent_city_bb_fab1_lib.crescent_city_bb_fab1(sch_1):clk_100m_cpu0_rc_refclk_dn") )
				( member ( electricalNetRef "@crescent_city_bb_fab1_lib.crescent_city_bb_fab1(sch_1):clk_100m_cpu0_rc_refclk_dp") )
				( objectStatus "DP_CLK_100M_CPU0_MCP_CLK1_R_D" )
			)
			( differentialPair "@crescent_city_bb_fab1_lib.crescent_city_bb_fab1(sch_1):\CLK_100M_CPU0_MCP_CLK2\"
				( memberType ( signal ) )
				( attribute "DIFFP_GATHER_CONTROL" "IGNORE"
					( Origin gBackEnd )
				)
				( attribute "DIFFP_UNCOUPLED_LENGTH" "10.00"
					( Origin gBackEnd )
				)
				( attribute "DIFFP_PHASE_TOL" "10 mil"
					( Units "uPhaseTol" "ns" 1.000000)
					( Origin gBackEnd )
				)
				( member ( electricalNetRef "@crescent_city_bb_fab1_lib.crescent_city_bb_fab1(sch_1):clk_100m_cpu0_mcp_dn") )
				( member ( electricalNetRef "@crescent_city_bb_fab1_lib.crescent_city_bb_fab1(sch_1):clk_100m_cpu0_mcp_dp") )
				( objectStatus "DP_CLK_100M_CPU0_MCP_CLK2" )
			)
			( differentialPair "@crescent_city_bb_fab1_lib.crescent_city_bb_fab1(sch_1):\CLK_100M_CPU0_PE_REFCLK_R_D\"
				( memberType ( signal ) )
				( attribute "DIFFP_GATHER_CONTROL" "IGNORE"
					( Origin gBackEnd )
				)
				( attribute "DIFFP_UNCOUPLED_LENGTH" "10.00"
					( Origin gBackEnd )
				)
				( attribute "DIFFP_PHASE_TOL" "10 mil"
					( Units "uPhaseTol" "ns" 1.000000)
					( Origin gBackEnd )
				)
				( member ( electricalNetRef "@crescent_city_bb_fab1_lib.crescent_city_bb_fab1(sch_1):clk_100m_cpu0_pe_refclk_dn") )
				( member ( electricalNetRef "@crescent_city_bb_fab1_lib.crescent_city_bb_fab1(sch_1):clk_100m_cpu0_pe_refclk_dp") )
				( objectStatus "DP_CLK_100M_CPU0_PE_REFCLK_R_D" )
			)
			( differentialPair "@sapphirecity_baseboard_lib.sapphirecity_baseboard(sch_1):\CLK_100M_CPU1_BCLK0\"
				( memberType ( signal ) )
				( attribute "DIFFP_GATHER_CONTROL" "IGNORE"
					( Origin gBackEnd )
				)
				( attribute "DIFFP_PHASE_TOL" "10 mil"
					( Units "uPhaseTol" "ns" 1.000000)
					( Origin gBackEnd )
				)
				( member ( electricalNetRef "@crescent_city_bb_fab1_lib.crescent_city_bb_fab1(sch_1):clk_100m_cpu1_bclk0_dn") )
				( member ( electricalNetRef "@crescent_city_bb_fab1_lib.crescent_city_bb_fab1(sch_1):clk_100m_cpu1_bclk0_dp") )
				( objectStatus "DP_CLK_100M_CPU1_BCLK0" )
			)
			( differentialPair "@sapphirecity_baseboard_lib.sapphirecity_baseboard(sch_1):\CLK_100M_CPU1_BCLK1\"
				( memberType ( signal ) )
				( attribute "DIFFP_GATHER_CONTROL" "IGNORE"
					( Origin gBackEnd )
				)
				( attribute "DIFFP_UNCOUPLED_LENGTH" "10.00"
					( Origin gBackEnd )
				)
				( attribute "DIFFP_PHASE_TOL" "10 mil"
					( Units "uPhaseTol" "ns" 1.000000)
					( Origin gBackEnd )
				)
				( member ( electricalNetRef "@crescent_city_bb_fab1_lib.crescent_city_bb_fab1(sch_1):clk_100m_cpu1_bclk1_dn") )
				( member ( electricalNetRef "@crescent_city_bb_fab1_lib.crescent_city_bb_fab1(sch_1):clk_100m_cpu1_bclk1_dp") )
				( objectStatus "DP_CLK_100M_CPU1_BCLK1" )
			)
			( differentialPair "@sapphirecity_baseboard_lib.sapphirecity_baseboard(sch_1):\CLK_100M_CPU1_BCLK2\"
				( memberType ( signal ) )
				( attribute "DIFFP_GATHER_CONTROL" "IGNORE"
					( Origin gBackEnd )
				)
				( attribute "DIFFP_UNCOUPLED_LENGTH" "10.00"
					( Origin gBackEnd )
				)
				( attribute "DIFFP_PHASE_TOL" "10 mil"
					( Units "uPhaseTol" "ns" 1.000000)
					( Origin gBackEnd )
				)
				( member ( electricalNetRef "@crescent_city_bb_fab1_lib.crescent_city_bb_fab1(sch_1):clk_100m_cpu1_bclk2_dn") )
				( member ( electricalNetRef "@crescent_city_bb_fab1_lib.crescent_city_bb_fab1(sch_1):clk_100m_cpu1_bclk2_dp") )
				( objectStatus "DP_CLK_100M_CPU1_BCLK2" )
			)
			( differentialPair "@crescent_city_bb_fab1_lib.crescent_city_bb_fab1(sch_1):\CLK_100M_CPU1_MCP_CLK1_R_D\"
				( memberType ( signal ) )
				( attribute "DIFFP_GATHER_CONTROL" "IGNORE"
					( Origin gBackEnd )
				)
				( attribute "DIFFP_UNCOUPLED_LENGTH" "10.00"
					( Origin gBackEnd )
				)
				( attribute "DIFFP_PHASE_TOL" "10 mil"
					( Units "uPhaseTol" "ns" 1.000000)
					( Origin gBackEnd )
				)
				( member ( electricalNetRef "@crescent_city_bb_fab1_lib.crescent_city_bb_fab1(sch_1):clk_100m_cpu1_rc_refclk_dn") )
				( member ( electricalNetRef "@crescent_city_bb_fab1_lib.crescent_city_bb_fab1(sch_1):clk_100m_cpu1_rc_refclk_dp") )
				( objectStatus "DP_CLK_100M_CPU1_MCP_CLK1_R_D" )
			)
			( differentialPair "@crescent_city_bb_fab1_lib.crescent_city_bb_fab1(sch_1):\CLK_100M_CPU1_PE_REFCLK_R_D\"
				( memberType ( signal ) )
				( attribute "DIFFP_GATHER_CONTROL" "IGNORE"
					( Origin gBackEnd )
				)
				( attribute "DIFFP_UNCOUPLED_LENGTH" "10.00"
					( Origin gBackEnd )
				)
				( attribute "DIFFP_PHASE_TOL" "10 mil"
					( Units "uPhaseTol" "ns" 1.000000)
					( Origin gBackEnd )
				)
				( member ( electricalNetRef "@crescent_city_bb_fab1_lib.crescent_city_bb_fab1(sch_1):clk_100m_cpu1_pe_refclk_dn") )
				( member ( electricalNetRef "@crescent_city_bb_fab1_lib.crescent_city_bb_fab1(sch_1):clk_100m_cpu1_pe_refclk_dp") )
				( objectStatus "DP_CLK_100M_CPU1_PE_REFCLK_R_D" )
			)
			( differentialPair "@crescent_city_bb_fab1_lib.crescent_city_bb_fab1(sch_1):\CLK_100M_DB1200\"
				( memberType ( signal ) )
				( attribute "PROPAGATION_DELAY_PATH_TYPE" "AD:AR"
					( Origin gBackEnd )
				)
				( attribute "PROPAGATION_DELAY_MAX" "11000.00 MIL"
					( Units "uMaxMinProp" "ns" 1.000000)
					( Origin gBackEnd )
				)
				( attribute "DIFFP_GATHER_CONTROL" "IGNORE"
					( Origin gBackEnd )
				)
				( attribute "DIFFP_PHASE_TOL" "10 mil"
					( Units "uPhaseTol" "ns" 1.000000)
					( Origin gBackEnd )
				)
				( member ( signalRef "@baseboard_fab2_lib.baseboard_fab2(sch_1):clk_100m_db1200_dn") )
				( member ( signalRef "@baseboard_fab2_lib.baseboard_fab2(sch_1):clk_100m_db1200_dp") )
				( objectStatus "DP_CLK_100M_DB1200" )
			)
			( differentialPair "@crescent_city_bb_fab1_lib.crescent_city_bb_fab1(sch_1):\CLK_100M_MEZZ1\"
				( memberType ( signal ) )
				( attribute "DIFFP_GATHER_CONTROL" "IGNORE"
					( Origin gBackEnd )
				)
				( attribute "DIFFP_UNCOUPLED_LENGTH" "10.00"
					( Origin gBackEnd )
				)
				( attribute "DIFFP_PHASE_TOL" "10 mil"
					( Units "uPhaseTol" "ns" 1.000000)
					( Origin gBackEnd )
				)
				( member ( signalRef "@baseboard_fab2_lib.baseboard_fab2(sch_1):clk_100m_mezz1_dn") )
				( member ( signalRef "@baseboard_fab2_lib.baseboard_fab2(sch_1):clk_100m_mezz1_dp") )
				( objectStatus "DP_CLK_100M_MEZZ1" )
			)
			( differentialPair "@crescent_city_bb_fab1_lib.crescent_city_bb_fab1(sch_1):\CLK_100M_MEZZ2\"
				( memberType ( signal ) )
				( attribute "DIFFP_GATHER_CONTROL" "IGNORE"
					( Origin gBackEnd )
				)
				( attribute "DIFFP_UNCOUPLED_LENGTH" "10.00"
					( Origin gBackEnd )
				)
				( attribute "DIFFP_PHASE_TOL" "10 mil"
					( Units "uPhaseTol" "ns" 1.000000)
					( Origin gBackEnd )
				)
				( member ( signalRef "@baseboard_fab2_lib.baseboard_fab2(sch_1):clk_100m_mezz2_dn") )
				( member ( signalRef "@baseboard_fab2_lib.baseboard_fab2(sch_1):clk_100m_mezz2_dp") )
				( objectStatus "DP_CLK_100M_MEZZ2" )
			)
			( differentialPair "@crescent_city_bb_fab1_lib.crescent_city_bb_fab1(sch_1):\DP_CLK_100M_MEZZ3_D\"
				( memberType ( signal ) )
				( attribute "DIFFP_GATHER_CONTROL" "IGNORE"
					( Origin gBackEnd )
				)
				( attribute "DIFFP_UNCOUPLED_LENGTH" "10.00"
					( Origin gBackEnd )
				)
				( attribute "DIFFP_PHASE_TOL" "10 mil"
					( Units "uPhaseTol" "ns" 1.000000)
					( Origin gBackEnd )
				)
				( member ( signalRef "@baseboard_fab2_lib.baseboard_fab2(sch_1):clk_100m_mezz3_dn") )
				( member ( signalRef "@baseboard_fab2_lib.baseboard_fab2(sch_1):clk_100m_mezz3_dp") )
				( objectStatus "DP_CLK_100M_MEZZ3" )
			)
			( differentialPair "@crescent_city_bb_fab1_lib.crescent_city_bb_fab1(sch_1):\DP_CLK_100M_MEZZ4_D\"
				( memberType ( signal ) )
				( attribute "DIFFP_GATHER_CONTROL" "IGNORE"
					( Origin gBackEnd )
				)
				( attribute "DIFFP_UNCOUPLED_LENGTH" "10.00"
					( Origin gBackEnd )
				)
				( attribute "DIFFP_PHASE_TOL" "10 mil"
					( Units "uPhaseTol" "ns" 1.000000)
					( Origin gBackEnd )
				)
				( member ( signalRef "@baseboard_fab2_lib.baseboard_fab2(sch_1):clk_100m_mezz4_dn") )
				( member ( signalRef "@baseboard_fab2_lib.baseboard_fab2(sch_1):clk_100m_mezz4_dp") )
				( objectStatus "DP_CLK_100M_MEZZ4" )
			)
			( differentialPair "@crescent_city_bb_fab1_lib.crescent_city_bb_fab1(sch_1):\CLK_100M_M2\"
				( memberType ( signal ) )
				( attribute "DIFFP_GATHER_CONTROL" "IGNORE"
					( Origin gBackEnd )
				)
				( attribute "DIFFP_UNCOUPLED_LENGTH" "10.00"
					( Origin gBackEnd )
				)
				( attribute "DIFFP_PHASE_TOL" "10 mil"
					( Units "uPhaseTol" "ns" 1.000000)
					( Origin gBackEnd )
				)
				( member ( signalRef "@baseboard_fab2_lib.baseboard_fab2(sch_1):clk_100m_m2_dn") )
				( member ( signalRef "@baseboard_fab2_lib.baseboard_fab2(sch_1):clk_100m_m2_dp") )
				( objectStatus "DP_CLK_100M_M2" )
			)
			( differentialPair "@crescent_city_bb_fab1_lib.crescent_city_bb_fab1(sch_1):\DP_CLK_100M_PCH_SLOTX24_S0\"
				( memberType ( signal ) )
				( attribute "DIFFP_GATHER_CONTROL" "IGNORE"
					( Origin gBackEnd )
				)
				( attribute "DIFFP_UNCOUPLED_LENGTH" "10.00"
					( Origin gBackEnd )
				)
				( attribute "DIFFP_PHASE_TOL" "10 mil"
					( Units "uPhaseTol" "ns" 1.000000)
					( Origin gBackEnd )
				)
				( member ( signalRef "@baseboard_fab2_lib.baseboard_fab2(sch_1):clk_100m_pch_slotx24_s0_dn") )
				( member ( signalRef "@baseboard_fab2_lib.baseboard_fab2(sch_1):clk_100m_pch_slotx24_s0_dp") )
				( objectStatus "DP_CLK_100M_PCH_SLOTX24_S0" )
			)
			( differentialPair "@crescent_city_bb_fab1_lib.crescent_city_bb_fab1(sch_1):\CLK_100M_PCH_SLOTX24_S1\"
				( memberType ( signal ) )
				( attribute "DIFFP_GATHER_CONTROL" "IGNORE"
					( Origin gBackEnd )
				)
				( attribute "DIFFP_UNCOUPLED_LENGTH" "10.00"
					( Origin gBackEnd )
				)
				( attribute "DIFFP_PHASE_TOL" "10 mil"
					( Units "uPhaseTol" "ns" 1.000000)
					( Origin gBackEnd )
				)
				( member ( signalRef "@baseboard_fab2_lib.baseboard_fab2(sch_1):clk_100m_pch_slotx24_s1_dn") )
				( member ( signalRef "@baseboard_fab2_lib.baseboard_fab2(sch_1):clk_100m_pch_slotx24_s1_dp") )
				( objectStatus "DP_CLK_100M_PCH_SLOTX24_S1" )
			)
			( differentialPair "@crescent_city_bb_fab1_lib.crescent_city_bb_fab1(sch_1):\CLK_100M_PCH_SLOTX24_S2\"
				( memberType ( signal ) )
				( attribute "DIFFP_GATHER_CONTROL" "IGNORE"
					( Origin gBackEnd )
				)
				( attribute "DIFFP_UNCOUPLED_LENGTH" "10.00"
					( Origin gBackEnd )
				)
				( attribute "DIFFP_PHASE_TOL" "10 mil"
					( Units "uPhaseTol" "ns" 1.000000)
					( Origin gBackEnd )
				)
				( member ( signalRef "@baseboard_fab2_lib.baseboard_fab2(sch_1):clk_100m_pch_slotx24_s2_dn") )
				( member ( signalRef "@baseboard_fab2_lib.baseboard_fab2(sch_1):clk_100m_pch_slotx24_s2_dp") )
				( objectStatus "DP_CLK_100M_PCH_SLOTX24_S2" )
			)
			( differentialPair "@crescent_city_bb_fab1_lib.crescent_city_bb_fab1(sch_1):\CLK_100M_PCH_SLOTX24_S3\"
				( memberType ( signal ) )
				( attribute "DIFFP_GATHER_CONTROL" "IGNORE"
					( Origin gBackEnd )
				)
				( attribute "DIFFP_PHASE_TOL" "10 mil"
					( Units "uPhaseTol" "ns" 1.000000)
					( Origin gBackEnd )
				)
				( member ( signalRef "@baseboard_fab2_lib.baseboard_fab2(sch_1):clk_100m_pch_slotx24_s3_dn") )
				( member ( signalRef "@baseboard_fab2_lib.baseboard_fab2(sch_1):clk_100m_pch_slotx24_s3_dp") )
				( objectStatus "DP_CLK_100M_PCH_SLOTX24_S3" )
			)
			( differentialPair "@crescent_city_bb_fab1_lib.crescent_city_bb_fab1(sch_1):\DP_CLK_100M_PCH_SLOTX24_S4\"
				( memberType ( signal ) )
				( attribute "DIFFP_GATHER_CONTROL" "IGNORE"
					( Origin gBackEnd )
				)
				( attribute "DIFFP_UNCOUPLED_LENGTH" "10.00"
					( Origin gBackEnd )
				)
				( attribute "DIFFP_PHASE_TOL" "10 mil"
					( Units "uPhaseTol" "ns" 1.000000)
					( Origin gBackEnd )
				)
				( member ( signalRef "@baseboard_fab2_lib.baseboard_fab2(sch_1):clk_100m_pch_slotx24_s4_dn") )
				( member ( signalRef "@baseboard_fab2_lib.baseboard_fab2(sch_1):clk_100m_pch_slotx24_s4_dp") )
				( objectStatus "DP_CLK_100M_PCH_SLOTX24_S4" )
			)
			( differentialPair "@crescent_city_bb_fab1_lib.crescent_city_bb_fab1(sch_1):\DP_CLK_100M_PCH_SLOTX24_S5\"
				( memberType ( signal ) )
				( attribute "DIFFP_GATHER_CONTROL" "IGNORE"
					( Origin gBackEnd )
				)
				( attribute "DIFFP_UNCOUPLED_LENGTH" "10.00"
					( Origin gBackEnd )
				)
				( attribute "DIFFP_PHASE_TOL" "10 mil"
					( Units "uPhaseTol" "ns" 1.000000)
					( Origin gBackEnd )
				)
				( member ( signalRef "@baseboard_fab2_lib.baseboard_fab2(sch_1):clk_100m_pch_slotx24_s5_dn") )
				( member ( signalRef "@baseboard_fab2_lib.baseboard_fab2(sch_1):clk_100m_pch_slotx24_s5_dp") )
				( objectStatus "DP_CLK_100M_PCH_SLOTX24_S5" )
			)
			( differentialPair "@sapphirecity_baseboard_lib.sapphirecity_baseboard(sch_1):\CLK_100M_PCH_XDP\"
				( memberType ( signal ) )
				( attribute "DIFFP_GATHER_CONTROL" "IGNORE"
					( Origin gBackEnd )
				)
				( attribute "DIFFP_UNCOUPLED_LENGTH" "10.00"
					( Origin gBackEnd )
				)
				( attribute "DIFFP_PHASE_TOL" "10 mil"
					( Units "uPhaseTol" "ns" 1.000000)
					( Origin gBackEnd )
				)
				( member ( signalRef "@baseboard_fab2_lib.baseboard_fab2(sch_1):clk_100m_pch_xdp_dn") )
				( member ( signalRef "@baseboard_fab2_lib.baseboard_fab2(sch_1):clk_100m_pch_xdp_dp") )
				( objectStatus "DP_CLK_100M_PCH_XDP" )
			)
			( differentialPair "@crescent_city_bb_fab1_lib.crescent_city_bb_fab1(sch_1):\CLK_100M_SPRV_D\"
				( memberType ( signal ) )
				( attribute "DIFFP_GATHER_CONTROL" "IGNORE"
					( Origin gBackEnd )
				)
				( attribute "DIFFP_UNCOUPLED_LENGTH" "10.00"
					( Origin gBackEnd )
				)
				( attribute "DIFFP_PHASE_TOL" "10 mil"
					( Units "uPhaseTol" "ns" 1.000000)
					( Origin gBackEnd )
				)
				( member ( signalRef "@baseboard_fab2_lib.baseboard_fab2(sch_1):clk_100m_sprv_dn") )
				( member ( signalRef "@baseboard_fab2_lib.baseboard_fab2(sch_1):clk_100m_sprv_dp") )
				( objectStatus "DP_CLK_100M_SPRV_D" )
			)
			( differentialPair "@crescent_city_bb_fab1_lib.crescent_city_bb_fab1(sch_1):\DP_CLK_156M_OSC_CPU0_HFI\"
				( memberType ( signal ) )
				( attribute "DIFFP_GATHER_CONTROL" "IGNORE"
					( Origin gBackEnd )
				)
				( attribute "DIFFP_UNCOUPLED_LENGTH" "770.00"
					( Origin gBackEnd )
				)
				( attribute "DIFFP_PHASE_TOL" "10 mil"
					( Units "uPhaseTol" "ns" 1.000000)
					( Origin gBackEnd )
				)
				( member ( signalRef "@baseboard_fab2_lib.baseboard_fab2(sch_1):clk_322m_osc_cpu0_rc_dn") )
				( member ( signalRef "@baseboard_fab2_lib.baseboard_fab2(sch_1):clk_322m_osc_cpu0_rc_dp") )
				( objectStatus "DP_CLK_322M_OSC_CPU0_RC" )
			)
			( differentialPair "@crescent_city_bb_fab1_lib.crescent_city_bb_fab1(sch_1):\DP_CLK_156M_OSC_CPU1_HFI\"
				( memberType ( signal ) )
				( attribute "DIFFP_GATHER_CONTROL" "IGNORE"
					( Origin gBackEnd )
				)
				( attribute "DIFFP_UNCOUPLED_LENGTH" "110.00"
					( Origin gBackEnd )
				)
				( attribute "DIFFP_PHASE_TOL" "10 mil"
					( Units "uPhaseTol" "ns" 1.000000)
					( Origin gBackEnd )
				)
				( member ( signalRef "@baseboard_fab2_lib.baseboard_fab2(sch_1):clk_322m_osc_cpu1_rc_dn") )
				( member ( signalRef "@baseboard_fab2_lib.baseboard_fab2(sch_1):clk_322m_osc_cpu1_rc_dp") )
				( objectStatus "DP_CLK_322M_OSC_CPU1_RC" )
			)
			( differentialPair "@crescent_city_bb_fab1_lib.crescent_city_bb_fab1(sch_1):\CLK_100M_CPU1_MCP_CLK2\"
				( memberType ( signal ) )
				( attribute "DIFFP_GATHER_CONTROL" "IGNORE"
					( Origin gBackEnd )
				)
				( attribute "DIFFP_UNCOUPLED_LENGTH" "10.00"
					( Origin gBackEnd )
				)
				( attribute "DIFFP_PHASE_TOL" "10 mil"
					( Units "uPhaseTol" "ns" 1.000000)
					( Origin gBackEnd )
				)
				( member ( electricalNetRef "@crescent_city_bb_fab1_lib.crescent_city_bb_fab1(sch_1):clk_100m_cpu1_mcp_dn") )
				( member ( electricalNetRef "@crescent_city_bb_fab1_lib.crescent_city_bb_fab1(sch_1):clk_100m_cpu1_mcp_dp") )
				( objectStatus "DP_CLK_100M_CPU1_MCP_CLK2" )
			)
			( differentialPair "@baseboard_fab2_lib.baseboard_fab2(sch_1):\DP_CLK_156M_OSC_BRD_CPU0\"
				( memberType ( signal ) )
				( attribute "DIFFP_PHASE_TOL" "10 mil"
					( Units "uPhaseTol" "ns" 1.000000)
					( Origin gBackEnd )
				)
				( member ( signalRef "@baseboard_fab2_lib.baseboard_fab2(sch_1):clk_156m_osc_brd_cpu0_dn") )
				( member ( signalRef "@baseboard_fab2_lib.baseboard_fab2(sch_1):clk_156m_osc_brd_cpu0_dp") )
				( objectStatus "DP_CLK_156M_OSC_BRD_CPU0" )
			)
			( differentialPair "@baseboard_fab2_lib.baseboard_fab2(sch_1):\DP_CLK_156M_OSC_BRD_CPU1\"
				( memberType ( signal ) )
				( attribute "DIFFP_PHASE_TOL" "10 mil"
					( Units "uPhaseTol" "ns" 1.000000)
					( Origin gBackEnd )
				)
				( member ( signalRef "@baseboard_fab2_lib.baseboard_fab2(sch_1):clk_156m_osc_brd_cpu1_dn") )
				( member ( signalRef "@baseboard_fab2_lib.baseboard_fab2(sch_1):clk_156m_osc_brd_cpu1_dp") )
				( objectStatus "DP_CLK_156M_OSC_BRD_CPU1" )
			)
			( differentialPair "@baseboard_fab2_lib.baseboard_fab2(sch_1):\DP_CLK_156M_OSC_CPU0_HFI\"
				( memberType ( signal ) )
				( attribute "DIFFP_PHASE_TOL" "10 mil"
					( Units "uPhaseTol" "ns" 1.000000)
					( Origin gBackEnd )
				)
				( member ( signalRef "@baseboard_fab2_lib.baseboard_fab2(sch_1):clk_156m_osc_cpu0_hfi_dn") )
				( member ( signalRef "@baseboard_fab2_lib.baseboard_fab2(sch_1):clk_156m_osc_cpu0_hfi_dp") )
				( objectStatus "DP_CLK_156M_OSC_CPU0_HFI" )
			)
			( differentialPair "@baseboard_fab2_lib.baseboard_fab2(sch_1):\DP_CLK_156M_OSC_CPU1_HFI\"
				( memberType ( signal ) )
				( attribute "DIFFP_PHASE_TOL" "10 mil"
					( Units "uPhaseTol" "ns" 1.000000)
					( Origin gBackEnd )
				)
				( member ( signalRef "@baseboard_fab2_lib.baseboard_fab2(sch_1):clk_156m_osc_cpu1_hfi_dn") )
				( member ( signalRef "@baseboard_fab2_lib.baseboard_fab2(sch_1):clk_156m_osc_cpu1_hfi_dp") )
				( objectStatus "DP_CLK_156M_OSC_CPU1_HFI" )
			)
			( differentialPair "@baseboard_fab2_lib.baseboard_fab2(sch_1):\DP_CLK_322M_156M_CPU0_OSC_VRM\"
				( memberType ( signal ) )
				( attribute "DIFFP_PHASE_TOL" "10 mil"
					( Units "uPhaseTol" "ns" 1.000000)
					( Origin gBackEnd )
				)
				( member ( signalRef "@baseboard_fab2_lib.baseboard_fab2(sch_1):clk_322m_156m_cpu0_osc_vrm_dn") )
				( member ( signalRef "@baseboard_fab2_lib.baseboard_fab2(sch_1):clk_322m_156m_cpu0_osc_vrm_dp") )
				( objectStatus "DP_CLK_322M_156M_CPU0_OSC_VRM" )
			)
			( differentialPair "@baseboard_fab2_lib.baseboard_fab2(sch_1):\DP_CLK_322M_156M_CPU1_OSC_VRM\"
				( memberType ( signal ) )
				( attribute "DIFFP_PHASE_TOL" "10 mil"
					( Units "uPhaseTol" "ns" 1.000000)
					( Origin gBackEnd )
				)
				( member ( signalRef "@baseboard_fab2_lib.baseboard_fab2(sch_1):clk_322m_156m_cpu1_osc_vrm_dn") )
				( member ( signalRef "@baseboard_fab2_lib.baseboard_fab2(sch_1):clk_322m_156m_cpu1_osc_vrm_dp") )
				( objectStatus "DP_CLK_322M_156M_CPU1_OSC_VRM" )
			)
			( differentialPair "@crescent_city_bb_fab1_lib.crescent_city_bb_fab1(sch_1):\DP_78\"
				( memberType ( signal ) )
				( attribute "DIFFP_PHASE_MAX_LENGTH" "600.00"
					( Origin gBackEnd )
				)
				( member ( electricalNetRef "@crescent_city_bb_fab1_lib.crescent_city_bb_fab1(sch_1):pe_pch_sprv_tx_c_dn") )
				( member ( electricalNetRef "@crescent_city_bb_fab1_lib.crescent_city_bb_fab1(sch_1):pe_pch_sprv_tx_c_dp") )
				( objectStatus "DP_PE_PCH_SPRV_TX" )
			)
			( differentialPair "@crescent_city_bb_fab1_lib.crescent_city_bb_fab1(sch_1):\DP_105\"
				( memberType ( signal ) )
				( electricalCSetRef "@crescent_city_bb_fab1_lib.crescent_city_bb_fab1(sch_1):\NIC_MDI_2-3\" )
				( attribute "DIFFP_PHASE_MAX_LENGTH" "600.00"
					( Origin gBackEnd )
				)
				( member ( electricalNetRef "@crescent_city_bb_fab1_lib.crescent_city_bb_fab1(sch_1):nic_mdi_sprv_rj45_3_r_dn") )
				( member ( electricalNetRef "@crescent_city_bb_fab1_lib.crescent_city_bb_fab1(sch_1):nic_mdi_sprv_rj45_3_r_dp") )
				( objectStatus "DP_NIC_SER_N_MDI_3" )
			)
			( differentialPair "@crescent_city_bb_fab1_lib.crescent_city_bb_fab1(sch_1):\DP_106\"
				( memberType ( signal ) )
				( attribute "DIFFP_PHASE_MAX_LENGTH" "600.00"
					( Origin gBackEnd )
				)
				( member ( electricalNetRef "@crescent_city_bb_fab1_lib.crescent_city_bb_fab1(sch_1):nic_mdi_sprv_rj45_2_r_dn") )
				( member ( electricalNetRef "@crescent_city_bb_fab1_lib.crescent_city_bb_fab1(sch_1):nic_mdi_sprv_rj45_2_r_dp") )
				( objectStatus "DP_NIC_SER_N_MDI_2" )
			)
			( differentialPair "@crescent_city_bb_fab1_lib.crescent_city_bb_fab1(sch_1):\DP_79\"
				( memberType ( signal ) )
				( attribute "DIFFP_PHASE_MAX_LENGTH" "600.00"
					( Origin gBackEnd )
				)
				( member ( electricalNetRef "@crescent_city_bb_fab1_lib.crescent_city_bb_fab1(sch_1):sata6g_p0_rx_c_dn") )
				( member ( electricalNetRef "@crescent_city_bb_fab1_lib.crescent_city_bb_fab1(sch_1):sata6g_p0_rx_c_dp") )
				( objectStatus "DP_SATA6G_PCH_PCIE_UP_SATA_RXN(0)" )
			)
			( differentialPair "@crescent_city_bb_fab1_lib.crescent_city_bb_fab1(sch_1):\DP_80\"
				( memberType ( signal ) )
				( attribute "DIFFP_PHASE_MAX_LENGTH" "600.00"
					( Origin gBackEnd )
				)
				( member ( electricalNetRef "@crescent_city_bb_fab1_lib.crescent_city_bb_fab1(sch_1):sata6g_p1_rx_c_dn") )
				( member ( electricalNetRef "@crescent_city_bb_fab1_lib.crescent_city_bb_fab1(sch_1):sata6g_p1_rx_c_dp") )
				( objectStatus "DP_SATA6G_PCH_PCIE_UP_SATA_RXN(1)" )
			)
			( differentialPair "@crescent_city_bb_fab1_lib.crescent_city_bb_fab1(sch_1):\DP_81\"
				( memberType ( signal ) )
				( attribute "DIFFP_PHASE_MAX_LENGTH" "600.00"
					( Origin gBackEnd )
				)
				( attribute "DIFFP_PHASE_TOL_DYNAMIC" "30 mil"
					( Units "uPhaseTol" "mil" 1.000000)
					( Origin gBackEnd )
				)
				( member ( electricalNetRef "@crescent_city_bb_fab1_lib.crescent_city_bb_fab1(sch_1):sata6g_p2_rx_c_dn") )
				( member ( electricalNetRef "@crescent_city_bb_fab1_lib.crescent_city_bb_fab1(sch_1):sata6g_p2_rx_c_dp") )
				( objectStatus "DP_SATA6G_PCH_PCIE_UP_SATA_RXN(2)" )
			)
			( differentialPair "@crescent_city_bb_fab1_lib.crescent_city_bb_fab1(sch_1):\DP_82\"
				( memberType ( signal ) )
				( attribute "DIFFP_PHASE_MAX_LENGTH" "600.00"
					( Origin gBackEnd )
				)
				( member ( electricalNetRef "@crescent_city_bb_fab1_lib.crescent_city_bb_fab1(sch_1):sata6g_p3_rx_c_dn") )
				( member ( electricalNetRef "@crescent_city_bb_fab1_lib.crescent_city_bb_fab1(sch_1):sata6g_p3_rx_c_dp") )
				( objectStatus "DP_SATA6G_PCH_PCIE_UP_SATA_RXN(3)" )
			)
			( differentialPair "@crescent_city_bb_fab1_lib.crescent_city_bb_fab1(sch_1):\DP_83\"
				( memberType ( signal ) )
				( attribute "DIFFP_PHASE_MAX_LENGTH" "600.00"
					( Origin gBackEnd )
				)
				( member ( electricalNetRef "@crescent_city_bb_fab1_lib.crescent_city_bb_fab1(sch_1):sata6g_p4_rx_c_dn") )
				( member ( electricalNetRef "@crescent_city_bb_fab1_lib.crescent_city_bb_fab1(sch_1):sata6g_p4_rx_c_dp") )
				( objectStatus "DP_SATA6G_PCH_PCIE_UP_SATA_RXN(4)" )
			)
			( differentialPair "@crescent_city_bb_fab1_lib.crescent_city_bb_fab1(sch_1):\DP_84\"
				( memberType ( signal ) )
				( attribute "DIFFP_PHASE_MAX_LENGTH" "600.00"
					( Origin gBackEnd )
				)
				( member ( electricalNetRef "@crescent_city_bb_fab1_lib.crescent_city_bb_fab1(sch_1):sata6g_p5_rx_c_dn") )
				( member ( electricalNetRef "@crescent_city_bb_fab1_lib.crescent_city_bb_fab1(sch_1):sata6g_p5_rx_c_dp") )
				( objectStatus "DP_SATA6G_PCH_PCIE_UP_SATA_RXN(5)" )
			)
			( differentialPair "@crescent_city_bb_fab1_lib.crescent_city_bb_fab1(sch_1):\DP_85\"
				( memberType ( signal ) )
				( attribute "DIFFP_PHASE_MAX_LENGTH" "600.00"
					( Origin gBackEnd )
				)
				( member ( electricalNetRef "@crescent_city_bb_fab1_lib.crescent_city_bb_fab1(sch_1):sata6g_p6_rx_c_dn") )
				( member ( electricalNetRef "@crescent_city_bb_fab1_lib.crescent_city_bb_fab1(sch_1):sata6g_p6_rx_c_dp") )
				( objectStatus "DP_SATA6G_PCH_PCIE_UP_SATA_RXN(6)" )
			)
			( differentialPair "@crescent_city_bb_fab1_lib.crescent_city_bb_fab1(sch_1):\DP_86\"
				( memberType ( signal ) )
				( attribute "DIFFP_PHASE_MAX_LENGTH" "600.00"
					( Origin gBackEnd )
				)
				( member ( electricalNetRef "@crescent_city_bb_fab1_lib.crescent_city_bb_fab1(sch_1):sata6g_p7_rx_c_dn") )
				( member ( electricalNetRef "@crescent_city_bb_fab1_lib.crescent_city_bb_fab1(sch_1):sata6g_p7_rx_c_dp") )
				( objectStatus "DP_SATA6G_PCH_PCIE_UP_SATA_RXN(7)" )
			)
			( differentialPair "@crescent_city_bb_fab1_lib.crescent_city_bb_fab1(sch_1):\DP_87\"
				( memberType ( signal ) )
				( attribute "DIFFP_PHASE_MAX_LENGTH" "600.00"
					( Origin gBackEnd )
				)
				( attribute "DIFFP_PHASE_TOL_DYNAMIC" "75 mil"
					( Units "uPhaseTol" "mil" 1.000000)
					( Origin gBackEnd )
				)
				( member ( electricalNetRef "@crescent_city_bb_fab1_lib.crescent_city_bb_fab1(sch_1):sata6g_p0_tx_c_dn") )
				( member ( electricalNetRef "@crescent_city_bb_fab1_lib.crescent_city_bb_fab1(sch_1):sata6g_p0_tx_c_dp") )
				( objectStatus "DP_SATA6G_PCH_PCIE_UP_SATA_TXN(0)" )
			)
			( differentialPair "@crescent_city_bb_fab1_lib.crescent_city_bb_fab1(sch_1):\DP_88\"
				( memberType ( signal ) )
				( attribute "DIFFP_PHASE_MAX_LENGTH" "600.00"
					( Origin gBackEnd )
				)
				( attribute "DIFFP_PHASE_TOL_DYNAMIC" "75 mil"
					( Units "uPhaseTol" "mil" 1.000000)
					( Origin gBackEnd )
				)
				( member ( electricalNetRef "@crescent_city_bb_fab1_lib.crescent_city_bb_fab1(sch_1):sata6g_p1_tx_c_dn") )
				( member ( electricalNetRef "@crescent_city_bb_fab1_lib.crescent_city_bb_fab1(sch_1):sata6g_p1_tx_c_dp") )
				( objectStatus "DP_SATA6G_PCH_PCIE_UP_SATA_TXN(1)" )
			)
			( differentialPair "@crescent_city_bb_fab1_lib.crescent_city_bb_fab1(sch_1):\DP_89\"
				( memberType ( signal ) )
				( attribute "DIFFP_PHASE_MAX_LENGTH" "600.00"
					( Origin gBackEnd )
				)
				( member ( electricalNetRef "@crescent_city_bb_fab1_lib.crescent_city_bb_fab1(sch_1):sata6g_p2_tx_c_dn") )
				( member ( electricalNetRef "@crescent_city_bb_fab1_lib.crescent_city_bb_fab1(sch_1):sata6g_p2_tx_c_dp") )
				( objectStatus "DP_SATA6G_PCH_PCIE_UP_SATA_TXN(2)" )
			)
			( differentialPair "@crescent_city_bb_fab1_lib.crescent_city_bb_fab1(sch_1):\DP_90\"
				( memberType ( signal ) )
				( attribute "DIFFP_PHASE_MAX_LENGTH" "600.00"
					( Origin gBackEnd )
				)
				( member ( electricalNetRef "@crescent_city_bb_fab1_lib.crescent_city_bb_fab1(sch_1):sata6g_p3_tx_c_dn") )
				( member ( electricalNetRef "@crescent_city_bb_fab1_lib.crescent_city_bb_fab1(sch_1):sata6g_p3_tx_c_dp") )
				( objectStatus "DP_SATA6G_PCH_PCIE_UP_SATA_TXN(3)" )
			)
			( differentialPair "@crescent_city_bb_fab1_lib.crescent_city_bb_fab1(sch_1):\DP_91\"
				( memberType ( signal ) )
				( attribute "DIFFP_PHASE_MAX_LENGTH" "600.00"
					( Origin gBackEnd )
				)
				( member ( electricalNetRef "@crescent_city_bb_fab1_lib.crescent_city_bb_fab1(sch_1):sata6g_p4_tx_c_dn") )
				( member ( electricalNetRef "@crescent_city_bb_fab1_lib.crescent_city_bb_fab1(sch_1):sata6g_p4_tx_c_dp") )
				( objectStatus "DP_SATA6G_PCH_PCIE_UP_SATA_TXN(4)" )
			)
			( differentialPair "@crescent_city_bb_fab1_lib.crescent_city_bb_fab1(sch_1):\DP_92\"
				( memberType ( signal ) )
				( attribute "DIFFP_PHASE_MAX_LENGTH" "600.00"
					( Origin gBackEnd )
				)
				( member ( electricalNetRef "@crescent_city_bb_fab1_lib.crescent_city_bb_fab1(sch_1):sata6g_p5_tx_c_dn") )
				( member ( electricalNetRef "@crescent_city_bb_fab1_lib.crescent_city_bb_fab1(sch_1):sata6g_p5_tx_c_dp") )
				( objectStatus "DP_SATA6G_PCH_PCIE_UP_SATA_TXN(5)" )
			)
			( differentialPair "@crescent_city_bb_fab1_lib.crescent_city_bb_fab1(sch_1):\DP_93\"
				( memberType ( signal ) )
				( attribute "DIFFP_PHASE_MAX_LENGTH" "600.00"
					( Origin gBackEnd )
				)
				( member ( electricalNetRef "@crescent_city_bb_fab1_lib.crescent_city_bb_fab1(sch_1):sata6g_p6_tx_c_dn") )
				( member ( electricalNetRef "@crescent_city_bb_fab1_lib.crescent_city_bb_fab1(sch_1):sata6g_p6_tx_c_dp") )
				( objectStatus "DP_SATA6G_PCH_PCIE_UP_SATA_TXN(6)" )
			)
			( differentialPair "@crescent_city_bb_fab1_lib.crescent_city_bb_fab1(sch_1):\DP_94\"
				( memberType ( signal ) )
				( attribute "DIFFP_PHASE_MAX_LENGTH" "600.00"
					( Origin gBackEnd )
				)
				( member ( electricalNetRef "@crescent_city_bb_fab1_lib.crescent_city_bb_fab1(sch_1):sata6g_p7_tx_c_dn") )
				( member ( electricalNetRef "@crescent_city_bb_fab1_lib.crescent_city_bb_fab1(sch_1):sata6g_p7_tx_c_dp") )
				( objectStatus "DP_SATA6G_PCH_PCIE_UP_SATA_TXN(7)" )
			)
			( differentialPair "@crescent_city_bb_fab1_lib.crescent_city_bb_fab1(sch_1):\DP_95\"
				( memberType ( signal ) )
				( attribute "DIFFP_PHASE_MAX_LENGTH" "600.00"
					( Origin gBackEnd )
				)
				( member ( electricalNetRef "@crescent_city_bb_fab1_lib.crescent_city_bb_fab1(sch_1):sata6g_p8_rx_c_dn") )
				( member ( electricalNetRef "@crescent_city_bb_fab1_lib.crescent_city_bb_fab1(sch_1):sata6g_p8_rx_c_dp") )
				( objectStatus "DP_SATA6G_RX_DN(0)" )
			)
			( differentialPair "@crescent_city_bb_fab1_lib.crescent_city_bb_fab1(sch_1):\DP_96\"
				( memberType ( signal ) )
				( attribute "DIFFP_PHASE_MAX_LENGTH" "600.00"
					( Origin gBackEnd )
				)
				( member ( electricalNetRef "@crescent_city_bb_fab1_lib.crescent_city_bb_fab1(sch_1):sata6g_p9_rx_c_dn") )
				( member ( electricalNetRef "@crescent_city_bb_fab1_lib.crescent_city_bb_fab1(sch_1):sata6g_p9_rx_c_dp") )
				( objectStatus "DP_SATA6G_RX_DN(1)" )
			)
			( differentialPair "@crescent_city_bb_fab1_lib.crescent_city_bb_fab1(sch_1):\DP_97\"
				( memberType ( signal ) )
				( attribute "DIFFP_PHASE_MAX_LENGTH" "600.00"
					( Origin gBackEnd )
				)
				( member ( electricalNetRef "@crescent_city_bb_fab1_lib.crescent_city_bb_fab1(sch_1):sata6g_p10_rx_c_dn") )
				( member ( electricalNetRef "@crescent_city_bb_fab1_lib.crescent_city_bb_fab1(sch_1):sata6g_p10_rx_c_dp") )
				( objectStatus "DP_SATA6G_RX_DN(2)" )
			)
			( differentialPair "@crescent_city_bb_fab1_lib.crescent_city_bb_fab1(sch_1):\DP_98\"
				( memberType ( signal ) )
				( attribute "DIFFP_PHASE_MAX_LENGTH" "600.00"
					( Origin gBackEnd )
				)
				( member ( electricalNetRef "@crescent_city_bb_fab1_lib.crescent_city_bb_fab1(sch_1):sata6g_p11_rx_c_dn") )
				( member ( electricalNetRef "@crescent_city_bb_fab1_lib.crescent_city_bb_fab1(sch_1):sata6g_p11_rx_c_dp") )
				( objectStatus "DP_SATA6G_RX_DN(3)" )
			)
			( differentialPair "@crescent_city_bb_fab1_lib.crescent_city_bb_fab1(sch_1):\DP_99\"
				( memberType ( signal ) )
				( member ( electricalNetRef "@crescent_city_bb_fab1_lib.crescent_city_bb_fab1(sch_1):sata6g_s1_rx_c_dn") )
				( member ( electricalNetRef "@crescent_city_bb_fab1_lib.crescent_city_bb_fab1(sch_1):sata6g_s1_rx_c_dp") )
				( objectStatus "DP_SATA6G_S1_RX_D" )
			)
			( differentialPair "@crescent_city_bb_fab1_lib.crescent_city_bb_fab1(sch_1):\DP_100\"
				( memberType ( signal ) )
				( member ( electricalNetRef "@crescent_city_bb_fab1_lib.crescent_city_bb_fab1(sch_1):sata6g_s1_tx_c_dn") )
				( member ( electricalNetRef "@crescent_city_bb_fab1_lib.crescent_city_bb_fab1(sch_1):sata6g_s1_tx_c_dp") )
				( objectStatus "DP_SATA6G_S1_TX_D" )
			)
			( differentialPair "@crescent_city_bb_fab1_lib.crescent_city_bb_fab1(sch_1):\DP_101\"
				( memberType ( signal ) )
				( attribute "DIFFP_PHASE_MAX_LENGTH" "600.00"
					( Origin gBackEnd )
				)
				( member ( electricalNetRef "@crescent_city_bb_fab1_lib.crescent_city_bb_fab1(sch_1):sata6g_p8_tx_c_dn") )
				( member ( electricalNetRef "@crescent_city_bb_fab1_lib.crescent_city_bb_fab1(sch_1):sata6g_p8_tx_c_dp") )
				( objectStatus "DP_SATA6G_TX_DN(0)" )
			)
			( differentialPair "@crescent_city_bb_fab1_lib.crescent_city_bb_fab1(sch_1):\DP_102\"
				( memberType ( signal ) )
				( attribute "DIFFP_PHASE_MAX_LENGTH" "600.00"
					( Origin gBackEnd )
				)
				( member ( electricalNetRef "@crescent_city_bb_fab1_lib.crescent_city_bb_fab1(sch_1):sata6g_p9_tx_c_dn") )
				( member ( electricalNetRef "@crescent_city_bb_fab1_lib.crescent_city_bb_fab1(sch_1):sata6g_p9_tx_c_dp") )
				( objectStatus "DP_SATA6G_TX_DN(1)" )
			)
			( differentialPair "@crescent_city_bb_fab1_lib.crescent_city_bb_fab1(sch_1):\DP_103\"
				( memberType ( signal ) )
				( attribute "DIFFP_PHASE_MAX_LENGTH" "600.00"
					( Origin gBackEnd )
				)
				( member ( electricalNetRef "@crescent_city_bb_fab1_lib.crescent_city_bb_fab1(sch_1):sata6g_p10_tx_c_dn") )
				( member ( electricalNetRef "@crescent_city_bb_fab1_lib.crescent_city_bb_fab1(sch_1):sata6g_p10_tx_c_dp") )
				( objectStatus "DP_SATA6G_TX_DN(2)" )
			)
			( differentialPair "@crescent_city_bb_fab1_lib.crescent_city_bb_fab1(sch_1):\DP_104\"
				( memberType ( signal ) )
				( attribute "DIFFP_PHASE_MAX_LENGTH" "600.00"
					( Origin gBackEnd )
				)
				( member ( electricalNetRef "@crescent_city_bb_fab1_lib.crescent_city_bb_fab1(sch_1):sata6g_p11_tx_c_dn") )
				( member ( electricalNetRef "@crescent_city_bb_fab1_lib.crescent_city_bb_fab1(sch_1):sata6g_p11_tx_c_dp") )
				( objectStatus "DP_SATA6G_TX_DN(3)" )
			)
			( differentialPair "@crescent_city_bb_fab1_lib.crescent_city_bb_fab1(sch_1):\P3E_PCH_M2_SATA6G_RX_D\"
				( memberType ( signal ) )
				( member ( signalRef "@baseboard_fab2_lib.baseboard_fab2(sch_1):sata6g_s0_rx_dn") )
				( member ( signalRef "@baseboard_fab2_lib.baseboard_fab2(sch_1):sata6g_s0_rx_dp") )
				( objectStatus "DP_SATA6G_S0_RX_D" )
			)
			( differentialPair "@crescent_city_bb_fab1_lib.crescent_city_bb_fab1(sch_1):\P3E_PCH_M2_SATA6G_TX_D\"
				( memberType ( signal ) )
				( member ( signalRef "@baseboard_fab2_lib.baseboard_fab2(sch_1):sata6g_s0_tx_dn") )
				( member ( signalRef "@baseboard_fab2_lib.baseboard_fab2(sch_1):sata6g_s0_tx_dp") )
				( objectStatus "DP_SATA6G_S0_TX_D" )
			)
			( differentialPair "@crescent_city_bb_fab1_lib.crescent_city_bb_fab1(sch_1):\USB2_PCH_BMC_P4_D\"
				( memberType ( signal ) )
				( attribute "MAX_VIA_COUNT" "4"
					( Origin gBackEnd )
				)
				( attribute "DIFFP_GATHER_CONTROL" "INCLUDE"
					( Origin gBackEnd )
				)
				( attribute "DIFFP_PHASE_TOL" "195 ns"
					( Units "uPhaseTol" "ns" 1.000000)
					( Origin gBackEnd )
				)
				( member ( signalRef "@baseboard_fab2_lib.baseboard_fab2(sch_1):usb_pch_bmc_p4_dn") )
				( member ( signalRef "@baseboard_fab2_lib.baseboard_fab2(sch_1):usb_pch_bmc_p4_dp") )
				( objectStatus "USB2_PCH_BMC_P4_D" )
			)
			( differentialPair "@crescent_city_bb_fab1_lib.crescent_city_bb_fab1(sch_1):\USB2_PCH_BMC_P5_D\"
				( memberType ( signal ) )
				( attribute "MAX_VIA_COUNT" "4"
					( Origin gBackEnd )
				)
				( attribute "DIFFP_GATHER_CONTROL" "INCLUDE"
					( Origin gBackEnd )
				)
				( attribute "DIFFP_UNCOUPLED_LENGTH" "525.00"
					( Origin gBackEnd )
				)
				( attribute "DIFFP_PHASE_TOL" "5 mil"
					( Units "uPhaseTol" "ns" 1.000000)
					( Origin gBackEnd )
				)
				( member ( signalRef "@baseboard_fab2_lib.baseboard_fab2(sch_1):usb2_pch_bmc_p5_dn") )
				( member ( signalRef "@baseboard_fab2_lib.baseboard_fab2(sch_1):usb2_pch_bmc_p5_dp") )
				( objectStatus "USB2_PCH_BMC_P5_D" )
			)
			( differentialPair "@crescent_city_bb_fab1_lib.crescent_city_bb_fab1(sch_1):\DP_USB2_P02\"
				( memberType ( signal ) )
				( attribute "MAX_VIA_COUNT" "2"
					( Origin gBackEnd )
				)
				( member ( electricalNetRef "@crescent_city_bb_fab1_lib.crescent_city_bb_fab1(sch_1):usb2_p01_dn") )
				( member ( electricalNetRef "@crescent_city_bb_fab1_lib.crescent_city_bb_fab1(sch_1):usb2_p01_dp") )
				( objectStatus "USB2_P01" )
			)
			( differentialPair "@sapphirecity_baseboard_lib.sapphirecity_baseboard(sch_1):\DMI_CPU0_PCH_TX_C_D\(0)"
				( memberType ( signal ) )
				( member ( electricalNetRef "@crescent_city_bb_fab1_lib.crescent_city_bb_fab1(sch_1):dmi_cpu0_pch_tx_c_dn(0)") )
				( member ( electricalNetRef "@crescent_city_bb_fab1_lib.crescent_city_bb_fab1(sch_1):dmi_cpu0_pch_tx_c_dp(0)") )
				( objectStatus "DP_DMI_CPU0_PCH_TX_C_D<0>" )
			)
			( differentialPair "@sapphirecity_baseboard_lib.sapphirecity_baseboard(sch_1):\DMI_CPU0_PCH_TX_C_D\(1)"
				( memberType ( signal ) )
				( member ( electricalNetRef "@crescent_city_bb_fab1_lib.crescent_city_bb_fab1(sch_1):dmi_cpu0_pch_tx_c_dn(1)") )
				( member ( electricalNetRef "@crescent_city_bb_fab1_lib.crescent_city_bb_fab1(sch_1):dmi_cpu0_pch_tx_c_dp(1)") )
				( objectStatus "DP_DMI_CPU0_PCH_TX_C_D<1>" )
			)
			( differentialPair "@sapphirecity_baseboard_lib.sapphirecity_baseboard(sch_1):\DMI_CPU0_PCH_TX_C_D\(2)"
				( memberType ( signal ) )
				( member ( electricalNetRef "@crescent_city_bb_fab1_lib.crescent_city_bb_fab1(sch_1):dmi_cpu0_pch_tx_c_dn(2)") )
				( member ( electricalNetRef "@crescent_city_bb_fab1_lib.crescent_city_bb_fab1(sch_1):dmi_cpu0_pch_tx_c_dp(2)") )
				( objectStatus "DP_DMI_CPU0_PCH_TX_C_D<2>" )
			)
			( differentialPair "@sapphirecity_baseboard_lib.sapphirecity_baseboard(sch_1):\DMI_CPU0_PCH_TX_C_D\(3)"
				( memberType ( signal ) )
				( member ( electricalNetRef "@crescent_city_bb_fab1_lib.crescent_city_bb_fab1(sch_1):dmi_cpu0_pch_tx_c_dn(3)") )
				( member ( electricalNetRef "@crescent_city_bb_fab1_lib.crescent_city_bb_fab1(sch_1):dmi_cpu0_pch_tx_c_dp(3)") )
				( objectStatus "DP_DMI_CPU0_PCH_TX_C_D<3>" )
			)
			( differentialPair "@crescent_city_bb_fab1_lib.crescent_city_bb_fab1(sch_1):\NIC_MDI_SPRV_RJ45_0_D\"
				( memberType ( signal ) )
				( attribute "DIFFP_UNCOUPLED_LENGTH" "10.00"
					( Origin gBackEnd )
				)
				( attribute "DIFFP_PHASE_TOL" "30 mil"
					( Units "uPhaseTol" "ns" 1.000000)
					( Origin gBackEnd )
				)
				( member ( electricalNetRef "@crescent_city_bb_fab1_lib.crescent_city_bb_fab1(sch_1):nic_mdi_sprv_rj45_0_dn") )
				( member ( electricalNetRef "@crescent_city_bb_fab1_lib.crescent_city_bb_fab1(sch_1):nic_mdi_sprv_rj45_0_dp") )
				( objectStatus "NIC_MDI_SPRV_RJ45_0_D" )
			)
			( differentialPair "@crescent_city_bb_fab1_lib.crescent_city_bb_fab1(sch_1):\NIC_MDI_SPRV_RJ45_1_D\"
				( memberType ( signal ) )
				( attribute "DIFFP_UNCOUPLED_LENGTH" "10.00"
					( Origin gBackEnd )
				)
				( attribute "DIFFP_PHASE_TOL" "30 mil"
					( Units "uPhaseTol" "ns" 1.000000)
					( Origin gBackEnd )
				)
				( member ( electricalNetRef "@crescent_city_bb_fab1_lib.crescent_city_bb_fab1(sch_1):nic_mdi_sprv_rj45_1_dn") )
				( member ( electricalNetRef "@crescent_city_bb_fab1_lib.crescent_city_bb_fab1(sch_1):nic_mdi_sprv_rj45_1_dp") )
				( objectStatus "NIC_MDI_SPRV_RJ45_1_D" )
			)
			( differentialPair "@crescent_city_bb_fab1_lib.crescent_city_bb_fab1(sch_1):\MDI_MNG_RX\"
				( memberType ( signal ) )
				( member ( signalRef "@baseboard_fab2_lib.baseboard_fab2(sch_1):nic_mdi_mng_rx_dn") )
				( member ( signalRef "@baseboard_fab2_lib.baseboard_fab2(sch_1):nic_mdi_mng_rx_dp") )
				( objectStatus "DP_NIC_MDI_MNG_RX" )
			)
			( differentialPair "@crescent_city_bb_fab1_lib.crescent_city_bb_fab1(sch_1):\MDI_MNG_TX\"
				( memberType ( signal ) )
				( member ( signalRef "@baseboard_fab2_lib.baseboard_fab2(sch_1):nic_mdi_mng_tx_dn") )
				( member ( signalRef "@baseboard_fab2_lib.baseboard_fab2(sch_1):nic_mdi_mng_tx_dp") )
				( objectStatus "DP_NIC_MDI_MNG_TX" )
			)
			( differentialPair "@crescent_city_bb_fab1_lib.crescent_city_bb_fab1(sch_1):\DP_73\"
				( memberType ( signal ) )
				( electricalCSetRef "@crescent_city_bb_fab1_lib.crescent_city_bb_fab1(sch_1):\PCIE_SLOT_C_A\" )
				( member ( electricalNetRef "@crescent_city_bb_fab1_lib.crescent_city_bb_fab1(sch_1):p3e_pch_m2_tx_c_dn(1)") )
				( member ( electricalNetRef "@crescent_city_bb_fab1_lib.crescent_city_bb_fab1(sch_1):p3e_pch_m2_tx_c_dp(1)") )
				( objectStatus "DP1_P3E_PCH_M2_TX_DN(2)" )
			)
			( differentialPair "@crescent_city_bb_fab1_lib.crescent_city_bb_fab1(sch_1):\DP_74\"
				( memberType ( signal ) )
				( electricalCSetRef "@crescent_city_bb_fab1_lib.crescent_city_bb_fab1(sch_1):\PCIE_SLOT_C_A\" )
				( member ( electricalNetRef "@crescent_city_bb_fab1_lib.crescent_city_bb_fab1(sch_1):p3e_pch_m2_tx_c_dn(2)") )
				( member ( electricalNetRef "@crescent_city_bb_fab1_lib.crescent_city_bb_fab1(sch_1):p3e_pch_m2_tx_c_dp(2)") )
				( objectStatus "DP1_P3E_PCH_M2_TX_DN(3)" )
			)
			( differentialPair "@crescent_city_bb_fab1_lib.crescent_city_bb_fab1(sch_1):\DP_75\"
				( memberType ( signal ) )
				( electricalCSetRef "@crescent_city_bb_fab1_lib.crescent_city_bb_fab1(sch_1):\PCIE_SLOT_C_A\" )
				( member ( electricalNetRef "@crescent_city_bb_fab1_lib.crescent_city_bb_fab1(sch_1):p3e_pch_m2_tx_c_dn(3)") )
				( member ( electricalNetRef "@crescent_city_bb_fab1_lib.crescent_city_bb_fab1(sch_1):p3e_pch_m2_tx_c_dp(3)") )
				( objectStatus "DP1_P3E_PCH_RX_0_D" )
			)
			( differentialPair "@crescent_city_bb_fab1_lib.crescent_city_bb_fab1(sch_1):\DP_77\"
				( memberType ( signal ) )
				( member ( electricalNetRef "@crescent_city_bb_fab1_lib.crescent_city_bb_fab1(sch_1):p3e_pch_m2_sata6g_tx_r_dn") )
				( member ( electricalNetRef "@crescent_city_bb_fab1_lib.crescent_city_bb_fab1(sch_1):p3e_pch_m2_sata6g_tx_r_dp") )
				( objectStatus "DP1_PE_PCH_SPRV_TX_D" )
			)
			( differentialPair "@crescent_city_bb_fab1_lib.crescent_city_bb_fab1(sch_1):\P3E_PCH_M2_RX_D\(1)"
				( memberType ( signal ) )
				( attribute "DIFFP_PHASE_TOL" "5 mil"
					( Units "uPhaseTol" "ns" 1.000000)
					( Origin gBackEnd )
				)
				( member ( signalRef "@baseboard_fab2_lib.baseboard_fab2(sch_1):p3e_pch_m2_rx_dn(1)") )
				( member ( signalRef "@baseboard_fab2_lib.baseboard_fab2(sch_1):p3e_pch_m2_rx_dp(1)") )
				( objectStatus "P3E_PCH_M2_RX_D<1>" )
			)
			( differentialPair "@crescent_city_bb_fab1_lib.crescent_city_bb_fab1(sch_1):\P3E_PCH_M2_RX_D\(2)"
				( memberType ( signal ) )
				( attribute "DIFFP_PHASE_TOL" "5 mil"
					( Units "uPhaseTol" "ns" 1.000000)
					( Origin gBackEnd )
				)
				( member ( signalRef "@baseboard_fab2_lib.baseboard_fab2(sch_1):p3e_pch_m2_rx_dn(2)") )
				( member ( signalRef "@baseboard_fab2_lib.baseboard_fab2(sch_1):p3e_pch_m2_rx_dp(2)") )
				( objectStatus "P3E_PCH_M2_RX_D<2>" )
			)
			( differentialPair "@crescent_city_bb_fab1_lib.crescent_city_bb_fab1(sch_1):\P3E_PCH_M2_RX_D\(3)"
				( memberType ( signal ) )
				( attribute "DIFFP_PHASE_TOL" "5 mil"
					( Units "uPhaseTol" "ns" 1.000000)
					( Origin gBackEnd )
				)
				( member ( signalRef "@baseboard_fab2_lib.baseboard_fab2(sch_1):p3e_pch_m2_rx_dn(3)") )
				( member ( signalRef "@baseboard_fab2_lib.baseboard_fab2(sch_1):p3e_pch_m2_rx_dp(3)") )
				( objectStatus "P3E_PCH_M2_RX_D<3>" )
			)
			( differentialPair "@crescent_city_bb_fab1_lib.crescent_city_bb_fab1(sch_1):\DP_76\"
				( memberType ( signal ) )
				( attribute "DIFFP_PHASE_TOL" "5 mil"
					( Units "uPhaseTol" "ns" 1.000000)
					( Origin gBackEnd )
				)
				( member ( electricalNetRef "@crescent_city_bb_fab1_lib.crescent_city_bb_fab1(sch_1):p3e_pch_m2_sata6g_rx_r_dn") )
				( member ( electricalNetRef "@crescent_city_bb_fab1_lib.crescent_city_bb_fab1(sch_1):p3e_pch_m2_sata6g_rx_r_dp") )
				( objectStatus "DP1_P3E_PCH_TX_0_D" )
			)
			( differentialPair "@crescent_city_bb_fab1_lib.crescent_city_bb_fab1(sch_1):\DP_USB3_P01_TX\"
				( memberType ( signal ) )
				( attribute "DIFFP_GATHER_CONTROL" "IGNORE"
					( Origin gBackEnd )
				)
				( attribute "DIFFP_UNCOUPLED_LENGTH" "550.00"
					( Origin gBackEnd )
				)
				( attribute "DIFFP_PHASE_TOL" "5 mil"
					( Units "uPhaseTol" "ns" 1.000000)
					( Origin gBackEnd )
				)
				( member ( electricalNetRef "@crescent_city_bb_fab1_lib.crescent_city_bb_fab1(sch_1):usb3_p01_c_txn") )
				( member ( electricalNetRef "@crescent_city_bb_fab1_lib.crescent_city_bb_fab1(sch_1):usb3_p01_c_txp") )
				( objectStatus "DP_USB3_P01_TX" )
			)
			( differentialPair "@crescent_city_bb_fab1_lib.crescent_city_bb_fab1(sch_1):\DP_V_M_BMC_DDR3_DQS0\"
				( memberType ( signal ) )
				( attribute "DIFFP_PHASE_TOL" "40 MILS"
					( Units "uPhaseTol" "ns" 1.000000)
					( Origin gBackEnd )
				)
				( member ( signalRef "@baseboard_fab2_lib.baseboard_fab2(sch_1):m_bmc_ddr3_mdqs_0_dn") )
				( member ( signalRef "@baseboard_fab2_lib.baseboard_fab2(sch_1):m_bmc_ddr3_mdqs_0_dp") )
				( objectStatus "V_M_BMC_DDR3_DQS0" )
			)
			( differentialPair "@crescent_city_bb_fab1_lib.crescent_city_bb_fab1(sch_1):\DP_V_M_BMC_DDR3_DQS1\"
				( memberType ( signal ) )
				( attribute "DIFFP_PHASE_TOL" "40 MILS"
					( Units "uPhaseTol" "ns" 1.000000)
					( Origin gBackEnd )
				)
				( member ( signalRef "@baseboard_fab2_lib.baseboard_fab2(sch_1):m_bmc_ddr3_mdqs_1_dn") )
				( member ( signalRef "@baseboard_fab2_lib.baseboard_fab2(sch_1):m_bmc_ddr3_mdqs_1_dp") )
				( objectStatus "V_M_BMC_DDR3_DQS1" )
			)
			( differentialPair "@crescent_city_bb_fab1_lib.crescent_city_bb_fab1(sch_1):\M_BMC_DDR3_MCK_\"
				( memberType ( signal ) )
				( attribute "DIFFP_PHASE_TOL" "25 MILS"
					( Units "uPhaseTol" "ns" 1.000000)
					( Origin gBackEnd )
				)
				( member ( signalRef "@baseboard_fab2_lib.baseboard_fab2(sch_1):m_bmc_ddr3_mck_n") )
				( member ( signalRef "@baseboard_fab2_lib.baseboard_fab2(sch_1):m_bmc_ddr3_mck_p") )
				( objectStatus "M_BMC_DDR3_MCK_" )
			)
			( differentialPair "@crescent_city_bb_fab1_lib.crescent_city_bb_fab1(sch_1):\KTI_CPU1_CPU0_P1P1\(0)"
				( memberType ( signal ) )
				( member ( signalRef "@baseboard_fab2_lib.baseboard_fab2(sch_1):upi_cpu1_cpu0_p1p1_dn(0)") )
				( member ( signalRef "@baseboard_fab2_lib.baseboard_fab2(sch_1):upi_cpu1_cpu0_p1p1_dp(0)") )
				( objectStatus "KTI_CPU1_CPU0_P1P1<0>" )
			)
			( differentialPair "@crescent_city_bb_fab1_lib.crescent_city_bb_fab1(sch_1):\KTI_CPU1_CPU0_P1P1\(1)"
				( memberType ( signal ) )
				( member ( signalRef "@baseboard_fab2_lib.baseboard_fab2(sch_1):upi_cpu1_cpu0_p1p1_dn(1)") )
				( member ( signalRef "@baseboard_fab2_lib.baseboard_fab2(sch_1):upi_cpu1_cpu0_p1p1_dp(1)") )
				( objectStatus "KTI_CPU1_CPU0_P1P1<1>" )
			)
			( differentialPair "@crescent_city_bb_fab1_lib.crescent_city_bb_fab1(sch_1):\KTI_CPU1_CPU0_P1P1\(2)"
				( memberType ( signal ) )
				( member ( signalRef "@baseboard_fab2_lib.baseboard_fab2(sch_1):upi_cpu1_cpu0_p1p1_dn(2)") )
				( member ( signalRef "@baseboard_fab2_lib.baseboard_fab2(sch_1):upi_cpu1_cpu0_p1p1_dp(2)") )
				( objectStatus "KTI_CPU1_CPU0_P1P1<2>" )
			)
			( differentialPair "@crescent_city_bb_fab1_lib.crescent_city_bb_fab1(sch_1):\KTI_CPU1_CPU0_P1P1\(3)"
				( memberType ( signal ) )
				( member ( signalRef "@baseboard_fab2_lib.baseboard_fab2(sch_1):upi_cpu1_cpu0_p1p1_dn(3)") )
				( member ( signalRef "@baseboard_fab2_lib.baseboard_fab2(sch_1):upi_cpu1_cpu0_p1p1_dp(3)") )
				( objectStatus "KTI_CPU1_CPU0_P1P1<3>" )
			)
			( differentialPair "@crescent_city_bb_fab1_lib.crescent_city_bb_fab1(sch_1):\KTI_CPU1_CPU0_P1P1\(4)"
				( memberType ( signal ) )
				( member ( signalRef "@baseboard_fab2_lib.baseboard_fab2(sch_1):upi_cpu1_cpu0_p1p1_dn(4)") )
				( member ( signalRef "@baseboard_fab2_lib.baseboard_fab2(sch_1):upi_cpu1_cpu0_p1p1_dp(4)") )
				( objectStatus "KTI_CPU1_CPU0_P1P1<4>" )
			)
			( differentialPair "@crescent_city_bb_fab1_lib.crescent_city_bb_fab1(sch_1):\KTI_CPU1_CPU0_P1P1\(5)"
				( memberType ( signal ) )
				( member ( signalRef "@baseboard_fab2_lib.baseboard_fab2(sch_1):upi_cpu1_cpu0_p1p1_dn(5)") )
				( member ( signalRef "@baseboard_fab2_lib.baseboard_fab2(sch_1):upi_cpu1_cpu0_p1p1_dp(5)") )
				( objectStatus "KTI_CPU1_CPU0_P1P1<5>" )
			)
			( differentialPair "@crescent_city_bb_fab1_lib.crescent_city_bb_fab1(sch_1):\KTI_CPU1_CPU0_P1P1\(6)"
				( memberType ( signal ) )
				( member ( signalRef "@baseboard_fab2_lib.baseboard_fab2(sch_1):upi_cpu1_cpu0_p1p1_dn(6)") )
				( member ( signalRef "@baseboard_fab2_lib.baseboard_fab2(sch_1):upi_cpu1_cpu0_p1p1_dp(6)") )
				( objectStatus "KTI_CPU1_CPU0_P1P1<6>" )
			)
			( differentialPair "@crescent_city_bb_fab1_lib.crescent_city_bb_fab1(sch_1):\KTI_CPU1_CPU0_P1P1\(7)"
				( memberType ( signal ) )
				( member ( signalRef "@baseboard_fab2_lib.baseboard_fab2(sch_1):upi_cpu1_cpu0_p1p1_dn(7)") )
				( member ( signalRef "@baseboard_fab2_lib.baseboard_fab2(sch_1):upi_cpu1_cpu0_p1p1_dp(7)") )
				( objectStatus "KTI_CPU1_CPU0_P1P1<7>" )
			)
			( differentialPair "@crescent_city_bb_fab1_lib.crescent_city_bb_fab1(sch_1):\KTI_CPU1_CPU0_P1P1\(8)"
				( memberType ( signal ) )
				( member ( signalRef "@baseboard_fab2_lib.baseboard_fab2(sch_1):upi_cpu1_cpu0_p1p1_dn(8)") )
				( member ( signalRef "@baseboard_fab2_lib.baseboard_fab2(sch_1):upi_cpu1_cpu0_p1p1_dp(8)") )
				( objectStatus "KTI_CPU1_CPU0_P1P1<8>" )
			)
			( differentialPair "@crescent_city_bb_fab1_lib.crescent_city_bb_fab1(sch_1):\KTI_CPU1_CPU0_P1P1\(9)"
				( memberType ( signal ) )
				( member ( signalRef "@baseboard_fab2_lib.baseboard_fab2(sch_1):upi_cpu1_cpu0_p1p1_dn(9)") )
				( member ( signalRef "@baseboard_fab2_lib.baseboard_fab2(sch_1):upi_cpu1_cpu0_p1p1_dp(9)") )
				( objectStatus "KTI_CPU1_CPU0_P1P1<9>" )
			)
			( differentialPair "@crescent_city_bb_fab1_lib.crescent_city_bb_fab1(sch_1):\KTI_CPU1_CPU0_P1P1\(10)"
				( memberType ( signal ) )
				( member ( signalRef "@baseboard_fab2_lib.baseboard_fab2(sch_1):upi_cpu1_cpu0_p1p1_dn(10)") )
				( member ( signalRef "@baseboard_fab2_lib.baseboard_fab2(sch_1):upi_cpu1_cpu0_p1p1_dp(10)") )
				( objectStatus "KTI_CPU1_CPU0_P1P1<10>" )
			)
			( differentialPair "@crescent_city_bb_fab1_lib.crescent_city_bb_fab1(sch_1):\KTI_CPU1_CPU0_P1P1\(11)"
				( memberType ( signal ) )
				( member ( signalRef "@baseboard_fab2_lib.baseboard_fab2(sch_1):upi_cpu1_cpu0_p1p1_dn(11)") )
				( member ( signalRef "@baseboard_fab2_lib.baseboard_fab2(sch_1):upi_cpu1_cpu0_p1p1_dp(11)") )
				( objectStatus "KTI_CPU1_CPU0_P1P1<11>" )
			)
			( differentialPair "@crescent_city_bb_fab1_lib.crescent_city_bb_fab1(sch_1):\KTI_CPU1_CPU0_P1P1\(12)"
				( memberType ( signal ) )
				( member ( signalRef "@baseboard_fab2_lib.baseboard_fab2(sch_1):upi_cpu1_cpu0_p1p1_dn(12)") )
				( member ( signalRef "@baseboard_fab2_lib.baseboard_fab2(sch_1):upi_cpu1_cpu0_p1p1_dp(12)") )
				( objectStatus "KTI_CPU1_CPU0_P1P1<12>" )
			)
			( differentialPair "@crescent_city_bb_fab1_lib.crescent_city_bb_fab1(sch_1):\KTI_CPU1_CPU0_P1P1\(13)"
				( memberType ( signal ) )
				( member ( signalRef "@baseboard_fab2_lib.baseboard_fab2(sch_1):upi_cpu1_cpu0_p1p1_dn(13)") )
				( member ( signalRef "@baseboard_fab2_lib.baseboard_fab2(sch_1):upi_cpu1_cpu0_p1p1_dp(13)") )
				( objectStatus "KTI_CPU1_CPU0_P1P1<13>" )
			)
			( differentialPair "@crescent_city_bb_fab1_lib.crescent_city_bb_fab1(sch_1):\KTI_CPU1_CPU0_P1P1\(14)"
				( memberType ( signal ) )
				( member ( signalRef "@baseboard_fab2_lib.baseboard_fab2(sch_1):upi_cpu1_cpu0_p1p1_dn(14)") )
				( member ( signalRef "@baseboard_fab2_lib.baseboard_fab2(sch_1):upi_cpu1_cpu0_p1p1_dp(14)") )
				( objectStatus "KTI_CPU1_CPU0_P1P1<14>" )
			)
			( differentialPair "@crescent_city_bb_fab1_lib.crescent_city_bb_fab1(sch_1):\KTI_CPU1_CPU0_P1P1\(15)"
				( memberType ( signal ) )
				( member ( signalRef "@baseboard_fab2_lib.baseboard_fab2(sch_1):upi_cpu1_cpu0_p1p1_dn(15)") )
				( member ( signalRef "@baseboard_fab2_lib.baseboard_fab2(sch_1):upi_cpu1_cpu0_p1p1_dp(15)") )
				( objectStatus "KTI_CPU1_CPU0_P1P1<15>" )
			)
			( differentialPair "@crescent_city_bb_fab1_lib.crescent_city_bb_fab1(sch_1):\KTI_CPU1_CPU0_P1P1\(16)"
				( memberType ( signal ) )
				( member ( signalRef "@baseboard_fab2_lib.baseboard_fab2(sch_1):upi_cpu1_cpu0_p1p1_dn(16)") )
				( member ( signalRef "@baseboard_fab2_lib.baseboard_fab2(sch_1):upi_cpu1_cpu0_p1p1_dp(16)") )
				( objectStatus "KTI_CPU1_CPU0_P1P1<16>" )
			)
			( differentialPair "@crescent_city_bb_fab1_lib.crescent_city_bb_fab1(sch_1):\KTI_CPU1_CPU0_P1P1\(17)"
				( memberType ( signal ) )
				( member ( signalRef "@baseboard_fab2_lib.baseboard_fab2(sch_1):upi_cpu1_cpu0_p1p1_dn(17)") )
				( member ( signalRef "@baseboard_fab2_lib.baseboard_fab2(sch_1):upi_cpu1_cpu0_p1p1_dp(17)") )
				( objectStatus "KTI_CPU1_CPU0_P1P1<17>" )
			)
			( differentialPair "@crescent_city_bb_fab1_lib.crescent_city_bb_fab1(sch_1):\KTI_CPU1_CPU0_P1P1\(18)"
				( memberType ( signal ) )
				( member ( signalRef "@baseboard_fab2_lib.baseboard_fab2(sch_1):upi_cpu1_cpu0_p1p1_dn(18)") )
				( member ( signalRef "@baseboard_fab2_lib.baseboard_fab2(sch_1):upi_cpu1_cpu0_p1p1_dp(18)") )
				( objectStatus "KTI_CPU1_CPU0_P1P1<18>" )
			)
			( differentialPair "@crescent_city_bb_fab1_lib.crescent_city_bb_fab1(sch_1):\KTI_CPU1_CPU0_P1P1\(19)"
				( memberType ( signal ) )
				( member ( signalRef "@baseboard_fab2_lib.baseboard_fab2(sch_1):upi_cpu1_cpu0_p1p1_dn(19)") )
				( member ( signalRef "@baseboard_fab2_lib.baseboard_fab2(sch_1):upi_cpu1_cpu0_p1p1_dp(19)") )
				( objectStatus "KTI_CPU1_CPU0_P1P1<19>" )
			)
			( differentialPair "@crescent_city_bb_fab1_lib.crescent_city_bb_fab1(sch_1):\KTI_CPU1_CPU0_P0P0\(0)"
				( memberType ( signal ) )
				( member ( signalRef "@baseboard_fab2_lib.baseboard_fab2(sch_1):upi_cpu1_cpu0_p0p0_dn(0)") )
				( member ( signalRef "@baseboard_fab2_lib.baseboard_fab2(sch_1):upi_cpu1_cpu0_p0p0_dp(0)") )
				( objectStatus "UPI_CPU1_CPU0_P0P0<0>" )
			)
			( differentialPair "@crescent_city_bb_fab1_lib.crescent_city_bb_fab1(sch_1):\KTI_CPU1_CPU0_P0P0\(1)"
				( memberType ( signal ) )
				( member ( signalRef "@baseboard_fab2_lib.baseboard_fab2(sch_1):upi_cpu1_cpu0_p0p0_dn(1)") )
				( member ( signalRef "@baseboard_fab2_lib.baseboard_fab2(sch_1):upi_cpu1_cpu0_p0p0_dp(1)") )
				( objectStatus "UPI_CPU1_CPU0_P0P0<1>" )
			)
			( differentialPair "@crescent_city_bb_fab1_lib.crescent_city_bb_fab1(sch_1):\KTI_CPU1_CPU0_P0P0\(2)"
				( memberType ( signal ) )
				( member ( signalRef "@baseboard_fab2_lib.baseboard_fab2(sch_1):upi_cpu1_cpu0_p0p0_dn(2)") )
				( member ( signalRef "@baseboard_fab2_lib.baseboard_fab2(sch_1):upi_cpu1_cpu0_p0p0_dp(2)") )
				( objectStatus "UPI_CPU1_CPU0_P0P0<2>" )
			)
			( differentialPair "@crescent_city_bb_fab1_lib.crescent_city_bb_fab1(sch_1):\KTI_CPU1_CPU0_P0P0\(3)"
				( memberType ( signal ) )
				( member ( signalRef "@baseboard_fab2_lib.baseboard_fab2(sch_1):upi_cpu1_cpu0_p0p0_dn(3)") )
				( member ( signalRef "@baseboard_fab2_lib.baseboard_fab2(sch_1):upi_cpu1_cpu0_p0p0_dp(3)") )
				( objectStatus "UPI_CPU1_CPU0_P0P0<3>" )
			)
			( differentialPair "@crescent_city_bb_fab1_lib.crescent_city_bb_fab1(sch_1):\KTI_CPU1_CPU0_P0P0\(4)"
				( memberType ( signal ) )
				( member ( signalRef "@baseboard_fab2_lib.baseboard_fab2(sch_1):upi_cpu1_cpu0_p0p0_dn(4)") )
				( member ( signalRef "@baseboard_fab2_lib.baseboard_fab2(sch_1):upi_cpu1_cpu0_p0p0_dp(4)") )
				( objectStatus "UPI_CPU1_CPU0_P0P0<4>" )
			)
			( differentialPair "@crescent_city_bb_fab1_lib.crescent_city_bb_fab1(sch_1):\KTI_CPU1_CPU0_P0P0\(5)"
				( memberType ( signal ) )
				( member ( signalRef "@baseboard_fab2_lib.baseboard_fab2(sch_1):upi_cpu1_cpu0_p0p0_dn(5)") )
				( member ( signalRef "@baseboard_fab2_lib.baseboard_fab2(sch_1):upi_cpu1_cpu0_p0p0_dp(5)") )
				( objectStatus "UPI_CPU1_CPU0_P0P0<5>" )
			)
			( differentialPair "@crescent_city_bb_fab1_lib.crescent_city_bb_fab1(sch_1):\KTI_CPU1_CPU0_P0P0\(6)"
				( memberType ( signal ) )
				( member ( signalRef "@baseboard_fab2_lib.baseboard_fab2(sch_1):upi_cpu1_cpu0_p0p0_dn(6)") )
				( member ( signalRef "@baseboard_fab2_lib.baseboard_fab2(sch_1):upi_cpu1_cpu0_p0p0_dp(6)") )
				( objectStatus "UPI_CPU1_CPU0_P0P0<6>" )
			)
			( differentialPair "@crescent_city_bb_fab1_lib.crescent_city_bb_fab1(sch_1):\KTI_CPU1_CPU0_P0P0\(7)"
				( memberType ( signal ) )
				( member ( signalRef "@baseboard_fab2_lib.baseboard_fab2(sch_1):upi_cpu1_cpu0_p0p0_dn(7)") )
				( member ( signalRef "@baseboard_fab2_lib.baseboard_fab2(sch_1):upi_cpu1_cpu0_p0p0_dp(7)") )
				( objectStatus "UPI_CPU1_CPU0_P0P0<7>" )
			)
			( differentialPair "@crescent_city_bb_fab1_lib.crescent_city_bb_fab1(sch_1):\KTI_CPU1_CPU0_P0P0\(8)"
				( memberType ( signal ) )
				( member ( signalRef "@baseboard_fab2_lib.baseboard_fab2(sch_1):upi_cpu1_cpu0_p0p0_dn(8)") )
				( member ( signalRef "@baseboard_fab2_lib.baseboard_fab2(sch_1):upi_cpu1_cpu0_p0p0_dp(8)") )
				( objectStatus "UPI_CPU1_CPU0_P0P0<8>" )
			)
			( differentialPair "@crescent_city_bb_fab1_lib.crescent_city_bb_fab1(sch_1):\KTI_CPU1_CPU0_P0P0\(9)"
				( memberType ( signal ) )
				( member ( signalRef "@baseboard_fab2_lib.baseboard_fab2(sch_1):upi_cpu1_cpu0_p0p0_dn(9)") )
				( member ( signalRef "@baseboard_fab2_lib.baseboard_fab2(sch_1):upi_cpu1_cpu0_p0p0_dp(9)") )
				( objectStatus "UPI_CPU1_CPU0_P0P0<9>" )
			)
			( differentialPair "@crescent_city_bb_fab1_lib.crescent_city_bb_fab1(sch_1):\KTI_CPU1_CPU0_P0P0\(10)"
				( memberType ( signal ) )
				( member ( signalRef "@baseboard_fab2_lib.baseboard_fab2(sch_1):upi_cpu1_cpu0_p0p0_dn(10)") )
				( member ( signalRef "@baseboard_fab2_lib.baseboard_fab2(sch_1):upi_cpu1_cpu0_p0p0_dp(10)") )
				( objectStatus "UPI_CPU1_CPU0_P0P0<10>" )
			)
			( differentialPair "@crescent_city_bb_fab1_lib.crescent_city_bb_fab1(sch_1):\KTI_CPU1_CPU0_P0P0\(11)"
				( memberType ( signal ) )
				( member ( signalRef "@baseboard_fab2_lib.baseboard_fab2(sch_1):upi_cpu1_cpu0_p0p0_dn(11)") )
				( member ( signalRef "@baseboard_fab2_lib.baseboard_fab2(sch_1):upi_cpu1_cpu0_p0p0_dp(11)") )
				( objectStatus "UPI_CPU1_CPU0_P0P0<11>" )
			)
			( differentialPair "@crescent_city_bb_fab1_lib.crescent_city_bb_fab1(sch_1):\KTI_CPU1_CPU0_P0P0\(12)"
				( memberType ( signal ) )
				( member ( signalRef "@baseboard_fab2_lib.baseboard_fab2(sch_1):upi_cpu1_cpu0_p0p0_dn(12)") )
				( member ( signalRef "@baseboard_fab2_lib.baseboard_fab2(sch_1):upi_cpu1_cpu0_p0p0_dp(12)") )
				( objectStatus "UPI_CPU1_CPU0_P0P0<12>" )
			)
			( differentialPair "@crescent_city_bb_fab1_lib.crescent_city_bb_fab1(sch_1):\KTI_CPU1_CPU0_P0P0\(13)"
				( memberType ( signal ) )
				( member ( signalRef "@baseboard_fab2_lib.baseboard_fab2(sch_1):upi_cpu1_cpu0_p0p0_dn(13)") )
				( member ( signalRef "@baseboard_fab2_lib.baseboard_fab2(sch_1):upi_cpu1_cpu0_p0p0_dp(13)") )
				( objectStatus "UPI_CPU1_CPU0_P0P0<13>" )
			)
			( differentialPair "@crescent_city_bb_fab1_lib.crescent_city_bb_fab1(sch_1):\KTI_CPU1_CPU0_P0P0\(14)"
				( memberType ( signal ) )
				( member ( signalRef "@baseboard_fab2_lib.baseboard_fab2(sch_1):upi_cpu1_cpu0_p0p0_dn(14)") )
				( member ( signalRef "@baseboard_fab2_lib.baseboard_fab2(sch_1):upi_cpu1_cpu0_p0p0_dp(14)") )
				( objectStatus "UPI_CPU1_CPU0_P0P0<14>" )
			)
			( differentialPair "@crescent_city_bb_fab1_lib.crescent_city_bb_fab1(sch_1):\KTI_CPU1_CPU0_P0P0\(15)"
				( memberType ( signal ) )
				( member ( signalRef "@baseboard_fab2_lib.baseboard_fab2(sch_1):upi_cpu1_cpu0_p0p0_dn(15)") )
				( member ( signalRef "@baseboard_fab2_lib.baseboard_fab2(sch_1):upi_cpu1_cpu0_p0p0_dp(15)") )
				( objectStatus "UPI_CPU1_CPU0_P0P0<15>" )
			)
			( differentialPair "@crescent_city_bb_fab1_lib.crescent_city_bb_fab1(sch_1):\KTI_CPU1_CPU0_P0P0\(16)"
				( memberType ( signal ) )
				( member ( signalRef "@baseboard_fab2_lib.baseboard_fab2(sch_1):upi_cpu1_cpu0_p0p0_dn(16)") )
				( member ( signalRef "@baseboard_fab2_lib.baseboard_fab2(sch_1):upi_cpu1_cpu0_p0p0_dp(16)") )
				( objectStatus "UPI_CPU1_CPU0_P0P0<16>" )
			)
			( differentialPair "@crescent_city_bb_fab1_lib.crescent_city_bb_fab1(sch_1):\KTI_CPU1_CPU0_P0P0\(17)"
				( memberType ( signal ) )
				( member ( signalRef "@baseboard_fab2_lib.baseboard_fab2(sch_1):upi_cpu1_cpu0_p0p0_dn(17)") )
				( member ( signalRef "@baseboard_fab2_lib.baseboard_fab2(sch_1):upi_cpu1_cpu0_p0p0_dp(17)") )
				( objectStatus "UPI_CPU1_CPU0_P0P0<17>" )
			)
			( differentialPair "@crescent_city_bb_fab1_lib.crescent_city_bb_fab1(sch_1):\KTI_CPU1_CPU0_P0P0\(18)"
				( memberType ( signal ) )
				( member ( signalRef "@baseboard_fab2_lib.baseboard_fab2(sch_1):upi_cpu1_cpu0_p0p0_dn(18)") )
				( member ( signalRef "@baseboard_fab2_lib.baseboard_fab2(sch_1):upi_cpu1_cpu0_p0p0_dp(18)") )
				( objectStatus "UPI_CPU1_CPU0_P0P0<18>" )
			)
			( differentialPair "@crescent_city_bb_fab1_lib.crescent_city_bb_fab1(sch_1):\KTI_CPU1_CPU0_P0P0\(19)"
				( memberType ( signal ) )
				( member ( signalRef "@baseboard_fab2_lib.baseboard_fab2(sch_1):upi_cpu1_cpu0_p0p0_dn(19)") )
				( member ( signalRef "@baseboard_fab2_lib.baseboard_fab2(sch_1):upi_cpu1_cpu0_p0p0_dp(19)") )
				( objectStatus "UPI_CPU1_CPU0_P0P0<19>" )
			)
			( differentialPair "@crescent_city_bb_fab1_lib.crescent_city_bb_fab1(sch_1):\KTI_CPU0_CPU1_P1P1\(0)"
				( memberType ( signal ) )
				( member ( signalRef "@baseboard_fab2_lib.baseboard_fab2(sch_1):upi_cpu0_cpu1_p1p1_dn(0)") )
				( member ( signalRef "@baseboard_fab2_lib.baseboard_fab2(sch_1):upi_cpu0_cpu1_p1p1_dp(0)") )
				( objectStatus "KTI_CPU0_CPU1_P1P1<0>" )
			)
			( differentialPair "@crescent_city_bb_fab1_lib.crescent_city_bb_fab1(sch_1):\KTI_CPU0_CPU1_P1P1\(1)"
				( memberType ( signal ) )
				( member ( signalRef "@baseboard_fab2_lib.baseboard_fab2(sch_1):upi_cpu0_cpu1_p1p1_dn(1)") )
				( member ( signalRef "@baseboard_fab2_lib.baseboard_fab2(sch_1):upi_cpu0_cpu1_p1p1_dp(1)") )
				( objectStatus "KTI_CPU0_CPU1_P1P1<1>" )
			)
			( differentialPair "@crescent_city_bb_fab1_lib.crescent_city_bb_fab1(sch_1):\KTI_CPU0_CPU1_P1P1\(2)"
				( memberType ( signal ) )
				( member ( signalRef "@baseboard_fab2_lib.baseboard_fab2(sch_1):upi_cpu0_cpu1_p1p1_dn(2)") )
				( member ( signalRef "@baseboard_fab2_lib.baseboard_fab2(sch_1):upi_cpu0_cpu1_p1p1_dp(2)") )
				( objectStatus "KTI_CPU0_CPU1_P1P1<2>" )
			)
			( differentialPair "@crescent_city_bb_fab1_lib.crescent_city_bb_fab1(sch_1):\KTI_CPU0_CPU1_P1P1\(3)"
				( memberType ( signal ) )
				( member ( signalRef "@baseboard_fab2_lib.baseboard_fab2(sch_1):upi_cpu0_cpu1_p1p1_dn(3)") )
				( member ( signalRef "@baseboard_fab2_lib.baseboard_fab2(sch_1):upi_cpu0_cpu1_p1p1_dp(3)") )
				( objectStatus "KTI_CPU0_CPU1_P1P1<3>" )
			)
			( differentialPair "@crescent_city_bb_fab1_lib.crescent_city_bb_fab1(sch_1):\KTI_CPU0_CPU1_P1P1\(4)"
				( memberType ( signal ) )
				( member ( signalRef "@baseboard_fab2_lib.baseboard_fab2(sch_1):upi_cpu0_cpu1_p1p1_dn(4)") )
				( member ( signalRef "@baseboard_fab2_lib.baseboard_fab2(sch_1):upi_cpu0_cpu1_p1p1_dp(4)") )
				( objectStatus "KTI_CPU0_CPU1_P1P1<4>" )
			)
			( differentialPair "@crescent_city_bb_fab1_lib.crescent_city_bb_fab1(sch_1):\KTI_CPU0_CPU1_P1P1\(5)"
				( memberType ( signal ) )
				( member ( signalRef "@baseboard_fab2_lib.baseboard_fab2(sch_1):upi_cpu0_cpu1_p1p1_dn(5)") )
				( member ( signalRef "@baseboard_fab2_lib.baseboard_fab2(sch_1):upi_cpu0_cpu1_p1p1_dp(5)") )
				( objectStatus "KTI_CPU0_CPU1_P1P1<5>" )
			)
			( differentialPair "@crescent_city_bb_fab1_lib.crescent_city_bb_fab1(sch_1):\KTI_CPU0_CPU1_P1P1\(6)"
				( memberType ( signal ) )
				( member ( signalRef "@baseboard_fab2_lib.baseboard_fab2(sch_1):upi_cpu0_cpu1_p1p1_dn(6)") )
				( member ( signalRef "@baseboard_fab2_lib.baseboard_fab2(sch_1):upi_cpu0_cpu1_p1p1_dp(6)") )
				( objectStatus "KTI_CPU0_CPU1_P1P1<6>" )
			)
			( differentialPair "@crescent_city_bb_fab1_lib.crescent_city_bb_fab1(sch_1):\KTI_CPU0_CPU1_P1P1\(7)"
				( memberType ( signal ) )
				( member ( signalRef "@baseboard_fab2_lib.baseboard_fab2(sch_1):upi_cpu0_cpu1_p1p1_dn(7)") )
				( member ( signalRef "@baseboard_fab2_lib.baseboard_fab2(sch_1):upi_cpu0_cpu1_p1p1_dp(7)") )
				( objectStatus "KTI_CPU0_CPU1_P1P1<7>" )
			)
			( differentialPair "@crescent_city_bb_fab1_lib.crescent_city_bb_fab1(sch_1):\KTI_CPU0_CPU1_P1P1\(8)"
				( memberType ( signal ) )
				( member ( signalRef "@baseboard_fab2_lib.baseboard_fab2(sch_1):upi_cpu0_cpu1_p1p1_dn(8)") )
				( member ( signalRef "@baseboard_fab2_lib.baseboard_fab2(sch_1):upi_cpu0_cpu1_p1p1_dp(8)") )
				( objectStatus "KTI_CPU0_CPU1_P1P1<8>" )
			)
			( differentialPair "@crescent_city_bb_fab1_lib.crescent_city_bb_fab1(sch_1):\KTI_CPU0_CPU1_P1P1\(9)"
				( memberType ( signal ) )
				( member ( signalRef "@baseboard_fab2_lib.baseboard_fab2(sch_1):upi_cpu0_cpu1_p1p1_dn(9)") )
				( member ( signalRef "@baseboard_fab2_lib.baseboard_fab2(sch_1):upi_cpu0_cpu1_p1p1_dp(9)") )
				( objectStatus "KTI_CPU0_CPU1_P1P1<9>" )
			)
			( differentialPair "@crescent_city_bb_fab1_lib.crescent_city_bb_fab1(sch_1):\KTI_CPU0_CPU1_P1P1\(10)"
				( memberType ( signal ) )
				( member ( signalRef "@baseboard_fab2_lib.baseboard_fab2(sch_1):upi_cpu0_cpu1_p1p1_dn(10)") )
				( member ( signalRef "@baseboard_fab2_lib.baseboard_fab2(sch_1):upi_cpu0_cpu1_p1p1_dp(10)") )
				( objectStatus "KTI_CPU0_CPU1_P1P1<10>" )
			)
			( differentialPair "@crescent_city_bb_fab1_lib.crescent_city_bb_fab1(sch_1):\KTI_CPU0_CPU1_P1P1\(11)"
				( memberType ( signal ) )
				( member ( signalRef "@baseboard_fab2_lib.baseboard_fab2(sch_1):upi_cpu0_cpu1_p1p1_dn(11)") )
				( member ( signalRef "@baseboard_fab2_lib.baseboard_fab2(sch_1):upi_cpu0_cpu1_p1p1_dp(11)") )
				( objectStatus "KTI_CPU0_CPU1_P1P1<11>" )
			)
			( differentialPair "@crescent_city_bb_fab1_lib.crescent_city_bb_fab1(sch_1):\KTI_CPU0_CPU1_P1P1\(12)"
				( memberType ( signal ) )
				( member ( signalRef "@baseboard_fab2_lib.baseboard_fab2(sch_1):upi_cpu0_cpu1_p1p1_dn(12)") )
				( member ( signalRef "@baseboard_fab2_lib.baseboard_fab2(sch_1):upi_cpu0_cpu1_p1p1_dp(12)") )
				( objectStatus "KTI_CPU0_CPU1_P1P1<12>" )
			)
			( differentialPair "@crescent_city_bb_fab1_lib.crescent_city_bb_fab1(sch_1):\KTI_CPU0_CPU1_P1P1\(13)"
				( memberType ( signal ) )
				( member ( signalRef "@baseboard_fab2_lib.baseboard_fab2(sch_1):upi_cpu0_cpu1_p1p1_dn(13)") )
				( member ( signalRef "@baseboard_fab2_lib.baseboard_fab2(sch_1):upi_cpu0_cpu1_p1p1_dp(13)") )
				( objectStatus "KTI_CPU0_CPU1_P1P1<13>" )
			)
			( differentialPair "@crescent_city_bb_fab1_lib.crescent_city_bb_fab1(sch_1):\KTI_CPU0_CPU1_P1P1\(14)"
				( memberType ( signal ) )
				( member ( signalRef "@baseboard_fab2_lib.baseboard_fab2(sch_1):upi_cpu0_cpu1_p1p1_dn(14)") )
				( member ( signalRef "@baseboard_fab2_lib.baseboard_fab2(sch_1):upi_cpu0_cpu1_p1p1_dp(14)") )
				( objectStatus "KTI_CPU0_CPU1_P1P1<14>" )
			)
			( differentialPair "@crescent_city_bb_fab1_lib.crescent_city_bb_fab1(sch_1):\KTI_CPU0_CPU1_P1P1\(15)"
				( memberType ( signal ) )
				( member ( signalRef "@baseboard_fab2_lib.baseboard_fab2(sch_1):upi_cpu0_cpu1_p1p1_dn(15)") )
				( member ( signalRef "@baseboard_fab2_lib.baseboard_fab2(sch_1):upi_cpu0_cpu1_p1p1_dp(15)") )
				( objectStatus "KTI_CPU0_CPU1_P1P1<15>" )
			)
			( differentialPair "@crescent_city_bb_fab1_lib.crescent_city_bb_fab1(sch_1):\KTI_CPU0_CPU1_P1P1\(16)"
				( memberType ( signal ) )
				( member ( signalRef "@baseboard_fab2_lib.baseboard_fab2(sch_1):upi_cpu0_cpu1_p1p1_dn(16)") )
				( member ( signalRef "@baseboard_fab2_lib.baseboard_fab2(sch_1):upi_cpu0_cpu1_p1p1_dp(16)") )
				( objectStatus "KTI_CPU0_CPU1_P1P1<16>" )
			)
			( differentialPair "@crescent_city_bb_fab1_lib.crescent_city_bb_fab1(sch_1):\KTI_CPU0_CPU1_P1P1\(17)"
				( memberType ( signal ) )
				( member ( signalRef "@baseboard_fab2_lib.baseboard_fab2(sch_1):upi_cpu0_cpu1_p1p1_dn(17)") )
				( member ( signalRef "@baseboard_fab2_lib.baseboard_fab2(sch_1):upi_cpu0_cpu1_p1p1_dp(17)") )
				( objectStatus "KTI_CPU0_CPU1_P1P1<17>" )
			)
			( differentialPair "@crescent_city_bb_fab1_lib.crescent_city_bb_fab1(sch_1):\KTI_CPU0_CPU1_P1P1\(18)"
				( memberType ( signal ) )
				( member ( signalRef "@baseboard_fab2_lib.baseboard_fab2(sch_1):upi_cpu0_cpu1_p1p1_dn(18)") )
				( member ( signalRef "@baseboard_fab2_lib.baseboard_fab2(sch_1):upi_cpu0_cpu1_p1p1_dp(18)") )
				( objectStatus "KTI_CPU0_CPU1_P1P1<18>" )
			)
			( differentialPair "@crescent_city_bb_fab1_lib.crescent_city_bb_fab1(sch_1):\KTI_CPU0_CPU1_P1P1\(19)"
				( memberType ( signal ) )
				( member ( signalRef "@baseboard_fab2_lib.baseboard_fab2(sch_1):upi_cpu0_cpu1_p1p1_dn(19)") )
				( member ( signalRef "@baseboard_fab2_lib.baseboard_fab2(sch_1):upi_cpu0_cpu1_p1p1_dp(19)") )
				( objectStatus "KTI_CPU0_CPU1_P1P1<19>" )
			)
			( differentialPair "@crescent_city_bb_fab1_lib.crescent_city_bb_fab1(sch_1):\KTI_CPU0_CPU1_P0P0\(0)"
				( memberType ( signal ) )
				( member ( signalRef "@baseboard_fab2_lib.baseboard_fab2(sch_1):upi_cpu0_cpu1_p0p0_dn(0)") )
				( member ( signalRef "@baseboard_fab2_lib.baseboard_fab2(sch_1):upi_cpu0_cpu1_p0p0_dp(0)") )
				( objectStatus "UPI_CPU0_CPU1_P0P0<0>" )
			)
			( differentialPair "@crescent_city_bb_fab1_lib.crescent_city_bb_fab1(sch_1):\KTI_CPU0_CPU1_P0P0\(1)"
				( memberType ( signal ) )
				( member ( signalRef "@baseboard_fab2_lib.baseboard_fab2(sch_1):upi_cpu0_cpu1_p0p0_dn(1)") )
				( member ( signalRef "@baseboard_fab2_lib.baseboard_fab2(sch_1):upi_cpu0_cpu1_p0p0_dp(1)") )
				( objectStatus "UPI_CPU0_CPU1_P0P0<1>" )
			)
			( differentialPair "@crescent_city_bb_fab1_lib.crescent_city_bb_fab1(sch_1):\KTI_CPU0_CPU1_P0P0\(2)"
				( memberType ( signal ) )
				( member ( signalRef "@baseboard_fab2_lib.baseboard_fab2(sch_1):upi_cpu0_cpu1_p0p0_dn(2)") )
				( member ( signalRef "@baseboard_fab2_lib.baseboard_fab2(sch_1):upi_cpu0_cpu1_p0p0_dp(2)") )
				( objectStatus "UPI_CPU0_CPU1_P0P0<2>" )
			)
			( differentialPair "@crescent_city_bb_fab1_lib.crescent_city_bb_fab1(sch_1):\KTI_CPU0_CPU1_P0P0\(3)"
				( memberType ( signal ) )
				( member ( signalRef "@baseboard_fab2_lib.baseboard_fab2(sch_1):upi_cpu0_cpu1_p0p0_dn(3)") )
				( member ( signalRef "@baseboard_fab2_lib.baseboard_fab2(sch_1):upi_cpu0_cpu1_p0p0_dp(3)") )
				( objectStatus "UPI_CPU0_CPU1_P0P0<3>" )
			)
			( differentialPair "@crescent_city_bb_fab1_lib.crescent_city_bb_fab1(sch_1):\KTI_CPU0_CPU1_P0P0\(4)"
				( memberType ( signal ) )
				( member ( signalRef "@baseboard_fab2_lib.baseboard_fab2(sch_1):upi_cpu0_cpu1_p0p0_dn(4)") )
				( member ( signalRef "@baseboard_fab2_lib.baseboard_fab2(sch_1):upi_cpu0_cpu1_p0p0_dp(4)") )
				( objectStatus "UPI_CPU0_CPU1_P0P0<4>" )
			)
			( differentialPair "@crescent_city_bb_fab1_lib.crescent_city_bb_fab1(sch_1):\KTI_CPU0_CPU1_P0P0\(5)"
				( memberType ( signal ) )
				( member ( signalRef "@baseboard_fab2_lib.baseboard_fab2(sch_1):upi_cpu0_cpu1_p0p0_dn(5)") )
				( member ( signalRef "@baseboard_fab2_lib.baseboard_fab2(sch_1):upi_cpu0_cpu1_p0p0_dp(5)") )
				( objectStatus "UPI_CPU0_CPU1_P0P0<5>" )
			)
			( differentialPair "@crescent_city_bb_fab1_lib.crescent_city_bb_fab1(sch_1):\KTI_CPU0_CPU1_P0P0\(6)"
				( memberType ( signal ) )
				( member ( signalRef "@baseboard_fab2_lib.baseboard_fab2(sch_1):upi_cpu0_cpu1_p0p0_dn(6)") )
				( member ( signalRef "@baseboard_fab2_lib.baseboard_fab2(sch_1):upi_cpu0_cpu1_p0p0_dp(6)") )
				( objectStatus "UPI_CPU0_CPU1_P0P0<6>" )
			)
			( differentialPair "@crescent_city_bb_fab1_lib.crescent_city_bb_fab1(sch_1):\KTI_CPU0_CPU1_P0P0\(7)"
				( memberType ( signal ) )
				( member ( signalRef "@baseboard_fab2_lib.baseboard_fab2(sch_1):upi_cpu0_cpu1_p0p0_dn(7)") )
				( member ( signalRef "@baseboard_fab2_lib.baseboard_fab2(sch_1):upi_cpu0_cpu1_p0p0_dp(7)") )
				( objectStatus "UPI_CPU0_CPU1_P0P0<7>" )
			)
			( differentialPair "@crescent_city_bb_fab1_lib.crescent_city_bb_fab1(sch_1):\KTI_CPU0_CPU1_P0P0\(8)"
				( memberType ( signal ) )
				( member ( signalRef "@baseboard_fab2_lib.baseboard_fab2(sch_1):upi_cpu0_cpu1_p0p0_dn(8)") )
				( member ( signalRef "@baseboard_fab2_lib.baseboard_fab2(sch_1):upi_cpu0_cpu1_p0p0_dp(8)") )
				( objectStatus "UPI_CPU0_CPU1_P0P0<8>" )
			)
			( differentialPair "@crescent_city_bb_fab1_lib.crescent_city_bb_fab1(sch_1):\KTI_CPU0_CPU1_P0P0\(9)"
				( memberType ( signal ) )
				( member ( signalRef "@baseboard_fab2_lib.baseboard_fab2(sch_1):upi_cpu0_cpu1_p0p0_dn(9)") )
				( member ( signalRef "@baseboard_fab2_lib.baseboard_fab2(sch_1):upi_cpu0_cpu1_p0p0_dp(9)") )
				( objectStatus "UPI_CPU0_CPU1_P0P0<9>" )
			)
			( differentialPair "@crescent_city_bb_fab1_lib.crescent_city_bb_fab1(sch_1):\KTI_CPU0_CPU1_P0P0\(10)"
				( memberType ( signal ) )
				( member ( signalRef "@baseboard_fab2_lib.baseboard_fab2(sch_1):upi_cpu0_cpu1_p0p0_dn(10)") )
				( member ( signalRef "@baseboard_fab2_lib.baseboard_fab2(sch_1):upi_cpu0_cpu1_p0p0_dp(10)") )
				( objectStatus "UPI_CPU0_CPU1_P0P0<10>" )
			)
			( differentialPair "@crescent_city_bb_fab1_lib.crescent_city_bb_fab1(sch_1):\KTI_CPU0_CPU1_P0P0\(11)"
				( memberType ( signal ) )
				( member ( signalRef "@baseboard_fab2_lib.baseboard_fab2(sch_1):upi_cpu0_cpu1_p0p0_dn(11)") )
				( member ( signalRef "@baseboard_fab2_lib.baseboard_fab2(sch_1):upi_cpu0_cpu1_p0p0_dp(11)") )
				( objectStatus "UPI_CPU0_CPU1_P0P0<11>" )
			)
			( differentialPair "@crescent_city_bb_fab1_lib.crescent_city_bb_fab1(sch_1):\KTI_CPU0_CPU1_P0P0\(12)"
				( memberType ( signal ) )
				( member ( signalRef "@baseboard_fab2_lib.baseboard_fab2(sch_1):upi_cpu0_cpu1_p0p0_dn(12)") )
				( member ( signalRef "@baseboard_fab2_lib.baseboard_fab2(sch_1):upi_cpu0_cpu1_p0p0_dp(12)") )
				( objectStatus "UPI_CPU0_CPU1_P0P0<12>" )
			)
			( differentialPair "@crescent_city_bb_fab1_lib.crescent_city_bb_fab1(sch_1):\KTI_CPU0_CPU1_P0P0\(13)"
				( memberType ( signal ) )
				( member ( signalRef "@baseboard_fab2_lib.baseboard_fab2(sch_1):upi_cpu0_cpu1_p0p0_dn(13)") )
				( member ( signalRef "@baseboard_fab2_lib.baseboard_fab2(sch_1):upi_cpu0_cpu1_p0p0_dp(13)") )
				( objectStatus "UPI_CPU0_CPU1_P0P0<13>" )
			)
			( differentialPair "@crescent_city_bb_fab1_lib.crescent_city_bb_fab1(sch_1):\KTI_CPU0_CPU1_P0P0\(14)"
				( memberType ( signal ) )
				( member ( signalRef "@baseboard_fab2_lib.baseboard_fab2(sch_1):upi_cpu0_cpu1_p0p0_dn(14)") )
				( member ( signalRef "@baseboard_fab2_lib.baseboard_fab2(sch_1):upi_cpu0_cpu1_p0p0_dp(14)") )
				( objectStatus "UPI_CPU0_CPU1_P0P0<14>" )
			)
			( differentialPair "@crescent_city_bb_fab1_lib.crescent_city_bb_fab1(sch_1):\KTI_CPU0_CPU1_P0P0\(15)"
				( memberType ( signal ) )
				( member ( signalRef "@baseboard_fab2_lib.baseboard_fab2(sch_1):upi_cpu0_cpu1_p0p0_dn(15)") )
				( member ( signalRef "@baseboard_fab2_lib.baseboard_fab2(sch_1):upi_cpu0_cpu1_p0p0_dp(15)") )
				( objectStatus "UPI_CPU0_CPU1_P0P0<15>" )
			)
			( differentialPair "@crescent_city_bb_fab1_lib.crescent_city_bb_fab1(sch_1):\KTI_CPU0_CPU1_P0P0\(16)"
				( memberType ( signal ) )
				( member ( signalRef "@baseboard_fab2_lib.baseboard_fab2(sch_1):upi_cpu0_cpu1_p0p0_dn(16)") )
				( member ( signalRef "@baseboard_fab2_lib.baseboard_fab2(sch_1):upi_cpu0_cpu1_p0p0_dp(16)") )
				( objectStatus "UPI_CPU0_CPU1_P0P0<16>" )
			)
			( differentialPair "@crescent_city_bb_fab1_lib.crescent_city_bb_fab1(sch_1):\KTI_CPU0_CPU1_P0P0\(17)"
				( memberType ( signal ) )
				( member ( signalRef "@baseboard_fab2_lib.baseboard_fab2(sch_1):upi_cpu0_cpu1_p0p0_dn(17)") )
				( member ( signalRef "@baseboard_fab2_lib.baseboard_fab2(sch_1):upi_cpu0_cpu1_p0p0_dp(17)") )
				( objectStatus "UPI_CPU0_CPU1_P0P0<17>" )
			)
			( differentialPair "@crescent_city_bb_fab1_lib.crescent_city_bb_fab1(sch_1):\KTI_CPU0_CPU1_P0P0\(18)"
				( memberType ( signal ) )
				( member ( signalRef "@baseboard_fab2_lib.baseboard_fab2(sch_1):upi_cpu0_cpu1_p0p0_dn(18)") )
				( member ( signalRef "@baseboard_fab2_lib.baseboard_fab2(sch_1):upi_cpu0_cpu1_p0p0_dp(18)") )
				( objectStatus "UPI_CPU0_CPU1_P0P0<18>" )
			)
			( differentialPair "@crescent_city_bb_fab1_lib.crescent_city_bb_fab1(sch_1):\KTI_CPU0_CPU1_P0P0\(19)"
				( memberType ( signal ) )
				( member ( signalRef "@baseboard_fab2_lib.baseboard_fab2(sch_1):upi_cpu0_cpu1_p0p0_dn(19)") )
				( member ( signalRef "@baseboard_fab2_lib.baseboard_fab2(sch_1):upi_cpu0_cpu1_p0p0_dp(19)") )
				( objectStatus "UPI_CPU0_CPU1_P0P0<19>" )
			)
			( differentialPair "@sapphirecity_baseboard_lib.sapphirecity_baseboard(sch_1):\M_M_CLK_D\(0)"
				( memberType ( signal ) )
				( member ( signalRef "@baseboard_fab2_lib.baseboard_fab2(sch_1):m_m_clk_dn(0)") )
				( member ( signalRef "@baseboard_fab2_lib.baseboard_fab2(sch_1):m_m_clk_dp(0)") )
				( objectStatus "DP_M_M_CLK_D<0>" )
			)
			( differentialPair "@sapphirecity_baseboard_lib.sapphirecity_baseboard(sch_1):\M_D_CLK_D\(3)"
				( memberType ( signal ) )
				( member ( signalRef "@baseboard_fab2_lib.baseboard_fab2(sch_1):m_m_clk_dn(2)") )
				( member ( signalRef "@baseboard_fab2_lib.baseboard_fab2(sch_1):m_m_clk_dp(2)") )
				( objectStatus "DP_M_M_CLK_D<1>" )
			)
			( differentialPair "@sapphirecity_baseboard_lib.sapphirecity_baseboard(sch_1):\M_L_CLK_D\(0)"
				( memberType ( signal ) )
				( member ( signalRef "@baseboard_fab2_lib.baseboard_fab2(sch_1):m_l_clk_dn(0)") )
				( member ( signalRef "@baseboard_fab2_lib.baseboard_fab2(sch_1):m_l_clk_dp(0)") )
				( objectStatus "DP_M_L_CLK_D<0>" )
			)
			( differentialPair "@sapphirecity_baseboard_lib.sapphirecity_baseboard(sch_1):\M_E_CLK_D\(3)"
				( memberType ( signal ) )
				( member ( signalRef "@baseboard_fab2_lib.baseboard_fab2(sch_1):m_l_clk_dn(2)") )
				( member ( signalRef "@baseboard_fab2_lib.baseboard_fab2(sch_1):m_l_clk_dp(2)") )
				( objectStatus "DP_M_L_CLK_D<1>" )
			)
			( differentialPair "@sapphirecity_baseboard_lib.sapphirecity_baseboard(sch_1):\M_K_CLK_D\(0)"
				( memberType ( signal ) )
				( member ( signalRef "@baseboard_fab2_lib.baseboard_fab2(sch_1):m_k_clk_dn(0)") )
				( member ( signalRef "@baseboard_fab2_lib.baseboard_fab2(sch_1):m_k_clk_dp(0)") )
				( objectStatus "DP_M_K_CLK_D<0>" )
			)
			( differentialPair "@crescent_city_bb_fab1_lib.crescent_city_bb_fab1(sch_1):\DP_M_K_CLK\(1)"
				( memberType ( signal ) )
				( member ( signalRef "@baseboard_fab2_lib.baseboard_fab2(sch_1):m_k_clk_dn(2)") )
				( member ( signalRef "@baseboard_fab2_lib.baseboard_fab2(sch_1):m_k_clk_dp(2)") )
				( objectStatus "DP_M_K_CLK_D<1>" )
			)
			( differentialPair "@sapphirecity_baseboard_lib.sapphirecity_baseboard(sch_1):\M_J_CLK_D\(0)"
				( memberType ( signal ) )
				( member ( signalRef "@baseboard_fab2_lib.baseboard_fab2(sch_1):m_j_clk_dn(0)") )
				( member ( signalRef "@baseboard_fab2_lib.baseboard_fab2(sch_1):m_j_clk_dp(0)") )
				( objectStatus "DP_M_J_CLK_D<0>" )
			)
			( differentialPair "@crescent_city_bb_fab1_lib.crescent_city_bb_fab1(sch_1):\DP_M_J_CLK\(1)"
				( memberType ( signal ) )
				( member ( signalRef "@baseboard_fab2_lib.baseboard_fab2(sch_1):m_j_clk_dn(2)") )
				( member ( signalRef "@baseboard_fab2_lib.baseboard_fab2(sch_1):m_j_clk_dp(2)") )
				( objectStatus "DP_M_J_CLK_D<1>" )
			)
			( differentialPair "@sapphirecity_baseboard_lib.sapphirecity_baseboard(sch_1):\M_H_CLK_D\(0)"
				( memberType ( signal ) )
				( member ( signalRef "@baseboard_fab2_lib.baseboard_fab2(sch_1):m_h_clk_dn(0)") )
				( member ( signalRef "@baseboard_fab2_lib.baseboard_fab2(sch_1):m_h_clk_dp(0)") )
				( objectStatus "DP_M_H_CLK_D<0>" )
			)
			( differentialPair "@sapphirecity_baseboard_lib.sapphirecity_baseboard(sch_1):\M_B_CLK_D\(1)"
				( memberType ( signal ) )
				( member ( signalRef "@baseboard_fab2_lib.baseboard_fab2(sch_1):m_h_clk_dn(2)") )
				( member ( signalRef "@baseboard_fab2_lib.baseboard_fab2(sch_1):m_h_clk_dp(2)") )
				( objectStatus "DP_M_H_CLK_D<1>" )
			)
			( differentialPair "@sapphirecity_baseboard_lib.sapphirecity_baseboard(sch_1):\M_G_CLK_D\(0)"
				( memberType ( signal ) )
				( member ( signalRef "@baseboard_fab2_lib.baseboard_fab2(sch_1):m_g_clk_dn(0)") )
				( member ( signalRef "@baseboard_fab2_lib.baseboard_fab2(sch_1):m_g_clk_dp(0)") )
				( objectStatus "DP_M_G_CLK_D<0>" )
			)
			( differentialPair "@crescent_city_bb_fab1_lib.crescent_city_bb_fab1(sch_1):\DP_M_G_CLK\(1)"
				( memberType ( signal ) )
				( member ( signalRef "@baseboard_fab2_lib.baseboard_fab2(sch_1):m_g_clk_dn(2)") )
				( member ( signalRef "@baseboard_fab2_lib.baseboard_fab2(sch_1):m_g_clk_dp(2)") )
				( objectStatus "DP_M_G_CLK_D<1>" )
			)
			( differentialPair "@sapphirecity_baseboard_lib.sapphirecity_baseboard(sch_1):\M_F_CLK_D\(0)"
				( memberType ( signal ) )
				( member ( signalRef "@baseboard_fab2_lib.baseboard_fab2(sch_1):m_f_clk_dn(0)") )
				( member ( signalRef "@baseboard_fab2_lib.baseboard_fab2(sch_1):m_f_clk_dp(0)") )
				( objectStatus "DP_M_F_CLK_D<0>" )
			)
			( differentialPair "@sapphirecity_baseboard_lib.sapphirecity_baseboard(sch_1):\M_K_CLK_D\(3)"
				( memberType ( signal ) )
				( member ( signalRef "@baseboard_fab2_lib.baseboard_fab2(sch_1):m_f_clk_dn(2)") )
				( member ( signalRef "@baseboard_fab2_lib.baseboard_fab2(sch_1):m_f_clk_dp(2)") )
				( objectStatus "DP_M_F_CLK_D<1>" )
			)
			( differentialPair "@sapphirecity_baseboard_lib.sapphirecity_baseboard(sch_1):\M_E_CLK_D\(0)"
				( memberType ( signal ) )
				( member ( signalRef "@baseboard_fab2_lib.baseboard_fab2(sch_1):m_e_clk_dn(0)") )
				( member ( signalRef "@baseboard_fab2_lib.baseboard_fab2(sch_1):m_e_clk_dp(0)") )
				( objectStatus "DP_M_E_CLK_D<0>" )
			)
			( differentialPair "@sapphirecity_baseboard_lib.sapphirecity_baseboard(sch_1):\M_L_CLK_D\(3)"
				( memberType ( signal ) )
				( member ( signalRef "@baseboard_fab2_lib.baseboard_fab2(sch_1):m_e_clk_dn(2)") )
				( member ( signalRef "@baseboard_fab2_lib.baseboard_fab2(sch_1):m_e_clk_dp(2)") )
				( objectStatus "DP_M_E_CLK_D<1>" )
			)
			( differentialPair "@sapphirecity_baseboard_lib.sapphirecity_baseboard(sch_1):\M_D_CLK_D\(0)"
				( memberType ( signal ) )
				( member ( signalRef "@baseboard_fab2_lib.baseboard_fab2(sch_1):m_d_clk_dn(0)") )
				( member ( signalRef "@baseboard_fab2_lib.baseboard_fab2(sch_1):m_d_clk_dp(0)") )
				( objectStatus "DP_M_D_CLK_D<0>" )
			)
			( differentialPair "@sapphirecity_baseboard_lib.sapphirecity_baseboard(sch_1):\DP_M_D_CLK_D1\"
				( memberType ( signal ) )
				( member ( signalRef "@baseboard_fab2_lib.baseboard_fab2(sch_1):m_d_clk_dn(2)") )
				( member ( signalRef "@baseboard_fab2_lib.baseboard_fab2(sch_1):m_d_clk_dp(2)") )
				( objectStatus "DP_M_D_CLK_D<1>" )
			)
			( differentialPair "@sapphirecity_baseboard_lib.sapphirecity_baseboard(sch_1):\M_C_CLK_D\(0)"
				( memberType ( signal ) )
				( attribute "DIFFP_PHASE_TOL" "5 mil"
					( Units "uPhaseTol" "ns" 1.000000)
					( Origin gBackEnd )
				)
				( member ( signalRef "@baseboard_fab2_lib.baseboard_fab2(sch_1):m_c_clk_dn(0)") )
				( member ( signalRef "@baseboard_fab2_lib.baseboard_fab2(sch_1):m_c_clk_dp(0)") )
				( objectStatus "DP_M_C_CLK_D<0>" )
			)
			( differentialPair "@sapphirecity_baseboard_lib.sapphirecity_baseboard(sch_1):\M_G_CLK_D\(1)"
				( memberType ( signal ) )
				( attribute "DIFFP_PHASE_TOL" "5 mil"
					( Units "uPhaseTol" "ns" 1.000000)
					( Origin gBackEnd )
				)
				( member ( signalRef "@baseboard_fab2_lib.baseboard_fab2(sch_1):m_c_clk_dn(2)") )
				( member ( signalRef "@baseboard_fab2_lib.baseboard_fab2(sch_1):m_c_clk_dp(2)") )
				( objectStatus "DP_M_C_CLK_D<1>" )
			)
			( differentialPair "@sapphirecity_baseboard_lib.sapphirecity_baseboard(sch_1):\M_B_CLK_D\(0)"
				( memberType ( signal ) )
				( attribute "DIFFP_PHASE_TOL" "5 mil"
					( Units "uPhaseTol" "ns" 1.000000)
					( Origin gBackEnd )
				)
				( member ( signalRef "@baseboard_fab2_lib.baseboard_fab2(sch_1):m_b_clk_dn(0)") )
				( member ( signalRef "@baseboard_fab2_lib.baseboard_fab2(sch_1):m_b_clk_dp(0)") )
				( objectStatus "DP_M_B_CLK_D<0>" )
			)
			( differentialPair "@sapphirecity_baseboard_lib.sapphirecity_baseboard(sch_1):\M_H_CLK_D\(1)"
				( memberType ( signal ) )
				( attribute "DIFFP_PHASE_TOL" "5 mil"
					( Units "uPhaseTol" "ns" 1.000000)
					( Origin gBackEnd )
				)
				( member ( signalRef "@baseboard_fab2_lib.baseboard_fab2(sch_1):m_b_clk_dn(2)") )
				( member ( signalRef "@baseboard_fab2_lib.baseboard_fab2(sch_1):m_b_clk_dp(2)") )
				( objectStatus "DP_M_B_CLK_D<1>" )
			)
			( differentialPair "@sapphirecity_baseboard_lib.sapphirecity_baseboard(sch_1):\M_A_CLK_D\(0)"
				( memberType ( signal ) )
				( attribute "DIFFP_PHASE_TOL" "5 mil"
					( Units "uPhaseTol" "ns" 1.000000)
					( Origin gBackEnd )
				)
				( member ( signalRef "@baseboard_fab2_lib.baseboard_fab2(sch_1):m_a_clk_dn(0)") )
				( member ( signalRef "@baseboard_fab2_lib.baseboard_fab2(sch_1):m_a_clk_dp(0)") )
				( objectStatus "DP_M_A_CLK_D<0>" )
			)
			( differentialPair "@sapphirecity_baseboard_lib.sapphirecity_baseboard(sch_1):\M_A_CLK_D\(1)"
				( memberType ( signal ) )
				( member ( signalRef "@baseboard_fab2_lib.baseboard_fab2(sch_1):m_a_clk_dn(2)") )
				( member ( signalRef "@baseboard_fab2_lib.baseboard_fab2(sch_1):m_a_clk_dp(2)") )
				( objectStatus "DP_M_A_CLK_D<1>" )
			)
			( differentialPair "@crescent_city_bb_fab1_lib.crescent_city_bb_fab1(sch_1):\DP_VSENSE_PVDDQ_ABC\"
				( memberType ( signal ) )
				( objectFlag fObjectRenamed )
				( member ( signalRef "@baseboard_fab2_lib.baseboard_fab2(sch_1):vsense_pvddq_abc_n") )
				( member ( signalRef "@baseboard_fab2_lib.baseboard_fab2(sch_1):vsense_pvddq_abc_p") )
				( objectStatus "DP_VSENSE_PVDDQ_ABC" )
			)
			( differentialPair "@crescent_city_bb_fab1_lib.crescent_city_bb_fab1(sch_1):\DP_VSENSE_PVDDQ_DEF\"
				( memberType ( signal ) )
				( member ( signalRef "@baseboard_fab2_lib.baseboard_fab2(sch_1):vsense_pvddq_def_n") )
				( member ( signalRef "@baseboard_fab2_lib.baseboard_fab2(sch_1):vsense_pvddq_def_p") )
				( objectStatus "DP_VSENSE_PVDDQ_DEF" )
			)
			( differentialPair "@crescent_city_bb_fab1_lib.crescent_city_bb_fab1(sch_1):\DP_VSENSE_PVDDQ_GHI\"
				( memberType ( signal ) )
				( objectFlag fObjectRenamed )
				( member ( signalRef "@baseboard_fab2_lib.baseboard_fab2(sch_1):vsense_pvddq_ghj_n") )
				( member ( signalRef "@baseboard_fab2_lib.baseboard_fab2(sch_1):vsense_pvddq_ghj_p") )
				( objectStatus "DP_VSENSE_PVDDQ_GHI" )
			)
			( differentialPair "@crescent_city_bb_fab1_lib.crescent_city_bb_fab1(sch_1):\DP_VSENSE_P1V0_CPU0_R\"
				( memberType ( signal ) )
				( member ( signalRef "@baseboard_fab2_lib.baseboard_fab2(sch_1):vsense_pvcciomcp_cpu0_skt_vrtn") )
				( member ( signalRef "@baseboard_fab2_lib.baseboard_fab2(sch_1):vsense_pvcciomcp_cpu0_skt_vsen") )
				( objectStatus "DP_VSENSE_PVCCP_CPU0_SKT" )
			)
			( differentialPair "@crescent_city_bb_fab1_lib.crescent_city_bb_fab1(sch_1):\DP_VSENSE_P1V0_CPU1_R\"
				( memberType ( signal ) )
				( member ( signalRef "@baseboard_fab2_lib.baseboard_fab2(sch_1):vsense_pvcciomcp_cpu1_skt_vrtn") )
				( member ( signalRef "@baseboard_fab2_lib.baseboard_fab2(sch_1):vsense_pvcciomcp_cpu1_skt_vsen") )
				( objectStatus "DP_VSENSE_PVCCP_CPU1_SKT" )
			)
			( differentialPair "@baseboard_fab2_lib.baseboard_fab2(sch_1):\DP_VSENSE_PVSA_CPU1_CPU1_SKT\"
				( memberType ( signal ) )
				( member ( electricalNetRef "@baseboard_fab2_lib.baseboard_fab2(sch_1):vsense_pvsa_cpu1_n") )
				( member ( electricalNetRef "@baseboard_fab2_lib.baseboard_fab2(sch_1):vsense_pvsa_cpu1_p") )
				( objectStatus "DP_VSENSE_PVSA_CPU1_CPU1_SKT" )
			)
			( differentialPair "@baseboard_fab2_lib.baseboard_fab2(sch_1):\DP_VSENSE_PVNN_PCH_STBY_AVS\"
				( memberType ( signal ) )
				( member ( signalRef "@baseboard_fab2_lib.baseboard_fab2(sch_1):vsense_pvnn_pch_stby_avsn") )
				( member ( signalRef "@baseboard_fab2_lib.baseboard_fab2(sch_1):vsense_pvnn_pch_stby_avsp") )
				( objectStatus "DP_VSENSE_PVNN_PCH_STBY_AVS" )
			)
			( differentialPair "@crescent_city_bb_fab1_lib.crescent_city_bb_fab1(sch_1):\VSENSE_PVSA_CPU0\"
				( memberType ( signal ) )
				( member ( electricalNetRef "@baseboard_fab2_lib.baseboard_fab2(sch_1):vsense_pvsa_cpu0_n") )
				( member ( electricalNetRef "@baseboard_fab2_lib.baseboard_fab2(sch_1):vsense_pvsa_cpu0_p") )
				( objectStatus "DP_VSENSE_PVSA_CPU0" )
			)
			( differentialPair "@baseboard_fab2_lib.baseboard_fab2(sch_1):\DP_VSENSE_PVCCMCP_CPU1_SKT\"
				( memberType ( signal ) )
				( member ( signalRef "@baseboard_fab2_lib.baseboard_fab2(sch_1):vsense_pvccmcp_cpu1_skt_vrtn") )
				( member ( signalRef "@baseboard_fab2_lib.baseboard_fab2(sch_1):vsense_pvccmcp_cpu1_skt_vsen") )
				( objectStatus "DP_VSENSE_PVCCMCP_CPU1_SKT" )
			)
			( differentialPair "@baseboard_fab2_lib.baseboard_fab2(sch_1):\DP_VSENSE_PVCCMCP_CPU0_SKT\"
				( memberType ( signal ) )
				( member ( signalRef "@baseboard_fab2_lib.baseboard_fab2(sch_1):vsense_pvccmcp_cpu0_skt_vrtn") )
				( member ( signalRef "@baseboard_fab2_lib.baseboard_fab2(sch_1):vsense_pvccmcp_cpu0_skt_vsen") )
				( objectStatus "DP_VSENSE_PVCCMCP_CPU0_SKT" )
			)
			( differentialPair "@baseboard_fab2_lib.baseboard_fab2(sch_1):\DP_VSENSE_PVCCIO_CPU1_SKT\"
				( memberType ( signal ) )
				( member ( electricalNetRef "@baseboard_fab2_lib.baseboard_fab2(sch_1):vsense_pvccio_cpu1_avsn") )
				( member ( electricalNetRef "@baseboard_fab2_lib.baseboard_fab2(sch_1):vsense_pvccio_cpu1_avsp") )
				( objectStatus "DP_VSENSE_PVCCIO_CPU1_SKT" )
			)
			( differentialPair "@baseboard_fab2_lib.baseboard_fab2(sch_1):\DP_VSENSE_PVCCIN_CPU1\"
				( memberType ( signal ) )
				( member ( electricalNetRef "@baseboard_fab2_lib.baseboard_fab2(sch_1):vsense_pvccin_cpu1_n") )
				( member ( electricalNetRef "@baseboard_fab2_lib.baseboard_fab2(sch_1):vsense_pvccin_cpu1_p") )
				( objectStatus "DP_VSENSE_PVCCIN_CPU1" )
			)
			( differentialPair "@crescent_city_bb_fab1_lib.crescent_city_bb_fab1(sch_1):\VSENSE_P1V05_PCH_STBY\"
				( memberType ( signal ) )
				( member ( electricalNetRef "@crescent_city_bb_fab1_lib.crescent_city_bb_fab1(sch_1):vr_p1v05_pch_stby_avsp") )
				( member ( signalRef "@baseboard_fab2_lib.baseboard_fab2(sch_1):vsense_p1v05_pch_stby_avsn") )
				( objectStatus "VSENSE_P1V05_PCH_STBY_AVS" )
			)
			( differentialPair "@crescent_city_bb_fab1_lib.crescent_city_bb_fab1(sch_1):\DP_VSENSE_PVDDQ_KLM\"
				( memberType ( signal ) )
				( member ( signalRef "@baseboard_fab2_lib.baseboard_fab2(sch_1):vsense_pvddq_klm_n") )
				( member ( signalRef "@baseboard_fab2_lib.baseboard_fab2(sch_1):vsense_pvddq_klm_p") )
				( objectStatus "DP_VSENSE_PVDDQ_KLM" )
			)
			( differentialPair "@baseboard_fab2_lib.baseboard_fab2(sch_1):\DP_VSENSE_PVCCIO_CPU0_AVS\"
				( memberType ( signal ) )
				( member ( electricalNetRef "@baseboard_fab2_lib.baseboard_fab2(sch_1):vsense_pvccio_cpu0_avsn") )
				( member ( electricalNetRef "@baseboard_fab2_lib.baseboard_fab2(sch_1):vsense_pvccio_cpu0_avsp") )
				( objectStatus "DP_VSENSE_PVCCIO_CPU0_AVS" )
			)
			( differentialPair "@baseboard_fab2_lib.baseboard_fab2(sch_1):\DP_VSENSE_PVCCIN_CPU0\"
				( memberType ( signal ) )
				( member ( signalRef "@baseboard_fab2_lib.baseboard_fab2(sch_1):vsense_pvccin_cpu0_n") )
				( member ( signalRef "@baseboard_fab2_lib.baseboard_fab2(sch_1):vsense_pvccin_cpu0_p") )
				( objectStatus "DP_VSENSE_PVCCIN_CPU0" )
			)
			( differentialPair "@baseboard_fab2_lib.baseboard_fab2(sch_1):\DP_VSENSE_PVNN_PCH_STBY\"
				( memberType ( signal ) )
				( member ( signalRef "@baseboard_fab2_lib.baseboard_fab2(sch_1):vsense_pvnn_pch_stby_fpk") )
				( member ( signalRef "@baseboard_fab2_lib.baseboard_fab2(sch_1):vsense_pvnn_pch_stby_qat") )
				( objectStatus "DP_VSENSE_PVNN_PCH_STBY" )
			)
			( differentialPair "@baseboard_fab2_lib.baseboard_fab2(sch_1):\DP_VSENSE_PVCCIN_CPU0_SKT\"
				( memberType ( signal ) )
				( member ( signalRef "@baseboard_fab2_lib.baseboard_fab2(sch_1):vsense_pvccin_cpu0_skt_vrtn") )
				( member ( signalRef "@baseboard_fab2_lib.baseboard_fab2(sch_1):vsense_pvccin_cpu0_skt_vsen") )
				( objectStatus "DP_VSENSE_PVCCIN_CPU0_SKT" )
			)
			( differentialPair "@baseboard_fab2_lib.baseboard_fab2(sch_1):\DP_VSENSE_P1V8MCP_CPU0_SKT\"
				( memberType ( signal ) )
				( member ( signalRef "@baseboard_fab2_lib.baseboard_fab2(sch_1):vsense_p1v8mcp_cpu0_skt_vrtn") )
				( member ( signalRef "@baseboard_fab2_lib.baseboard_fab2(sch_1):vsense_p1v8mcp_cpu0_skt_vsen") )
				( objectStatus "DP_VSENSE_P1V8MCP_CPU0_SKT" )
			)
			( differentialPair "@baseboard_fab2_lib.baseboard_fab2(sch_1):\DP_VSENSE_P1V8MCP_CPU1_SKT\"
				( memberType ( signal ) )
				( member ( signalRef "@baseboard_fab2_lib.baseboard_fab2(sch_1):vsense_p1v8mcp_cpu1_skt_vrtn") )
				( member ( signalRef "@baseboard_fab2_lib.baseboard_fab2(sch_1):vsense_p1v8mcp_cpu1_skt_vsen") )
				( objectStatus "DP_VSENSE_P1V8MCP_CPU1_SKT" )
			)
			( differentialPair "@sapphirecity_baseboard_lib.sapphirecity_baseboard(sch_1):\M_H_DQS_D\(2)"
				( memberType ( signal ) )
				( electricalCSetRef "@crescent_city_bb_fab1_lib.crescent_city_bb_fab1(sch_1):\DDR_DQS_A\" )
				( member ( signalRef "@baseboard_fab2_lib.baseboard_fab2(sch_1):m_h_dqs_dn(2)") )
				( member ( signalRef "@baseboard_fab2_lib.baseboard_fab2(sch_1):m_h_dqs_dp(2)") )
				( objectStatus "M_H_DQS_D<2>" )
			)
			( differentialPair "@sapphirecity_baseboard_lib.sapphirecity_baseboard(sch_1):\M_H_DQS_D\(3)"
				( memberType ( signal ) )
				( electricalCSetRef "@crescent_city_bb_fab1_lib.crescent_city_bb_fab1(sch_1):\DDR_DQS_A\" )
				( member ( signalRef "@baseboard_fab2_lib.baseboard_fab2(sch_1):m_h_dqs_dn(3)") )
				( member ( signalRef "@baseboard_fab2_lib.baseboard_fab2(sch_1):m_h_dqs_dp(3)") )
				( objectStatus "M_H_DQS_D<3>" )
			)
			( differentialPair "@sapphirecity_baseboard_lib.sapphirecity_baseboard(sch_1):\M_H_DQS_D\(4)"
				( memberType ( signal ) )
				( electricalCSetRef "@crescent_city_bb_fab1_lib.crescent_city_bb_fab1(sch_1):\DDR_DQS_A\" )
				( member ( signalRef "@baseboard_fab2_lib.baseboard_fab2(sch_1):m_h_dqs_dn(4)") )
				( member ( signalRef "@baseboard_fab2_lib.baseboard_fab2(sch_1):m_h_dqs_dp(4)") )
				( objectStatus "M_H_DQS_D<4>" )
			)
			( differentialPair "@sapphirecity_baseboard_lib.sapphirecity_baseboard(sch_1):\M_H_DQS_D\(5)"
				( memberType ( signal ) )
				( electricalCSetRef "@crescent_city_bb_fab1_lib.crescent_city_bb_fab1(sch_1):\DDR_DQS_A\" )
				( member ( signalRef "@baseboard_fab2_lib.baseboard_fab2(sch_1):m_h_dqs_dn(5)") )
				( member ( signalRef "@baseboard_fab2_lib.baseboard_fab2(sch_1):m_h_dqs_dp(5)") )
				( objectStatus "M_H_DQS_D<5>" )
			)
			( differentialPair "@sapphirecity_baseboard_lib.sapphirecity_baseboard(sch_1):\M_H_DQS_D\(6)"
				( memberType ( signal ) )
				( electricalCSetRef "@crescent_city_bb_fab1_lib.crescent_city_bb_fab1(sch_1):\DDR_DQS_A\" )
				( member ( signalRef "@baseboard_fab2_lib.baseboard_fab2(sch_1):m_h_dqs_dn(6)") )
				( member ( signalRef "@baseboard_fab2_lib.baseboard_fab2(sch_1):m_h_dqs_dp(6)") )
				( objectStatus "M_H_DQS_D<6>" )
			)
			( differentialPair "@sapphirecity_baseboard_lib.sapphirecity_baseboard(sch_1):\M_H_DQS_D\(7)"
				( memberType ( signal ) )
				( electricalCSetRef "@crescent_city_bb_fab1_lib.crescent_city_bb_fab1(sch_1):\DDR_DQS_A\" )
				( member ( signalRef "@baseboard_fab2_lib.baseboard_fab2(sch_1):m_h_dqs_dn(7)") )
				( member ( signalRef "@baseboard_fab2_lib.baseboard_fab2(sch_1):m_h_dqs_dp(7)") )
				( objectStatus "M_H_DQS_D<7>" )
			)
			( differentialPair "@sapphirecity_baseboard_lib.sapphirecity_baseboard(sch_1):\M_H_DQS_D\(8)"
				( memberType ( signal ) )
				( electricalCSetRef "@crescent_city_bb_fab1_lib.crescent_city_bb_fab1(sch_1):\DDR_DQS_A\" )
				( member ( signalRef "@baseboard_fab2_lib.baseboard_fab2(sch_1):m_h_dqs_dn(8)") )
				( member ( signalRef "@baseboard_fab2_lib.baseboard_fab2(sch_1):m_h_dqs_dp(8)") )
				( objectStatus "M_H_DQS_D<8>" )
			)
			( differentialPair "@sapphirecity_baseboard_lib.sapphirecity_baseboard(sch_1):\M_H_DQS_D\(9)"
				( memberType ( signal ) )
				( electricalCSetRef "@crescent_city_bb_fab1_lib.crescent_city_bb_fab1(sch_1):\DDR_DQS_A\" )
				( member ( signalRef "@baseboard_fab2_lib.baseboard_fab2(sch_1):m_h_dqs_dn(9)") )
				( member ( signalRef "@baseboard_fab2_lib.baseboard_fab2(sch_1):m_h_dqs_dp(9)") )
				( objectStatus "M_H_DQS_D<9>" )
			)
			( differentialPair "@sapphirecity_baseboard_lib.sapphirecity_baseboard(sch_1):\M_H_DQS_D\(10)"
				( memberType ( signal ) )
				( electricalCSetRef "@crescent_city_bb_fab1_lib.crescent_city_bb_fab1(sch_1):\DDR_DQS_A\" )
				( member ( signalRef "@baseboard_fab2_lib.baseboard_fab2(sch_1):m_h_dqs_dn(10)") )
				( member ( signalRef "@baseboard_fab2_lib.baseboard_fab2(sch_1):m_h_dqs_dp(10)") )
				( objectStatus "M_H_DQS_D<10>" )
			)
			( differentialPair "@sapphirecity_baseboard_lib.sapphirecity_baseboard(sch_1):\M_H_DQS_D\(11)"
				( memberType ( signal ) )
				( electricalCSetRef "@crescent_city_bb_fab1_lib.crescent_city_bb_fab1(sch_1):\DDR_DQS_A\" )
				( member ( signalRef "@baseboard_fab2_lib.baseboard_fab2(sch_1):m_h_dqs_dn(11)") )
				( member ( signalRef "@baseboard_fab2_lib.baseboard_fab2(sch_1):m_h_dqs_dp(11)") )
				( objectStatus "M_H_DQS_D<11>" )
			)
			( differentialPair "@sapphirecity_baseboard_lib.sapphirecity_baseboard(sch_1):\M_H_DQS_D\(12)"
				( memberType ( signal ) )
				( electricalCSetRef "@crescent_city_bb_fab1_lib.crescent_city_bb_fab1(sch_1):\DDR_DQS_A\" )
				( member ( signalRef "@baseboard_fab2_lib.baseboard_fab2(sch_1):m_h_dqs_dn(12)") )
				( member ( signalRef "@baseboard_fab2_lib.baseboard_fab2(sch_1):m_h_dqs_dp(12)") )
				( objectStatus "M_H_DQS_D<12>" )
			)
			( differentialPair "@sapphirecity_baseboard_lib.sapphirecity_baseboard(sch_1):\M_H_DQS_D\(13)"
				( memberType ( signal ) )
				( electricalCSetRef "@crescent_city_bb_fab1_lib.crescent_city_bb_fab1(sch_1):\DDR_DQS_A\" )
				( member ( signalRef "@baseboard_fab2_lib.baseboard_fab2(sch_1):m_h_dqs_dn(13)") )
				( member ( signalRef "@baseboard_fab2_lib.baseboard_fab2(sch_1):m_h_dqs_dp(13)") )
				( objectStatus "M_H_DQS_D<13>" )
			)
			( differentialPair "@sapphirecity_baseboard_lib.sapphirecity_baseboard(sch_1):\M_H_DQS_D\(14)"
				( memberType ( signal ) )
				( electricalCSetRef "@crescent_city_bb_fab1_lib.crescent_city_bb_fab1(sch_1):\DDR_DQS_A\" )
				( member ( signalRef "@baseboard_fab2_lib.baseboard_fab2(sch_1):m_h_dqs_dn(14)") )
				( member ( signalRef "@baseboard_fab2_lib.baseboard_fab2(sch_1):m_h_dqs_dp(14)") )
				( objectStatus "M_H_DQS_D<14>" )
			)
			( differentialPair "@sapphirecity_baseboard_lib.sapphirecity_baseboard(sch_1):\M_H_DQS_D\(15)"
				( memberType ( signal ) )
				( electricalCSetRef "@crescent_city_bb_fab1_lib.crescent_city_bb_fab1(sch_1):\DDR_DQS_A\" )
				( member ( signalRef "@baseboard_fab2_lib.baseboard_fab2(sch_1):m_h_dqs_dn(15)") )
				( member ( signalRef "@baseboard_fab2_lib.baseboard_fab2(sch_1):m_h_dqs_dp(15)") )
				( objectStatus "M_H_DQS_D<15>" )
			)
			( differentialPair "@sapphirecity_baseboard_lib.sapphirecity_baseboard(sch_1):\M_H_DQS_D\(16)"
				( memberType ( signal ) )
				( electricalCSetRef "@crescent_city_bb_fab1_lib.crescent_city_bb_fab1(sch_1):\DDR_DQS_A\" )
				( member ( signalRef "@baseboard_fab2_lib.baseboard_fab2(sch_1):m_h_dqs_dn(16)") )
				( member ( signalRef "@baseboard_fab2_lib.baseboard_fab2(sch_1):m_h_dqs_dp(16)") )
				( objectStatus "M_H_DQS_D<16>" )
			)
			( differentialPair "@sapphirecity_baseboard_lib.sapphirecity_baseboard(sch_1):\M_H_DQS_D\(17)"
				( memberType ( signal ) )
				( electricalCSetRef "@crescent_city_bb_fab1_lib.crescent_city_bb_fab1(sch_1):\DDR_DQS_A\" )
				( member ( signalRef "@baseboard_fab2_lib.baseboard_fab2(sch_1):m_h_dqs_dn(17)") )
				( member ( signalRef "@baseboard_fab2_lib.baseboard_fab2(sch_1):m_h_dqs_dp(17)") )
				( objectStatus "M_H_DQS_D<17>" )
			)
			( differentialPair "@sapphirecity_baseboard_lib.sapphirecity_baseboard(sch_1):\M_J_DQS_D\(0)"
				( memberType ( signal ) )
				( electricalCSetRef "@crescent_city_bb_fab1_lib.crescent_city_bb_fab1(sch_1):\DDR_DQS_A\" )
				( member ( signalRef "@baseboard_fab2_lib.baseboard_fab2(sch_1):m_j_dqs_dn(0)") )
				( member ( signalRef "@baseboard_fab2_lib.baseboard_fab2(sch_1):m_j_dqs_dp(0)") )
				( objectStatus "M_J_DQS_D<0>" )
			)
			( differentialPair "@sapphirecity_baseboard_lib.sapphirecity_baseboard(sch_1):\M_J_DQS_D\(1)"
				( memberType ( signal ) )
				( electricalCSetRef "@crescent_city_bb_fab1_lib.crescent_city_bb_fab1(sch_1):\DDR_DQS_A\" )
				( member ( signalRef "@baseboard_fab2_lib.baseboard_fab2(sch_1):m_j_dqs_dn(1)") )
				( member ( signalRef "@baseboard_fab2_lib.baseboard_fab2(sch_1):m_j_dqs_dp(1)") )
				( objectStatus "M_J_DQS_D<1>" )
			)
			( differentialPair "@sapphirecity_baseboard_lib.sapphirecity_baseboard(sch_1):\M_J_DQS_D\(2)"
				( memberType ( signal ) )
				( electricalCSetRef "@crescent_city_bb_fab1_lib.crescent_city_bb_fab1(sch_1):\DDR_DQS_A\" )
				( member ( signalRef "@baseboard_fab2_lib.baseboard_fab2(sch_1):m_j_dqs_dn(2)") )
				( member ( signalRef "@baseboard_fab2_lib.baseboard_fab2(sch_1):m_j_dqs_dp(2)") )
				( objectStatus "M_J_DQS_D<2>" )
			)
			( differentialPair "@sapphirecity_baseboard_lib.sapphirecity_baseboard(sch_1):\M_J_DQS_D\(3)"
				( memberType ( signal ) )
				( electricalCSetRef "@crescent_city_bb_fab1_lib.crescent_city_bb_fab1(sch_1):\DDR_DQS_A\" )
				( member ( signalRef "@baseboard_fab2_lib.baseboard_fab2(sch_1):m_j_dqs_dn(3)") )
				( member ( signalRef "@baseboard_fab2_lib.baseboard_fab2(sch_1):m_j_dqs_dp(3)") )
				( objectStatus "M_J_DQS_D<3>" )
			)
			( differentialPair "@sapphirecity_baseboard_lib.sapphirecity_baseboard(sch_1):\M_J_DQS_D\(4)"
				( memberType ( signal ) )
				( electricalCSetRef "@crescent_city_bb_fab1_lib.crescent_city_bb_fab1(sch_1):\DDR_DQS_A\" )
				( member ( signalRef "@baseboard_fab2_lib.baseboard_fab2(sch_1):m_j_dqs_dn(4)") )
				( member ( signalRef "@baseboard_fab2_lib.baseboard_fab2(sch_1):m_j_dqs_dp(4)") )
				( objectStatus "M_J_DQS_D<4>" )
			)
			( differentialPair "@sapphirecity_baseboard_lib.sapphirecity_baseboard(sch_1):\M_J_DQS_D\(5)"
				( memberType ( signal ) )
				( electricalCSetRef "@crescent_city_bb_fab1_lib.crescent_city_bb_fab1(sch_1):\DDR_DQS_A\" )
				( member ( signalRef "@baseboard_fab2_lib.baseboard_fab2(sch_1):m_j_dqs_dn(5)") )
				( member ( signalRef "@baseboard_fab2_lib.baseboard_fab2(sch_1):m_j_dqs_dp(5)") )
				( objectStatus "M_J_DQS_D<5>" )
			)
			( differentialPair "@sapphirecity_baseboard_lib.sapphirecity_baseboard(sch_1):\M_J_DQS_D\(6)"
				( memberType ( signal ) )
				( electricalCSetRef "@crescent_city_bb_fab1_lib.crescent_city_bb_fab1(sch_1):\DDR_DQS_A\" )
				( member ( signalRef "@baseboard_fab2_lib.baseboard_fab2(sch_1):m_j_dqs_dn(6)") )
				( member ( signalRef "@baseboard_fab2_lib.baseboard_fab2(sch_1):m_j_dqs_dp(6)") )
				( objectStatus "M_J_DQS_D<6>" )
			)
			( differentialPair "@sapphirecity_baseboard_lib.sapphirecity_baseboard(sch_1):\M_J_DQS_D\(7)"
				( memberType ( signal ) )
				( electricalCSetRef "@crescent_city_bb_fab1_lib.crescent_city_bb_fab1(sch_1):\DDR_DQS_A\" )
				( member ( signalRef "@baseboard_fab2_lib.baseboard_fab2(sch_1):m_j_dqs_dn(7)") )
				( member ( signalRef "@baseboard_fab2_lib.baseboard_fab2(sch_1):m_j_dqs_dp(7)") )
				( objectStatus "M_J_DQS_D<7>" )
			)
			( differentialPair "@sapphirecity_baseboard_lib.sapphirecity_baseboard(sch_1):\M_J_DQS_D\(8)"
				( memberType ( signal ) )
				( electricalCSetRef "@crescent_city_bb_fab1_lib.crescent_city_bb_fab1(sch_1):\DDR_DQS_A\" )
				( member ( signalRef "@baseboard_fab2_lib.baseboard_fab2(sch_1):m_j_dqs_dn(8)") )
				( member ( signalRef "@baseboard_fab2_lib.baseboard_fab2(sch_1):m_j_dqs_dp(8)") )
				( objectStatus "M_J_DQS_D<8>" )
			)
			( differentialPair "@sapphirecity_baseboard_lib.sapphirecity_baseboard(sch_1):\M_J_DQS_D\(9)"
				( memberType ( signal ) )
				( electricalCSetRef "@crescent_city_bb_fab1_lib.crescent_city_bb_fab1(sch_1):\DDR_DQS_A\" )
				( member ( signalRef "@baseboard_fab2_lib.baseboard_fab2(sch_1):m_j_dqs_dn(9)") )
				( member ( signalRef "@baseboard_fab2_lib.baseboard_fab2(sch_1):m_j_dqs_dp(9)") )
				( objectStatus "M_J_DQS_D<9>" )
			)
			( differentialPair "@sapphirecity_baseboard_lib.sapphirecity_baseboard(sch_1):\M_J_DQS_D\(10)"
				( memberType ( signal ) )
				( electricalCSetRef "@crescent_city_bb_fab1_lib.crescent_city_bb_fab1(sch_1):\DDR_DQS_A\" )
				( member ( signalRef "@baseboard_fab2_lib.baseboard_fab2(sch_1):m_j_dqs_dn(10)") )
				( member ( signalRef "@baseboard_fab2_lib.baseboard_fab2(sch_1):m_j_dqs_dp(10)") )
				( objectStatus "M_J_DQS_D<10>" )
			)
			( differentialPair "@sapphirecity_baseboard_lib.sapphirecity_baseboard(sch_1):\M_J_DQS_D\(11)"
				( memberType ( signal ) )
				( electricalCSetRef "@crescent_city_bb_fab1_lib.crescent_city_bb_fab1(sch_1):\DDR_DQS_A\" )
				( member ( signalRef "@baseboard_fab2_lib.baseboard_fab2(sch_1):m_j_dqs_dn(11)") )
				( member ( signalRef "@baseboard_fab2_lib.baseboard_fab2(sch_1):m_j_dqs_dp(11)") )
				( objectStatus "M_J_DQS_D<11>" )
			)
			( differentialPair "@sapphirecity_baseboard_lib.sapphirecity_baseboard(sch_1):\M_J_DQS_D\(12)"
				( memberType ( signal ) )
				( electricalCSetRef "@crescent_city_bb_fab1_lib.crescent_city_bb_fab1(sch_1):\DDR_DQS_A\" )
				( member ( signalRef "@baseboard_fab2_lib.baseboard_fab2(sch_1):m_j_dqs_dn(12)") )
				( member ( signalRef "@baseboard_fab2_lib.baseboard_fab2(sch_1):m_j_dqs_dp(12)") )
				( objectStatus "M_J_DQS_D<12>" )
			)
			( differentialPair "@sapphirecity_baseboard_lib.sapphirecity_baseboard(sch_1):\M_J_DQS_D\(13)"
				( memberType ( signal ) )
				( electricalCSetRef "@crescent_city_bb_fab1_lib.crescent_city_bb_fab1(sch_1):\DDR_DQS_A\" )
				( member ( signalRef "@baseboard_fab2_lib.baseboard_fab2(sch_1):m_j_dqs_dn(13)") )
				( member ( signalRef "@baseboard_fab2_lib.baseboard_fab2(sch_1):m_j_dqs_dp(13)") )
				( objectStatus "M_J_DQS_D<13>" )
			)
			( differentialPair "@sapphirecity_baseboard_lib.sapphirecity_baseboard(sch_1):\M_J_DQS_D\(14)"
				( memberType ( signal ) )
				( electricalCSetRef "@crescent_city_bb_fab1_lib.crescent_city_bb_fab1(sch_1):\DDR_DQS_A\" )
				( member ( signalRef "@baseboard_fab2_lib.baseboard_fab2(sch_1):m_j_dqs_dn(14)") )
				( member ( signalRef "@baseboard_fab2_lib.baseboard_fab2(sch_1):m_j_dqs_dp(14)") )
				( objectStatus "M_J_DQS_D<14>" )
			)
			( differentialPair "@sapphirecity_baseboard_lib.sapphirecity_baseboard(sch_1):\M_J_DQS_D\(15)"
				( memberType ( signal ) )
				( electricalCSetRef "@crescent_city_bb_fab1_lib.crescent_city_bb_fab1(sch_1):\DDR_DQS_A\" )
				( member ( signalRef "@baseboard_fab2_lib.baseboard_fab2(sch_1):m_j_dqs_dn(15)") )
				( member ( signalRef "@baseboard_fab2_lib.baseboard_fab2(sch_1):m_j_dqs_dp(15)") )
				( objectStatus "M_J_DQS_D<15>" )
			)
			( differentialPair "@sapphirecity_baseboard_lib.sapphirecity_baseboard(sch_1):\M_J_DQS_D\(16)"
				( memberType ( signal ) )
				( electricalCSetRef "@crescent_city_bb_fab1_lib.crescent_city_bb_fab1(sch_1):\DDR_DQS_A\" )
				( member ( signalRef "@baseboard_fab2_lib.baseboard_fab2(sch_1):m_j_dqs_dn(16)") )
				( member ( signalRef "@baseboard_fab2_lib.baseboard_fab2(sch_1):m_j_dqs_dp(16)") )
				( objectStatus "M_J_DQS_D<16>" )
			)
			( differentialPair "@sapphirecity_baseboard_lib.sapphirecity_baseboard(sch_1):\M_J_DQS_D\(17)"
				( memberType ( signal ) )
				( electricalCSetRef "@crescent_city_bb_fab1_lib.crescent_city_bb_fab1(sch_1):\DDR_DQS_A\" )
				( member ( signalRef "@baseboard_fab2_lib.baseboard_fab2(sch_1):m_j_dqs_dn(17)") )
				( member ( signalRef "@baseboard_fab2_lib.baseboard_fab2(sch_1):m_j_dqs_dp(17)") )
				( objectStatus "M_J_DQS_D<17>" )
			)
			( differentialPair "@sapphirecity_baseboard_lib.sapphirecity_baseboard(sch_1):\M_K_DQS_D\(0)"
				( memberType ( signal ) )
				( electricalCSetRef "@crescent_city_bb_fab1_lib.crescent_city_bb_fab1(sch_1):\DDR_DQS_A\" )
				( member ( signalRef "@baseboard_fab2_lib.baseboard_fab2(sch_1):m_k_dqs_dn(0)") )
				( member ( signalRef "@baseboard_fab2_lib.baseboard_fab2(sch_1):m_k_dqs_dp(0)") )
				( objectStatus "M_K_DQS_D<0>" )
			)
			( differentialPair "@sapphirecity_baseboard_lib.sapphirecity_baseboard(sch_1):\M_K_DQS_D\(1)"
				( memberType ( signal ) )
				( electricalCSetRef "@crescent_city_bb_fab1_lib.crescent_city_bb_fab1(sch_1):\DDR_DQS_A\" )
				( member ( signalRef "@baseboard_fab2_lib.baseboard_fab2(sch_1):m_k_dqs_dn(1)") )
				( member ( signalRef "@baseboard_fab2_lib.baseboard_fab2(sch_1):m_k_dqs_dp(1)") )
				( objectStatus "M_K_DQS_D<1>" )
			)
			( differentialPair "@sapphirecity_baseboard_lib.sapphirecity_baseboard(sch_1):\M_K_DQS_D\(2)"
				( memberType ( signal ) )
				( electricalCSetRef "@crescent_city_bb_fab1_lib.crescent_city_bb_fab1(sch_1):\DDR_DQS_A\" )
				( member ( signalRef "@baseboard_fab2_lib.baseboard_fab2(sch_1):m_k_dqs_dn(2)") )
				( member ( signalRef "@baseboard_fab2_lib.baseboard_fab2(sch_1):m_k_dqs_dp(2)") )
				( objectStatus "M_K_DQS_D<2>" )
			)
			( differentialPair "@sapphirecity_baseboard_lib.sapphirecity_baseboard(sch_1):\M_K_DQS_D\(3)"
				( memberType ( signal ) )
				( electricalCSetRef "@crescent_city_bb_fab1_lib.crescent_city_bb_fab1(sch_1):\DDR_DQS_A\" )
				( member ( signalRef "@baseboard_fab2_lib.baseboard_fab2(sch_1):m_k_dqs_dn(3)") )
				( member ( signalRef "@baseboard_fab2_lib.baseboard_fab2(sch_1):m_k_dqs_dp(3)") )
				( objectStatus "M_K_DQS_D<3>" )
			)
			( differentialPair "@sapphirecity_baseboard_lib.sapphirecity_baseboard(sch_1):\M_K_DQS_D\(4)"
				( memberType ( signal ) )
				( electricalCSetRef "@crescent_city_bb_fab1_lib.crescent_city_bb_fab1(sch_1):\DDR_DQS_A\" )
				( member ( signalRef "@baseboard_fab2_lib.baseboard_fab2(sch_1):m_k_dqs_dn(4)") )
				( member ( signalRef "@baseboard_fab2_lib.baseboard_fab2(sch_1):m_k_dqs_dp(4)") )
				( objectStatus "M_K_DQS_D<4>" )
			)
			( differentialPair "@sapphirecity_baseboard_lib.sapphirecity_baseboard(sch_1):\M_K_DQS_D\(5)"
				( memberType ( signal ) )
				( electricalCSetRef "@crescent_city_bb_fab1_lib.crescent_city_bb_fab1(sch_1):\DDR_DQS_A\" )
				( member ( signalRef "@baseboard_fab2_lib.baseboard_fab2(sch_1):m_k_dqs_dn(5)") )
				( member ( signalRef "@baseboard_fab2_lib.baseboard_fab2(sch_1):m_k_dqs_dp(5)") )
				( objectStatus "M_K_DQS_D<5>" )
			)
			( differentialPair "@sapphirecity_baseboard_lib.sapphirecity_baseboard(sch_1):\M_K_DQS_D\(6)"
				( memberType ( signal ) )
				( electricalCSetRef "@crescent_city_bb_fab1_lib.crescent_city_bb_fab1(sch_1):\DDR_DQS_A\" )
				( member ( signalRef "@baseboard_fab2_lib.baseboard_fab2(sch_1):m_k_dqs_dn(6)") )
				( member ( signalRef "@baseboard_fab2_lib.baseboard_fab2(sch_1):m_k_dqs_dp(6)") )
				( objectStatus "M_K_DQS_D<6>" )
			)
			( differentialPair "@sapphirecity_baseboard_lib.sapphirecity_baseboard(sch_1):\M_K_DQS_D\(7)"
				( memberType ( signal ) )
				( electricalCSetRef "@crescent_city_bb_fab1_lib.crescent_city_bb_fab1(sch_1):\DDR_DQS_A\" )
				( member ( signalRef "@baseboard_fab2_lib.baseboard_fab2(sch_1):m_k_dqs_dn(7)") )
				( member ( signalRef "@baseboard_fab2_lib.baseboard_fab2(sch_1):m_k_dqs_dp(7)") )
				( objectStatus "M_K_DQS_D<7>" )
			)
			( differentialPair "@sapphirecity_baseboard_lib.sapphirecity_baseboard(sch_1):\M_K_DQS_D\(8)"
				( memberType ( signal ) )
				( electricalCSetRef "@crescent_city_bb_fab1_lib.crescent_city_bb_fab1(sch_1):\DDR_DQS_A\" )
				( member ( signalRef "@baseboard_fab2_lib.baseboard_fab2(sch_1):m_k_dqs_dn(8)") )
				( member ( signalRef "@baseboard_fab2_lib.baseboard_fab2(sch_1):m_k_dqs_dp(8)") )
				( objectStatus "M_K_DQS_D<8>" )
			)
			( differentialPair "@sapphirecity_baseboard_lib.sapphirecity_baseboard(sch_1):\M_K_DQS_D\(9)"
				( memberType ( signal ) )
				( electricalCSetRef "@crescent_city_bb_fab1_lib.crescent_city_bb_fab1(sch_1):\DDR_DQS_A\" )
				( member ( signalRef "@baseboard_fab2_lib.baseboard_fab2(sch_1):m_k_dqs_dn(9)") )
				( member ( signalRef "@baseboard_fab2_lib.baseboard_fab2(sch_1):m_k_dqs_dp(9)") )
				( objectStatus "M_K_DQS_D<9>" )
			)
			( differentialPair "@sapphirecity_baseboard_lib.sapphirecity_baseboard(sch_1):\M_K_DQS_D\(10)"
				( memberType ( signal ) )
				( electricalCSetRef "@crescent_city_bb_fab1_lib.crescent_city_bb_fab1(sch_1):\DDR_DQS_A\" )
				( member ( signalRef "@baseboard_fab2_lib.baseboard_fab2(sch_1):m_k_dqs_dn(10)") )
				( member ( signalRef "@baseboard_fab2_lib.baseboard_fab2(sch_1):m_k_dqs_dp(10)") )
				( objectStatus "M_K_DQS_D<10>" )
			)
			( differentialPair "@sapphirecity_baseboard_lib.sapphirecity_baseboard(sch_1):\M_K_DQS_D\(11)"
				( memberType ( signal ) )
				( electricalCSetRef "@crescent_city_bb_fab1_lib.crescent_city_bb_fab1(sch_1):\DDR_DQS_A\" )
				( member ( signalRef "@baseboard_fab2_lib.baseboard_fab2(sch_1):m_k_dqs_dn(11)") )
				( member ( signalRef "@baseboard_fab2_lib.baseboard_fab2(sch_1):m_k_dqs_dp(11)") )
				( objectStatus "M_K_DQS_D<11>" )
			)
			( differentialPair "@sapphirecity_baseboard_lib.sapphirecity_baseboard(sch_1):\M_K_DQS_D\(12)"
				( memberType ( signal ) )
				( electricalCSetRef "@crescent_city_bb_fab1_lib.crescent_city_bb_fab1(sch_1):\DDR_DQS_A\" )
				( member ( signalRef "@baseboard_fab2_lib.baseboard_fab2(sch_1):m_k_dqs_dn(12)") )
				( member ( signalRef "@baseboard_fab2_lib.baseboard_fab2(sch_1):m_k_dqs_dp(12)") )
				( objectStatus "M_K_DQS_D<12>" )
			)
			( differentialPair "@sapphirecity_baseboard_lib.sapphirecity_baseboard(sch_1):\M_K_DQS_D\(13)"
				( memberType ( signal ) )
				( electricalCSetRef "@crescent_city_bb_fab1_lib.crescent_city_bb_fab1(sch_1):\DDR_DQS_A\" )
				( member ( signalRef "@baseboard_fab2_lib.baseboard_fab2(sch_1):m_k_dqs_dn(13)") )
				( member ( signalRef "@baseboard_fab2_lib.baseboard_fab2(sch_1):m_k_dqs_dp(13)") )
				( objectStatus "M_K_DQS_D<13>" )
			)
			( differentialPair "@sapphirecity_baseboard_lib.sapphirecity_baseboard(sch_1):\M_K_DQS_D\(14)"
				( memberType ( signal ) )
				( electricalCSetRef "@crescent_city_bb_fab1_lib.crescent_city_bb_fab1(sch_1):\DDR_DQS_A\" )
				( member ( signalRef "@baseboard_fab2_lib.baseboard_fab2(sch_1):m_k_dqs_dn(14)") )
				( member ( signalRef "@baseboard_fab2_lib.baseboard_fab2(sch_1):m_k_dqs_dp(14)") )
				( objectStatus "M_K_DQS_D<14>" )
			)
			( differentialPair "@sapphirecity_baseboard_lib.sapphirecity_baseboard(sch_1):\M_K_DQS_D\(15)"
				( memberType ( signal ) )
				( electricalCSetRef "@crescent_city_bb_fab1_lib.crescent_city_bb_fab1(sch_1):\DDR_DQS_A\" )
				( member ( signalRef "@baseboard_fab2_lib.baseboard_fab2(sch_1):m_k_dqs_dn(15)") )
				( member ( signalRef "@baseboard_fab2_lib.baseboard_fab2(sch_1):m_k_dqs_dp(15)") )
				( objectStatus "M_K_DQS_D<15>" )
			)
			( differentialPair "@sapphirecity_baseboard_lib.sapphirecity_baseboard(sch_1):\M_K_DQS_D\(16)"
				( memberType ( signal ) )
				( electricalCSetRef "@crescent_city_bb_fab1_lib.crescent_city_bb_fab1(sch_1):\DDR_DQS_A\" )
				( member ( signalRef "@baseboard_fab2_lib.baseboard_fab2(sch_1):m_k_dqs_dn(16)") )
				( member ( signalRef "@baseboard_fab2_lib.baseboard_fab2(sch_1):m_k_dqs_dp(16)") )
				( objectStatus "M_K_DQS_D<16>" )
			)
			( differentialPair "@sapphirecity_baseboard_lib.sapphirecity_baseboard(sch_1):\M_K_DQS_D\(17)"
				( memberType ( signal ) )
				( electricalCSetRef "@crescent_city_bb_fab1_lib.crescent_city_bb_fab1(sch_1):\DDR_DQS_A\" )
				( member ( signalRef "@baseboard_fab2_lib.baseboard_fab2(sch_1):m_k_dqs_dn(17)") )
				( member ( signalRef "@baseboard_fab2_lib.baseboard_fab2(sch_1):m_k_dqs_dp(17)") )
				( objectStatus "M_K_DQS_D<17>" )
			)
			( differentialPair "@sapphirecity_baseboard_lib.sapphirecity_baseboard(sch_1):\M_L_DQS_D\(0)"
				( memberType ( signal ) )
				( electricalCSetRef "@crescent_city_bb_fab1_lib.crescent_city_bb_fab1(sch_1):\DDR_DQS_A\" )
				( member ( signalRef "@baseboard_fab2_lib.baseboard_fab2(sch_1):m_l_dqs_dn(0)") )
				( member ( signalRef "@baseboard_fab2_lib.baseboard_fab2(sch_1):m_l_dqs_dp(0)") )
				( objectStatus "M_L_DQS_D<0>" )
			)
			( differentialPair "@sapphirecity_baseboard_lib.sapphirecity_baseboard(sch_1):\M_L_DQS_D\(1)"
				( memberType ( signal ) )
				( electricalCSetRef "@crescent_city_bb_fab1_lib.crescent_city_bb_fab1(sch_1):\DDR_DQS_A\" )
				( member ( signalRef "@baseboard_fab2_lib.baseboard_fab2(sch_1):m_l_dqs_dn(1)") )
				( member ( signalRef "@baseboard_fab2_lib.baseboard_fab2(sch_1):m_l_dqs_dp(1)") )
				( objectStatus "M_L_DQS_D<1>" )
			)
			( differentialPair "@sapphirecity_baseboard_lib.sapphirecity_baseboard(sch_1):\M_L_DQS_D\(2)"
				( memberType ( signal ) )
				( electricalCSetRef "@crescent_city_bb_fab1_lib.crescent_city_bb_fab1(sch_1):\DDR_DQS_A\" )
				( member ( signalRef "@baseboard_fab2_lib.baseboard_fab2(sch_1):m_l_dqs_dn(2)") )
				( member ( signalRef "@baseboard_fab2_lib.baseboard_fab2(sch_1):m_l_dqs_dp(2)") )
				( objectStatus "M_L_DQS_D<2>" )
			)
			( differentialPair "@sapphirecity_baseboard_lib.sapphirecity_baseboard(sch_1):\M_L_DQS_D\(3)"
				( memberType ( signal ) )
				( electricalCSetRef "@crescent_city_bb_fab1_lib.crescent_city_bb_fab1(sch_1):\DDR_DQS_A\" )
				( member ( signalRef "@baseboard_fab2_lib.baseboard_fab2(sch_1):m_l_dqs_dn(3)") )
				( member ( signalRef "@baseboard_fab2_lib.baseboard_fab2(sch_1):m_l_dqs_dp(3)") )
				( objectStatus "M_L_DQS_D<3>" )
			)
			( differentialPair "@sapphirecity_baseboard_lib.sapphirecity_baseboard(sch_1):\M_L_DQS_D\(4)"
				( memberType ( signal ) )
				( electricalCSetRef "@crescent_city_bb_fab1_lib.crescent_city_bb_fab1(sch_1):\DDR_DQS_A\" )
				( member ( signalRef "@baseboard_fab2_lib.baseboard_fab2(sch_1):m_l_dqs_dn(4)") )
				( member ( signalRef "@baseboard_fab2_lib.baseboard_fab2(sch_1):m_l_dqs_dp(4)") )
				( objectStatus "M_L_DQS_D<4>" )
			)
			( differentialPair "@sapphirecity_baseboard_lib.sapphirecity_baseboard(sch_1):\M_L_DQS_D\(5)"
				( memberType ( signal ) )
				( electricalCSetRef "@crescent_city_bb_fab1_lib.crescent_city_bb_fab1(sch_1):\DDR_DQS_A\" )
				( member ( signalRef "@baseboard_fab2_lib.baseboard_fab2(sch_1):m_l_dqs_dn(5)") )
				( member ( signalRef "@baseboard_fab2_lib.baseboard_fab2(sch_1):m_l_dqs_dp(5)") )
				( objectStatus "M_L_DQS_D<5>" )
			)
			( differentialPair "@sapphirecity_baseboard_lib.sapphirecity_baseboard(sch_1):\M_L_DQS_D\(6)"
				( memberType ( signal ) )
				( electricalCSetRef "@crescent_city_bb_fab1_lib.crescent_city_bb_fab1(sch_1):\DDR_DQS_A\" )
				( member ( signalRef "@baseboard_fab2_lib.baseboard_fab2(sch_1):m_l_dqs_dn(6)") )
				( member ( signalRef "@baseboard_fab2_lib.baseboard_fab2(sch_1):m_l_dqs_dp(6)") )
				( objectStatus "M_L_DQS_D<6>" )
			)
			( differentialPair "@sapphirecity_baseboard_lib.sapphirecity_baseboard(sch_1):\M_L_DQS_D\(7)"
				( memberType ( signal ) )
				( electricalCSetRef "@crescent_city_bb_fab1_lib.crescent_city_bb_fab1(sch_1):\DDR_DQS_A\" )
				( member ( signalRef "@baseboard_fab2_lib.baseboard_fab2(sch_1):m_l_dqs_dn(7)") )
				( member ( signalRef "@baseboard_fab2_lib.baseboard_fab2(sch_1):m_l_dqs_dp(7)") )
				( objectStatus "M_L_DQS_D<7>" )
			)
			( differentialPair "@sapphirecity_baseboard_lib.sapphirecity_baseboard(sch_1):\M_L_DQS_D\(8)"
				( memberType ( signal ) )
				( electricalCSetRef "@crescent_city_bb_fab1_lib.crescent_city_bb_fab1(sch_1):\DDR_DQS_A\" )
				( member ( signalRef "@baseboard_fab2_lib.baseboard_fab2(sch_1):m_l_dqs_dn(8)") )
				( member ( signalRef "@baseboard_fab2_lib.baseboard_fab2(sch_1):m_l_dqs_dp(8)") )
				( objectStatus "M_L_DQS_D<8>" )
			)
			( differentialPair "@sapphirecity_baseboard_lib.sapphirecity_baseboard(sch_1):\M_L_DQS_D\(9)"
				( memberType ( signal ) )
				( electricalCSetRef "@crescent_city_bb_fab1_lib.crescent_city_bb_fab1(sch_1):\DDR_DQS_A\" )
				( member ( signalRef "@baseboard_fab2_lib.baseboard_fab2(sch_1):m_l_dqs_dn(9)") )
				( member ( signalRef "@baseboard_fab2_lib.baseboard_fab2(sch_1):m_l_dqs_dp(9)") )
				( objectStatus "M_L_DQS_D<9>" )
			)
			( differentialPair "@sapphirecity_baseboard_lib.sapphirecity_baseboard(sch_1):\M_L_DQS_D\(10)"
				( memberType ( signal ) )
				( electricalCSetRef "@crescent_city_bb_fab1_lib.crescent_city_bb_fab1(sch_1):\DDR_DQS_A\" )
				( member ( signalRef "@baseboard_fab2_lib.baseboard_fab2(sch_1):m_l_dqs_dn(10)") )
				( member ( signalRef "@baseboard_fab2_lib.baseboard_fab2(sch_1):m_l_dqs_dp(10)") )
				( objectStatus "M_L_DQS_D<10>" )
			)
			( differentialPair "@sapphirecity_baseboard_lib.sapphirecity_baseboard(sch_1):\M_L_DQS_D\(11)"
				( memberType ( signal ) )
				( electricalCSetRef "@crescent_city_bb_fab1_lib.crescent_city_bb_fab1(sch_1):\DDR_DQS_A\" )
				( member ( signalRef "@baseboard_fab2_lib.baseboard_fab2(sch_1):m_l_dqs_dn(11)") )
				( member ( signalRef "@baseboard_fab2_lib.baseboard_fab2(sch_1):m_l_dqs_dp(11)") )
				( objectStatus "M_L_DQS_D<11>" )
			)
			( differentialPair "@sapphirecity_baseboard_lib.sapphirecity_baseboard(sch_1):\M_L_DQS_D\(12)"
				( memberType ( signal ) )
				( electricalCSetRef "@crescent_city_bb_fab1_lib.crescent_city_bb_fab1(sch_1):\DDR_DQS_A\" )
				( member ( signalRef "@baseboard_fab2_lib.baseboard_fab2(sch_1):m_l_dqs_dn(12)") )
				( member ( signalRef "@baseboard_fab2_lib.baseboard_fab2(sch_1):m_l_dqs_dp(12)") )
				( objectStatus "M_L_DQS_D<12>" )
			)
			( differentialPair "@sapphirecity_baseboard_lib.sapphirecity_baseboard(sch_1):\M_L_DQS_D\(13)"
				( memberType ( signal ) )
				( electricalCSetRef "@crescent_city_bb_fab1_lib.crescent_city_bb_fab1(sch_1):\DDR_DQS_A\" )
				( member ( signalRef "@baseboard_fab2_lib.baseboard_fab2(sch_1):m_l_dqs_dn(13)") )
				( member ( signalRef "@baseboard_fab2_lib.baseboard_fab2(sch_1):m_l_dqs_dp(13)") )
				( objectStatus "M_L_DQS_D<13>" )
			)
			( differentialPair "@sapphirecity_baseboard_lib.sapphirecity_baseboard(sch_1):\M_L_DQS_D\(14)"
				( memberType ( signal ) )
				( electricalCSetRef "@crescent_city_bb_fab1_lib.crescent_city_bb_fab1(sch_1):\DDR_DQS_A\" )
				( member ( signalRef "@baseboard_fab2_lib.baseboard_fab2(sch_1):m_l_dqs_dn(14)") )
				( member ( signalRef "@baseboard_fab2_lib.baseboard_fab2(sch_1):m_l_dqs_dp(14)") )
				( objectStatus "M_L_DQS_D<14>" )
			)
			( differentialPair "@sapphirecity_baseboard_lib.sapphirecity_baseboard(sch_1):\M_L_DQS_D\(15)"
				( memberType ( signal ) )
				( electricalCSetRef "@crescent_city_bb_fab1_lib.crescent_city_bb_fab1(sch_1):\DDR_DQS_A\" )
				( member ( signalRef "@baseboard_fab2_lib.baseboard_fab2(sch_1):m_l_dqs_dn(15)") )
				( member ( signalRef "@baseboard_fab2_lib.baseboard_fab2(sch_1):m_l_dqs_dp(15)") )
				( objectStatus "M_L_DQS_D<15>" )
			)
			( differentialPair "@sapphirecity_baseboard_lib.sapphirecity_baseboard(sch_1):\M_L_DQS_D\(16)"
				( memberType ( signal ) )
				( electricalCSetRef "@crescent_city_bb_fab1_lib.crescent_city_bb_fab1(sch_1):\DDR_DQS_A\" )
				( member ( signalRef "@baseboard_fab2_lib.baseboard_fab2(sch_1):m_l_dqs_dn(16)") )
				( member ( signalRef "@baseboard_fab2_lib.baseboard_fab2(sch_1):m_l_dqs_dp(16)") )
				( objectStatus "M_L_DQS_D<16>" )
			)
			( differentialPair "@sapphirecity_baseboard_lib.sapphirecity_baseboard(sch_1):\M_L_DQS_D\(17)"
				( memberType ( signal ) )
				( electricalCSetRef "@crescent_city_bb_fab1_lib.crescent_city_bb_fab1(sch_1):\DDR_DQS_A\" )
				( member ( signalRef "@baseboard_fab2_lib.baseboard_fab2(sch_1):m_l_dqs_dn(17)") )
				( member ( signalRef "@baseboard_fab2_lib.baseboard_fab2(sch_1):m_l_dqs_dp(17)") )
				( objectStatus "M_L_DQS_D<17>" )
			)
			( differentialPair "@sapphirecity_baseboard_lib.sapphirecity_baseboard(sch_1):\M_M_DQS_D\(0)"
				( memberType ( signal ) )
				( electricalCSetRef "@crescent_city_bb_fab1_lib.crescent_city_bb_fab1(sch_1):\DDR_DQS_A\" )
				( member ( signalRef "@baseboard_fab2_lib.baseboard_fab2(sch_1):m_m_dqs_dn(0)") )
				( member ( signalRef "@baseboard_fab2_lib.baseboard_fab2(sch_1):m_m_dqs_dp(0)") )
				( objectStatus "M_M_DQS_D<0>" )
			)
			( differentialPair "@sapphirecity_baseboard_lib.sapphirecity_baseboard(sch_1):\M_M_DQS_D\(1)"
				( memberType ( signal ) )
				( electricalCSetRef "@crescent_city_bb_fab1_lib.crescent_city_bb_fab1(sch_1):\DDR_DQS_A\" )
				( member ( signalRef "@baseboard_fab2_lib.baseboard_fab2(sch_1):m_m_dqs_dn(1)") )
				( member ( signalRef "@baseboard_fab2_lib.baseboard_fab2(sch_1):m_m_dqs_dp(1)") )
				( objectStatus "M_M_DQS_D<1>" )
			)
			( differentialPair "@sapphirecity_baseboard_lib.sapphirecity_baseboard(sch_1):\M_M_DQS_D\(2)"
				( memberType ( signal ) )
				( electricalCSetRef "@crescent_city_bb_fab1_lib.crescent_city_bb_fab1(sch_1):\DDR_DQS_A\" )
				( member ( signalRef "@baseboard_fab2_lib.baseboard_fab2(sch_1):m_m_dqs_dn(2)") )
				( member ( signalRef "@baseboard_fab2_lib.baseboard_fab2(sch_1):m_m_dqs_dp(2)") )
				( objectStatus "M_M_DQS_D<2>" )
			)
			( differentialPair "@sapphirecity_baseboard_lib.sapphirecity_baseboard(sch_1):\M_M_DQS_D\(3)"
				( memberType ( signal ) )
				( electricalCSetRef "@crescent_city_bb_fab1_lib.crescent_city_bb_fab1(sch_1):\DDR_DQS_A\" )
				( member ( signalRef "@baseboard_fab2_lib.baseboard_fab2(sch_1):m_m_dqs_dn(3)") )
				( member ( signalRef "@baseboard_fab2_lib.baseboard_fab2(sch_1):m_m_dqs_dp(3)") )
				( objectStatus "M_M_DQS_D<3>" )
			)
			( differentialPair "@sapphirecity_baseboard_lib.sapphirecity_baseboard(sch_1):\M_M_DQS_D\(4)"
				( memberType ( signal ) )
				( electricalCSetRef "@crescent_city_bb_fab1_lib.crescent_city_bb_fab1(sch_1):\DDR_DQS_A\" )
				( member ( signalRef "@baseboard_fab2_lib.baseboard_fab2(sch_1):m_m_dqs_dn(4)") )
				( member ( signalRef "@baseboard_fab2_lib.baseboard_fab2(sch_1):m_m_dqs_dp(4)") )
				( objectStatus "M_M_DQS_D<4>" )
			)
			( differentialPair "@sapphirecity_baseboard_lib.sapphirecity_baseboard(sch_1):\M_M_DQS_D\(5)"
				( memberType ( signal ) )
				( electricalCSetRef "@crescent_city_bb_fab1_lib.crescent_city_bb_fab1(sch_1):\DDR_DQS_A\" )
				( member ( signalRef "@baseboard_fab2_lib.baseboard_fab2(sch_1):m_m_dqs_dn(5)") )
				( member ( signalRef "@baseboard_fab2_lib.baseboard_fab2(sch_1):m_m_dqs_dp(5)") )
				( objectStatus "M_M_DQS_D<5>" )
			)
			( differentialPair "@sapphirecity_baseboard_lib.sapphirecity_baseboard(sch_1):\M_M_DQS_D\(6)"
				( memberType ( signal ) )
				( electricalCSetRef "@crescent_city_bb_fab1_lib.crescent_city_bb_fab1(sch_1):\DDR_DQS_A\" )
				( member ( signalRef "@baseboard_fab2_lib.baseboard_fab2(sch_1):m_m_dqs_dn(6)") )
				( member ( signalRef "@baseboard_fab2_lib.baseboard_fab2(sch_1):m_m_dqs_dp(6)") )
				( objectStatus "M_M_DQS_D<6>" )
			)
			( differentialPair "@sapphirecity_baseboard_lib.sapphirecity_baseboard(sch_1):\M_M_DQS_D\(7)"
				( memberType ( signal ) )
				( electricalCSetRef "@crescent_city_bb_fab1_lib.crescent_city_bb_fab1(sch_1):\DDR_DQS_A\" )
				( member ( signalRef "@baseboard_fab2_lib.baseboard_fab2(sch_1):m_m_dqs_dn(7)") )
				( member ( signalRef "@baseboard_fab2_lib.baseboard_fab2(sch_1):m_m_dqs_dp(7)") )
				( objectStatus "M_M_DQS_D<7>" )
			)
			( differentialPair "@sapphirecity_baseboard_lib.sapphirecity_baseboard(sch_1):\M_M_DQS_D\(8)"
				( memberType ( signal ) )
				( electricalCSetRef "@crescent_city_bb_fab1_lib.crescent_city_bb_fab1(sch_1):\DDR_DQS_A\" )
				( member ( signalRef "@baseboard_fab2_lib.baseboard_fab2(sch_1):m_m_dqs_dn(8)") )
				( member ( signalRef "@baseboard_fab2_lib.baseboard_fab2(sch_1):m_m_dqs_dp(8)") )
				( objectStatus "M_M_DQS_D<8>" )
			)
			( differentialPair "@sapphirecity_baseboard_lib.sapphirecity_baseboard(sch_1):\M_M_DQS_D\(9)"
				( memberType ( signal ) )
				( electricalCSetRef "@crescent_city_bb_fab1_lib.crescent_city_bb_fab1(sch_1):\DDR_DQS_A\" )
				( member ( signalRef "@baseboard_fab2_lib.baseboard_fab2(sch_1):m_m_dqs_dn(9)") )
				( member ( signalRef "@baseboard_fab2_lib.baseboard_fab2(sch_1):m_m_dqs_dp(9)") )
				( objectStatus "M_M_DQS_D<9>" )
			)
			( differentialPair "@sapphirecity_baseboard_lib.sapphirecity_baseboard(sch_1):\M_M_DQS_D\(10)"
				( memberType ( signal ) )
				( electricalCSetRef "@crescent_city_bb_fab1_lib.crescent_city_bb_fab1(sch_1):\DDR_DQS_A\" )
				( member ( signalRef "@baseboard_fab2_lib.baseboard_fab2(sch_1):m_m_dqs_dn(10)") )
				( member ( signalRef "@baseboard_fab2_lib.baseboard_fab2(sch_1):m_m_dqs_dp(10)") )
				( objectStatus "M_M_DQS_D<10>" )
			)
			( differentialPair "@sapphirecity_baseboard_lib.sapphirecity_baseboard(sch_1):\M_M_DQS_D\(11)"
				( memberType ( signal ) )
				( electricalCSetRef "@crescent_city_bb_fab1_lib.crescent_city_bb_fab1(sch_1):\DDR_DQS_A\" )
				( member ( signalRef "@baseboard_fab2_lib.baseboard_fab2(sch_1):m_m_dqs_dn(11)") )
				( member ( signalRef "@baseboard_fab2_lib.baseboard_fab2(sch_1):m_m_dqs_dp(11)") )
				( objectStatus "M_M_DQS_D<11>" )
			)
			( differentialPair "@sapphirecity_baseboard_lib.sapphirecity_baseboard(sch_1):\M_M_DQS_D\(12)"
				( memberType ( signal ) )
				( electricalCSetRef "@crescent_city_bb_fab1_lib.crescent_city_bb_fab1(sch_1):\DDR_DQS_A\" )
				( member ( signalRef "@baseboard_fab2_lib.baseboard_fab2(sch_1):m_m_dqs_dn(12)") )
				( member ( signalRef "@baseboard_fab2_lib.baseboard_fab2(sch_1):m_m_dqs_dp(12)") )
				( objectStatus "M_M_DQS_D<12>" )
			)
			( differentialPair "@sapphirecity_baseboard_lib.sapphirecity_baseboard(sch_1):\M_M_DQS_D\(13)"
				( memberType ( signal ) )
				( electricalCSetRef "@crescent_city_bb_fab1_lib.crescent_city_bb_fab1(sch_1):\DDR_DQS_A\" )
				( member ( signalRef "@baseboard_fab2_lib.baseboard_fab2(sch_1):m_m_dqs_dn(13)") )
				( member ( signalRef "@baseboard_fab2_lib.baseboard_fab2(sch_1):m_m_dqs_dp(13)") )
				( objectStatus "M_M_DQS_D<13>" )
			)
			( differentialPair "@sapphirecity_baseboard_lib.sapphirecity_baseboard(sch_1):\M_M_DQS_D\(14)"
				( memberType ( signal ) )
				( electricalCSetRef "@crescent_city_bb_fab1_lib.crescent_city_bb_fab1(sch_1):\DDR_DQS_A\" )
				( member ( signalRef "@baseboard_fab2_lib.baseboard_fab2(sch_1):m_m_dqs_dn(14)") )
				( member ( signalRef "@baseboard_fab2_lib.baseboard_fab2(sch_1):m_m_dqs_dp(14)") )
				( objectStatus "M_M_DQS_D<14>" )
			)
			( differentialPair "@sapphirecity_baseboard_lib.sapphirecity_baseboard(sch_1):\M_M_DQS_D\(15)"
				( memberType ( signal ) )
				( electricalCSetRef "@crescent_city_bb_fab1_lib.crescent_city_bb_fab1(sch_1):\DDR_DQS_A\" )
				( member ( signalRef "@baseboard_fab2_lib.baseboard_fab2(sch_1):m_m_dqs_dn(15)") )
				( member ( signalRef "@baseboard_fab2_lib.baseboard_fab2(sch_1):m_m_dqs_dp(15)") )
				( objectStatus "M_M_DQS_D<15>" )
			)
			( differentialPair "@sapphirecity_baseboard_lib.sapphirecity_baseboard(sch_1):\M_M_DQS_D\(16)"
				( memberType ( signal ) )
				( electricalCSetRef "@crescent_city_bb_fab1_lib.crescent_city_bb_fab1(sch_1):\DDR_DQS_A\" )
				( member ( signalRef "@baseboard_fab2_lib.baseboard_fab2(sch_1):m_m_dqs_dn(16)") )
				( member ( signalRef "@baseboard_fab2_lib.baseboard_fab2(sch_1):m_m_dqs_dp(16)") )
				( objectStatus "M_M_DQS_D<16>" )
			)
			( differentialPair "@sapphirecity_baseboard_lib.sapphirecity_baseboard(sch_1):\M_M_DQS_D\(17)"
				( memberType ( signal ) )
				( electricalCSetRef "@crescent_city_bb_fab1_lib.crescent_city_bb_fab1(sch_1):\DDR_DQS_A\" )
				( member ( signalRef "@baseboard_fab2_lib.baseboard_fab2(sch_1):m_m_dqs_dn(17)") )
				( member ( signalRef "@baseboard_fab2_lib.baseboard_fab2(sch_1):m_m_dqs_dp(17)") )
				( objectStatus "M_M_DQS_D<17>" )
			)
			( differentialPair "@sapphirecity_baseboard_lib.sapphirecity_baseboard(sch_1):\M_G_DQS_D\(0)"
				( memberType ( signal ) )
				( electricalCSetRef "@crescent_city_bb_fab1_lib.crescent_city_bb_fab1(sch_1):\DDR_DQS_A\" )
				( member ( signalRef "@baseboard_fab2_lib.baseboard_fab2(sch_1):m_g_dqs_dn(0)") )
				( member ( signalRef "@baseboard_fab2_lib.baseboard_fab2(sch_1):m_g_dqs_dp(0)") )
				( objectStatus "M_G_DQS_D<0>" )
			)
			( differentialPair "@sapphirecity_baseboard_lib.sapphirecity_baseboard(sch_1):\M_G_DQS_D\(1)"
				( memberType ( signal ) )
				( electricalCSetRef "@crescent_city_bb_fab1_lib.crescent_city_bb_fab1(sch_1):\DDR_DQS_A\" )
				( member ( signalRef "@baseboard_fab2_lib.baseboard_fab2(sch_1):m_g_dqs_dn(1)") )
				( member ( signalRef "@baseboard_fab2_lib.baseboard_fab2(sch_1):m_g_dqs_dp(1)") )
				( objectStatus "M_G_DQS_D<1>" )
			)
			( differentialPair "@sapphirecity_baseboard_lib.sapphirecity_baseboard(sch_1):\M_G_DQS_D\(2)"
				( memberType ( signal ) )
				( electricalCSetRef "@crescent_city_bb_fab1_lib.crescent_city_bb_fab1(sch_1):\DDR_DQS_A\" )
				( member ( signalRef "@baseboard_fab2_lib.baseboard_fab2(sch_1):m_g_dqs_dn(2)") )
				( member ( signalRef "@baseboard_fab2_lib.baseboard_fab2(sch_1):m_g_dqs_dp(2)") )
				( objectStatus "M_G_DQS_D<2>" )
			)
			( differentialPair "@sapphirecity_baseboard_lib.sapphirecity_baseboard(sch_1):\M_G_DQS_D\(3)"
				( memberType ( signal ) )
				( electricalCSetRef "@crescent_city_bb_fab1_lib.crescent_city_bb_fab1(sch_1):\DDR_DQS_A\" )
				( member ( signalRef "@baseboard_fab2_lib.baseboard_fab2(sch_1):m_g_dqs_dn(3)") )
				( member ( signalRef "@baseboard_fab2_lib.baseboard_fab2(sch_1):m_g_dqs_dp(3)") )
				( objectStatus "M_G_DQS_D<3>" )
			)
			( differentialPair "@sapphirecity_baseboard_lib.sapphirecity_baseboard(sch_1):\M_G_DQS_D\(4)"
				( memberType ( signal ) )
				( electricalCSetRef "@crescent_city_bb_fab1_lib.crescent_city_bb_fab1(sch_1):\DDR_DQS_A\" )
				( member ( signalRef "@baseboard_fab2_lib.baseboard_fab2(sch_1):m_g_dqs_dn(4)") )
				( member ( signalRef "@baseboard_fab2_lib.baseboard_fab2(sch_1):m_g_dqs_dp(4)") )
				( objectStatus "M_G_DQS_D<4>" )
			)
			( differentialPair "@sapphirecity_baseboard_lib.sapphirecity_baseboard(sch_1):\M_G_DQS_D\(5)"
				( memberType ( signal ) )
				( electricalCSetRef "@crescent_city_bb_fab1_lib.crescent_city_bb_fab1(sch_1):\DDR_DQS_A\" )
				( member ( signalRef "@baseboard_fab2_lib.baseboard_fab2(sch_1):m_g_dqs_dn(5)") )
				( member ( signalRef "@baseboard_fab2_lib.baseboard_fab2(sch_1):m_g_dqs_dp(5)") )
				( objectStatus "M_G_DQS_D<5>" )
			)
			( differentialPair "@sapphirecity_baseboard_lib.sapphirecity_baseboard(sch_1):\M_G_DQS_D\(6)"
				( memberType ( signal ) )
				( electricalCSetRef "@crescent_city_bb_fab1_lib.crescent_city_bb_fab1(sch_1):\DDR_DQS_A\" )
				( member ( signalRef "@baseboard_fab2_lib.baseboard_fab2(sch_1):m_g_dqs_dn(6)") )
				( member ( signalRef "@baseboard_fab2_lib.baseboard_fab2(sch_1):m_g_dqs_dp(6)") )
				( objectStatus "M_G_DQS_D<6>" )
			)
			( differentialPair "@sapphirecity_baseboard_lib.sapphirecity_baseboard(sch_1):\M_G_DQS_D\(7)"
				( memberType ( signal ) )
				( electricalCSetRef "@crescent_city_bb_fab1_lib.crescent_city_bb_fab1(sch_1):\DDR_DQS_A\" )
				( member ( signalRef "@baseboard_fab2_lib.baseboard_fab2(sch_1):m_g_dqs_dn(7)") )
				( member ( signalRef "@baseboard_fab2_lib.baseboard_fab2(sch_1):m_g_dqs_dp(7)") )
				( objectStatus "M_G_DQS_D<7>" )
			)
			( differentialPair "@sapphirecity_baseboard_lib.sapphirecity_baseboard(sch_1):\M_G_DQS_D\(8)"
				( memberType ( signal ) )
				( electricalCSetRef "@crescent_city_bb_fab1_lib.crescent_city_bb_fab1(sch_1):\DDR_DQS_A\" )
				( member ( signalRef "@baseboard_fab2_lib.baseboard_fab2(sch_1):m_g_dqs_dn(8)") )
				( member ( signalRef "@baseboard_fab2_lib.baseboard_fab2(sch_1):m_g_dqs_dp(8)") )
				( objectStatus "M_G_DQS_D<8>" )
			)
			( differentialPair "@sapphirecity_baseboard_lib.sapphirecity_baseboard(sch_1):\M_G_DQS_D\(9)"
				( memberType ( signal ) )
				( electricalCSetRef "@crescent_city_bb_fab1_lib.crescent_city_bb_fab1(sch_1):\DDR_DQS_A\" )
				( member ( signalRef "@baseboard_fab2_lib.baseboard_fab2(sch_1):m_g_dqs_dn(9)") )
				( member ( signalRef "@baseboard_fab2_lib.baseboard_fab2(sch_1):m_g_dqs_dp(9)") )
				( objectStatus "M_G_DQS_D<9>" )
			)
			( differentialPair "@sapphirecity_baseboard_lib.sapphirecity_baseboard(sch_1):\M_G_DQS_D\(10)"
				( memberType ( signal ) )
				( electricalCSetRef "@crescent_city_bb_fab1_lib.crescent_city_bb_fab1(sch_1):\DDR_DQS_A\" )
				( member ( signalRef "@baseboard_fab2_lib.baseboard_fab2(sch_1):m_g_dqs_dn(10)") )
				( member ( signalRef "@baseboard_fab2_lib.baseboard_fab2(sch_1):m_g_dqs_dp(10)") )
				( objectStatus "M_G_DQS_D<10>" )
			)
			( differentialPair "@sapphirecity_baseboard_lib.sapphirecity_baseboard(sch_1):\M_G_DQS_D\(11)"
				( memberType ( signal ) )
				( electricalCSetRef "@crescent_city_bb_fab1_lib.crescent_city_bb_fab1(sch_1):\DDR_DQS_A\" )
				( member ( signalRef "@baseboard_fab2_lib.baseboard_fab2(sch_1):m_g_dqs_dn(11)") )
				( member ( signalRef "@baseboard_fab2_lib.baseboard_fab2(sch_1):m_g_dqs_dp(11)") )
				( objectStatus "M_G_DQS_D<11>" )
			)
			( differentialPair "@sapphirecity_baseboard_lib.sapphirecity_baseboard(sch_1):\M_G_DQS_D\(12)"
				( memberType ( signal ) )
				( electricalCSetRef "@crescent_city_bb_fab1_lib.crescent_city_bb_fab1(sch_1):\DDR_DQS_A\" )
				( member ( signalRef "@baseboard_fab2_lib.baseboard_fab2(sch_1):m_g_dqs_dn(12)") )
				( member ( signalRef "@baseboard_fab2_lib.baseboard_fab2(sch_1):m_g_dqs_dp(12)") )
				( objectStatus "M_G_DQS_D<12>" )
			)
			( differentialPair "@sapphirecity_baseboard_lib.sapphirecity_baseboard(sch_1):\M_G_DQS_D\(13)"
				( memberType ( signal ) )
				( electricalCSetRef "@crescent_city_bb_fab1_lib.crescent_city_bb_fab1(sch_1):\DDR_DQS_A\" )
				( member ( signalRef "@baseboard_fab2_lib.baseboard_fab2(sch_1):m_g_dqs_dn(13)") )
				( member ( signalRef "@baseboard_fab2_lib.baseboard_fab2(sch_1):m_g_dqs_dp(13)") )
				( objectStatus "M_G_DQS_D<13>" )
			)
			( differentialPair "@sapphirecity_baseboard_lib.sapphirecity_baseboard(sch_1):\M_G_DQS_D\(14)"
				( memberType ( signal ) )
				( electricalCSetRef "@crescent_city_bb_fab1_lib.crescent_city_bb_fab1(sch_1):\DDR_DQS_A\" )
				( member ( signalRef "@baseboard_fab2_lib.baseboard_fab2(sch_1):m_g_dqs_dn(14)") )
				( member ( signalRef "@baseboard_fab2_lib.baseboard_fab2(sch_1):m_g_dqs_dp(14)") )
				( objectStatus "M_G_DQS_D<14>" )
			)
			( differentialPair "@sapphirecity_baseboard_lib.sapphirecity_baseboard(sch_1):\M_G_DQS_D\(15)"
				( memberType ( signal ) )
				( electricalCSetRef "@crescent_city_bb_fab1_lib.crescent_city_bb_fab1(sch_1):\DDR_DQS_A\" )
				( member ( signalRef "@baseboard_fab2_lib.baseboard_fab2(sch_1):m_g_dqs_dn(15)") )
				( member ( signalRef "@baseboard_fab2_lib.baseboard_fab2(sch_1):m_g_dqs_dp(15)") )
				( objectStatus "M_G_DQS_D<15>" )
			)
			( differentialPair "@sapphirecity_baseboard_lib.sapphirecity_baseboard(sch_1):\M_G_DQS_D\(16)"
				( memberType ( signal ) )
				( electricalCSetRef "@crescent_city_bb_fab1_lib.crescent_city_bb_fab1(sch_1):\DDR_DQS_A\" )
				( member ( signalRef "@baseboard_fab2_lib.baseboard_fab2(sch_1):m_g_dqs_dn(16)") )
				( member ( signalRef "@baseboard_fab2_lib.baseboard_fab2(sch_1):m_g_dqs_dp(16)") )
				( objectStatus "M_G_DQS_D<16>" )
			)
			( differentialPair "@sapphirecity_baseboard_lib.sapphirecity_baseboard(sch_1):\M_G_DQS_D\(17)"
				( memberType ( signal ) )
				( electricalCSetRef "@crescent_city_bb_fab1_lib.crescent_city_bb_fab1(sch_1):\DDR_DQS_A\" )
				( member ( signalRef "@baseboard_fab2_lib.baseboard_fab2(sch_1):m_g_dqs_dn(17)") )
				( member ( signalRef "@baseboard_fab2_lib.baseboard_fab2(sch_1):m_g_dqs_dp(17)") )
				( objectStatus "M_G_DQS_D<17>" )
			)
			( differentialPair "@sapphirecity_baseboard_lib.sapphirecity_baseboard(sch_1):\M_H_DQS_D\(0)"
				( memberType ( signal ) )
				( electricalCSetRef "@crescent_city_bb_fab1_lib.crescent_city_bb_fab1(sch_1):\DDR_DQS_A\" )
				( member ( signalRef "@baseboard_fab2_lib.baseboard_fab2(sch_1):m_h_dqs_dn(0)") )
				( member ( signalRef "@baseboard_fab2_lib.baseboard_fab2(sch_1):m_h_dqs_dp(0)") )
				( objectStatus "M_H_DQS_D<0>" )
			)
			( differentialPair "@sapphirecity_baseboard_lib.sapphirecity_baseboard(sch_1):\M_H_DQS_D\(1)"
				( memberType ( signal ) )
				( electricalCSetRef "@crescent_city_bb_fab1_lib.crescent_city_bb_fab1(sch_1):\DDR_DQS_A\" )
				( member ( signalRef "@baseboard_fab2_lib.baseboard_fab2(sch_1):m_h_dqs_dn(1)") )
				( member ( signalRef "@baseboard_fab2_lib.baseboard_fab2(sch_1):m_h_dqs_dp(1)") )
				( objectStatus "M_H_DQS_D<1>" )
			)
			( differentialPair "@sapphirecity_baseboard_lib.sapphirecity_baseboard(sch_1):\M_A_CLK_D\(2)"
				( memberType ( signal ) )
				( attribute "DIFFP_PHASE_TOL" "5 mil"
					( Units "uPhaseTol" "ns" 1.000000)
					( Origin gBackEnd )
				)
				( member ( signalRef "@baseboard_fab2_lib.baseboard_fab2(sch_1):m_a_clk_dn(1)") )
				( member ( signalRef "@baseboard_fab2_lib.baseboard_fab2(sch_1):m_a_clk_dp(1)") )
				( objectStatus "DP_M_A_CLK_D<2>" )
			)
			( differentialPair "@sapphirecity_baseboard_lib.sapphirecity_baseboard(sch_1):\M_A_CLK_D\(3)"
				( memberType ( signal ) )
				( attribute "DIFFP_PHASE_TOL" "5 mil"
					( Units "uPhaseTol" "ns" 1.000000)
					( Origin gBackEnd )
				)
				( member ( signalRef "@baseboard_fab2_lib.baseboard_fab2(sch_1):m_a_clk_dn(3)") )
				( member ( signalRef "@baseboard_fab2_lib.baseboard_fab2(sch_1):m_a_clk_dp(3)") )
				( objectStatus "DP_M_A_CLK_D<3>" )
			)
			( differentialPair "@sapphirecity_baseboard_lib.sapphirecity_baseboard(sch_1):\M_B_CLK_D\(2)"
				( memberType ( signal ) )
				( attribute "DIFFP_PHASE_TOL" "5 mil"
					( Units "uPhaseTol" "ns" 1.000000)
					( Origin gBackEnd )
				)
				( member ( signalRef "@baseboard_fab2_lib.baseboard_fab2(sch_1):m_b_clk_dn(1)") )
				( member ( signalRef "@baseboard_fab2_lib.baseboard_fab2(sch_1):m_b_clk_dp(1)") )
				( objectStatus "DP_M_B_CLK_D<2>" )
			)
			( differentialPair "@sapphirecity_baseboard_lib.sapphirecity_baseboard(sch_1):\M_B_CLK_D\(3)"
				( memberType ( signal ) )
				( member ( signalRef "@baseboard_fab2_lib.baseboard_fab2(sch_1):m_h_clk_dn(3)") )
				( member ( signalRef "@baseboard_fab2_lib.baseboard_fab2(sch_1):m_h_clk_dp(3)") )
				( objectStatus "DP_M_H_CLK_D<3>" )
			)
			( differentialPair "@sapphirecity_baseboard_lib.sapphirecity_baseboard(sch_1):\M_C_CLK_D\(2)"
				( memberType ( signal ) )
				( attribute "DIFFP_PHASE_TOL" "5 mil"
					( Units "uPhaseTol" "ns" 1.000000)
					( Origin gBackEnd )
				)
				( member ( signalRef "@baseboard_fab2_lib.baseboard_fab2(sch_1):m_c_clk_dn(1)") )
				( member ( signalRef "@baseboard_fab2_lib.baseboard_fab2(sch_1):m_c_clk_dp(1)") )
				( objectStatus "DP_M_C_CLK_D<2>" )
			)
			( differentialPair "@sapphirecity_baseboard_lib.sapphirecity_baseboard(sch_1):\M_D_CLK_D\(2)"
				( memberType ( signal ) )
				( attribute "DIFFP_PHASE_TOL" "5 mil"
					( Units "uPhaseTol" "ns" 1.000000)
					( Origin gBackEnd )
				)
				( member ( signalRef "@baseboard_fab2_lib.baseboard_fab2(sch_1):m_d_clk_dn(1)") )
				( member ( signalRef "@baseboard_fab2_lib.baseboard_fab2(sch_1):m_d_clk_dp(1)") )
				( objectStatus "DP_M_D_CLK_D<2>" )
			)
			( differentialPair "@sapphirecity_baseboard_lib.sapphirecity_baseboard(sch_1):\DP_M_D_CLK_D3\"
				( memberType ( signal ) )
				( attribute "DIFFP_PHASE_TOL" "5 mil"
					( Units "uPhaseTol" "ns" 1.000000)
					( Origin gBackEnd )
				)
				( member ( signalRef "@baseboard_fab2_lib.baseboard_fab2(sch_1):m_d_clk_dn(3)") )
				( member ( signalRef "@baseboard_fab2_lib.baseboard_fab2(sch_1):m_d_clk_dp(3)") )
				( objectStatus "DP_M_D_CLK_D<3>" )
			)
			( differentialPair "@sapphirecity_baseboard_lib.sapphirecity_baseboard(sch_1):\M_E_CLK_D\(1)"
				( memberType ( signal ) )
				( member ( signalRef "@baseboard_fab2_lib.baseboard_fab2(sch_1):m_l_clk_dn(3)") )
				( member ( signalRef "@baseboard_fab2_lib.baseboard_fab2(sch_1):m_l_clk_dp(3)") )
				( objectStatus "DP_M_L_CLK_D<3>" )
			)
			( differentialPair "@sapphirecity_baseboard_lib.sapphirecity_baseboard(sch_1):\M_E_CLK_D\(2)"
				( memberType ( signal ) )
				( attribute "DIFFP_PHASE_TOL" "5 mil"
					( Units "uPhaseTol" "ns" 1.000000)
					( Origin gBackEnd )
				)
				( member ( signalRef "@baseboard_fab2_lib.baseboard_fab2(sch_1):m_e_clk_dn(1)") )
				( member ( signalRef "@baseboard_fab2_lib.baseboard_fab2(sch_1):m_e_clk_dp(1)") )
				( objectStatus "DP_M_E_CLK_D<2>" )
			)
			( differentialPair "@sapphirecity_baseboard_lib.sapphirecity_baseboard(sch_1):\M_F_CLK_D\(2)"
				( memberType ( signal ) )
				( attribute "DIFFP_PHASE_TOL" "5 mil"
					( Units "uPhaseTol" "ns" 1.000000)
					( Origin gBackEnd )
				)
				( member ( signalRef "@baseboard_fab2_lib.baseboard_fab2(sch_1):m_f_clk_dn(1)") )
				( member ( signalRef "@baseboard_fab2_lib.baseboard_fab2(sch_1):m_f_clk_dp(1)") )
				( objectStatus "DP_M_F_CLK_D<2>" )
			)
			( differentialPair "@crescent_city_bb_fab1_lib.crescent_city_bb_fab1(sch_1):\DP_M_G_CLK\(3)"
				( memberType ( signal ) )
				( member ( signalRef "@baseboard_fab2_lib.baseboard_fab2(sch_1):m_g_clk_dn(3)") )
				( member ( signalRef "@baseboard_fab2_lib.baseboard_fab2(sch_1):m_g_clk_dp(3)") )
				( objectStatus "DP_M_G_CLK_D<3>" )
			)
			( differentialPair "@sapphirecity_baseboard_lib.sapphirecity_baseboard(sch_1):\M_G_CLK_D\(2)"
				( memberType ( signal ) )
				( member ( signalRef "@baseboard_fab2_lib.baseboard_fab2(sch_1):m_g_clk_dn(1)") )
				( member ( signalRef "@baseboard_fab2_lib.baseboard_fab2(sch_1):m_g_clk_dp(1)") )
				( objectStatus "DP_M_G_CLK_D<2>" )
			)
			( differentialPair "@sapphirecity_baseboard_lib.sapphirecity_baseboard(sch_1):\M_G_CLK_D\(3)"
				( memberType ( signal ) )
				( attribute "DIFFP_PHASE_TOL" "5 mil"
					( Units "uPhaseTol" "ns" 1.000000)
					( Origin gBackEnd )
				)
				( member ( signalRef "@baseboard_fab2_lib.baseboard_fab2(sch_1):m_c_clk_dn(3)") )
				( member ( signalRef "@baseboard_fab2_lib.baseboard_fab2(sch_1):m_c_clk_dp(3)") )
				( objectStatus "DP_M_C_CLK_D<3>" )
			)
			( differentialPair "@sapphirecity_baseboard_lib.sapphirecity_baseboard(sch_1):\M_H_CLK_D\(2)"
				( memberType ( signal ) )
				( member ( signalRef "@baseboard_fab2_lib.baseboard_fab2(sch_1):m_h_clk_dn(1)") )
				( member ( signalRef "@baseboard_fab2_lib.baseboard_fab2(sch_1):m_h_clk_dp(1)") )
				( objectStatus "DP_M_H_CLK_D<2>" )
			)
			( differentialPair "@sapphirecity_baseboard_lib.sapphirecity_baseboard(sch_1):\M_H_CLK_D\(3)"
				( memberType ( signal ) )
				( attribute "DIFFP_PHASE_TOL" "5 mil"
					( Units "uPhaseTol" "ns" 1.000000)
					( Origin gBackEnd )
				)
				( member ( signalRef "@baseboard_fab2_lib.baseboard_fab2(sch_1):m_b_clk_dn(3)") )
				( member ( signalRef "@baseboard_fab2_lib.baseboard_fab2(sch_1):m_b_clk_dp(3)") )
				( objectStatus "DP_M_B_CLK_D<3>" )
			)
			( differentialPair "@crescent_city_bb_fab1_lib.crescent_city_bb_fab1(sch_1):\DP_M_J_CLK\(3)"
				( memberType ( signal ) )
				( member ( signalRef "@baseboard_fab2_lib.baseboard_fab2(sch_1):m_j_clk_dn(3)") )
				( member ( signalRef "@baseboard_fab2_lib.baseboard_fab2(sch_1):m_j_clk_dp(3)") )
				( objectStatus "DP_M_J_CLK_D<3>" )
			)
			( differentialPair "@sapphirecity_baseboard_lib.sapphirecity_baseboard(sch_1):\M_J_CLK_D\(2)"
				( memberType ( signal ) )
				( member ( signalRef "@baseboard_fab2_lib.baseboard_fab2(sch_1):m_j_clk_dn(1)") )
				( member ( signalRef "@baseboard_fab2_lib.baseboard_fab2(sch_1):m_j_clk_dp(1)") )
				( objectStatus "DP_M_J_CLK_D<2>" )
			)
			( differentialPair "@crescent_city_bb_fab1_lib.crescent_city_bb_fab1(sch_1):\DP_M_K_CLK\(3)"
				( memberType ( signal ) )
				( member ( signalRef "@baseboard_fab2_lib.baseboard_fab2(sch_1):m_k_clk_dn(3)") )
				( member ( signalRef "@baseboard_fab2_lib.baseboard_fab2(sch_1):m_k_clk_dp(3)") )
				( objectStatus "DP_M_K_CLK_D<3>" )
			)
			( differentialPair "@sapphirecity_baseboard_lib.sapphirecity_baseboard(sch_1):\M_K_CLK_D\(1)"
				( memberType ( signal ) )
				( attribute "DIFFP_PHASE_TOL" "5 mil"
					( Units "uPhaseTol" "ns" 1.000000)
					( Origin gBackEnd )
				)
				( member ( signalRef "@baseboard_fab2_lib.baseboard_fab2(sch_1):m_f_clk_dn(3)") )
				( member ( signalRef "@baseboard_fab2_lib.baseboard_fab2(sch_1):m_f_clk_dp(3)") )
				( objectStatus "DP_M_F_CLK_D<3>" )
			)
			( differentialPair "@sapphirecity_baseboard_lib.sapphirecity_baseboard(sch_1):\M_K_CLK_D\(2)"
				( memberType ( signal ) )
				( member ( signalRef "@baseboard_fab2_lib.baseboard_fab2(sch_1):m_k_clk_dn(1)") )
				( member ( signalRef "@baseboard_fab2_lib.baseboard_fab2(sch_1):m_k_clk_dp(1)") )
				( objectStatus "DP_M_K_CLK_D<2>" )
			)
			( differentialPair "@sapphirecity_baseboard_lib.sapphirecity_baseboard(sch_1):\M_L_CLK_D\(1)"
				( memberType ( signal ) )
				( attribute "DIFFP_PHASE_TOL" "5 mil"
					( Units "uPhaseTol" "ns" 1.000000)
					( Origin gBackEnd )
				)
				( member ( signalRef "@baseboard_fab2_lib.baseboard_fab2(sch_1):m_e_clk_dn(3)") )
				( member ( signalRef "@baseboard_fab2_lib.baseboard_fab2(sch_1):m_e_clk_dp(3)") )
				( objectStatus "DP_M_E_CLK_D<3>" )
			)
			( differentialPair "@sapphirecity_baseboard_lib.sapphirecity_baseboard(sch_1):\M_L_CLK_D\(2)"
				( memberType ( signal ) )
				( member ( signalRef "@baseboard_fab2_lib.baseboard_fab2(sch_1):m_l_clk_dn(1)") )
				( member ( signalRef "@baseboard_fab2_lib.baseboard_fab2(sch_1):m_l_clk_dp(1)") )
				( objectStatus "DP_M_L_CLK_D<2>" )
			)
			( differentialPair "@sapphirecity_baseboard_lib.sapphirecity_baseboard(sch_1):\M_D_CLK_D\(1)"
				( memberType ( signal ) )
				( member ( signalRef "@baseboard_fab2_lib.baseboard_fab2(sch_1):m_m_clk_dn(3)") )
				( member ( signalRef "@baseboard_fab2_lib.baseboard_fab2(sch_1):m_m_clk_dp(3)") )
				( objectStatus "DP_M_M_CLK_D<3>" )
			)
			( differentialPair "@sapphirecity_baseboard_lib.sapphirecity_baseboard(sch_1):\M_M_CLK_D\(2)"
				( memberType ( signal ) )
				( member ( signalRef "@baseboard_fab2_lib.baseboard_fab2(sch_1):m_m_clk_dn(1)") )
				( member ( signalRef "@baseboard_fab2_lib.baseboard_fab2(sch_1):m_m_clk_dp(1)") )
				( objectStatus "DP_M_M_CLK_D<2>" )
			)
			( differentialPair "@crescent_city_bb_fab1_lib.crescent_city_bb_fab1(sch_1):\P3E_CPU0_PE3_OCP_RX\(0)"
				( memberType ( signal ) )
				( attribute "DIFFP_PHASE_TOL" "5 mil"
					( Units "uPhaseTol" "ns" 1.000000)
					( Origin gBackEnd )
				)
				( member ( signalRef "@baseboard_fab2_lib.baseboard_fab2(sch_1):p3e_cpu0_pe3_ocp_rxn(0)") )
				( member ( signalRef "@baseboard_fab2_lib.baseboard_fab2(sch_1):p3e_cpu0_pe3_ocp_rxp(0)") )
				( objectStatus "P3E_CPU0_PE3_OCP_RX<0>" )
			)
			( differentialPair "@crescent_city_bb_fab1_lib.crescent_city_bb_fab1(sch_1):\P3E_CPU0_PE3_OCP_RX\(1)"
				( memberType ( signal ) )
				( attribute "DIFFP_PHASE_TOL" "5 mil"
					( Units "uPhaseTol" "ns" 1.000000)
					( Origin gBackEnd )
				)
				( member ( signalRef "@baseboard_fab2_lib.baseboard_fab2(sch_1):p3e_cpu0_pe3_ocp_rxn(1)") )
				( member ( signalRef "@baseboard_fab2_lib.baseboard_fab2(sch_1):p3e_cpu0_pe3_ocp_rxp(1)") )
				( objectStatus "P3E_CPU0_PE3_OCP_RX<1>" )
			)
			( differentialPair "@crescent_city_bb_fab1_lib.crescent_city_bb_fab1(sch_1):\P3E_CPU0_PE3_OCP_RX\(2)"
				( memberType ( signal ) )
				( attribute "DIFFP_PHASE_TOL" "5 mil"
					( Units "uPhaseTol" "ns" 1.000000)
					( Origin gBackEnd )
				)
				( member ( signalRef "@baseboard_fab2_lib.baseboard_fab2(sch_1):p3e_cpu0_pe3_ocp_rxn(2)") )
				( member ( signalRef "@baseboard_fab2_lib.baseboard_fab2(sch_1):p3e_cpu0_pe3_ocp_rxp(2)") )
				( objectStatus "P3E_CPU0_PE3_OCP_RX<2>" )
			)
			( differentialPair "@crescent_city_bb_fab1_lib.crescent_city_bb_fab1(sch_1):\P3E_CPU0_PE3_OCP_RX\(3)"
				( memberType ( signal ) )
				( attribute "DIFFP_PHASE_TOL" "5 mil"
					( Units "uPhaseTol" "ns" 1.000000)
					( Origin gBackEnd )
				)
				( member ( signalRef "@baseboard_fab2_lib.baseboard_fab2(sch_1):p3e_cpu0_pe3_ocp_rxn(3)") )
				( member ( signalRef "@baseboard_fab2_lib.baseboard_fab2(sch_1):p3e_cpu0_pe3_ocp_rxp(3)") )
				( objectStatus "P3E_CPU0_PE3_OCP_RX<3>" )
			)
			( differentialPair "@crescent_city_bb_fab1_lib.crescent_city_bb_fab1(sch_1):\P3E_CPU0_PE3_OCP_RX\(6)"
				( memberType ( signal ) )
				( attribute "DIFFP_PHASE_TOL" "5 mil"
					( Units "uPhaseTol" "ns" 1.000000)
					( Origin gBackEnd )
				)
				( member ( signalRef "@baseboard_fab2_lib.baseboard_fab2(sch_1):p3e_cpu0_pe3_ocp_rxn(6)") )
				( member ( signalRef "@baseboard_fab2_lib.baseboard_fab2(sch_1):p3e_cpu0_pe3_ocp_rxp(6)") )
				( objectStatus "P3E_CPU0_PE3_OCP_RX<6>" )
			)
			( differentialPair "@crescent_city_bb_fab1_lib.crescent_city_bb_fab1(sch_1):\P3E_CPU0_PE3_OCP_RX\(7)"
				( memberType ( signal ) )
				( attribute "DIFFP_PHASE_TOL" "5 mil"
					( Units "uPhaseTol" "ns" 1.000000)
					( Origin gBackEnd )
				)
				( member ( signalRef "@baseboard_fab2_lib.baseboard_fab2(sch_1):p3e_cpu0_pe3_ocp_rxn(7)") )
				( member ( signalRef "@baseboard_fab2_lib.baseboard_fab2(sch_1):p3e_cpu0_pe3_ocp_rxp(7)") )
				( objectStatus "P3E_CPU0_PE3_OCP_RX<7>" )
			)
			( differentialPair "@crescent_city_bb_fab1_lib.crescent_city_bb_fab1(sch_1):\P3E_CPU0_PE3_OCP_RX\(8)"
				( memberType ( signal ) )
				( attribute "DIFFP_PHASE_TOL" "5 mil"
					( Units "uPhaseTol" "ns" 1.000000)
					( Origin gBackEnd )
				)
				( member ( signalRef "@baseboard_fab2_lib.baseboard_fab2(sch_1):p3e_cpu0_pe3_ocp_rxn(8)") )
				( member ( signalRef "@baseboard_fab2_lib.baseboard_fab2(sch_1):p3e_cpu0_pe3_ocp_rxp(8)") )
				( objectStatus "P3E_CPU0_PE3_OCP_RX<8>" )
			)
			( differentialPair "@crescent_city_bb_fab1_lib.crescent_city_bb_fab1(sch_1):\P3E_CPU0_PE3_OCP_RX\(9)"
				( memberType ( signal ) )
				( attribute "DIFFP_PHASE_TOL" "5 mil"
					( Units "uPhaseTol" "ns" 1.000000)
					( Origin gBackEnd )
				)
				( member ( signalRef "@baseboard_fab2_lib.baseboard_fab2(sch_1):p3e_cpu0_pe3_ocp_rxn(9)") )
				( member ( signalRef "@baseboard_fab2_lib.baseboard_fab2(sch_1):p3e_cpu0_pe3_ocp_rxp(9)") )
				( objectStatus "P3E_CPU0_PE3_OCP_RX<9>" )
			)
			( differentialPair "@crescent_city_bb_fab1_lib.crescent_city_bb_fab1(sch_1):\P3E_CPU0_PE3_OCP_RX\(10)"
				( memberType ( signal ) )
				( attribute "DIFFP_PHASE_TOL" "5 mil"
					( Units "uPhaseTol" "ns" 1.000000)
					( Origin gBackEnd )
				)
				( member ( signalRef "@baseboard_fab2_lib.baseboard_fab2(sch_1):p3e_cpu0_pe3_ocp_rxn(10)") )
				( member ( signalRef "@baseboard_fab2_lib.baseboard_fab2(sch_1):p3e_cpu0_pe3_ocp_rxp(10)") )
				( objectStatus "P3E_CPU0_PE3_OCP_RX<10>" )
			)
			( differentialPair "@crescent_city_bb_fab1_lib.crescent_city_bb_fab1(sch_1):\P3E_CPU0_PE3_OCP_RX\(11)"
				( memberType ( signal ) )
				( attribute "DIFFP_PHASE_TOL" "5 mil"
					( Units "uPhaseTol" "ns" 1.000000)
					( Origin gBackEnd )
				)
				( member ( signalRef "@baseboard_fab2_lib.baseboard_fab2(sch_1):p3e_cpu0_pe3_ocp_rxn(11)") )
				( member ( signalRef "@baseboard_fab2_lib.baseboard_fab2(sch_1):p3e_cpu0_pe3_ocp_rxp(11)") )
				( objectStatus "P3E_CPU0_PE3_OCP_RX<11>" )
			)
			( differentialPair "@crescent_city_bb_fab1_lib.crescent_city_bb_fab1(sch_1):\P3E_CPU0_PE3_OCP_RX\(12)"
				( memberType ( signal ) )
				( attribute "DIFFP_PHASE_TOL" "5 mil"
					( Units "uPhaseTol" "ns" 1.000000)
					( Origin gBackEnd )
				)
				( member ( signalRef "@baseboard_fab2_lib.baseboard_fab2(sch_1):p3e_cpu0_pe3_ocp_rxn(12)") )
				( member ( signalRef "@baseboard_fab2_lib.baseboard_fab2(sch_1):p3e_cpu0_pe3_ocp_rxp(12)") )
				( objectStatus "P3E_CPU0_PE3_OCP_RX<12>" )
			)
			( differentialPair "@crescent_city_bb_fab1_lib.crescent_city_bb_fab1(sch_1):\P3E_CPU0_PE3_OCP_RX\(13)"
				( memberType ( signal ) )
				( attribute "DIFFP_PHASE_TOL" "5 mil"
					( Units "uPhaseTol" "ns" 1.000000)
					( Origin gBackEnd )
				)
				( member ( signalRef "@baseboard_fab2_lib.baseboard_fab2(sch_1):p3e_cpu0_pe3_ocp_rxn(13)") )
				( member ( signalRef "@baseboard_fab2_lib.baseboard_fab2(sch_1):p3e_cpu0_pe3_ocp_rxp(13)") )
				( objectStatus "P3E_CPU0_PE3_OCP_RX<13>" )
			)
			( differentialPair "@crescent_city_bb_fab1_lib.crescent_city_bb_fab1(sch_1):\P3E_CPU0_PE3_OCP_RX\(14)"
				( memberType ( signal ) )
				( attribute "DIFFP_PHASE_TOL" "5 mil"
					( Units "uPhaseTol" "ns" 1.000000)
					( Origin gBackEnd )
				)
				( member ( signalRef "@baseboard_fab2_lib.baseboard_fab2(sch_1):p3e_cpu0_pe3_ocp_rxn(14)") )
				( member ( signalRef "@baseboard_fab2_lib.baseboard_fab2(sch_1):p3e_cpu0_pe3_ocp_rxp(14)") )
				( objectStatus "P3E_CPU0_PE3_OCP_RX<14>" )
			)
			( differentialPair "@crescent_city_bb_fab1_lib.crescent_city_bb_fab1(sch_1):\P3E_CPU0_PE3_OCP_RX\(15)"
				( memberType ( signal ) )
				( attribute "DIFFP_PHASE_TOL" "5 mil"
					( Units "uPhaseTol" "ns" 1.000000)
					( Origin gBackEnd )
				)
				( member ( signalRef "@baseboard_fab2_lib.baseboard_fab2(sch_1):p3e_cpu0_pe3_ocp_rxn(15)") )
				( member ( signalRef "@baseboard_fab2_lib.baseboard_fab2(sch_1):p3e_cpu0_pe3_ocp_rxp(15)") )
				( objectStatus "P3E_CPU0_PE3_OCP_RX<15>" )
			)
			( differentialPair "@crescent_city_bb_fab1_lib.crescent_city_bb_fab1(sch_1):\DP_P3E_CPU1_PE3_MP_C\(10)"
				( memberType ( signal ) )
				( member ( electricalNetRef "@crescent_city_bb_fab1_lib.crescent_city_bb_fab1(sch_1):p3e_cpu1_pe3_mp_c_txn(10)") )
				( member ( electricalNetRef "@crescent_city_bb_fab1_lib.crescent_city_bb_fab1(sch_1):p3e_cpu1_pe3_mp_c_txp(10)") )
				( objectStatus "DP_P3E_CPU1_PE3_MP_C<10>" )
			)
			( differentialPair "@crescent_city_bb_fab1_lib.crescent_city_bb_fab1(sch_1):\DP_USB3_P01_RX\"
				( memberType ( signal ) )
				( attribute "DIFFP_GATHER_CONTROL" "IGNORE"
					( Origin gBackEnd )
				)
				( attribute "DIFFP_UNCOUPLED_LENGTH" "380.00"
					( Origin gBackEnd )
				)
				( attribute "DIFFP_PHASE_TOL" "5 mil"
					( Units "uPhaseTol" "ns" 1.000000)
					( Origin gBackEnd )
				)
				( member ( electricalNetRef "@crescent_city_bb_fab1_lib.crescent_city_bb_fab1(sch_1):usb3_p01_fb_rxn") )
				( member ( electricalNetRef "@crescent_city_bb_fab1_lib.crescent_city_bb_fab1(sch_1):usb3_p01_fb_rxp") )
				( objectStatus "DP_USB3_P01_RX" )
			)
			( differentialPair "@crescent_city_bb_fab1_lib.crescent_city_bb_fab1(sch_1):\P3E_CPU0_PE3_OCP_RXN\(4)"
				( memberType ( signal ) )
				( attribute "DIFFP_PHASE_TOL" "5 mil"
					( Units "uPhaseTol" "ns" 1.000000)
					( Origin gBackEnd )
				)
				( member ( signalRef "@baseboard_fab2_lib.baseboard_fab2(sch_1):p3e_cpu0_pe3_ocp_rxn(4)") )
				( member ( signalRef "@baseboard_fab2_lib.baseboard_fab2(sch_1):p3e_cpu0_pe3_ocp_rxp(4)") )
				( objectStatus "P3E_CPU0_PE3_OCP_RX<4>" )
			)
			( differentialPair "@crescent_city_bb_fab1_lib.crescent_city_bb_fab1(sch_1):\P3E_CPU0_PE3_OCP_RXN\(5)"
				( memberType ( signal ) )
				( attribute "DIFFP_PHASE_TOL" "5 mil"
					( Units "uPhaseTol" "ns" 1.000000)
					( Origin gBackEnd )
				)
				( member ( signalRef "@baseboard_fab2_lib.baseboard_fab2(sch_1):p3e_cpu0_pe3_ocp_rxn(5)") )
				( member ( signalRef "@baseboard_fab2_lib.baseboard_fab2(sch_1):p3e_cpu0_pe3_ocp_rxp(5)") )
				( objectStatus "P3E_CPU0_PE3_OCP_RX<5>" )
			)
			( differentialPair "@crescent_city_bb_fab1_lib.crescent_city_bb_fab1(sch_1):\P3E_CPU0_PE1_PCH_RX\(10)"
				( memberType ( signal ) )
				( attribute "DIFFP_PHASE_TOL" "5 mil"
					( Units "uPhaseTol" "ns" 1.000000)
					( Origin gBackEnd )
				)
				( member ( electricalNetRef "@crescent_city_bb_fab1_lib.crescent_city_bb_fab1(sch_1):p3e_cpu0_pe1_pch_rxn(10)") )
				( member ( electricalNetRef "@crescent_city_bb_fab1_lib.crescent_city_bb_fab1(sch_1):p3e_cpu0_pe1_pch_rxp(10)") )
				( objectStatus "P3E_CPU0_PE1_PCH_RX<10>" )
			)
			( differentialPair "@crescent_city_bb_fab1_lib.crescent_city_bb_fab1(sch_1):\P3E_CPU0_PE1_PCH_RX\(11)"
				( memberType ( signal ) )
				( attribute "DIFFP_PHASE_TOL" "5 mil"
					( Units "uPhaseTol" "ns" 1.000000)
					( Origin gBackEnd )
				)
				( member ( electricalNetRef "@crescent_city_bb_fab1_lib.crescent_city_bb_fab1(sch_1):p3e_cpu0_pe1_pch_rxn(11)") )
				( member ( electricalNetRef "@crescent_city_bb_fab1_lib.crescent_city_bb_fab1(sch_1):p3e_cpu0_pe1_pch_rxp(11)") )
				( objectStatus "P3E_CPU0_PE1_PCH_RX<11>" )
			)
			( differentialPair "@crescent_city_bb_fab1_lib.crescent_city_bb_fab1(sch_1):\P3E_CPU0_PE1_PCH_RX\(12)"
				( memberType ( signal ) )
				( attribute "DIFFP_PHASE_TOL" "5 mil"
					( Units "uPhaseTol" "ns" 1.000000)
					( Origin gBackEnd )
				)
				( member ( electricalNetRef "@crescent_city_bb_fab1_lib.crescent_city_bb_fab1(sch_1):p3e_cpu0_pe1_pch_rxn(12)") )
				( member ( electricalNetRef "@crescent_city_bb_fab1_lib.crescent_city_bb_fab1(sch_1):p3e_cpu0_pe1_pch_rxp(12)") )
				( objectStatus "P3E_CPU0_PE1_PCH_RX<12>" )
			)
			( differentialPair "@crescent_city_bb_fab1_lib.crescent_city_bb_fab1(sch_1):\P3E_CPU0_PE1_PCH_RX\(13)"
				( memberType ( signal ) )
				( attribute "DIFFP_PHASE_TOL" "5 mil"
					( Units "uPhaseTol" "ns" 1.000000)
					( Origin gBackEnd )
				)
				( member ( electricalNetRef "@crescent_city_bb_fab1_lib.crescent_city_bb_fab1(sch_1):p3e_cpu0_pe1_pch_rxn(13)") )
				( member ( electricalNetRef "@crescent_city_bb_fab1_lib.crescent_city_bb_fab1(sch_1):p3e_cpu0_pe1_pch_rxp(13)") )
				( objectStatus "P3E_CPU0_PE1_PCH_RX<13>" )
			)
			( differentialPair "@crescent_city_bb_fab1_lib.crescent_city_bb_fab1(sch_1):\P3E_CPU0_PE1_PCH_RX\(14)"
				( memberType ( signal ) )
				( attribute "DIFFP_PHASE_TOL" "5 mil"
					( Units "uPhaseTol" "ns" 1.000000)
					( Origin gBackEnd )
				)
				( member ( electricalNetRef "@crescent_city_bb_fab1_lib.crescent_city_bb_fab1(sch_1):p3e_cpu0_pe1_pch_rxn(14)") )
				( member ( electricalNetRef "@crescent_city_bb_fab1_lib.crescent_city_bb_fab1(sch_1):p3e_cpu0_pe1_pch_rxp(14)") )
				( objectStatus "P3E_CPU0_PE1_PCH_RX<14>" )
			)
			( differentialPair "@crescent_city_bb_fab1_lib.crescent_city_bb_fab1(sch_1):\P3E_CPU0_PE1_PCH_RX\(15)"
				( memberType ( signal ) )
				( attribute "DIFFP_PHASE_TOL" "5 mil"
					( Units "uPhaseTol" "ns" 1.000000)
					( Origin gBackEnd )
				)
				( member ( electricalNetRef "@crescent_city_bb_fab1_lib.crescent_city_bb_fab1(sch_1):p3e_cpu0_pe1_pch_rxn(15)") )
				( member ( electricalNetRef "@crescent_city_bb_fab1_lib.crescent_city_bb_fab1(sch_1):p3e_cpu0_pe1_pch_rxp(15)") )
				( objectStatus "P3E_CPU0_PE1_PCH_RX<15>" )
			)
			( differentialPair "@crescent_city_bb_fab1_lib.crescent_city_bb_fab1(sch_1):\DP_P3E_CPU1_PE3_MP_C\(8)"
				( memberType ( signal ) )
				( member ( electricalNetRef "@crescent_city_bb_fab1_lib.crescent_city_bb_fab1(sch_1):p3e_cpu1_pe3_mp_c_txn(8)") )
				( member ( electricalNetRef "@crescent_city_bb_fab1_lib.crescent_city_bb_fab1(sch_1):p3e_cpu1_pe3_mp_c_txp(8)") )
				( objectStatus "DP_P3E_CPU1_PE3_MP_C<8>" )
			)
			( differentialPair "@crescent_city_bb_fab1_lib.crescent_city_bb_fab1(sch_1):\PE_PCH_SPRV_RX_D\"
				( memberType ( signal ) )
				( member ( electricalNetRef "@crescent_city_bb_fab1_lib.crescent_city_bb_fab1(sch_1):pe_pch_sprv_rx_c_dn") )
				( member ( electricalNetRef "@crescent_city_bb_fab1_lib.crescent_city_bb_fab1(sch_1):pe_pch_sprv_rx_c_dp") )
				( objectStatus "DP_PE_PCH_SPRV_RX" )
			)
			( differentialPair "@crescent_city_bb_fab1_lib.crescent_city_bb_fab1(sch_1):\DP_5\"
				( memberType ( signal ) )
				( electricalCSetRef "@crescent_city_bb_fab1_lib.crescent_city_bb_fab1(sch_1):\PCIE_C_D\" )
				( member ( electricalNetRef "@crescent_city_bb_fab1_lib.crescent_city_bb_fab1(sch_1):p3e_cpu0_pe1_ss_rxn(7)") )
				( member ( electricalNetRef "@crescent_city_bb_fab1_lib.crescent_city_bb_fab1(sch_1):p3e_cpu0_pe1_ss_rxp(7)") )
				( objectStatus "DP1_P3E_CPU0_PE1_PCH_RXN(7)" )
			)
			( differentialPair "@crescent_city_bb_fab1_lib.crescent_city_bb_fab1(sch_1):\DP_6\"
				( memberType ( signal ) )
				( electricalCSetRef "@crescent_city_bb_fab1_lib.crescent_city_bb_fab1(sch_1):\PCIE_DEVICE_C\" )
				( member ( electricalNetRef "@crescent_city_bb_fab1_lib.crescent_city_bb_fab1(sch_1):p3e_cpu0_pe1_pch_c_txn(8)") )
				( member ( electricalNetRef "@crescent_city_bb_fab1_lib.crescent_city_bb_fab1(sch_1):p3e_cpu0_pe1_pch_c_txp(8)") )
				( objectStatus "DP1_P3E_CPU0_PE1_PCH_TXN(8)" )
			)
			( differentialPair "@crescent_city_bb_fab1_lib.crescent_city_bb_fab1(sch_1):\DP_7\"
				( memberType ( signal ) )
				( electricalCSetRef "@crescent_city_bb_fab1_lib.crescent_city_bb_fab1(sch_1):\PCIE_DEVICE_C\" )
				( member ( electricalNetRef "@crescent_city_bb_fab1_lib.crescent_city_bb_fab1(sch_1):p3e_cpu0_pe1_pch_c_txn(9)") )
				( member ( electricalNetRef "@crescent_city_bb_fab1_lib.crescent_city_bb_fab1(sch_1):p3e_cpu0_pe1_pch_c_txp(9)") )
				( objectStatus "DP1_P3E_CPU0_PE1_PCH_TXN(9)" )
			)
			( differentialPair "@crescent_city_bb_fab1_lib.crescent_city_bb_fab1(sch_1):\DP_8\"
				( memberType ( signal ) )
				( electricalCSetRef "@crescent_city_bb_fab1_lib.crescent_city_bb_fab1(sch_1):\PCIE_DEVICE_C\" )
				( member ( electricalNetRef "@crescent_city_bb_fab1_lib.crescent_city_bb_fab1(sch_1):p3e_cpu0_pe1_pch_c_txn(10)") )
				( member ( electricalNetRef "@crescent_city_bb_fab1_lib.crescent_city_bb_fab1(sch_1):p3e_cpu0_pe1_pch_c_txp(10)") )
				( objectStatus "DP1_P3E_CPU0_PE1_PCH_TXN(10)" )
			)
			( differentialPair "@crescent_city_bb_fab1_lib.crescent_city_bb_fab1(sch_1):\DP_9\"
				( memberType ( signal ) )
				( electricalCSetRef "@crescent_city_bb_fab1_lib.crescent_city_bb_fab1(sch_1):\PCIE_DEVICE_C\" )
				( member ( electricalNetRef "@crescent_city_bb_fab1_lib.crescent_city_bb_fab1(sch_1):p3e_cpu0_pe1_pch_c_txn(11)") )
				( member ( electricalNetRef "@crescent_city_bb_fab1_lib.crescent_city_bb_fab1(sch_1):p3e_cpu0_pe1_pch_c_txp(11)") )
				( objectStatus "DP1_P3E_CPU0_PE1_PCH_TXN(11)" )
			)
			( differentialPair "@crescent_city_bb_fab1_lib.crescent_city_bb_fab1(sch_1):\DP_10\"
				( memberType ( signal ) )
				( electricalCSetRef "@crescent_city_bb_fab1_lib.crescent_city_bb_fab1(sch_1):\PCIE_DEVICE_C\" )
				( member ( electricalNetRef "@crescent_city_bb_fab1_lib.crescent_city_bb_fab1(sch_1):p3e_cpu0_pe1_pch_c_txn(12)") )
				( member ( electricalNetRef "@crescent_city_bb_fab1_lib.crescent_city_bb_fab1(sch_1):p3e_cpu0_pe1_pch_c_txp(12)") )
				( objectStatus "DP1_P3E_CPU0_PE1_PCH_TXN(12)" )
			)
			( differentialPair "@crescent_city_bb_fab1_lib.crescent_city_bb_fab1(sch_1):\DP_11\"
				( memberType ( signal ) )
				( electricalCSetRef "@crescent_city_bb_fab1_lib.crescent_city_bb_fab1(sch_1):\PCIE_DEVICE_C\" )
				( member ( electricalNetRef "@crescent_city_bb_fab1_lib.crescent_city_bb_fab1(sch_1):p3e_cpu0_pe1_pch_c_txn(13)") )
				( member ( electricalNetRef "@crescent_city_bb_fab1_lib.crescent_city_bb_fab1(sch_1):p3e_cpu0_pe1_pch_c_txp(13)") )
				( objectStatus "DP1_P3E_CPU0_PE1_PCH_TXN(13)" )
			)
			( differentialPair "@crescent_city_bb_fab1_lib.crescent_city_bb_fab1(sch_1):\DP_12\"
				( memberType ( signal ) )
				( electricalCSetRef "@crescent_city_bb_fab1_lib.crescent_city_bb_fab1(sch_1):\PCIE_DEVICE_C\" )
				( member ( electricalNetRef "@crescent_city_bb_fab1_lib.crescent_city_bb_fab1(sch_1):p3e_cpu0_pe1_pch_c_txn(14)") )
				( member ( electricalNetRef "@crescent_city_bb_fab1_lib.crescent_city_bb_fab1(sch_1):p3e_cpu0_pe1_pch_c_txp(14)") )
				( objectStatus "DP1_P3E_CPU0_PE1_PCH_TXN(14)" )
			)
			( differentialPair "@crescent_city_bb_fab1_lib.crescent_city_bb_fab1(sch_1):\DP_13\"
				( memberType ( signal ) )
				( electricalCSetRef "@crescent_city_bb_fab1_lib.crescent_city_bb_fab1(sch_1):\PCIE_DEVICE_C\" )
				( member ( electricalNetRef "@crescent_city_bb_fab1_lib.crescent_city_bb_fab1(sch_1):p3e_cpu0_pe1_pch_c_txn(15)") )
				( member ( electricalNetRef "@crescent_city_bb_fab1_lib.crescent_city_bb_fab1(sch_1):p3e_cpu0_pe1_pch_c_txp(15)") )
				( objectStatus "DP1_P3E_CPU0_PE1_PCH_TXN(15)" )
			)
			( differentialPair "@crescent_city_bb_fab1_lib.crescent_city_bb_fab1(sch_1):\DP_15\"
				( memberType ( signal ) )
				( electricalCSetRef "@crescent_city_bb_fab1_lib.crescent_city_bb_fab1(sch_1):\PCIE_C_D\" )
				( attribute "DIFFP_UNCOUPLED_LENGTH" "550.00"
					( Origin gBackEnd )
				)
				( attribute "DIFFP_PHASE_TOL" "5 mil"
					( Units "uPhaseTol" "ns" 1.000000)
					( Origin gBackEnd )
				)
				( member ( electricalNetRef "@crescent_city_bb_fab1_lib.crescent_city_bb_fab1(sch_1):p3e_cpu0_pe1_pch_txn(0)") )
				( member ( electricalNetRef "@crescent_city_bb_fab1_lib.crescent_city_bb_fab1(sch_1):p3e_cpu0_pe1_pch_txp(0)") )
				( objectStatus "DP1_P3E_CPU0_PE1_SS_TXN(1)" )
			)
			( differentialPair "@crescent_city_bb_fab1_lib.crescent_city_bb_fab1(sch_1):\DP_16\"
				( memberType ( signal ) )
				( electricalCSetRef "@crescent_city_bb_fab1_lib.crescent_city_bb_fab1(sch_1):\PCIE_C_D\" )
				( attribute "DIFFP_UNCOUPLED_LENGTH" "550.00"
					( Origin gBackEnd )
				)
				( attribute "DIFFP_PHASE_TOL" "5 mil"
					( Units "uPhaseTol" "ns" 1.000000)
					( Origin gBackEnd )
				)
				( member ( electricalNetRef "@crescent_city_bb_fab1_lib.crescent_city_bb_fab1(sch_1):p3e_cpu0_pe1_pch_txn(1)") )
				( member ( electricalNetRef "@crescent_city_bb_fab1_lib.crescent_city_bb_fab1(sch_1):p3e_cpu0_pe1_pch_txp(1)") )
				( objectStatus "DP1_P3E_CPU0_PE1_SS_TXN(2)" )
			)
			( differentialPair "@crescent_city_bb_fab1_lib.crescent_city_bb_fab1(sch_1):\DP_17\"
				( memberType ( signal ) )
				( electricalCSetRef "@crescent_city_bb_fab1_lib.crescent_city_bb_fab1(sch_1):\PCIE_C_D\" )
				( attribute "DIFFP_UNCOUPLED_LENGTH" "540.00"
					( Origin gBackEnd )
				)
				( attribute "DIFFP_PHASE_TOL" "5 mil"
					( Units "uPhaseTol" "ns" 1.000000)
					( Origin gBackEnd )
				)
				( member ( electricalNetRef "@crescent_city_bb_fab1_lib.crescent_city_bb_fab1(sch_1):p3e_cpu0_pe1_pch_txn(2)") )
				( member ( electricalNetRef "@crescent_city_bb_fab1_lib.crescent_city_bb_fab1(sch_1):p3e_cpu0_pe1_pch_txp(2)") )
				( objectStatus "DP1_P3E_CPU0_PE1_SS_TXN(3)" )
			)
			( differentialPair "@crescent_city_bb_fab1_lib.crescent_city_bb_fab1(sch_1):\DP_18\"
				( memberType ( signal ) )
				( electricalCSetRef "@crescent_city_bb_fab1_lib.crescent_city_bb_fab1(sch_1):\PCIE_C_D\" )
				( attribute "DIFFP_UNCOUPLED_LENGTH" "460.00"
					( Origin gBackEnd )
				)
				( attribute "DIFFP_PHASE_TOL" "5 mil"
					( Units "uPhaseTol" "ns" 1.000000)
					( Origin gBackEnd )
				)
				( member ( electricalNetRef "@crescent_city_bb_fab1_lib.crescent_city_bb_fab1(sch_1):p3e_cpu0_pe1_pch_txn(3)") )
				( member ( electricalNetRef "@crescent_city_bb_fab1_lib.crescent_city_bb_fab1(sch_1):p3e_cpu0_pe1_pch_txp(3)") )
				( objectStatus "DP1_P3E_CPU0_PE1_SS_TXN(4)" )
			)
			( differentialPair "@crescent_city_bb_fab1_lib.crescent_city_bb_fab1(sch_1):\DP_19\"
				( memberType ( signal ) )
				( electricalCSetRef "@crescent_city_bb_fab1_lib.crescent_city_bb_fab1(sch_1):\PCIE_C_D\" )
				( attribute "DIFFP_UNCOUPLED_LENGTH" "485.00"
					( Origin gBackEnd )
				)
				( attribute "DIFFP_PHASE_TOL" "5 mil"
					( Units "uPhaseTol" "ns" 1.000000)
					( Origin gBackEnd )
				)
				( member ( electricalNetRef "@crescent_city_bb_fab1_lib.crescent_city_bb_fab1(sch_1):p3e_cpu0_pe1_pch_txn(4)") )
				( member ( electricalNetRef "@crescent_city_bb_fab1_lib.crescent_city_bb_fab1(sch_1):p3e_cpu0_pe1_pch_txp(4)") )
				( objectStatus "DP1_P3E_CPU0_PE1_SS_TXN(5)" )
			)
			( differentialPair "@crescent_city_bb_fab1_lib.crescent_city_bb_fab1(sch_1):\DP_20\"
				( memberType ( signal ) )
				( electricalCSetRef "@crescent_city_bb_fab1_lib.crescent_city_bb_fab1(sch_1):\PCIE_C_D\" )
				( attribute "DIFFP_UNCOUPLED_LENGTH" "450.00"
					( Origin gBackEnd )
				)
				( attribute "DIFFP_PHASE_TOL" "5 mil"
					( Units "uPhaseTol" "ns" 1.000000)
					( Origin gBackEnd )
				)
				( member ( electricalNetRef "@crescent_city_bb_fab1_lib.crescent_city_bb_fab1(sch_1):p3e_cpu0_pe1_pch_txn(5)") )
				( member ( electricalNetRef "@crescent_city_bb_fab1_lib.crescent_city_bb_fab1(sch_1):p3e_cpu0_pe1_pch_txp(5)") )
				( objectStatus "DP1_P3E_CPU0_PE1_SS_TXN(6)" )
			)
			( differentialPair "@crescent_city_bb_fab1_lib.crescent_city_bb_fab1(sch_1):\DP_21\"
				( memberType ( signal ) )
				( electricalCSetRef "@crescent_city_bb_fab1_lib.crescent_city_bb_fab1(sch_1):\PCIE_C_D\" )
				( attribute "DIFFP_UNCOUPLED_LENGTH" "420.00"
					( Origin gBackEnd )
				)
				( attribute "DIFFP_PHASE_TOL" "5 mil"
					( Units "uPhaseTol" "ns" 1.000000)
					( Origin gBackEnd )
				)
				( member ( electricalNetRef "@crescent_city_bb_fab1_lib.crescent_city_bb_fab1(sch_1):p3e_cpu0_pe1_pch_txn(6)") )
				( member ( electricalNetRef "@crescent_city_bb_fab1_lib.crescent_city_bb_fab1(sch_1):p3e_cpu0_pe1_pch_txp(6)") )
				( objectStatus "DP1_P3E_CPU0_PE1_SS_TXN(7)" )
			)
			( differentialPair "@crescent_city_bb_fab1_lib.crescent_city_bb_fab1(sch_1):\DP_22\"
				( memberType ( signal ) )
				( electricalCSetRef "@crescent_city_bb_fab1_lib.crescent_city_bb_fab1(sch_1):\PCIE_C_D\" )
				( attribute "DIFFP_UNCOUPLED_LENGTH" "555.00"
					( Origin gBackEnd )
				)
				( attribute "DIFFP_PHASE_TOL" "5 mil"
					( Units "uPhaseTol" "ns" 1.000000)
					( Origin gBackEnd )
				)
				( member ( electricalNetRef "@crescent_city_bb_fab1_lib.crescent_city_bb_fab1(sch_1):p3e_cpu0_pe1_pch_txn(7)") )
				( member ( electricalNetRef "@crescent_city_bb_fab1_lib.crescent_city_bb_fab1(sch_1):p3e_cpu0_pe1_pch_txp(7)") )
				( objectStatus "DP1_P3E_CPU0_PE2_SS_TXN(0)" )
			)
			( differentialPair "@crescent_city_bb_fab1_lib.crescent_city_bb_fab1(sch_1):\DP_23\"
				( memberType ( signal ) )
				( electricalCSetRef "@crescent_city_bb_fab1_lib.crescent_city_bb_fab1(sch_1):\PCIE_SLOT\" )
				( member ( electricalNetRef "@crescent_city_bb_fab1_lib.crescent_city_bb_fab1(sch_1):p3e_cpu0_pe2_ss_c_txn(0)") )
				( member ( electricalNetRef "@crescent_city_bb_fab1_lib.crescent_city_bb_fab1(sch_1):p3e_cpu0_pe2_ss_c_txp(0)") )
				( objectStatus "DP1_P3E_CPU0_PE2_SS_TXN(1)" )
			)
			( differentialPair "@crescent_city_bb_fab1_lib.crescent_city_bb_fab1(sch_1):\DP_24\"
				( memberType ( signal ) )
				( electricalCSetRef "@crescent_city_bb_fab1_lib.crescent_city_bb_fab1(sch_1):\PCIE_SLOT\" )
				( member ( electricalNetRef "@crescent_city_bb_fab1_lib.crescent_city_bb_fab1(sch_1):p3e_cpu0_pe2_ss_c_txn(1)") )
				( member ( electricalNetRef "@crescent_city_bb_fab1_lib.crescent_city_bb_fab1(sch_1):p3e_cpu0_pe2_ss_c_txp(1)") )
				( objectStatus "DP1_P3E_CPU0_PE2_SS_TXN(2)" )
			)
			( differentialPair "@crescent_city_bb_fab1_lib.crescent_city_bb_fab1(sch_1):\DP_25\"
				( memberType ( signal ) )
				( electricalCSetRef "@crescent_city_bb_fab1_lib.crescent_city_bb_fab1(sch_1):\PCIE_SLOT\" )
				( member ( electricalNetRef "@crescent_city_bb_fab1_lib.crescent_city_bb_fab1(sch_1):p3e_cpu0_pe2_ss_c_txn(2)") )
				( member ( electricalNetRef "@crescent_city_bb_fab1_lib.crescent_city_bb_fab1(sch_1):p3e_cpu0_pe2_ss_c_txp(2)") )
				( objectStatus "DP1_P3E_CPU0_PE2_SS_TXN(3)" )
			)
			( differentialPair "@crescent_city_bb_fab1_lib.crescent_city_bb_fab1(sch_1):\DP_26\"
				( memberType ( signal ) )
				( electricalCSetRef "@crescent_city_bb_fab1_lib.crescent_city_bb_fab1(sch_1):\PCIE_SLOT\" )
				( member ( electricalNetRef "@crescent_city_bb_fab1_lib.crescent_city_bb_fab1(sch_1):p3e_cpu0_pe2_ss_c_txn(3)") )
				( member ( electricalNetRef "@crescent_city_bb_fab1_lib.crescent_city_bb_fab1(sch_1):p3e_cpu0_pe2_ss_c_txp(3)") )
				( objectStatus "DP1_P3E_CPU0_PE2_SS_TXN(4)" )
			)
			( differentialPair "@crescent_city_bb_fab1_lib.crescent_city_bb_fab1(sch_1):\DP_27\"
				( memberType ( signal ) )
				( electricalCSetRef "@crescent_city_bb_fab1_lib.crescent_city_bb_fab1(sch_1):\PCIE_SLOT\" )
				( member ( electricalNetRef "@crescent_city_bb_fab1_lib.crescent_city_bb_fab1(sch_1):p3e_cpu0_pe2_ss_c_txn(4)") )
				( member ( electricalNetRef "@crescent_city_bb_fab1_lib.crescent_city_bb_fab1(sch_1):p3e_cpu0_pe2_ss_c_txp(4)") )
				( objectStatus "DP1_P3E_CPU0_PE2_SS_TXN(5)" )
			)
			( differentialPair "@crescent_city_bb_fab1_lib.crescent_city_bb_fab1(sch_1):\DP_28\"
				( memberType ( signal ) )
				( electricalCSetRef "@crescent_city_bb_fab1_lib.crescent_city_bb_fab1(sch_1):\PCIE_SLOT\" )
				( member ( electricalNetRef "@crescent_city_bb_fab1_lib.crescent_city_bb_fab1(sch_1):p3e_cpu0_pe2_ss_c_txn(5)") )
				( member ( electricalNetRef "@crescent_city_bb_fab1_lib.crescent_city_bb_fab1(sch_1):p3e_cpu0_pe2_ss_c_txp(5)") )
				( objectStatus "DP1_P3E_CPU0_PE2_SS_TXN(6)" )
			)
			( differentialPair "@crescent_city_bb_fab1_lib.crescent_city_bb_fab1(sch_1):\DP_29\"
				( memberType ( signal ) )
				( electricalCSetRef "@crescent_city_bb_fab1_lib.crescent_city_bb_fab1(sch_1):\PCIE_SLOT\" )
				( member ( electricalNetRef "@crescent_city_bb_fab1_lib.crescent_city_bb_fab1(sch_1):p3e_cpu0_pe2_ss_c_txn(6)") )
				( member ( electricalNetRef "@crescent_city_bb_fab1_lib.crescent_city_bb_fab1(sch_1):p3e_cpu0_pe2_ss_c_txp(6)") )
				( objectStatus "DP1_P3E_CPU0_PE2_SS_TXN(7)" )
			)
			( differentialPair "@crescent_city_bb_fab1_lib.crescent_city_bb_fab1(sch_1):\DP_30\"
				( memberType ( signal ) )
				( electricalCSetRef "@crescent_city_bb_fab1_lib.crescent_city_bb_fab1(sch_1):\PCIE_SLOT\" )
				( member ( electricalNetRef "@crescent_city_bb_fab1_lib.crescent_city_bb_fab1(sch_1):p3e_cpu0_pe2_ss_c_txn(7)") )
				( member ( electricalNetRef "@crescent_city_bb_fab1_lib.crescent_city_bb_fab1(sch_1):p3e_cpu0_pe2_ss_c_txp(7)") )
				( objectStatus "DP1_P3E_CPU0_PE2_SS_TXN(8)" )
			)
			( differentialPair "@crescent_city_bb_fab1_lib.crescent_city_bb_fab1(sch_1):\DP_31\"
				( memberType ( signal ) )
				( electricalCSetRef "@crescent_city_bb_fab1_lib.crescent_city_bb_fab1(sch_1):\PCIE_SLOT\" )
				( member ( electricalNetRef "@crescent_city_bb_fab1_lib.crescent_city_bb_fab1(sch_1):p3e_cpu0_pe2_ss_c_txn(8)") )
				( member ( electricalNetRef "@crescent_city_bb_fab1_lib.crescent_city_bb_fab1(sch_1):p3e_cpu0_pe2_ss_c_txp(8)") )
				( objectStatus "DP1_P3E_CPU0_PE2_SS_TXN(9)" )
			)
			( differentialPair "@crescent_city_bb_fab1_lib.crescent_city_bb_fab1(sch_1):\DP_32\"
				( memberType ( signal ) )
				( electricalCSetRef "@crescent_city_bb_fab1_lib.crescent_city_bb_fab1(sch_1):\PCIE_SLOT\" )
				( member ( electricalNetRef "@crescent_city_bb_fab1_lib.crescent_city_bb_fab1(sch_1):p3e_cpu0_pe2_ss_c_txn(9)") )
				( member ( electricalNetRef "@crescent_city_bb_fab1_lib.crescent_city_bb_fab1(sch_1):p3e_cpu0_pe2_ss_c_txp(9)") )
				( objectStatus "DP1_P3E_CPU0_PE2_SS_TXN(10)" )
			)
			( differentialPair "@crescent_city_bb_fab1_lib.crescent_city_bb_fab1(sch_1):\DP_33\"
				( memberType ( signal ) )
				( electricalCSetRef "@crescent_city_bb_fab1_lib.crescent_city_bb_fab1(sch_1):\PCIE_SLOT\" )
				( member ( electricalNetRef "@crescent_city_bb_fab1_lib.crescent_city_bb_fab1(sch_1):p3e_cpu0_pe2_ss_c_txn(10)") )
				( member ( electricalNetRef "@crescent_city_bb_fab1_lib.crescent_city_bb_fab1(sch_1):p3e_cpu0_pe2_ss_c_txp(10)") )
				( objectStatus "DP1_P3E_CPU0_PE2_SS_TXN(11)" )
			)
			( differentialPair "@crescent_city_bb_fab1_lib.crescent_city_bb_fab1(sch_1):\DP_34\"
				( memberType ( signal ) )
				( electricalCSetRef "@crescent_city_bb_fab1_lib.crescent_city_bb_fab1(sch_1):\PCIE_SLOT\" )
				( member ( electricalNetRef "@crescent_city_bb_fab1_lib.crescent_city_bb_fab1(sch_1):p3e_cpu0_pe2_ss_c_txn(11)") )
				( member ( electricalNetRef "@crescent_city_bb_fab1_lib.crescent_city_bb_fab1(sch_1):p3e_cpu0_pe2_ss_c_txp(11)") )
				( objectStatus "DP1_P3E_CPU0_PE2_SS_TXN(12)" )
			)
			( differentialPair "@crescent_city_bb_fab1_lib.crescent_city_bb_fab1(sch_1):\DP_35\"
				( memberType ( signal ) )
				( electricalCSetRef "@crescent_city_bb_fab1_lib.crescent_city_bb_fab1(sch_1):\PCIE_SLOT\" )
				( member ( electricalNetRef "@crescent_city_bb_fab1_lib.crescent_city_bb_fab1(sch_1):p3e_cpu0_pe2_ss_c_txn(12)") )
				( member ( electricalNetRef "@crescent_city_bb_fab1_lib.crescent_city_bb_fab1(sch_1):p3e_cpu0_pe2_ss_c_txp(12)") )
				( objectStatus "DP1_P3E_CPU0_PE2_SS_TXN(13)" )
			)
			( differentialPair "@crescent_city_bb_fab1_lib.crescent_city_bb_fab1(sch_1):\DP_36\"
				( memberType ( signal ) )
				( electricalCSetRef "@crescent_city_bb_fab1_lib.crescent_city_bb_fab1(sch_1):\PCIE_SLOT\" )
				( member ( electricalNetRef "@crescent_city_bb_fab1_lib.crescent_city_bb_fab1(sch_1):p3e_cpu0_pe2_ss_c_txn(13)") )
				( member ( electricalNetRef "@crescent_city_bb_fab1_lib.crescent_city_bb_fab1(sch_1):p3e_cpu0_pe2_ss_c_txp(13)") )
				( objectStatus "DP1_P3E_CPU0_PE2_SS_TXN(14)" )
			)
			( differentialPair "@crescent_city_bb_fab1_lib.crescent_city_bb_fab1(sch_1):\DP_37\"
				( memberType ( signal ) )
				( electricalCSetRef "@crescent_city_bb_fab1_lib.crescent_city_bb_fab1(sch_1):\PCIE_SLOT\" )
				( member ( electricalNetRef "@crescent_city_bb_fab1_lib.crescent_city_bb_fab1(sch_1):p3e_cpu0_pe2_ss_c_txn(14)") )
				( member ( electricalNetRef "@crescent_city_bb_fab1_lib.crescent_city_bb_fab1(sch_1):p3e_cpu0_pe2_ss_c_txp(14)") )
				( objectStatus "DP1_P3E_CPU0_PE2_SS_TXN(15)" )
			)
			( differentialPair "@crescent_city_bb_fab1_lib.crescent_city_bb_fab1(sch_1):\DP_38\"
				( memberType ( signal ) )
				( electricalCSetRef "@crescent_city_bb_fab1_lib.crescent_city_bb_fab1(sch_1):\PCIE_SLOT\" )
				( member ( electricalNetRef "@crescent_city_bb_fab1_lib.crescent_city_bb_fab1(sch_1):p3e_cpu0_pe2_ss_c_txn(15)") )
				( member ( electricalNetRef "@crescent_city_bb_fab1_lib.crescent_city_bb_fab1(sch_1):p3e_cpu0_pe2_ss_c_txp(15)") )
				( objectStatus "DP1_P3E_CPU0_PE3_OCP_TXN(0)" )
			)
			( differentialPair "@crescent_city_bb_fab1_lib.crescent_city_bb_fab1(sch_1):\DP_39\"
				( memberType ( signal ) )
				( electricalCSetRef "@crescent_city_bb_fab1_lib.crescent_city_bb_fab1(sch_1):\PCIE_SLOT\" )
				( member ( electricalNetRef "@crescent_city_bb_fab1_lib.crescent_city_bb_fab1(sch_1):p3e_cpu0_pe3_ocp_txn(0)") )
				( member ( electricalNetRef "@crescent_city_bb_fab1_lib.crescent_city_bb_fab1(sch_1):p3e_cpu0_pe3_ocp_txp(0)") )
				( objectStatus "DP1_P3E_CPU0_PE3_OCP_TXN(1)" )
			)
			( differentialPair "@crescent_city_bb_fab1_lib.crescent_city_bb_fab1(sch_1):\DP_40\"
				( memberType ( signal ) )
				( electricalCSetRef "@crescent_city_bb_fab1_lib.crescent_city_bb_fab1(sch_1):\PCIE_SLOT\" )
				( member ( electricalNetRef "@crescent_city_bb_fab1_lib.crescent_city_bb_fab1(sch_1):p3e_cpu0_pe3_ocp_txn(1)") )
				( member ( electricalNetRef "@crescent_city_bb_fab1_lib.crescent_city_bb_fab1(sch_1):p3e_cpu0_pe3_ocp_txp(1)") )
				( objectStatus "DP1_P3E_CPU0_PE3_OCP_TXN(2)" )
			)
			( differentialPair "@crescent_city_bb_fab1_lib.crescent_city_bb_fab1(sch_1):\DP_41\"
				( memberType ( signal ) )
				( electricalCSetRef "@crescent_city_bb_fab1_lib.crescent_city_bb_fab1(sch_1):\PCIE_SLOT\" )
				( member ( electricalNetRef "@crescent_city_bb_fab1_lib.crescent_city_bb_fab1(sch_1):p3e_cpu0_pe3_ocp_txn(2)") )
				( member ( electricalNetRef "@crescent_city_bb_fab1_lib.crescent_city_bb_fab1(sch_1):p3e_cpu0_pe3_ocp_txp(2)") )
				( objectStatus "DP1_P3E_CPU0_PE3_OCP_TXN(3)" )
			)
			( differentialPair "@crescent_city_bb_fab1_lib.crescent_city_bb_fab1(sch_1):\DP_42\"
				( memberType ( signal ) )
				( electricalCSetRef "@crescent_city_bb_fab1_lib.crescent_city_bb_fab1(sch_1):\PCIE_SLOT\" )
				( member ( electricalNetRef "@crescent_city_bb_fab1_lib.crescent_city_bb_fab1(sch_1):p3e_cpu0_pe3_ocp_txn(3)") )
				( member ( electricalNetRef "@crescent_city_bb_fab1_lib.crescent_city_bb_fab1(sch_1):p3e_cpu0_pe3_ocp_txp(3)") )
				( objectStatus "DP1_P3E_CPU0_PE3_OCP_TXN(4)" )
			)
			( differentialPair "@crescent_city_bb_fab1_lib.crescent_city_bb_fab1(sch_1):\DP_43\"
				( memberType ( signal ) )
				( electricalCSetRef "@crescent_city_bb_fab1_lib.crescent_city_bb_fab1(sch_1):\PCIE_SLOT\" )
				( member ( electricalNetRef "@crescent_city_bb_fab1_lib.crescent_city_bb_fab1(sch_1):p3e_cpu0_pe3_ocp_txn(4)") )
				( member ( electricalNetRef "@crescent_city_bb_fab1_lib.crescent_city_bb_fab1(sch_1):p3e_cpu0_pe3_ocp_txp(4)") )
				( objectStatus "DP1_P3E_CPU0_PE3_OCP_TXN(5)" )
			)
			( differentialPair "@crescent_city_bb_fab1_lib.crescent_city_bb_fab1(sch_1):\DP_44\"
				( memberType ( signal ) )
				( electricalCSetRef "@crescent_city_bb_fab1_lib.crescent_city_bb_fab1(sch_1):\PCIE_SLOT\" )
				( member ( electricalNetRef "@crescent_city_bb_fab1_lib.crescent_city_bb_fab1(sch_1):p3e_cpu0_pe3_ocp_txn(5)") )
				( member ( electricalNetRef "@crescent_city_bb_fab1_lib.crescent_city_bb_fab1(sch_1):p3e_cpu0_pe3_ocp_txp(5)") )
				( objectStatus "DP1_P3E_CPU0_PE3_OCP_TXN(6)" )
			)
			( differentialPair "@crescent_city_bb_fab1_lib.crescent_city_bb_fab1(sch_1):\DP_45\"
				( memberType ( signal ) )
				( electricalCSetRef "@crescent_city_bb_fab1_lib.crescent_city_bb_fab1(sch_1):\PCIE_SLOT\" )
				( member ( electricalNetRef "@crescent_city_bb_fab1_lib.crescent_city_bb_fab1(sch_1):p3e_cpu0_pe3_ocp_txn(6)") )
				( member ( electricalNetRef "@crescent_city_bb_fab1_lib.crescent_city_bb_fab1(sch_1):p3e_cpu0_pe3_ocp_txp(6)") )
				( objectStatus "DP1_P3E_CPU0_PE3_OCP_TXN(7)" )
			)
			( differentialPair "@crescent_city_bb_fab1_lib.crescent_city_bb_fab1(sch_1):\DP_46\"
				( memberType ( signal ) )
				( electricalCSetRef "@crescent_city_bb_fab1_lib.crescent_city_bb_fab1(sch_1):\PCIE_SLOT\" )
				( member ( electricalNetRef "@crescent_city_bb_fab1_lib.crescent_city_bb_fab1(sch_1):p3e_cpu0_pe3_ocp_txn(7)") )
				( member ( electricalNetRef "@crescent_city_bb_fab1_lib.crescent_city_bb_fab1(sch_1):p3e_cpu0_pe3_ocp_txp(7)") )
				( objectStatus "DP1_P3E_CPU0_PE3_OCP_TXN(8)" )
			)
			( differentialPair "@crescent_city_bb_fab1_lib.crescent_city_bb_fab1(sch_1):\DP_47\"
				( memberType ( signal ) )
				( electricalCSetRef "@crescent_city_bb_fab1_lib.crescent_city_bb_fab1(sch_1):\PCIE_SLOT\" )
				( member ( electricalNetRef "@crescent_city_bb_fab1_lib.crescent_city_bb_fab1(sch_1):p3e_cpu0_pe3_ocp_txn(8)") )
				( member ( electricalNetRef "@crescent_city_bb_fab1_lib.crescent_city_bb_fab1(sch_1):p3e_cpu0_pe3_ocp_txp(8)") )
				( objectStatus "DP1_P3E_CPU0_PE3_OCP_TXN(9)" )
			)
			( differentialPair "@crescent_city_bb_fab1_lib.crescent_city_bb_fab1(sch_1):\DP_48\"
				( memberType ( signal ) )
				( electricalCSetRef "@crescent_city_bb_fab1_lib.crescent_city_bb_fab1(sch_1):\PCIE_SLOT\" )
				( member ( electricalNetRef "@crescent_city_bb_fab1_lib.crescent_city_bb_fab1(sch_1):p3e_cpu0_pe3_ocp_txn(9)") )
				( member ( electricalNetRef "@crescent_city_bb_fab1_lib.crescent_city_bb_fab1(sch_1):p3e_cpu0_pe3_ocp_txp(9)") )
				( objectStatus "DP1_P3E_CPU0_PE3_OCP_TXN(10)" )
			)
			( differentialPair "@crescent_city_bb_fab1_lib.crescent_city_bb_fab1(sch_1):\DP_49\"
				( memberType ( signal ) )
				( electricalCSetRef "@crescent_city_bb_fab1_lib.crescent_city_bb_fab1(sch_1):\PCIE_SLOT\" )
				( member ( electricalNetRef "@crescent_city_bb_fab1_lib.crescent_city_bb_fab1(sch_1):p3e_cpu0_pe3_ocp_txn(10)") )
				( member ( electricalNetRef "@crescent_city_bb_fab1_lib.crescent_city_bb_fab1(sch_1):p3e_cpu0_pe3_ocp_txp(10)") )
				( objectStatus "DP1_P3E_CPU0_PE3_OCP_TXN(11)" )
			)
			( differentialPair "@crescent_city_bb_fab1_lib.crescent_city_bb_fab1(sch_1):\DP_50\"
				( memberType ( signal ) )
				( electricalCSetRef "@crescent_city_bb_fab1_lib.crescent_city_bb_fab1(sch_1):\PCIE_SLOT\" )
				( member ( electricalNetRef "@crescent_city_bb_fab1_lib.crescent_city_bb_fab1(sch_1):p3e_cpu0_pe3_ocp_txn(11)") )
				( member ( electricalNetRef "@crescent_city_bb_fab1_lib.crescent_city_bb_fab1(sch_1):p3e_cpu0_pe3_ocp_txp(11)") )
				( objectStatus "DP1_P3E_CPU0_PE3_OCP_TXN(12)" )
			)
			( differentialPair "@crescent_city_bb_fab1_lib.crescent_city_bb_fab1(sch_1):\DP_51\"
				( memberType ( signal ) )
				( electricalCSetRef "@crescent_city_bb_fab1_lib.crescent_city_bb_fab1(sch_1):\PCIE_SLOT\" )
				( member ( electricalNetRef "@crescent_city_bb_fab1_lib.crescent_city_bb_fab1(sch_1):p3e_cpu0_pe3_ocp_txn(12)") )
				( member ( electricalNetRef "@crescent_city_bb_fab1_lib.crescent_city_bb_fab1(sch_1):p3e_cpu0_pe3_ocp_txp(12)") )
				( objectStatus "DP1_P3E_CPU0_PE3_OCP_TXN(13)" )
			)
			( differentialPair "@crescent_city_bb_fab1_lib.crescent_city_bb_fab1(sch_1):\DP_52\"
				( memberType ( signal ) )
				( electricalCSetRef "@crescent_city_bb_fab1_lib.crescent_city_bb_fab1(sch_1):\PCIE_SLOT\" )
				( member ( electricalNetRef "@crescent_city_bb_fab1_lib.crescent_city_bb_fab1(sch_1):p3e_cpu0_pe3_ocp_txn(13)") )
				( member ( electricalNetRef "@crescent_city_bb_fab1_lib.crescent_city_bb_fab1(sch_1):p3e_cpu0_pe3_ocp_txp(13)") )
				( objectStatus "DP1_P3E_CPU0_PE3_OCP_TXN(14)" )
			)
			( differentialPair "@crescent_city_bb_fab1_lib.crescent_city_bb_fab1(sch_1):\DP_53\"
				( memberType ( signal ) )
				( electricalCSetRef "@crescent_city_bb_fab1_lib.crescent_city_bb_fab1(sch_1):\PCIE_SLOT\" )
				( member ( electricalNetRef "@crescent_city_bb_fab1_lib.crescent_city_bb_fab1(sch_1):p3e_cpu0_pe3_ocp_txn(14)") )
				( member ( electricalNetRef "@crescent_city_bb_fab1_lib.crescent_city_bb_fab1(sch_1):p3e_cpu0_pe3_ocp_txp(14)") )
				( objectStatus "DP1_P3E_CPU0_PE3_OCP_TXN(15)" )
			)
			( differentialPair "@crescent_city_bb_fab1_lib.crescent_city_bb_fab1(sch_1):\DP_54\"
				( memberType ( signal ) )
				( electricalCSetRef "@crescent_city_bb_fab1_lib.crescent_city_bb_fab1(sch_1):\PCIE_SLOT\" )
				( member ( electricalNetRef "@crescent_city_bb_fab1_lib.crescent_city_bb_fab1(sch_1):p3e_cpu0_pe3_ocp_txn(15)") )
				( member ( electricalNetRef "@crescent_city_bb_fab1_lib.crescent_city_bb_fab1(sch_1):p3e_cpu0_pe3_ocp_txp(15)") )
				( objectStatus "DP1_P3E_CPU1_PE3_MP_TXN(0)" )
			)
			( differentialPair "@crescent_city_bb_fab1_lib.crescent_city_bb_fab1(sch_1):\DP_55\"
				( memberType ( signal ) )
				( electricalCSetRef "@crescent_city_bb_fab1_lib.crescent_city_bb_fab1(sch_1):\PCIE_SLOT\" )
				( member ( electricalNetRef "@crescent_city_bb_fab1_lib.crescent_city_bb_fab1(sch_1):p3e_cpu1_pe3_mp_c_txn(0)") )
				( member ( electricalNetRef "@crescent_city_bb_fab1_lib.crescent_city_bb_fab1(sch_1):p3e_cpu1_pe3_mp_c_txp(0)") )
				( objectStatus "DP1_P3E_CPU1_PE3_MP_TXN(1)" )
			)
			( differentialPair "@crescent_city_bb_fab1_lib.crescent_city_bb_fab1(sch_1):\DP_56\"
				( memberType ( signal ) )
				( electricalCSetRef "@crescent_city_bb_fab1_lib.crescent_city_bb_fab1(sch_1):\PCIE_SLOT\" )
				( member ( electricalNetRef "@crescent_city_bb_fab1_lib.crescent_city_bb_fab1(sch_1):p3e_cpu1_pe3_mp_c_txn(1)") )
				( member ( electricalNetRef "@crescent_city_bb_fab1_lib.crescent_city_bb_fab1(sch_1):p3e_cpu1_pe3_mp_c_txp(1)") )
				( objectStatus "DP1_P3E_CPU1_PE3_MP_TXN(2)" )
			)
			( differentialPair "@crescent_city_bb_fab1_lib.crescent_city_bb_fab1(sch_1):\P3E_CPU0_PE1_PCH_PCIEUP_RX\(0)"
				( memberType ( signal ) )
				( attribute "DIFFP_PHASE_TOL" "5 mil"
					( Units "uPhaseTol" "ns" 1.000000)
					( Origin gBackEnd )
				)
				( member ( electricalNetRef "@crescent_city_bb_fab1_lib.crescent_city_bb_fab1(sch_1):p3e_cpu0_pe1_ss_rxn(0)") )
				( member ( electricalNetRef "@crescent_city_bb_fab1_lib.crescent_city_bb_fab1(sch_1):p3e_cpu0_pe1_ss_rxp(0)") )
				( objectStatus "P3E_CPU0_PE1_PCH_PCIEUP_RX<0>" )
			)
			( differentialPair "@crescent_city_bb_fab1_lib.crescent_city_bb_fab1(sch_1):\P3E_CPU0_PE1_PCH_PCIEUP_RX\(1)"
				( memberType ( signal ) )
				( attribute "DIFFP_PHASE_TOL" "5 mil"
					( Units "uPhaseTol" "ns" 1.000000)
					( Origin gBackEnd )
				)
				( member ( electricalNetRef "@crescent_city_bb_fab1_lib.crescent_city_bb_fab1(sch_1):p3e_cpu0_pe1_ss_rxn(1)") )
				( member ( electricalNetRef "@crescent_city_bb_fab1_lib.crescent_city_bb_fab1(sch_1):p3e_cpu0_pe1_ss_rxp(1)") )
				( objectStatus "P3E_CPU0_PE1_PCH_PCIEUP_RX<1>" )
			)
			( differentialPair "@crescent_city_bb_fab1_lib.crescent_city_bb_fab1(sch_1):\P3E_CPU0_PE1_PCH_PCIEUP_RX\(2)"
				( memberType ( signal ) )
				( attribute "DIFFP_PHASE_TOL" "5 mil"
					( Units "uPhaseTol" "ns" 1.000000)
					( Origin gBackEnd )
				)
				( member ( electricalNetRef "@crescent_city_bb_fab1_lib.crescent_city_bb_fab1(sch_1):p3e_cpu0_pe1_ss_rxn(2)") )
				( member ( electricalNetRef "@crescent_city_bb_fab1_lib.crescent_city_bb_fab1(sch_1):p3e_cpu0_pe1_ss_rxp(2)") )
				( objectStatus "P3E_CPU0_PE1_PCH_PCIEUP_RX<2>" )
			)
			( differentialPair "@crescent_city_bb_fab1_lib.crescent_city_bb_fab1(sch_1):\P3E_CPU0_PE1_PCH_PCIEUP_RX\(3)"
				( memberType ( signal ) )
				( attribute "DIFFP_PHASE_TOL" "5 mil"
					( Units "uPhaseTol" "ns" 1.000000)
					( Origin gBackEnd )
				)
				( member ( electricalNetRef "@crescent_city_bb_fab1_lib.crescent_city_bb_fab1(sch_1):p3e_cpu0_pe1_ss_rxn(3)") )
				( member ( electricalNetRef "@crescent_city_bb_fab1_lib.crescent_city_bb_fab1(sch_1):p3e_cpu0_pe1_ss_rxp(3)") )
				( objectStatus "P3E_CPU0_PE1_PCH_PCIEUP_RX<3>" )
			)
			( differentialPair "@crescent_city_bb_fab1_lib.crescent_city_bb_fab1(sch_1):\P3E_CPU0_PE1_PCH_PCIEUP_RX\(4)"
				( memberType ( signal ) )
				( attribute "DIFFP_PHASE_TOL" "5 mil"
					( Units "uPhaseTol" "ns" 1.000000)
					( Origin gBackEnd )
				)
				( member ( electricalNetRef "@crescent_city_bb_fab1_lib.crescent_city_bb_fab1(sch_1):p3e_cpu0_pe1_ss_rxn(4)") )
				( member ( electricalNetRef "@crescent_city_bb_fab1_lib.crescent_city_bb_fab1(sch_1):p3e_cpu0_pe1_ss_rxp(4)") )
				( objectStatus "P3E_CPU0_PE1_PCH_PCIEUP_RX<4>" )
			)
			( differentialPair "@crescent_city_bb_fab1_lib.crescent_city_bb_fab1(sch_1):\P3E_CPU0_PE1_PCH_PCIEUP_RX\(5)"
				( memberType ( signal ) )
				( attribute "DIFFP_PHASE_TOL" "5 mil"
					( Units "uPhaseTol" "ns" 1.000000)
					( Origin gBackEnd )
				)
				( member ( electricalNetRef "@crescent_city_bb_fab1_lib.crescent_city_bb_fab1(sch_1):p3e_cpu0_pe1_ss_rxn(5)") )
				( member ( electricalNetRef "@crescent_city_bb_fab1_lib.crescent_city_bb_fab1(sch_1):p3e_cpu0_pe1_ss_rxp(5)") )
				( objectStatus "P3E_CPU0_PE1_PCH_PCIEUP_RX<5>" )
			)
			( differentialPair "@crescent_city_bb_fab1_lib.crescent_city_bb_fab1(sch_1):\P3E_CPU0_PE1_PCH_PCIEUP_RX\(6)"
				( memberType ( signal ) )
				( attribute "DIFFP_PHASE_TOL" "5 mil"
					( Units "uPhaseTol" "ns" 1.000000)
					( Origin gBackEnd )
				)
				( member ( electricalNetRef "@crescent_city_bb_fab1_lib.crescent_city_bb_fab1(sch_1):p3e_cpu0_pe1_ss_rxn(6)") )
				( member ( electricalNetRef "@crescent_city_bb_fab1_lib.crescent_city_bb_fab1(sch_1):p3e_cpu0_pe1_ss_rxp(6)") )
				( objectStatus "P3E_CPU0_PE1_PCH_PCIEUP_RX<6>" )
			)
			( differentialPair "@crescent_city_bb_fab1_lib.crescent_city_bb_fab1(sch_1):\P3E_CPU0_PE1_PCH_PCIEUP_RX\(8)"
				( memberType ( signal ) )
				( attribute "DIFFP_PHASE_TOL" "5 mil"
					( Units "uPhaseTol" "ns" 1.000000)
					( Origin gBackEnd )
				)
				( member ( electricalNetRef "@crescent_city_bb_fab1_lib.crescent_city_bb_fab1(sch_1):p3e_cpu0_pe1_pch_rxn(8)") )
				( member ( electricalNetRef "@crescent_city_bb_fab1_lib.crescent_city_bb_fab1(sch_1):p3e_cpu0_pe1_pch_rxp(8)") )
				( objectStatus "P3E_CPU0_PE1_PCH_PCIEUP_RX<8>" )
			)
			( differentialPair "@crescent_city_bb_fab1_lib.crescent_city_bb_fab1(sch_1):\P3E_CPU0_PE1_PCH_PCIEUP_RX\(9)"
				( memberType ( signal ) )
				( attribute "DIFFP_PHASE_TOL" "5 mil"
					( Units "uPhaseTol" "ns" 1.000000)
					( Origin gBackEnd )
				)
				( member ( electricalNetRef "@crescent_city_bb_fab1_lib.crescent_city_bb_fab1(sch_1):p3e_cpu0_pe1_pch_rxn(9)") )
				( member ( electricalNetRef "@crescent_city_bb_fab1_lib.crescent_city_bb_fab1(sch_1):p3e_cpu0_pe1_pch_rxp(9)") )
				( objectStatus "P3E_CPU0_PE1_PCH_PCIEUP_RX<9>" )
			)
			( differentialPair "@crescent_city_bb_fab1_lib.crescent_city_bb_fab1(sch_1):\DP_57\"
				( memberType ( signal ) )
				( electricalCSetRef "@crescent_city_bb_fab1_lib.crescent_city_bb_fab1(sch_1):\PCIE_SLOT\" )
				( member ( electricalNetRef "@crescent_city_bb_fab1_lib.crescent_city_bb_fab1(sch_1):p3e_cpu1_pe3_mp_c_txn(2)") )
				( member ( electricalNetRef "@crescent_city_bb_fab1_lib.crescent_city_bb_fab1(sch_1):p3e_cpu1_pe3_mp_c_txp(2)") )
				( objectStatus "DP1_P3E_CPU1_PE3_MP_TXN(3)" )
			)
			( differentialPair "@crescent_city_bb_fab1_lib.crescent_city_bb_fab1(sch_1):\DP_58\"
				( memberType ( signal ) )
				( electricalCSetRef "@crescent_city_bb_fab1_lib.crescent_city_bb_fab1(sch_1):\PCIE_SLOT\" )
				( member ( electricalNetRef "@crescent_city_bb_fab1_lib.crescent_city_bb_fab1(sch_1):p3e_cpu1_pe3_mp_c_txn(3)") )
				( member ( electricalNetRef "@crescent_city_bb_fab1_lib.crescent_city_bb_fab1(sch_1):p3e_cpu1_pe3_mp_c_txp(3)") )
				( objectStatus "DP1_P3E_CPU1_PE3_MP_TXN(4)" )
			)
			( differentialPair "@crescent_city_bb_fab1_lib.crescent_city_bb_fab1(sch_1):\DP_59\"
				( memberType ( signal ) )
				( electricalCSetRef "@crescent_city_bb_fab1_lib.crescent_city_bb_fab1(sch_1):\PCIE_SLOT\" )
				( member ( electricalNetRef "@crescent_city_bb_fab1_lib.crescent_city_bb_fab1(sch_1):p3e_cpu1_pe3_mp_c_txn(4)") )
				( member ( electricalNetRef "@crescent_city_bb_fab1_lib.crescent_city_bb_fab1(sch_1):p3e_cpu1_pe3_mp_c_txp(4)") )
				( objectStatus "DP1_P3E_CPU1_PE3_MP_TXN(5)" )
			)
			( differentialPair "@crescent_city_bb_fab1_lib.crescent_city_bb_fab1(sch_1):\DP_60\"
				( memberType ( signal ) )
				( electricalCSetRef "@crescent_city_bb_fab1_lib.crescent_city_bb_fab1(sch_1):\PCIE_SLOT\" )
				( member ( electricalNetRef "@crescent_city_bb_fab1_lib.crescent_city_bb_fab1(sch_1):p3e_cpu1_pe3_mp_c_txn(5)") )
				( member ( electricalNetRef "@crescent_city_bb_fab1_lib.crescent_city_bb_fab1(sch_1):p3e_cpu1_pe3_mp_c_txp(5)") )
				( objectStatus "DP1_P3E_CPU1_PE3_MP_TXN(6)" )
			)
			( differentialPair "@crescent_city_bb_fab1_lib.crescent_city_bb_fab1(sch_1):\DP_61\"
				( memberType ( signal ) )
				( electricalCSetRef "@crescent_city_bb_fab1_lib.crescent_city_bb_fab1(sch_1):\PCIE_SLOT\" )
				( member ( electricalNetRef "@crescent_city_bb_fab1_lib.crescent_city_bb_fab1(sch_1):p3e_cpu1_pe3_mp_c_txn(6)") )
				( member ( electricalNetRef "@crescent_city_bb_fab1_lib.crescent_city_bb_fab1(sch_1):p3e_cpu1_pe3_mp_c_txp(6)") )
				( objectStatus "DP1_P3E_CPU1_PE3_MP_TXN(7)" )
			)
			( differentialPair "@crescent_city_bb_fab1_lib.crescent_city_bb_fab1(sch_1):\DP_66\"
				( memberType ( signal ) )
				( electricalCSetRef "@crescent_city_bb_fab1_lib.crescent_city_bb_fab1(sch_1):\PCIE_SLOT\" )
				( member ( electricalNetRef "@crescent_city_bb_fab1_lib.crescent_city_bb_fab1(sch_1):p3e_cpu1_pe3_mp_c_txn(11)") )
				( member ( electricalNetRef "@crescent_city_bb_fab1_lib.crescent_city_bb_fab1(sch_1):p3e_cpu1_pe3_mp_c_txp(11)") )
				( objectStatus "DP1_P3E_CPU1_PE3_MP_TXN(12)" )
			)
			( differentialPair "@crescent_city_bb_fab1_lib.crescent_city_bb_fab1(sch_1):\DP_67\"
				( memberType ( signal ) )
				( electricalCSetRef "@crescent_city_bb_fab1_lib.crescent_city_bb_fab1(sch_1):\PCIE_SLOT\" )
				( member ( electricalNetRef "@crescent_city_bb_fab1_lib.crescent_city_bb_fab1(sch_1):p3e_cpu1_pe3_mp_c_txn(12)") )
				( member ( electricalNetRef "@crescent_city_bb_fab1_lib.crescent_city_bb_fab1(sch_1):p3e_cpu1_pe3_mp_c_txp(12)") )
				( objectStatus "DP1_P3E_CPU1_PE3_MP_TXN(13)" )
			)
			( differentialPair "@crescent_city_bb_fab1_lib.crescent_city_bb_fab1(sch_1):\DP_68\"
				( memberType ( signal ) )
				( electricalCSetRef "@crescent_city_bb_fab1_lib.crescent_city_bb_fab1(sch_1):\PCIE_SLOT\" )
				( member ( electricalNetRef "@crescent_city_bb_fab1_lib.crescent_city_bb_fab1(sch_1):p3e_cpu1_pe3_mp_c_txn(13)") )
				( member ( electricalNetRef "@crescent_city_bb_fab1_lib.crescent_city_bb_fab1(sch_1):p3e_cpu1_pe3_mp_c_txp(13)") )
				( objectStatus "DP1_P3E_CPU1_PE3_MP_TXN(14)" )
			)
			( differentialPair "@crescent_city_bb_fab1_lib.crescent_city_bb_fab1(sch_1):\DP_69\"
				( memberType ( signal ) )
				( electricalCSetRef "@crescent_city_bb_fab1_lib.crescent_city_bb_fab1(sch_1):\PCIE_SLOT\" )
				( member ( electricalNetRef "@crescent_city_bb_fab1_lib.crescent_city_bb_fab1(sch_1):p3e_cpu1_pe3_mp_c_txn(14)") )
				( member ( electricalNetRef "@crescent_city_bb_fab1_lib.crescent_city_bb_fab1(sch_1):p3e_cpu1_pe3_mp_c_txp(14)") )
				( objectStatus "DP1_P3E_CPU1_PE3_MP_TXN(15)" )
			)
			( differentialPair "@crescent_city_bb_fab1_lib.crescent_city_bb_fab1(sch_1):\DP_70\"
				( memberType ( signal ) )
				( electricalCSetRef "@crescent_city_bb_fab1_lib.crescent_city_bb_fab1(sch_1):\PCIE_SLOT\" )
				( member ( electricalNetRef "@crescent_city_bb_fab1_lib.crescent_city_bb_fab1(sch_1):p3e_cpu1_pe3_mp_c_txn(15)") )
				( member ( electricalNetRef "@crescent_city_bb_fab1_lib.crescent_city_bb_fab1(sch_1):p3e_cpu1_pe3_mp_c_txp(15)") )
				( objectStatus "DP_P3E_CPU1_PE3_MP_TX" )
			)
			( differentialPair "@crescent_city_bb_fab1_lib.crescent_city_bb_fab1(sch_1):\DP_62\"
				( memberType ( signal ) )
				( electricalCSetRef "@crescent_city_bb_fab1_lib.crescent_city_bb_fab1(sch_1):\PCIE_SLOT\" )
				( member ( electricalNetRef "@crescent_city_bb_fab1_lib.crescent_city_bb_fab1(sch_1):p3e_cpu1_pe3_mp_c_txn(7)") )
				( member ( electricalNetRef "@crescent_city_bb_fab1_lib.crescent_city_bb_fab1(sch_1):p3e_cpu1_pe3_mp_c_txp(7)") )
				( objectStatus "DP_P3E_CPU1_PE3_MP_TXN(8)" )
			)
			( differentialPair "@crescent_city_bb_fab1_lib.crescent_city_bb_fab1(sch_1):\DP_64\"
				( memberType ( signal ) )
				( electricalCSetRef "@crescent_city_bb_fab1_lib.crescent_city_bb_fab1(sch_1):\PCIE_SLOT\" )
				( member ( electricalNetRef "@crescent_city_bb_fab1_lib.crescent_city_bb_fab1(sch_1):p3e_cpu1_pe3_mp_c_txn(9)") )
				( member ( electricalNetRef "@crescent_city_bb_fab1_lib.crescent_city_bb_fab1(sch_1):p3e_cpu1_pe3_mp_c_txp(9)") )
				( objectStatus "DP_P3E_CPU1_PE3_MP_TXN(10)" )
			)
			( differentialPair "@crescent_city_bb_fab1_lib.crescent_city_bb_fab1(sch_1):\DP_P3E_CPU1_PE3_MP_R\(0)"
				( memberType ( signal ) )
				( attribute "DIFFP_PHASE_TOL" "5 mil"
					( Units "uPhaseTol" "ns" 1.000000)
					( Origin gBackEnd )
				)
				( member ( signalRef "@baseboard_fab2_lib.baseboard_fab2(sch_1):p3e_cpu1_pe3_mp_rxn(0)") )
				( member ( signalRef "@baseboard_fab2_lib.baseboard_fab2(sch_1):p3e_cpu1_pe3_mp_rxp(0)") )
				( objectStatus "P3E_CPU1_PE3_MP_R<0>" )
			)
			( differentialPair "@crescent_city_bb_fab1_lib.crescent_city_bb_fab1(sch_1):\DP_P3E_CPU1_PE3_MP_R\(1)"
				( memberType ( signal ) )
				( attribute "DIFFP_PHASE_TOL" "5 mil"
					( Units "uPhaseTol" "ns" 1.000000)
					( Origin gBackEnd )
				)
				( member ( signalRef "@baseboard_fab2_lib.baseboard_fab2(sch_1):p3e_cpu1_pe3_mp_rxn(1)") )
				( member ( signalRef "@baseboard_fab2_lib.baseboard_fab2(sch_1):p3e_cpu1_pe3_mp_rxp(1)") )
				( objectStatus "P3E_CPU1_PE3_MP_R<1>" )
			)
			( differentialPair "@crescent_city_bb_fab1_lib.crescent_city_bb_fab1(sch_1):\DP_P3E_CPU1_PE3_MP_R\(2)"
				( memberType ( signal ) )
				( attribute "DIFFP_PHASE_TOL" "5 mil"
					( Units "uPhaseTol" "ns" 1.000000)
					( Origin gBackEnd )
				)
				( member ( signalRef "@baseboard_fab2_lib.baseboard_fab2(sch_1):p3e_cpu1_pe3_mp_rxn(2)") )
				( member ( signalRef "@baseboard_fab2_lib.baseboard_fab2(sch_1):p3e_cpu1_pe3_mp_rxp(2)") )
				( objectStatus "P3E_CPU1_PE3_MP_R<2>" )
			)
			( differentialPair "@crescent_city_bb_fab1_lib.crescent_city_bb_fab1(sch_1):\DP_P3E_CPU1_PE3_MP_R\(3)"
				( memberType ( signal ) )
				( attribute "DIFFP_PHASE_TOL" "5 mil"
					( Units "uPhaseTol" "ns" 1.000000)
					( Origin gBackEnd )
				)
				( member ( signalRef "@baseboard_fab2_lib.baseboard_fab2(sch_1):p3e_cpu1_pe3_mp_rxn(3)") )
				( member ( signalRef "@baseboard_fab2_lib.baseboard_fab2(sch_1):p3e_cpu1_pe3_mp_rxp(3)") )
				( objectStatus "P3E_CPU1_PE3_MP_R<3>" )
			)
			( differentialPair "@crescent_city_bb_fab1_lib.crescent_city_bb_fab1(sch_1):\DP_P3E_CPU1_PE3_MP_R\(4)"
				( memberType ( signal ) )
				( attribute "DIFFP_PHASE_TOL" "5 mil"
					( Units "uPhaseTol" "ns" 1.000000)
					( Origin gBackEnd )
				)
				( member ( signalRef "@baseboard_fab2_lib.baseboard_fab2(sch_1):p3e_cpu1_pe3_mp_rxn(4)") )
				( member ( signalRef "@baseboard_fab2_lib.baseboard_fab2(sch_1):p3e_cpu1_pe3_mp_rxp(4)") )
				( objectStatus "P3E_CPU1_PE3_MP_R<4>" )
			)
			( differentialPair "@crescent_city_bb_fab1_lib.crescent_city_bb_fab1(sch_1):\DP_P3E_CPU1_PE3_MP_R\(5)"
				( memberType ( signal ) )
				( attribute "DIFFP_PHASE_TOL" "5 mil"
					( Units "uPhaseTol" "ns" 1.000000)
					( Origin gBackEnd )
				)
				( member ( signalRef "@baseboard_fab2_lib.baseboard_fab2(sch_1):p3e_cpu1_pe3_mp_rxn(5)") )
				( member ( signalRef "@baseboard_fab2_lib.baseboard_fab2(sch_1):p3e_cpu1_pe3_mp_rxp(5)") )
				( objectStatus "P3E_CPU1_PE3_MP_R<5>" )
			)
			( differentialPair "@crescent_city_bb_fab1_lib.crescent_city_bb_fab1(sch_1):\DP_P3E_CPU1_PE3_MP_R\(6)"
				( memberType ( signal ) )
				( attribute "DIFFP_PHASE_TOL" "5 mil"
					( Units "uPhaseTol" "ns" 1.000000)
					( Origin gBackEnd )
				)
				( member ( signalRef "@baseboard_fab2_lib.baseboard_fab2(sch_1):p3e_cpu1_pe3_mp_rxn(6)") )
				( member ( signalRef "@baseboard_fab2_lib.baseboard_fab2(sch_1):p3e_cpu1_pe3_mp_rxp(6)") )
				( objectStatus "P3E_CPU1_PE3_MP_R<6>" )
			)
			( differentialPair "@crescent_city_bb_fab1_lib.crescent_city_bb_fab1(sch_1):\DP_P3E_CPU1_PE3_MP_R\(7)"
				( memberType ( signal ) )
				( attribute "DIFFP_PHASE_TOL" "5 mil"
					( Units "uPhaseTol" "ns" 1.000000)
					( Origin gBackEnd )
				)
				( member ( signalRef "@baseboard_fab2_lib.baseboard_fab2(sch_1):p3e_cpu1_pe3_mp_rxn(7)") )
				( member ( signalRef "@baseboard_fab2_lib.baseboard_fab2(sch_1):p3e_cpu1_pe3_mp_rxp(7)") )
				( objectStatus "P3E_CPU1_PE3_MP_R<7>" )
			)
			( differentialPair "@crescent_city_bb_fab1_lib.crescent_city_bb_fab1(sch_1):\P3E_CPU0_PE2_SS_RX\(0)"
				( memberType ( signal ) )
				( attribute "DIFFP_PHASE_TOL" "5 mil"
					( Units "uPhaseTol" "ns" 1.000000)
					( Origin gBackEnd )
				)
				( member ( signalRef "@baseboard_fab2_lib.baseboard_fab2(sch_1):p3e_cpu0_pe2_ss_rxn(0)") )
				( member ( signalRef "@baseboard_fab2_lib.baseboard_fab2(sch_1):p3e_cpu0_pe2_ss_rxp(0)") )
				( objectStatus "P3E_CPU0_PE2_SS_RX<0>" )
			)
			( differentialPair "@crescent_city_bb_fab1_lib.crescent_city_bb_fab1(sch_1):\P3E_CPU0_PE2_SS_RX\(1)"
				( memberType ( signal ) )
				( attribute "DIFFP_PHASE_TOL" "5 mil"
					( Units "uPhaseTol" "ns" 1.000000)
					( Origin gBackEnd )
				)
				( member ( signalRef "@baseboard_fab2_lib.baseboard_fab2(sch_1):p3e_cpu0_pe2_ss_rxn(1)") )
				( member ( signalRef "@baseboard_fab2_lib.baseboard_fab2(sch_1):p3e_cpu0_pe2_ss_rxp(1)") )
				( objectStatus "P3E_CPU0_PE2_SS_RX<1>" )
			)
			( differentialPair "@crescent_city_bb_fab1_lib.crescent_city_bb_fab1(sch_1):\P3E_CPU0_PE2_SS_RX\(2)"
				( memberType ( signal ) )
				( attribute "DIFFP_PHASE_TOL" "5 mil"
					( Units "uPhaseTol" "ns" 1.000000)
					( Origin gBackEnd )
				)
				( member ( signalRef "@baseboard_fab2_lib.baseboard_fab2(sch_1):p3e_cpu0_pe2_ss_rxn(2)") )
				( member ( signalRef "@baseboard_fab2_lib.baseboard_fab2(sch_1):p3e_cpu0_pe2_ss_rxp(2)") )
				( objectStatus "P3E_CPU0_PE2_SS_RX<2>" )
			)
			( differentialPair "@crescent_city_bb_fab1_lib.crescent_city_bb_fab1(sch_1):\P3E_CPU0_PE2_SS_RX\(3)"
				( memberType ( signal ) )
				( attribute "DIFFP_PHASE_TOL" "5 mil"
					( Units "uPhaseTol" "ns" 1.000000)
					( Origin gBackEnd )
				)
				( member ( signalRef "@baseboard_fab2_lib.baseboard_fab2(sch_1):p3e_cpu0_pe2_ss_rxn(3)") )
				( member ( signalRef "@baseboard_fab2_lib.baseboard_fab2(sch_1):p3e_cpu0_pe2_ss_rxp(3)") )
				( objectStatus "P3E_CPU0_PE2_SS_RX<3>" )
			)
			( differentialPair "@crescent_city_bb_fab1_lib.crescent_city_bb_fab1(sch_1):\P3E_CPU0_PE2_SS_RX\(4)"
				( memberType ( signal ) )
				( attribute "DIFFP_PHASE_TOL" "5 mil"
					( Units "uPhaseTol" "ns" 1.000000)
					( Origin gBackEnd )
				)
				( member ( signalRef "@baseboard_fab2_lib.baseboard_fab2(sch_1):p3e_cpu0_pe2_ss_rxn(4)") )
				( member ( signalRef "@baseboard_fab2_lib.baseboard_fab2(sch_1):p3e_cpu0_pe2_ss_rxp(4)") )
				( objectStatus "P3E_CPU0_PE2_SS_RX<4>" )
			)
			( differentialPair "@crescent_city_bb_fab1_lib.crescent_city_bb_fab1(sch_1):\P3E_CPU0_PE2_SS_RX\(5)"
				( memberType ( signal ) )
				( attribute "DIFFP_PHASE_TOL" "5 mil"
					( Units "uPhaseTol" "ns" 1.000000)
					( Origin gBackEnd )
				)
				( member ( signalRef "@baseboard_fab2_lib.baseboard_fab2(sch_1):p3e_cpu0_pe2_ss_rxn(5)") )
				( member ( signalRef "@baseboard_fab2_lib.baseboard_fab2(sch_1):p3e_cpu0_pe2_ss_rxp(5)") )
				( objectStatus "P3E_CPU0_PE2_SS_RX<5>" )
			)
			( differentialPair "@crescent_city_bb_fab1_lib.crescent_city_bb_fab1(sch_1):\DP_DMI_CPU0_PCH_RX_C\(0)"
				( memberType ( signal ) )
				( attribute "DIFFP_PHASE_TOL" "5 mil"
					( Units "uPhaseTol" "ns" 1.000000)
					( Origin gBackEnd )
				)
				( attribute "DIFFP_PHASE_MAX_LENGTH" "600.00"
					( Origin gBackEnd )
				)
				( attribute "DIFFP_PHASE_TOL_DYNAMIC" "30 mil"
					( Units "uPhaseTol" "mil" 1.000000)
					( Origin gBackEnd )
				)
				( member ( electricalNetRef "@crescent_city_bb_fab1_lib.crescent_city_bb_fab1(sch_1):dmi_cpu0_pch_rx_c_dn(0)") )
				( member ( electricalNetRef "@crescent_city_bb_fab1_lib.crescent_city_bb_fab1(sch_1):dmi_cpu0_pch_rx_c_dp(0)") )
				( objectStatus "DP_DMI_CPU0_PCH_RX_C<0>" )
			)
			( differentialPair "@crescent_city_bb_fab1_lib.crescent_city_bb_fab1(sch_1):\DP_DMI_CPU0_PCH_RX_C\(1)"
				( memberType ( signal ) )
				( attribute "DIFFP_PHASE_TOL" "5 mil"
					( Units "uPhaseTol" "ns" 1.000000)
					( Origin gBackEnd )
				)
				( attribute "DIFFP_PHASE_MAX_LENGTH" "600.00"
					( Origin gBackEnd )
				)
				( attribute "DIFFP_PHASE_TOL_DYNAMIC" "30 mil"
					( Units "uPhaseTol" "mil" 1.000000)
					( Origin gBackEnd )
				)
				( member ( electricalNetRef "@crescent_city_bb_fab1_lib.crescent_city_bb_fab1(sch_1):dmi_cpu0_pch_rx_c_dn(1)") )
				( member ( electricalNetRef "@crescent_city_bb_fab1_lib.crescent_city_bb_fab1(sch_1):dmi_cpu0_pch_rx_c_dp(1)") )
				( objectStatus "DP_DMI_CPU0_PCH_RX_C<1>" )
			)
			( differentialPair "@crescent_city_bb_fab1_lib.crescent_city_bb_fab1(sch_1):\DP_DMI_CPU0_PCH_RX_C\(2)"
				( memberType ( signal ) )
				( attribute "DIFFP_PHASE_TOL" "5 mil"
					( Units "uPhaseTol" "ns" 1.000000)
					( Origin gBackEnd )
				)
				( attribute "DIFFP_PHASE_MAX_LENGTH" "600.00"
					( Origin gBackEnd )
				)
				( attribute "DIFFP_PHASE_TOL_DYNAMIC" "30 mil"
					( Units "uPhaseTol" "mil" 1.000000)
					( Origin gBackEnd )
				)
				( member ( electricalNetRef "@crescent_city_bb_fab1_lib.crescent_city_bb_fab1(sch_1):dmi_cpu0_pch_rx_c_dn(2)") )
				( member ( electricalNetRef "@crescent_city_bb_fab1_lib.crescent_city_bb_fab1(sch_1):dmi_cpu0_pch_rx_c_dp(2)") )
				( objectStatus "DP_DMI_CPU0_PCH_RX_C<2>" )
			)
			( differentialPair "@crescent_city_bb_fab1_lib.crescent_city_bb_fab1(sch_1):\DP_DMI_CPU0_PCH_RX_C\(3)"
				( memberType ( signal ) )
				( attribute "DIFFP_PHASE_TOL" "5 mil"
					( Units "uPhaseTol" "ns" 1.000000)
					( Origin gBackEnd )
				)
				( attribute "DIFFP_PHASE_MAX_LENGTH" "600.00"
					( Origin gBackEnd )
				)
				( attribute "DIFFP_PHASE_TOL_DYNAMIC" "30 mil"
					( Units "uPhaseTol" "mil" 1.000000)
					( Origin gBackEnd )
				)
				( member ( electricalNetRef "@crescent_city_bb_fab1_lib.crescent_city_bb_fab1(sch_1):dmi_cpu0_pch_rx_c_dn(3)") )
				( member ( electricalNetRef "@crescent_city_bb_fab1_lib.crescent_city_bb_fab1(sch_1):dmi_cpu0_pch_rx_c_dp(3)") )
				( objectStatus "DP_DMI_CPU0_PCH_RX_C<3>" )
			)
			( differentialPair "@crescent_city_bb_fab1_lib.crescent_city_bb_fab1(sch_1):\P3E_CPU0_PE2_SS_RX\(6)"
				( memberType ( signal ) )
				( attribute "DIFFP_PHASE_TOL" "5 mil"
					( Units "uPhaseTol" "ns" 1.000000)
					( Origin gBackEnd )
				)
				( member ( signalRef "@baseboard_fab2_lib.baseboard_fab2(sch_1):p3e_cpu0_pe2_ss_rxn(6)") )
				( member ( signalRef "@baseboard_fab2_lib.baseboard_fab2(sch_1):p3e_cpu0_pe2_ss_rxp(6)") )
				( objectStatus "P3E_CPU0_PE2_SS_RX<6>" )
			)
			( differentialPair "@crescent_city_bb_fab1_lib.crescent_city_bb_fab1(sch_1):\DP_P2E_SSB_BMC_TX_C\"
				( memberType ( signal ) )
				( attribute "DIFFP_PHASE_TOL" "5 mil"
					( Units "uPhaseTol" "ns" 1.000000)
					( Origin gBackEnd )
				)
				( member ( signalRef "@baseboard_fab2_lib.baseboard_fab2(sch_1):p2e_ssb_bmc_tx_c_dn") )
				( member ( signalRef "@baseboard_fab2_lib.baseboard_fab2(sch_1):p2e_ssb_bmc_tx_c_dp") )
				( objectStatus "P2E_SSB_BMC_TX_C" )
			)
			( differentialPair "@crescent_city_bb_fab1_lib.crescent_city_bb_fab1(sch_1):\DP_P2E_SSB_BMC_TX\"
				( memberType ( signal ) )
				( attribute "DIFFP_PHASE_TOL" "5 mil"
					( Units "uPhaseTol" "ns" 1.000000)
					( Origin gBackEnd )
				)
				( member ( signalRef "@baseboard_fab2_lib.baseboard_fab2(sch_1):p2e_ssb_bmc_tx_dn") )
				( member ( signalRef "@baseboard_fab2_lib.baseboard_fab2(sch_1):p2e_ssb_bmc_tx_dp") )
				( objectStatus "P2E_SSB_BMC_TX" )
			)
			( differentialPair "@crescent_city_bb_fab1_lib.crescent_city_bb_fab1(sch_1):\DP_P2E_SSB_BMC_RX\"
				( memberType ( signal ) )
				( attribute "DIFFP_PHASE_TOL" "5 mil"
					( Units "uPhaseTol" "ns" 1.000000)
					( Origin gBackEnd )
				)
				( member ( signalRef "@baseboard_fab2_lib.baseboard_fab2(sch_1):p2e_ssb_bmc_rx_dn") )
				( member ( signalRef "@baseboard_fab2_lib.baseboard_fab2(sch_1):p2e_ssb_bmc_rx_dp") )
				( objectStatus "P2E_SSB_BMC_RX" )
			)
			( differentialPair "@crescent_city_bb_fab1_lib.crescent_city_bb_fab1(sch_1):\DP_P2E_SSB_BMC_RX_C\"
				( memberType ( signal ) )
				( attribute "DIFFP_PHASE_TOL" "5 mil"
					( Units "uPhaseTol" "ns" 1.000000)
					( Origin gBackEnd )
				)
				( member ( signalRef "@baseboard_fab2_lib.baseboard_fab2(sch_1):p2e_ssb_bmc_rx_c_dn") )
				( member ( signalRef "@baseboard_fab2_lib.baseboard_fab2(sch_1):p2e_ssb_bmc_rx_c_dp") )
				( objectStatus "P2E_SSB_BMC_RX_C" )
			)
			( differentialPair "@crescent_city_bb_fab1_lib.crescent_city_bb_fab1(sch_1):\P3E_CPU0_PE2_SS_RX\(7)"
				( memberType ( signal ) )
				( attribute "DIFFP_PHASE_TOL" "5 mil"
					( Units "uPhaseTol" "ns" 1.000000)
					( Origin gBackEnd )
				)
				( member ( signalRef "@baseboard_fab2_lib.baseboard_fab2(sch_1):p3e_cpu0_pe2_ss_rxn(7)") )
				( member ( signalRef "@baseboard_fab2_lib.baseboard_fab2(sch_1):p3e_cpu0_pe2_ss_rxp(7)") )
				( objectStatus "P3E_CPU0_PE2_SS_RX<7>" )
			)
			( differentialPair "@crescent_city_bb_fab1_lib.crescent_city_bb_fab1(sch_1):\P3E_CPU0_PE2_SS_RX\(8)"
				( memberType ( signal ) )
				( attribute "DIFFP_PHASE_TOL" "5 mil"
					( Units "uPhaseTol" "ns" 1.000000)
					( Origin gBackEnd )
				)
				( member ( signalRef "@baseboard_fab2_lib.baseboard_fab2(sch_1):p3e_cpu0_pe2_ss_rxn(8)") )
				( member ( signalRef "@baseboard_fab2_lib.baseboard_fab2(sch_1):p3e_cpu0_pe2_ss_rxp(8)") )
				( objectStatus "P3E_CPU0_PE2_SS_RX<8>" )
			)
			( differentialPair "@crescent_city_bb_fab1_lib.crescent_city_bb_fab1(sch_1):\P3E_CPU0_PE2_SS_RX\(15)"
				( memberType ( signal ) )
				( attribute "DIFFP_PHASE_TOL" "5 mil"
					( Units "uPhaseTol" "ns" 1.000000)
					( Origin gBackEnd )
				)
				( member ( signalRef "@baseboard_fab2_lib.baseboard_fab2(sch_1):p3e_cpu0_pe2_ss_rxn(15)") )
				( member ( signalRef "@baseboard_fab2_lib.baseboard_fab2(sch_1):p3e_cpu0_pe2_ss_rxp(15)") )
				( objectStatus "P3E_CPU0_PE2_SS_RX<15>" )
			)
			( differentialPair "@crescent_city_bb_fab1_lib.crescent_city_bb_fab1(sch_1):\P3E_CPU0_PE2_SS_RX\(14)"
				( memberType ( signal ) )
				( attribute "DIFFP_PHASE_TOL" "5 mil"
					( Units "uPhaseTol" "ns" 1.000000)
					( Origin gBackEnd )
				)
				( member ( signalRef "@baseboard_fab2_lib.baseboard_fab2(sch_1):p3e_cpu0_pe2_ss_rxn(14)") )
				( member ( signalRef "@baseboard_fab2_lib.baseboard_fab2(sch_1):p3e_cpu0_pe2_ss_rxp(14)") )
				( objectStatus "P3E_CPU0_PE2_SS_RX<14>" )
			)
			( differentialPair "@crescent_city_bb_fab1_lib.crescent_city_bb_fab1(sch_1):\P3E_CPU0_PE2_SS_RX\(13)"
				( memberType ( signal ) )
				( attribute "DIFFP_PHASE_TOL" "5 mil"
					( Units "uPhaseTol" "ns" 1.000000)
					( Origin gBackEnd )
				)
				( member ( signalRef "@baseboard_fab2_lib.baseboard_fab2(sch_1):p3e_cpu0_pe2_ss_rxn(13)") )
				( member ( signalRef "@baseboard_fab2_lib.baseboard_fab2(sch_1):p3e_cpu0_pe2_ss_rxp(13)") )
				( objectStatus "P3E_CPU0_PE2_SS_RX<13>" )
			)
			( differentialPair "@crescent_city_bb_fab1_lib.crescent_city_bb_fab1(sch_1):\P3E_CPU0_PE2_SS_RX\(12)"
				( memberType ( signal ) )
				( attribute "DIFFP_PHASE_TOL" "5 mil"
					( Units "uPhaseTol" "ns" 1.000000)
					( Origin gBackEnd )
				)
				( member ( signalRef "@baseboard_fab2_lib.baseboard_fab2(sch_1):p3e_cpu0_pe2_ss_rxn(12)") )
				( member ( signalRef "@baseboard_fab2_lib.baseboard_fab2(sch_1):p3e_cpu0_pe2_ss_rxp(12)") )
				( objectStatus "P3E_CPU0_PE2_SS_RX<12>" )
			)
			( differentialPair "@crescent_city_bb_fab1_lib.crescent_city_bb_fab1(sch_1):\P3E_CPU0_PE2_SS_RX\(11)"
				( memberType ( signal ) )
				( attribute "DIFFP_PHASE_TOL" "5 mil"
					( Units "uPhaseTol" "ns" 1.000000)
					( Origin gBackEnd )
				)
				( member ( signalRef "@baseboard_fab2_lib.baseboard_fab2(sch_1):p3e_cpu0_pe2_ss_rxn(11)") )
				( member ( signalRef "@baseboard_fab2_lib.baseboard_fab2(sch_1):p3e_cpu0_pe2_ss_rxp(11)") )
				( objectStatus "P3E_CPU0_PE2_SS_RX<11>" )
			)
			( differentialPair "@crescent_city_bb_fab1_lib.crescent_city_bb_fab1(sch_1):\P3E_CPU0_PE2_SS_RX\(10)"
				( memberType ( signal ) )
				( attribute "DIFFP_PHASE_TOL" "5 mil"
					( Units "uPhaseTol" "ns" 1.000000)
					( Origin gBackEnd )
				)
				( member ( signalRef "@baseboard_fab2_lib.baseboard_fab2(sch_1):p3e_cpu0_pe2_ss_rxn(10)") )
				( member ( signalRef "@baseboard_fab2_lib.baseboard_fab2(sch_1):p3e_cpu0_pe2_ss_rxp(10)") )
				( objectStatus "P3E_CPU0_PE2_SS_RX<10>" )
			)
			( differentialPair "@crescent_city_bb_fab1_lib.crescent_city_bb_fab1(sch_1):\P3E_CPU0_PE2_SS_RX\(9)"
				( memberType ( signal ) )
				( attribute "DIFFP_PHASE_TOL" "5 mil"
					( Units "uPhaseTol" "ns" 1.000000)
					( Origin gBackEnd )
				)
				( member ( signalRef "@baseboard_fab2_lib.baseboard_fab2(sch_1):p3e_cpu0_pe2_ss_rxn(9)") )
				( member ( signalRef "@baseboard_fab2_lib.baseboard_fab2(sch_1):p3e_cpu0_pe2_ss_rxp(9)") )
				( objectStatus "P3E_CPU0_PE2_SS_RX<9>" )
			)
			( differentialPair "@crescent_city_bb_fab1_lib.crescent_city_bb_fab1(sch_1):\DP_P3E_CPU1_PE3_MP_R\(8)"
				( memberType ( signal ) )
				( attribute "DIFFP_PHASE_TOL" "5 mil"
					( Units "uPhaseTol" "ns" 1.000000)
					( Origin gBackEnd )
				)
				( member ( signalRef "@baseboard_fab2_lib.baseboard_fab2(sch_1):p3e_cpu1_pe3_mp_rxn(8)") )
				( member ( signalRef "@baseboard_fab2_lib.baseboard_fab2(sch_1):p3e_cpu1_pe3_mp_rxp(8)") )
				( objectStatus "P3E_CPU1_PE3_MP_R<8>" )
			)
			( differentialPair "@crescent_city_bb_fab1_lib.crescent_city_bb_fab1(sch_1):\DP_P3E_CPU1_PE3_MP_R\(9)"
				( memberType ( signal ) )
				( attribute "DIFFP_PHASE_TOL" "5 mil"
					( Units "uPhaseTol" "ns" 1.000000)
					( Origin gBackEnd )
				)
				( member ( signalRef "@baseboard_fab2_lib.baseboard_fab2(sch_1):p3e_cpu1_pe3_mp_rxn(9)") )
				( member ( signalRef "@baseboard_fab2_lib.baseboard_fab2(sch_1):p3e_cpu1_pe3_mp_rxp(9)") )
				( objectStatus "P3E_CPU1_PE3_MP_R<9>" )
			)
			( differentialPair "@crescent_city_bb_fab1_lib.crescent_city_bb_fab1(sch_1):\DP_P3E_CPU1_PE3_MP_R\(10)"
				( memberType ( signal ) )
				( attribute "DIFFP_PHASE_TOL" "5 mil"
					( Units "uPhaseTol" "ns" 1.000000)
					( Origin gBackEnd )
				)
				( member ( signalRef "@baseboard_fab2_lib.baseboard_fab2(sch_1):p3e_cpu1_pe3_mp_rxn(10)") )
				( member ( signalRef "@baseboard_fab2_lib.baseboard_fab2(sch_1):p3e_cpu1_pe3_mp_rxp(10)") )
				( objectStatus "P3E_CPU1_PE3_MP_R<10>" )
			)
			( differentialPair "@crescent_city_bb_fab1_lib.crescent_city_bb_fab1(sch_1):\DP_P3E_CPU1_PE3_MP_R\(11)"
				( memberType ( signal ) )
				( attribute "DIFFP_PHASE_TOL" "5 mil"
					( Units "uPhaseTol" "ns" 1.000000)
					( Origin gBackEnd )
				)
				( member ( signalRef "@baseboard_fab2_lib.baseboard_fab2(sch_1):p3e_cpu1_pe3_mp_rxn(11)") )
				( member ( signalRef "@baseboard_fab2_lib.baseboard_fab2(sch_1):p3e_cpu1_pe3_mp_rxp(11)") )
				( objectStatus "P3E_CPU1_PE3_MP_R<11>" )
			)
			( differentialPair "@crescent_city_bb_fab1_lib.crescent_city_bb_fab1(sch_1):\DP_P3E_CPU1_PE3_MP_R\(12)"
				( memberType ( signal ) )
				( attribute "DIFFP_PHASE_TOL" "5 mil"
					( Units "uPhaseTol" "ns" 1.000000)
					( Origin gBackEnd )
				)
				( member ( signalRef "@baseboard_fab2_lib.baseboard_fab2(sch_1):p3e_cpu1_pe3_mp_rxn(12)") )
				( member ( signalRef "@baseboard_fab2_lib.baseboard_fab2(sch_1):p3e_cpu1_pe3_mp_rxp(12)") )
				( objectStatus "P3E_CPU1_PE3_MP_R<12>" )
			)
			( differentialPair "@crescent_city_bb_fab1_lib.crescent_city_bb_fab1(sch_1):\DP_P3E_CPU1_PE3_MP_R\(13)"
				( memberType ( signal ) )
				( attribute "DIFFP_PHASE_TOL" "5 mil"
					( Units "uPhaseTol" "ns" 1.000000)
					( Origin gBackEnd )
				)
				( member ( signalRef "@baseboard_fab2_lib.baseboard_fab2(sch_1):p3e_cpu1_pe3_mp_rxn(13)") )
				( member ( signalRef "@baseboard_fab2_lib.baseboard_fab2(sch_1):p3e_cpu1_pe3_mp_rxp(13)") )
				( objectStatus "P3E_CPU1_PE3_MP_R<13>" )
			)
			( differentialPair "@crescent_city_bb_fab1_lib.crescent_city_bb_fab1(sch_1):\DP_P3E_CPU1_PE3_MP_R\(14)"
				( memberType ( signal ) )
				( attribute "DIFFP_PHASE_TOL" "5 mil"
					( Units "uPhaseTol" "ns" 1.000000)
					( Origin gBackEnd )
				)
				( member ( signalRef "@baseboard_fab2_lib.baseboard_fab2(sch_1):p3e_cpu1_pe3_mp_rxn(14)") )
				( member ( signalRef "@baseboard_fab2_lib.baseboard_fab2(sch_1):p3e_cpu1_pe3_mp_rxp(14)") )
				( objectStatus "P3E_CPU1_PE3_MP_R<14>" )
			)
			( differentialPair "@crescent_city_bb_fab1_lib.crescent_city_bb_fab1(sch_1):\DP_P3E_CPU1_PE3_MP_R\(15)"
				( memberType ( signal ) )
				( attribute "DIFFP_PHASE_TOL" "5 mil"
					( Units "uPhaseTol" "ns" 1.000000)
					( Origin gBackEnd )
				)
				( member ( signalRef "@baseboard_fab2_lib.baseboard_fab2(sch_1):p3e_cpu1_pe3_mp_rxn(15)") )
				( member ( signalRef "@baseboard_fab2_lib.baseboard_fab2(sch_1):p3e_cpu1_pe3_mp_rxp(15)") )
				( objectStatus "P3E_CPU1_PE3_MP_R<15>" )
			)
			( differentialPair "@sapphirecity_baseboard_lib.sapphirecity_baseboard(sch_1):\M_A_DQS_D\(7)"
				( memberType ( signal ) )
				( member ( signalRef "@baseboard_fab2_lib.baseboard_fab2(sch_1):m_a_dqs_dn(7)") )
				( member ( signalRef "@baseboard_fab2_lib.baseboard_fab2(sch_1):m_a_dqs_dp(7)") )
				( objectStatus "M_A_DQS_D<7>" )
			)
			( differentialPair "@sapphirecity_baseboard_lib.sapphirecity_baseboard(sch_1):\M_A_DQS_D\(16)"
				( memberType ( signal ) )
				( member ( signalRef "@baseboard_fab2_lib.baseboard_fab2(sch_1):m_a_dqs_dn(16)") )
				( member ( signalRef "@baseboard_fab2_lib.baseboard_fab2(sch_1):m_a_dqs_dp(16)") )
				( objectStatus "M_A_DQS_D<16>" )
			)
			( differentialPair "@sapphirecity_baseboard_lib.sapphirecity_baseboard(sch_1):\M_A_DQS_D\(6)"
				( memberType ( signal ) )
				( electricalCSetRef "@crescent_city_bb_fab1_lib.crescent_city_bb_fab1(sch_1):\DDR_DQS_A\" )
				( member ( signalRef "@baseboard_fab2_lib.baseboard_fab2(sch_1):m_a_dqs_dn(6)") )
				( member ( signalRef "@baseboard_fab2_lib.baseboard_fab2(sch_1):m_a_dqs_dp(6)") )
				( objectStatus "M_A_DQS_D<6>" )
			)
			( differentialPair "@sapphirecity_baseboard_lib.sapphirecity_baseboard(sch_1):\M_A_DQS_D\(15)"
				( memberType ( signal ) )
				( electricalCSetRef "@crescent_city_bb_fab1_lib.crescent_city_bb_fab1(sch_1):\DDR_DQS_A\" )
				( member ( signalRef "@baseboard_fab2_lib.baseboard_fab2(sch_1):m_a_dqs_dn(15)") )
				( member ( signalRef "@baseboard_fab2_lib.baseboard_fab2(sch_1):m_a_dqs_dp(15)") )
				( objectStatus "M_A_DQS_D<15>" )
			)
			( differentialPair "@sapphirecity_baseboard_lib.sapphirecity_baseboard(sch_1):\M_A_DQS_D\(5)"
				( memberType ( signal ) )
				( electricalCSetRef "@crescent_city_bb_fab1_lib.crescent_city_bb_fab1(sch_1):\DDR_DQS_A\" )
				( member ( signalRef "@baseboard_fab2_lib.baseboard_fab2(sch_1):m_a_dqs_dn(5)") )
				( member ( signalRef "@baseboard_fab2_lib.baseboard_fab2(sch_1):m_a_dqs_dp(5)") )
				( objectStatus "M_A_DQS_D<5>" )
			)
			( differentialPair "@sapphirecity_baseboard_lib.sapphirecity_baseboard(sch_1):\M_A_DQS_D\(14)"
				( memberType ( signal ) )
				( electricalCSetRef "@crescent_city_bb_fab1_lib.crescent_city_bb_fab1(sch_1):\DDR_DQS_A\" )
				( member ( signalRef "@baseboard_fab2_lib.baseboard_fab2(sch_1):m_a_dqs_dn(14)") )
				( member ( signalRef "@baseboard_fab2_lib.baseboard_fab2(sch_1):m_a_dqs_dp(14)") )
				( objectStatus "M_A_DQS_D<14>" )
			)
			( differentialPair "@sapphirecity_baseboard_lib.sapphirecity_baseboard(sch_1):\M_A_DQS_D\(4)"
				( memberType ( signal ) )
				( electricalCSetRef "@crescent_city_bb_fab1_lib.crescent_city_bb_fab1(sch_1):\DDR_DQS_A\" )
				( member ( signalRef "@baseboard_fab2_lib.baseboard_fab2(sch_1):m_a_dqs_dn(4)") )
				( member ( signalRef "@baseboard_fab2_lib.baseboard_fab2(sch_1):m_a_dqs_dp(4)") )
				( objectStatus "M_A_DQS_D<4>" )
			)
			( differentialPair "@sapphirecity_baseboard_lib.sapphirecity_baseboard(sch_1):\M_A_DQS_D\(13)"
				( memberType ( signal ) )
				( electricalCSetRef "@crescent_city_bb_fab1_lib.crescent_city_bb_fab1(sch_1):\DDR_DQS_A\" )
				( member ( signalRef "@baseboard_fab2_lib.baseboard_fab2(sch_1):m_a_dqs_dn(13)") )
				( member ( signalRef "@baseboard_fab2_lib.baseboard_fab2(sch_1):m_a_dqs_dp(13)") )
				( objectStatus "M_A_DQS_D<13>" )
			)
			( differentialPair "@sapphirecity_baseboard_lib.sapphirecity_baseboard(sch_1):\M_A_DQS_D\(3)"
				( memberType ( signal ) )
				( electricalCSetRef "@crescent_city_bb_fab1_lib.crescent_city_bb_fab1(sch_1):\DDR_DQS_A\" )
				( member ( signalRef "@baseboard_fab2_lib.baseboard_fab2(sch_1):m_a_dqs_dn(3)") )
				( member ( signalRef "@baseboard_fab2_lib.baseboard_fab2(sch_1):m_a_dqs_dp(3)") )
				( objectStatus "M_A_DQS_D<3>" )
			)
			( differentialPair "@sapphirecity_baseboard_lib.sapphirecity_baseboard(sch_1):\M_A_DQS_D\(12)"
				( memberType ( signal ) )
				( electricalCSetRef "@crescent_city_bb_fab1_lib.crescent_city_bb_fab1(sch_1):\DDR_DQS_A\" )
				( member ( signalRef "@baseboard_fab2_lib.baseboard_fab2(sch_1):m_a_dqs_dn(12)") )
				( member ( signalRef "@baseboard_fab2_lib.baseboard_fab2(sch_1):m_a_dqs_dp(12)") )
				( objectStatus "M_A_DQS_D<12>" )
			)
			( differentialPair "@sapphirecity_baseboard_lib.sapphirecity_baseboard(sch_1):\M_A_DQS_D\(2)"
				( memberType ( signal ) )
				( electricalCSetRef "@crescent_city_bb_fab1_lib.crescent_city_bb_fab1(sch_1):\DDR_DQS_A\" )
				( member ( signalRef "@baseboard_fab2_lib.baseboard_fab2(sch_1):m_a_dqs_dn(2)") )
				( member ( signalRef "@baseboard_fab2_lib.baseboard_fab2(sch_1):m_a_dqs_dp(2)") )
				( objectStatus "M_A_DQS_D<2>" )
			)
			( differentialPair "@sapphirecity_baseboard_lib.sapphirecity_baseboard(sch_1):\M_A_DQS_D\(11)"
				( memberType ( signal ) )
				( electricalCSetRef "@crescent_city_bb_fab1_lib.crescent_city_bb_fab1(sch_1):\DDR_DQS_A\" )
				( member ( signalRef "@baseboard_fab2_lib.baseboard_fab2(sch_1):m_a_dqs_dn(11)") )
				( member ( signalRef "@baseboard_fab2_lib.baseboard_fab2(sch_1):m_a_dqs_dp(11)") )
				( objectStatus "M_A_DQS_D<11>" )
			)
			( differentialPair "@sapphirecity_baseboard_lib.sapphirecity_baseboard(sch_1):\M_A_DQS_D\(1)"
				( memberType ( signal ) )
				( electricalCSetRef "@crescent_city_bb_fab1_lib.crescent_city_bb_fab1(sch_1):\DDR_DQS_A\" )
				( member ( signalRef "@baseboard_fab2_lib.baseboard_fab2(sch_1):m_a_dqs_dn(1)") )
				( member ( signalRef "@baseboard_fab2_lib.baseboard_fab2(sch_1):m_a_dqs_dp(1)") )
				( objectStatus "M_A_DQS_D<1>" )
			)
			( differentialPair "@sapphirecity_baseboard_lib.sapphirecity_baseboard(sch_1):\M_A_DQS_D\(10)"
				( memberType ( signal ) )
				( electricalCSetRef "@crescent_city_bb_fab1_lib.crescent_city_bb_fab1(sch_1):\DDR_DQS_A\" )
				( member ( signalRef "@baseboard_fab2_lib.baseboard_fab2(sch_1):m_a_dqs_dn(10)") )
				( member ( signalRef "@baseboard_fab2_lib.baseboard_fab2(sch_1):m_a_dqs_dp(10)") )
				( objectStatus "M_A_DQS_D<10>" )
			)
			( differentialPair "@sapphirecity_baseboard_lib.sapphirecity_baseboard(sch_1):\M_A_DQS_D\(9)"
				( memberType ( signal ) )
				( electricalCSetRef "@crescent_city_bb_fab1_lib.crescent_city_bb_fab1(sch_1):\DDR_DQS_A\" )
				( member ( signalRef "@baseboard_fab2_lib.baseboard_fab2(sch_1):m_a_dqs_dn(9)") )
				( member ( signalRef "@baseboard_fab2_lib.baseboard_fab2(sch_1):m_a_dqs_dp(9)") )
				( objectStatus "M_A_DQS_D<9>" )
			)
			( differentialPair "@sapphirecity_baseboard_lib.sapphirecity_baseboard(sch_1):\M_A_DQS_D\(0)"
				( memberType ( signal ) )
				( electricalCSetRef "@crescent_city_bb_fab1_lib.crescent_city_bb_fab1(sch_1):\DDR_DQS_A\" )
				( member ( signalRef "@baseboard_fab2_lib.baseboard_fab2(sch_1):m_a_dqs_dn(0)") )
				( member ( signalRef "@baseboard_fab2_lib.baseboard_fab2(sch_1):m_a_dqs_dp(0)") )
				( objectStatus "M_A_DQS_D<0>" )
			)
			( differentialPair "@sapphirecity_baseboard_lib.sapphirecity_baseboard(sch_1):\M_B_DQS_D\(7)"
				( memberType ( signal ) )
				( electricalCSetRef "@crescent_city_bb_fab1_lib.crescent_city_bb_fab1(sch_1):\DDR_DQS_A\" )
				( member ( signalRef "@baseboard_fab2_lib.baseboard_fab2(sch_1):m_b_dqs_dn(7)") )
				( member ( signalRef "@baseboard_fab2_lib.baseboard_fab2(sch_1):m_b_dqs_dp(7)") )
				( objectStatus "M_B_DQS_D<7>" )
			)
			( differentialPair "@sapphirecity_baseboard_lib.sapphirecity_baseboard(sch_1):\M_B_DQS_D\(16)"
				( memberType ( signal ) )
				( electricalCSetRef "@crescent_city_bb_fab1_lib.crescent_city_bb_fab1(sch_1):\DDR_DQS_A\" )
				( member ( signalRef "@baseboard_fab2_lib.baseboard_fab2(sch_1):m_b_dqs_dn(16)") )
				( member ( signalRef "@baseboard_fab2_lib.baseboard_fab2(sch_1):m_b_dqs_dp(16)") )
				( objectStatus "M_B_DQS_D<16>" )
			)
			( differentialPair "@sapphirecity_baseboard_lib.sapphirecity_baseboard(sch_1):\M_B_DQS_D\(6)"
				( memberType ( signal ) )
				( electricalCSetRef "@crescent_city_bb_fab1_lib.crescent_city_bb_fab1(sch_1):\DDR_DQS_A\" )
				( member ( signalRef "@baseboard_fab2_lib.baseboard_fab2(sch_1):m_b_dqs_dn(6)") )
				( member ( signalRef "@baseboard_fab2_lib.baseboard_fab2(sch_1):m_b_dqs_dp(6)") )
				( objectStatus "M_B_DQS_D<6>" )
			)
			( differentialPair "@sapphirecity_baseboard_lib.sapphirecity_baseboard(sch_1):\M_B_DQS_D\(15)"
				( memberType ( signal ) )
				( electricalCSetRef "@crescent_city_bb_fab1_lib.crescent_city_bb_fab1(sch_1):\DDR_DQS_A\" )
				( member ( signalRef "@baseboard_fab2_lib.baseboard_fab2(sch_1):m_b_dqs_dn(15)") )
				( member ( signalRef "@baseboard_fab2_lib.baseboard_fab2(sch_1):m_b_dqs_dp(15)") )
				( objectStatus "M_B_DQS_D<15>" )
			)
			( differentialPair "@sapphirecity_baseboard_lib.sapphirecity_baseboard(sch_1):\M_B_DQS_D\(5)"
				( memberType ( signal ) )
				( electricalCSetRef "@crescent_city_bb_fab1_lib.crescent_city_bb_fab1(sch_1):\DDR_DQS_A\" )
				( member ( signalRef "@baseboard_fab2_lib.baseboard_fab2(sch_1):m_b_dqs_dn(5)") )
				( member ( signalRef "@baseboard_fab2_lib.baseboard_fab2(sch_1):m_b_dqs_dp(5)") )
				( objectStatus "M_B_DQS_D<5>" )
			)
			( differentialPair "@sapphirecity_baseboard_lib.sapphirecity_baseboard(sch_1):\M_B_DQS_D\(14)"
				( memberType ( signal ) )
				( electricalCSetRef "@crescent_city_bb_fab1_lib.crescent_city_bb_fab1(sch_1):\DDR_DQS_A\" )
				( member ( signalRef "@baseboard_fab2_lib.baseboard_fab2(sch_1):m_b_dqs_dn(14)") )
				( member ( signalRef "@baseboard_fab2_lib.baseboard_fab2(sch_1):m_b_dqs_dp(14)") )
				( objectStatus "M_B_DQS_D<14>" )
			)
			( differentialPair "@sapphirecity_baseboard_lib.sapphirecity_baseboard(sch_1):\M_B_DQS_D\(4)"
				( memberType ( signal ) )
				( electricalCSetRef "@crescent_city_bb_fab1_lib.crescent_city_bb_fab1(sch_1):\DDR_DQS_A\" )
				( member ( signalRef "@baseboard_fab2_lib.baseboard_fab2(sch_1):m_b_dqs_dn(4)") )
				( member ( signalRef "@baseboard_fab2_lib.baseboard_fab2(sch_1):m_b_dqs_dp(4)") )
				( objectStatus "M_B_DQS_D<4>" )
			)
			( differentialPair "@sapphirecity_baseboard_lib.sapphirecity_baseboard(sch_1):\M_B_DQS_D\(13)"
				( memberType ( signal ) )
				( electricalCSetRef "@crescent_city_bb_fab1_lib.crescent_city_bb_fab1(sch_1):\DDR_DQS_A\" )
				( member ( signalRef "@baseboard_fab2_lib.baseboard_fab2(sch_1):m_b_dqs_dn(13)") )
				( member ( signalRef "@baseboard_fab2_lib.baseboard_fab2(sch_1):m_b_dqs_dp(13)") )
				( objectStatus "M_B_DQS_D<13>" )
			)
			( differentialPair "@sapphirecity_baseboard_lib.sapphirecity_baseboard(sch_1):\M_B_DQS_D\(3)"
				( memberType ( signal ) )
				( electricalCSetRef "@crescent_city_bb_fab1_lib.crescent_city_bb_fab1(sch_1):\DDR_DQS_A\" )
				( member ( signalRef "@baseboard_fab2_lib.baseboard_fab2(sch_1):m_b_dqs_dn(3)") )
				( member ( signalRef "@baseboard_fab2_lib.baseboard_fab2(sch_1):m_b_dqs_dp(3)") )
				( objectStatus "M_B_DQS_D<3>" )
			)
			( differentialPair "@sapphirecity_baseboard_lib.sapphirecity_baseboard(sch_1):\M_B_DQS_D\(12)"
				( memberType ( signal ) )
				( electricalCSetRef "@crescent_city_bb_fab1_lib.crescent_city_bb_fab1(sch_1):\DDR_DQS_A\" )
				( member ( signalRef "@baseboard_fab2_lib.baseboard_fab2(sch_1):m_b_dqs_dn(12)") )
				( member ( signalRef "@baseboard_fab2_lib.baseboard_fab2(sch_1):m_b_dqs_dp(12)") )
				( objectStatus "M_B_DQS_D<12>" )
			)
			( differentialPair "@sapphirecity_baseboard_lib.sapphirecity_baseboard(sch_1):\M_B_DQS_D\(2)"
				( memberType ( signal ) )
				( electricalCSetRef "@crescent_city_bb_fab1_lib.crescent_city_bb_fab1(sch_1):\DDR_DQS_A\" )
				( member ( signalRef "@baseboard_fab2_lib.baseboard_fab2(sch_1):m_b_dqs_dn(2)") )
				( member ( signalRef "@baseboard_fab2_lib.baseboard_fab2(sch_1):m_b_dqs_dp(2)") )
				( objectStatus "M_B_DQS_D<2>" )
			)
			( differentialPair "@sapphirecity_baseboard_lib.sapphirecity_baseboard(sch_1):\M_B_DQS_D\(11)"
				( memberType ( signal ) )
				( electricalCSetRef "@crescent_city_bb_fab1_lib.crescent_city_bb_fab1(sch_1):\DDR_DQS_A\" )
				( member ( signalRef "@baseboard_fab2_lib.baseboard_fab2(sch_1):m_b_dqs_dn(11)") )
				( member ( signalRef "@baseboard_fab2_lib.baseboard_fab2(sch_1):m_b_dqs_dp(11)") )
				( objectStatus "M_B_DQS_D<11>" )
			)
			( differentialPair "@sapphirecity_baseboard_lib.sapphirecity_baseboard(sch_1):\M_B_DQS_D\(1)"
				( memberType ( signal ) )
				( electricalCSetRef "@crescent_city_bb_fab1_lib.crescent_city_bb_fab1(sch_1):\DDR_DQS_A\" )
				( member ( signalRef "@baseboard_fab2_lib.baseboard_fab2(sch_1):m_b_dqs_dn(1)") )
				( member ( signalRef "@baseboard_fab2_lib.baseboard_fab2(sch_1):m_b_dqs_dp(1)") )
				( objectStatus "M_B_DQS_D<1>" )
			)
			( differentialPair "@sapphirecity_baseboard_lib.sapphirecity_baseboard(sch_1):\M_B_DQS_D\(10)"
				( memberType ( signal ) )
				( electricalCSetRef "@crescent_city_bb_fab1_lib.crescent_city_bb_fab1(sch_1):\DDR_DQS_A\" )
				( member ( signalRef "@baseboard_fab2_lib.baseboard_fab2(sch_1):m_b_dqs_dn(10)") )
				( member ( signalRef "@baseboard_fab2_lib.baseboard_fab2(sch_1):m_b_dqs_dp(10)") )
				( objectStatus "M_B_DQS_D<10>" )
			)
			( differentialPair "@sapphirecity_baseboard_lib.sapphirecity_baseboard(sch_1):\M_B_DQS_D\(0)"
				( memberType ( signal ) )
				( electricalCSetRef "@crescent_city_bb_fab1_lib.crescent_city_bb_fab1(sch_1):\DDR_DQS_A\" )
				( member ( signalRef "@baseboard_fab2_lib.baseboard_fab2(sch_1):m_b_dqs_dn(0)") )
				( member ( signalRef "@baseboard_fab2_lib.baseboard_fab2(sch_1):m_b_dqs_dp(0)") )
				( objectStatus "M_B_DQS_D<0>" )
			)
			( differentialPair "@sapphirecity_baseboard_lib.sapphirecity_baseboard(sch_1):\M_B_DQS_D\(9)"
				( memberType ( signal ) )
				( electricalCSetRef "@crescent_city_bb_fab1_lib.crescent_city_bb_fab1(sch_1):\DDR_DQS_A\" )
				( member ( signalRef "@baseboard_fab2_lib.baseboard_fab2(sch_1):m_b_dqs_dn(9)") )
				( member ( signalRef "@baseboard_fab2_lib.baseboard_fab2(sch_1):m_b_dqs_dp(9)") )
				( objectStatus "M_B_DQS_D<9>" )
			)
			( differentialPair "@sapphirecity_baseboard_lib.sapphirecity_baseboard(sch_1):\M_C_DQS_D\(7)"
				( memberType ( signal ) )
				( electricalCSetRef "@crescent_city_bb_fab1_lib.crescent_city_bb_fab1(sch_1):\DDR_DQS_A\" )
				( member ( signalRef "@baseboard_fab2_lib.baseboard_fab2(sch_1):m_c_dqs_dn(7)") )
				( member ( signalRef "@baseboard_fab2_lib.baseboard_fab2(sch_1):m_c_dqs_dp(7)") )
				( objectStatus "M_C_DQS_D<7>" )
			)
			( differentialPair "@sapphirecity_baseboard_lib.sapphirecity_baseboard(sch_1):\M_C_DQS_D\(16)"
				( memberType ( signal ) )
				( electricalCSetRef "@crescent_city_bb_fab1_lib.crescent_city_bb_fab1(sch_1):\DDR_DQS_A\" )
				( member ( signalRef "@baseboard_fab2_lib.baseboard_fab2(sch_1):m_c_dqs_dn(16)") )
				( member ( signalRef "@baseboard_fab2_lib.baseboard_fab2(sch_1):m_c_dqs_dp(16)") )
				( objectStatus "M_C_DQS_D<16>" )
			)
			( differentialPair "@sapphirecity_baseboard_lib.sapphirecity_baseboard(sch_1):\M_C_DQS_D\(6)"
				( memberType ( signal ) )
				( electricalCSetRef "@crescent_city_bb_fab1_lib.crescent_city_bb_fab1(sch_1):\DDR_DQS_A\" )
				( member ( signalRef "@baseboard_fab2_lib.baseboard_fab2(sch_1):m_c_dqs_dn(6)") )
				( member ( signalRef "@baseboard_fab2_lib.baseboard_fab2(sch_1):m_c_dqs_dp(6)") )
				( objectStatus "M_C_DQS_D<6>" )
			)
			( differentialPair "@sapphirecity_baseboard_lib.sapphirecity_baseboard(sch_1):\M_C_DQS_D\(15)"
				( memberType ( signal ) )
				( electricalCSetRef "@crescent_city_bb_fab1_lib.crescent_city_bb_fab1(sch_1):\DDR_DQS_A\" )
				( member ( signalRef "@baseboard_fab2_lib.baseboard_fab2(sch_1):m_c_dqs_dn(15)") )
				( member ( signalRef "@baseboard_fab2_lib.baseboard_fab2(sch_1):m_c_dqs_dp(15)") )
				( objectStatus "M_C_DQS_D<15>" )
			)
			( differentialPair "@sapphirecity_baseboard_lib.sapphirecity_baseboard(sch_1):\M_C_DQS_D\(5)"
				( memberType ( signal ) )
				( electricalCSetRef "@crescent_city_bb_fab1_lib.crescent_city_bb_fab1(sch_1):\DDR_DQS_A\" )
				( member ( signalRef "@baseboard_fab2_lib.baseboard_fab2(sch_1):m_c_dqs_dn(5)") )
				( member ( signalRef "@baseboard_fab2_lib.baseboard_fab2(sch_1):m_c_dqs_dp(5)") )
				( objectStatus "M_C_DQS_D<5>" )
			)
			( differentialPair "@sapphirecity_baseboard_lib.sapphirecity_baseboard(sch_1):\M_C_DQS_D\(14)"
				( memberType ( signal ) )
				( electricalCSetRef "@crescent_city_bb_fab1_lib.crescent_city_bb_fab1(sch_1):\DDR_DQS_A\" )
				( member ( signalRef "@baseboard_fab2_lib.baseboard_fab2(sch_1):m_c_dqs_dn(14)") )
				( member ( signalRef "@baseboard_fab2_lib.baseboard_fab2(sch_1):m_c_dqs_dp(14)") )
				( objectStatus "M_C_DQS_D<14>" )
			)
			( differentialPair "@sapphirecity_baseboard_lib.sapphirecity_baseboard(sch_1):\M_C_DQS_D\(4)"
				( memberType ( signal ) )
				( electricalCSetRef "@crescent_city_bb_fab1_lib.crescent_city_bb_fab1(sch_1):\DDR_DQS_A\" )
				( member ( signalRef "@baseboard_fab2_lib.baseboard_fab2(sch_1):m_c_dqs_dn(4)") )
				( member ( signalRef "@baseboard_fab2_lib.baseboard_fab2(sch_1):m_c_dqs_dp(4)") )
				( objectStatus "M_C_DQS_D<4>" )
			)
			( differentialPair "@sapphirecity_baseboard_lib.sapphirecity_baseboard(sch_1):\M_C_DQS_D\(13)"
				( memberType ( signal ) )
				( electricalCSetRef "@crescent_city_bb_fab1_lib.crescent_city_bb_fab1(sch_1):\DDR_DQS_A\" )
				( member ( signalRef "@baseboard_fab2_lib.baseboard_fab2(sch_1):m_c_dqs_dn(13)") )
				( member ( signalRef "@baseboard_fab2_lib.baseboard_fab2(sch_1):m_c_dqs_dp(13)") )
				( objectStatus "M_C_DQS_D<13>" )
			)
			( differentialPair "@sapphirecity_baseboard_lib.sapphirecity_baseboard(sch_1):\M_C_DQS_D\(3)"
				( memberType ( signal ) )
				( electricalCSetRef "@crescent_city_bb_fab1_lib.crescent_city_bb_fab1(sch_1):\DDR_DQS_A\" )
				( member ( signalRef "@baseboard_fab2_lib.baseboard_fab2(sch_1):m_c_dqs_dn(3)") )
				( member ( signalRef "@baseboard_fab2_lib.baseboard_fab2(sch_1):m_c_dqs_dp(3)") )
				( objectStatus "M_C_DQS_D<3>" )
			)
			( differentialPair "@sapphirecity_baseboard_lib.sapphirecity_baseboard(sch_1):\M_C_DQS_D\(12)"
				( memberType ( signal ) )
				( electricalCSetRef "@crescent_city_bb_fab1_lib.crescent_city_bb_fab1(sch_1):\DDR_DQS_A\" )
				( member ( signalRef "@baseboard_fab2_lib.baseboard_fab2(sch_1):m_c_dqs_dn(12)") )
				( member ( signalRef "@baseboard_fab2_lib.baseboard_fab2(sch_1):m_c_dqs_dp(12)") )
				( objectStatus "M_C_DQS_D<12>" )
			)
			( differentialPair "@sapphirecity_baseboard_lib.sapphirecity_baseboard(sch_1):\M_C_DQS_D\(2)"
				( memberType ( signal ) )
				( electricalCSetRef "@crescent_city_bb_fab1_lib.crescent_city_bb_fab1(sch_1):\DDR_DQS_A\" )
				( member ( signalRef "@baseboard_fab2_lib.baseboard_fab2(sch_1):m_c_dqs_dn(2)") )
				( member ( signalRef "@baseboard_fab2_lib.baseboard_fab2(sch_1):m_c_dqs_dp(2)") )
				( objectStatus "M_C_DQS_D<2>" )
			)
			( differentialPair "@sapphirecity_baseboard_lib.sapphirecity_baseboard(sch_1):\M_C_DQS_D\(11)"
				( memberType ( signal ) )
				( electricalCSetRef "@crescent_city_bb_fab1_lib.crescent_city_bb_fab1(sch_1):\DDR_DQS_A\" )
				( member ( signalRef "@baseboard_fab2_lib.baseboard_fab2(sch_1):m_c_dqs_dn(11)") )
				( member ( signalRef "@baseboard_fab2_lib.baseboard_fab2(sch_1):m_c_dqs_dp(11)") )
				( objectStatus "M_C_DQS_D<11>" )
			)
			( differentialPair "@sapphirecity_baseboard_lib.sapphirecity_baseboard(sch_1):\M_C_DQS_D\(1)"
				( memberType ( signal ) )
				( electricalCSetRef "@crescent_city_bb_fab1_lib.crescent_city_bb_fab1(sch_1):\DDR_DQS_A\" )
				( member ( signalRef "@baseboard_fab2_lib.baseboard_fab2(sch_1):m_c_dqs_dn(1)") )
				( member ( signalRef "@baseboard_fab2_lib.baseboard_fab2(sch_1):m_c_dqs_dp(1)") )
				( objectStatus "M_C_DQS_D<1>" )
			)
			( differentialPair "@sapphirecity_baseboard_lib.sapphirecity_baseboard(sch_1):\M_C_DQS_D\(10)"
				( memberType ( signal ) )
				( electricalCSetRef "@crescent_city_bb_fab1_lib.crescent_city_bb_fab1(sch_1):\DDR_DQS_A\" )
				( member ( signalRef "@baseboard_fab2_lib.baseboard_fab2(sch_1):m_c_dqs_dn(10)") )
				( member ( signalRef "@baseboard_fab2_lib.baseboard_fab2(sch_1):m_c_dqs_dp(10)") )
				( objectStatus "M_C_DQS_D<10>" )
			)
			( differentialPair "@sapphirecity_baseboard_lib.sapphirecity_baseboard(sch_1):\M_C_DQS_D\(0)"
				( memberType ( signal ) )
				( electricalCSetRef "@crescent_city_bb_fab1_lib.crescent_city_bb_fab1(sch_1):\DDR_DQS_A\" )
				( member ( signalRef "@baseboard_fab2_lib.baseboard_fab2(sch_1):m_c_dqs_dn(0)") )
				( member ( signalRef "@baseboard_fab2_lib.baseboard_fab2(sch_1):m_c_dqs_dp(0)") )
				( objectStatus "M_C_DQS_D<0>" )
			)
			( differentialPair "@sapphirecity_baseboard_lib.sapphirecity_baseboard(sch_1):\M_C_DQS_D\(9)"
				( memberType ( signal ) )
				( electricalCSetRef "@crescent_city_bb_fab1_lib.crescent_city_bb_fab1(sch_1):\DDR_DQS_A\" )
				( member ( signalRef "@baseboard_fab2_lib.baseboard_fab2(sch_1):m_c_dqs_dn(9)") )
				( member ( signalRef "@baseboard_fab2_lib.baseboard_fab2(sch_1):m_c_dqs_dp(9)") )
				( objectStatus "M_C_DQS_D<9>" )
			)
			( differentialPair "@sapphirecity_baseboard_lib.sapphirecity_baseboard(sch_1):\M_D_DQS_D\(0)"
				( memberType ( signal ) )
				( electricalCSetRef "@crescent_city_bb_fab1_lib.crescent_city_bb_fab1(sch_1):\DDR_DQS_A\" )
				( member ( signalRef "@baseboard_fab2_lib.baseboard_fab2(sch_1):m_d_dqs_dn(0)") )
				( member ( signalRef "@baseboard_fab2_lib.baseboard_fab2(sch_1):m_d_dqs_dp(0)") )
				( objectStatus "M_D_DQS_D<0>" )
			)
			( differentialPair "@sapphirecity_baseboard_lib.sapphirecity_baseboard(sch_1):\M_D_DQS_D\(9)"
				( memberType ( signal ) )
				( electricalCSetRef "@crescent_city_bb_fab1_lib.crescent_city_bb_fab1(sch_1):\DDR_DQS_A\" )
				( member ( signalRef "@baseboard_fab2_lib.baseboard_fab2(sch_1):m_d_dqs_dn(9)") )
				( member ( signalRef "@baseboard_fab2_lib.baseboard_fab2(sch_1):m_d_dqs_dp(9)") )
				( objectStatus "M_D_DQS_D<9>" )
			)
			( differentialPair "@sapphirecity_baseboard_lib.sapphirecity_baseboard(sch_1):\M_D_DQS_D\(1)"
				( memberType ( signal ) )
				( electricalCSetRef "@crescent_city_bb_fab1_lib.crescent_city_bb_fab1(sch_1):\DDR_DQS_A\" )
				( member ( signalRef "@baseboard_fab2_lib.baseboard_fab2(sch_1):m_d_dqs_dn(1)") )
				( member ( signalRef "@baseboard_fab2_lib.baseboard_fab2(sch_1):m_d_dqs_dp(1)") )
				( objectStatus "M_D_DQS_D<1>" )
			)
			( differentialPair "@sapphirecity_baseboard_lib.sapphirecity_baseboard(sch_1):\M_D_DQS_D\(10)"
				( memberType ( signal ) )
				( electricalCSetRef "@crescent_city_bb_fab1_lib.crescent_city_bb_fab1(sch_1):\DDR_DQS_A\" )
				( member ( signalRef "@baseboard_fab2_lib.baseboard_fab2(sch_1):m_d_dqs_dn(10)") )
				( member ( signalRef "@baseboard_fab2_lib.baseboard_fab2(sch_1):m_d_dqs_dp(10)") )
				( objectStatus "M_D_DQS_D<10>" )
			)
			( differentialPair "@sapphirecity_baseboard_lib.sapphirecity_baseboard(sch_1):\M_D_DQS_D\(2)"
				( memberType ( signal ) )
				( electricalCSetRef "@crescent_city_bb_fab1_lib.crescent_city_bb_fab1(sch_1):\DDR_DQS_A\" )
				( member ( signalRef "@baseboard_fab2_lib.baseboard_fab2(sch_1):m_d_dqs_dn(2)") )
				( member ( signalRef "@baseboard_fab2_lib.baseboard_fab2(sch_1):m_d_dqs_dp(2)") )
				( objectStatus "M_D_DQS_D<2>" )
			)
			( differentialPair "@sapphirecity_baseboard_lib.sapphirecity_baseboard(sch_1):\M_D_DQS_D\(11)"
				( memberType ( signal ) )
				( electricalCSetRef "@crescent_city_bb_fab1_lib.crescent_city_bb_fab1(sch_1):\DDR_DQS_A\" )
				( member ( signalRef "@baseboard_fab2_lib.baseboard_fab2(sch_1):m_d_dqs_dn(11)") )
				( member ( signalRef "@baseboard_fab2_lib.baseboard_fab2(sch_1):m_d_dqs_dp(11)") )
				( objectStatus "M_D_DQS_D<11>" )
			)
			( differentialPair "@sapphirecity_baseboard_lib.sapphirecity_baseboard(sch_1):\M_D_DQS_D\(3)"
				( memberType ( signal ) )
				( electricalCSetRef "@crescent_city_bb_fab1_lib.crescent_city_bb_fab1(sch_1):\DDR_DQS_A\" )
				( member ( signalRef "@baseboard_fab2_lib.baseboard_fab2(sch_1):m_d_dqs_dn(3)") )
				( member ( signalRef "@baseboard_fab2_lib.baseboard_fab2(sch_1):m_d_dqs_dp(3)") )
				( objectStatus "M_D_DQS_D<3>" )
			)
			( differentialPair "@sapphirecity_baseboard_lib.sapphirecity_baseboard(sch_1):\M_D_DQS_D\(12)"
				( memberType ( signal ) )
				( electricalCSetRef "@crescent_city_bb_fab1_lib.crescent_city_bb_fab1(sch_1):\DDR_DQS_A\" )
				( member ( signalRef "@baseboard_fab2_lib.baseboard_fab2(sch_1):m_d_dqs_dn(12)") )
				( member ( signalRef "@baseboard_fab2_lib.baseboard_fab2(sch_1):m_d_dqs_dp(12)") )
				( objectStatus "M_D_DQS_D<12>" )
			)
			( differentialPair "@sapphirecity_baseboard_lib.sapphirecity_baseboard(sch_1):\M_D_DQS_D\(4)"
				( memberType ( signal ) )
				( electricalCSetRef "@crescent_city_bb_fab1_lib.crescent_city_bb_fab1(sch_1):\DDR_DQS_A\" )
				( member ( signalRef "@baseboard_fab2_lib.baseboard_fab2(sch_1):m_d_dqs_dn(4)") )
				( member ( signalRef "@baseboard_fab2_lib.baseboard_fab2(sch_1):m_d_dqs_dp(4)") )
				( objectStatus "M_D_DQS_D<4>" )
			)
			( differentialPair "@sapphirecity_baseboard_lib.sapphirecity_baseboard(sch_1):\M_D_DQS_D\(13)"
				( memberType ( signal ) )
				( electricalCSetRef "@crescent_city_bb_fab1_lib.crescent_city_bb_fab1(sch_1):\DDR_DQS_A\" )
				( member ( signalRef "@baseboard_fab2_lib.baseboard_fab2(sch_1):m_d_dqs_dn(13)") )
				( member ( signalRef "@baseboard_fab2_lib.baseboard_fab2(sch_1):m_d_dqs_dp(13)") )
				( objectStatus "M_D_DQS_D<13>" )
			)
			( differentialPair "@sapphirecity_baseboard_lib.sapphirecity_baseboard(sch_1):\M_D_DQS_D\(5)"
				( memberType ( signal ) )
				( electricalCSetRef "@crescent_city_bb_fab1_lib.crescent_city_bb_fab1(sch_1):\DDR_DQS_A\" )
				( member ( signalRef "@baseboard_fab2_lib.baseboard_fab2(sch_1):m_d_dqs_dn(5)") )
				( member ( signalRef "@baseboard_fab2_lib.baseboard_fab2(sch_1):m_d_dqs_dp(5)") )
				( objectStatus "M_D_DQS_D<5>" )
			)
			( differentialPair "@sapphirecity_baseboard_lib.sapphirecity_baseboard(sch_1):\M_D_DQS_D\(14)"
				( memberType ( signal ) )
				( electricalCSetRef "@crescent_city_bb_fab1_lib.crescent_city_bb_fab1(sch_1):\DDR_DQS_A\" )
				( member ( signalRef "@baseboard_fab2_lib.baseboard_fab2(sch_1):m_d_dqs_dn(14)") )
				( member ( signalRef "@baseboard_fab2_lib.baseboard_fab2(sch_1):m_d_dqs_dp(14)") )
				( objectStatus "M_D_DQS_D<14>" )
			)
			( differentialPair "@sapphirecity_baseboard_lib.sapphirecity_baseboard(sch_1):\M_D_DQS_D\(6)"
				( memberType ( signal ) )
				( electricalCSetRef "@crescent_city_bb_fab1_lib.crescent_city_bb_fab1(sch_1):\DDR_DQS_A\" )
				( member ( signalRef "@baseboard_fab2_lib.baseboard_fab2(sch_1):m_d_dqs_dn(6)") )
				( member ( signalRef "@baseboard_fab2_lib.baseboard_fab2(sch_1):m_d_dqs_dp(6)") )
				( objectStatus "M_D_DQS_D<6>" )
			)
			( differentialPair "@sapphirecity_baseboard_lib.sapphirecity_baseboard(sch_1):\M_D_DQS_D\(15)"
				( memberType ( signal ) )
				( electricalCSetRef "@crescent_city_bb_fab1_lib.crescent_city_bb_fab1(sch_1):\DDR_DQS_A\" )
				( member ( signalRef "@baseboard_fab2_lib.baseboard_fab2(sch_1):m_d_dqs_dn(15)") )
				( member ( signalRef "@baseboard_fab2_lib.baseboard_fab2(sch_1):m_d_dqs_dp(15)") )
				( objectStatus "M_D_DQS_D<15>" )
			)
			( differentialPair "@sapphirecity_baseboard_lib.sapphirecity_baseboard(sch_1):\M_D_DQS_D\(7)"
				( memberType ( signal ) )
				( electricalCSetRef "@crescent_city_bb_fab1_lib.crescent_city_bb_fab1(sch_1):\DDR_DQS_A\" )
				( member ( signalRef "@baseboard_fab2_lib.baseboard_fab2(sch_1):m_d_dqs_dn(7)") )
				( member ( signalRef "@baseboard_fab2_lib.baseboard_fab2(sch_1):m_d_dqs_dp(7)") )
				( objectStatus "M_D_DQS_D<7>" )
			)
			( differentialPair "@sapphirecity_baseboard_lib.sapphirecity_baseboard(sch_1):\M_D_DQS_D\(16)"
				( memberType ( signal ) )
				( electricalCSetRef "@crescent_city_bb_fab1_lib.crescent_city_bb_fab1(sch_1):\DDR_DQS_A\" )
				( member ( signalRef "@baseboard_fab2_lib.baseboard_fab2(sch_1):m_d_dqs_dn(16)") )
				( member ( signalRef "@baseboard_fab2_lib.baseboard_fab2(sch_1):m_d_dqs_dp(16)") )
				( objectStatus "M_D_DQS_D<16>" )
			)
			( differentialPair "@sapphirecity_baseboard_lib.sapphirecity_baseboard(sch_1):\M_F_DQS_D\(8)"
				( memberType ( signal ) )
				( electricalCSetRef "@crescent_city_bb_fab1_lib.crescent_city_bb_fab1(sch_1):\DDR_DQS_A\" )
				( member ( signalRef "@baseboard_fab2_lib.baseboard_fab2(sch_1):m_f_dqs_dn(8)") )
				( member ( signalRef "@baseboard_fab2_lib.baseboard_fab2(sch_1):m_f_dqs_dp(8)") )
				( objectStatus "M_F_DQS_D<8>" )
			)
			( differentialPair "@sapphirecity_baseboard_lib.sapphirecity_baseboard(sch_1):\M_F_DQS_D\(17)"
				( memberType ( signal ) )
				( electricalCSetRef "@crescent_city_bb_fab1_lib.crescent_city_bb_fab1(sch_1):\DDR_DQS_A\" )
				( member ( signalRef "@baseboard_fab2_lib.baseboard_fab2(sch_1):m_f_dqs_dn(17)") )
				( member ( signalRef "@baseboard_fab2_lib.baseboard_fab2(sch_1):m_f_dqs_dp(17)") )
				( objectStatus "M_F_DQS_D<17>" )
			)
			( differentialPair "@sapphirecity_baseboard_lib.sapphirecity_baseboard(sch_1):\M_F_DQS_D\(7)"
				( memberType ( signal ) )
				( electricalCSetRef "@crescent_city_bb_fab1_lib.crescent_city_bb_fab1(sch_1):\DDR_DQS_A\" )
				( member ( signalRef "@baseboard_fab2_lib.baseboard_fab2(sch_1):m_f_dqs_dn(7)") )
				( member ( signalRef "@baseboard_fab2_lib.baseboard_fab2(sch_1):m_f_dqs_dp(7)") )
				( objectStatus "M_F_DQS_D<7>" )
			)
			( differentialPair "@sapphirecity_baseboard_lib.sapphirecity_baseboard(sch_1):\M_F_DQS_D\(16)"
				( memberType ( signal ) )
				( electricalCSetRef "@crescent_city_bb_fab1_lib.crescent_city_bb_fab1(sch_1):\DDR_DQS_A\" )
				( member ( signalRef "@baseboard_fab2_lib.baseboard_fab2(sch_1):m_f_dqs_dn(16)") )
				( member ( signalRef "@baseboard_fab2_lib.baseboard_fab2(sch_1):m_f_dqs_dp(16)") )
				( objectStatus "M_F_DQS_D<16>" )
			)
			( differentialPair "@sapphirecity_baseboard_lib.sapphirecity_baseboard(sch_1):\M_F_DQS_D\(6)"
				( memberType ( signal ) )
				( electricalCSetRef "@crescent_city_bb_fab1_lib.crescent_city_bb_fab1(sch_1):\DDR_DQS_A\" )
				( member ( signalRef "@baseboard_fab2_lib.baseboard_fab2(sch_1):m_f_dqs_dn(6)") )
				( member ( signalRef "@baseboard_fab2_lib.baseboard_fab2(sch_1):m_f_dqs_dp(6)") )
				( objectStatus "M_F_DQS_D<6>" )
			)
			( differentialPair "@sapphirecity_baseboard_lib.sapphirecity_baseboard(sch_1):\M_F_DQS_D\(15)"
				( memberType ( signal ) )
				( electricalCSetRef "@crescent_city_bb_fab1_lib.crescent_city_bb_fab1(sch_1):\DDR_DQS_A\" )
				( member ( signalRef "@baseboard_fab2_lib.baseboard_fab2(sch_1):m_f_dqs_dn(15)") )
				( member ( signalRef "@baseboard_fab2_lib.baseboard_fab2(sch_1):m_f_dqs_dp(15)") )
				( objectStatus "M_F_DQS_D<15>" )
			)
			( differentialPair "@sapphirecity_baseboard_lib.sapphirecity_baseboard(sch_1):\M_F_DQS_D\(5)"
				( memberType ( signal ) )
				( electricalCSetRef "@crescent_city_bb_fab1_lib.crescent_city_bb_fab1(sch_1):\DDR_DQS_A\" )
				( member ( signalRef "@baseboard_fab2_lib.baseboard_fab2(sch_1):m_f_dqs_dn(5)") )
				( member ( signalRef "@baseboard_fab2_lib.baseboard_fab2(sch_1):m_f_dqs_dp(5)") )
				( objectStatus "M_F_DQS_D<5>" )
			)
			( differentialPair "@sapphirecity_baseboard_lib.sapphirecity_baseboard(sch_1):\M_F_DQS_D\(14)"
				( memberType ( signal ) )
				( electricalCSetRef "@crescent_city_bb_fab1_lib.crescent_city_bb_fab1(sch_1):\DDR_DQS_A\" )
				( member ( signalRef "@baseboard_fab2_lib.baseboard_fab2(sch_1):m_f_dqs_dn(14)") )
				( member ( signalRef "@baseboard_fab2_lib.baseboard_fab2(sch_1):m_f_dqs_dp(14)") )
				( objectStatus "M_F_DQS_D<14>" )
			)
			( differentialPair "@sapphirecity_baseboard_lib.sapphirecity_baseboard(sch_1):\M_F_DQS_D\(4)"
				( memberType ( signal ) )
				( electricalCSetRef "@crescent_city_bb_fab1_lib.crescent_city_bb_fab1(sch_1):\DDR_DQS_A\" )
				( member ( signalRef "@baseboard_fab2_lib.baseboard_fab2(sch_1):m_f_dqs_dn(4)") )
				( member ( signalRef "@baseboard_fab2_lib.baseboard_fab2(sch_1):m_f_dqs_dp(4)") )
				( objectStatus "M_F_DQS_D<4>" )
			)
			( differentialPair "@sapphirecity_baseboard_lib.sapphirecity_baseboard(sch_1):\M_F_DQS_D\(13)"
				( memberType ( signal ) )
				( electricalCSetRef "@crescent_city_bb_fab1_lib.crescent_city_bb_fab1(sch_1):\DDR_DQS_A\" )
				( member ( signalRef "@baseboard_fab2_lib.baseboard_fab2(sch_1):m_f_dqs_dn(13)") )
				( member ( signalRef "@baseboard_fab2_lib.baseboard_fab2(sch_1):m_f_dqs_dp(13)") )
				( objectStatus "M_F_DQS_D<13>" )
			)
			( differentialPair "@sapphirecity_baseboard_lib.sapphirecity_baseboard(sch_1):\M_F_DQS_D\(3)"
				( memberType ( signal ) )
				( electricalCSetRef "@crescent_city_bb_fab1_lib.crescent_city_bb_fab1(sch_1):\DDR_DQS_A\" )
				( member ( signalRef "@baseboard_fab2_lib.baseboard_fab2(sch_1):m_f_dqs_dn(3)") )
				( member ( signalRef "@baseboard_fab2_lib.baseboard_fab2(sch_1):m_f_dqs_dp(3)") )
				( objectStatus "M_F_DQS_D<3>" )
			)
			( differentialPair "@sapphirecity_baseboard_lib.sapphirecity_baseboard(sch_1):\M_F_DQS_D\(12)"
				( memberType ( signal ) )
				( electricalCSetRef "@crescent_city_bb_fab1_lib.crescent_city_bb_fab1(sch_1):\DDR_DQS_A\" )
				( member ( signalRef "@baseboard_fab2_lib.baseboard_fab2(sch_1):m_f_dqs_dn(12)") )
				( member ( signalRef "@baseboard_fab2_lib.baseboard_fab2(sch_1):m_f_dqs_dp(12)") )
				( objectStatus "M_F_DQS_D<12>" )
			)
			( differentialPair "@sapphirecity_baseboard_lib.sapphirecity_baseboard(sch_1):\M_F_DQS_D\(2)"
				( memberType ( signal ) )
				( electricalCSetRef "@crescent_city_bb_fab1_lib.crescent_city_bb_fab1(sch_1):\DDR_DQS_A\" )
				( member ( signalRef "@baseboard_fab2_lib.baseboard_fab2(sch_1):m_f_dqs_dn(2)") )
				( member ( signalRef "@baseboard_fab2_lib.baseboard_fab2(sch_1):m_f_dqs_dp(2)") )
				( objectStatus "M_F_DQS_D<2>" )
			)
			( differentialPair "@sapphirecity_baseboard_lib.sapphirecity_baseboard(sch_1):\M_F_DQS_D\(11)"
				( memberType ( signal ) )
				( electricalCSetRef "@crescent_city_bb_fab1_lib.crescent_city_bb_fab1(sch_1):\DDR_DQS_A\" )
				( member ( signalRef "@baseboard_fab2_lib.baseboard_fab2(sch_1):m_f_dqs_dn(11)") )
				( member ( signalRef "@baseboard_fab2_lib.baseboard_fab2(sch_1):m_f_dqs_dp(11)") )
				( objectStatus "M_F_DQS_D<11>" )
			)
			( differentialPair "@sapphirecity_baseboard_lib.sapphirecity_baseboard(sch_1):\M_F_DQS_D\(1)"
				( memberType ( signal ) )
				( electricalCSetRef "@crescent_city_bb_fab1_lib.crescent_city_bb_fab1(sch_1):\DDR_DQS_A\" )
				( member ( signalRef "@baseboard_fab2_lib.baseboard_fab2(sch_1):m_f_dqs_dn(1)") )
				( member ( signalRef "@baseboard_fab2_lib.baseboard_fab2(sch_1):m_f_dqs_dp(1)") )
				( objectStatus "M_F_DQS_D<1>" )
			)
			( differentialPair "@sapphirecity_baseboard_lib.sapphirecity_baseboard(sch_1):\M_F_DQS_D\(10)"
				( memberType ( signal ) )
				( electricalCSetRef "@crescent_city_bb_fab1_lib.crescent_city_bb_fab1(sch_1):\DDR_DQS_A\" )
				( member ( signalRef "@baseboard_fab2_lib.baseboard_fab2(sch_1):m_f_dqs_dn(10)") )
				( member ( signalRef "@baseboard_fab2_lib.baseboard_fab2(sch_1):m_f_dqs_dp(10)") )
				( objectStatus "M_F_DQS_D<10>" )
			)
			( differentialPair "@sapphirecity_baseboard_lib.sapphirecity_baseboard(sch_1):\M_F_DQS_D\(0)"
				( memberType ( signal ) )
				( electricalCSetRef "@crescent_city_bb_fab1_lib.crescent_city_bb_fab1(sch_1):\DDR_DQS_A\" )
				( member ( signalRef "@baseboard_fab2_lib.baseboard_fab2(sch_1):m_f_dqs_dn(0)") )
				( member ( signalRef "@baseboard_fab2_lib.baseboard_fab2(sch_1):m_f_dqs_dp(0)") )
				( objectStatus "M_F_DQS_D<0>" )
			)
			( differentialPair "@sapphirecity_baseboard_lib.sapphirecity_baseboard(sch_1):\M_F_DQS_D\(9)"
				( memberType ( signal ) )
				( electricalCSetRef "@crescent_city_bb_fab1_lib.crescent_city_bb_fab1(sch_1):\DDR_DQS_A\" )
				( member ( signalRef "@baseboard_fab2_lib.baseboard_fab2(sch_1):m_f_dqs_dn(9)") )
				( member ( signalRef "@baseboard_fab2_lib.baseboard_fab2(sch_1):m_f_dqs_dp(9)") )
				( objectStatus "M_F_DQS_D<9>" )
			)
			( differentialPair "@sapphirecity_baseboard_lib.sapphirecity_baseboard(sch_1):\M_E_DQS_D\(8)"
				( memberType ( signal ) )
				( electricalCSetRef "@crescent_city_bb_fab1_lib.crescent_city_bb_fab1(sch_1):\DDR_DQS_A\" )
				( member ( signalRef "@baseboard_fab2_lib.baseboard_fab2(sch_1):m_e_dqs_dn(8)") )
				( member ( signalRef "@baseboard_fab2_lib.baseboard_fab2(sch_1):m_e_dqs_dp(8)") )
				( objectStatus "M_E_DQS_D<8>" )
			)
			( differentialPair "@sapphirecity_baseboard_lib.sapphirecity_baseboard(sch_1):\M_E_DQS_D\(17)"
				( memberType ( signal ) )
				( electricalCSetRef "@crescent_city_bb_fab1_lib.crescent_city_bb_fab1(sch_1):\DDR_DQS_A\" )
				( member ( signalRef "@baseboard_fab2_lib.baseboard_fab2(sch_1):m_e_dqs_dn(17)") )
				( member ( signalRef "@baseboard_fab2_lib.baseboard_fab2(sch_1):m_e_dqs_dp(17)") )
				( objectStatus "M_E_DQS_D<17>" )
			)
			( differentialPair "@sapphirecity_baseboard_lib.sapphirecity_baseboard(sch_1):\M_E_DQS_D\(7)"
				( memberType ( signal ) )
				( electricalCSetRef "@crescent_city_bb_fab1_lib.crescent_city_bb_fab1(sch_1):\DDR_DQS_A\" )
				( member ( signalRef "@baseboard_fab2_lib.baseboard_fab2(sch_1):m_e_dqs_dn(7)") )
				( member ( signalRef "@baseboard_fab2_lib.baseboard_fab2(sch_1):m_e_dqs_dp(7)") )
				( objectStatus "M_E_DQS_D<7>" )
			)
			( differentialPair "@sapphirecity_baseboard_lib.sapphirecity_baseboard(sch_1):\M_E_DQS_D\(16)"
				( memberType ( signal ) )
				( electricalCSetRef "@crescent_city_bb_fab1_lib.crescent_city_bb_fab1(sch_1):\DDR_DQS_A\" )
				( member ( signalRef "@baseboard_fab2_lib.baseboard_fab2(sch_1):m_e_dqs_dn(16)") )
				( member ( signalRef "@baseboard_fab2_lib.baseboard_fab2(sch_1):m_e_dqs_dp(16)") )
				( objectStatus "M_E_DQS_D<16>" )
			)
			( differentialPair "@sapphirecity_baseboard_lib.sapphirecity_baseboard(sch_1):\M_E_DQS_D\(6)"
				( memberType ( signal ) )
				( electricalCSetRef "@crescent_city_bb_fab1_lib.crescent_city_bb_fab1(sch_1):\DDR_DQS_A\" )
				( member ( signalRef "@baseboard_fab2_lib.baseboard_fab2(sch_1):m_e_dqs_dn(6)") )
				( member ( signalRef "@baseboard_fab2_lib.baseboard_fab2(sch_1):m_e_dqs_dp(6)") )
				( objectStatus "M_E_DQS_D<6>" )
			)
			( differentialPair "@sapphirecity_baseboard_lib.sapphirecity_baseboard(sch_1):\M_E_DQS_D\(15)"
				( memberType ( signal ) )
				( electricalCSetRef "@crescent_city_bb_fab1_lib.crescent_city_bb_fab1(sch_1):\DDR_DQS_A\" )
				( member ( signalRef "@baseboard_fab2_lib.baseboard_fab2(sch_1):m_e_dqs_dn(15)") )
				( member ( signalRef "@baseboard_fab2_lib.baseboard_fab2(sch_1):m_e_dqs_dp(15)") )
				( objectStatus "M_E_DQS_D<15>" )
			)
			( differentialPair "@sapphirecity_baseboard_lib.sapphirecity_baseboard(sch_1):\M_E_DQS_D\(5)"
				( memberType ( signal ) )
				( electricalCSetRef "@crescent_city_bb_fab1_lib.crescent_city_bb_fab1(sch_1):\DDR_DQS_A\" )
				( member ( signalRef "@baseboard_fab2_lib.baseboard_fab2(sch_1):m_e_dqs_dn(5)") )
				( member ( signalRef "@baseboard_fab2_lib.baseboard_fab2(sch_1):m_e_dqs_dp(5)") )
				( objectStatus "M_E_DQS_D<5>" )
			)
			( differentialPair "@sapphirecity_baseboard_lib.sapphirecity_baseboard(sch_1):\M_E_DQS_D\(14)"
				( memberType ( signal ) )
				( electricalCSetRef "@crescent_city_bb_fab1_lib.crescent_city_bb_fab1(sch_1):\DDR_DQS_A\" )
				( member ( signalRef "@baseboard_fab2_lib.baseboard_fab2(sch_1):m_e_dqs_dn(14)") )
				( member ( signalRef "@baseboard_fab2_lib.baseboard_fab2(sch_1):m_e_dqs_dp(14)") )
				( objectStatus "M_E_DQS_D<14>" )
			)
			( differentialPair "@sapphirecity_baseboard_lib.sapphirecity_baseboard(sch_1):\M_E_DQS_D\(4)"
				( memberType ( signal ) )
				( electricalCSetRef "@crescent_city_bb_fab1_lib.crescent_city_bb_fab1(sch_1):\DDR_DQS_A\" )
				( member ( signalRef "@baseboard_fab2_lib.baseboard_fab2(sch_1):m_e_dqs_dn(4)") )
				( member ( signalRef "@baseboard_fab2_lib.baseboard_fab2(sch_1):m_e_dqs_dp(4)") )
				( objectStatus "M_E_DQS_D<4>" )
			)
			( differentialPair "@sapphirecity_baseboard_lib.sapphirecity_baseboard(sch_1):\M_E_DQS_D\(13)"
				( memberType ( signal ) )
				( electricalCSetRef "@crescent_city_bb_fab1_lib.crescent_city_bb_fab1(sch_1):\DDR_DQS_A\" )
				( member ( signalRef "@baseboard_fab2_lib.baseboard_fab2(sch_1):m_e_dqs_dn(13)") )
				( member ( signalRef "@baseboard_fab2_lib.baseboard_fab2(sch_1):m_e_dqs_dp(13)") )
				( objectStatus "M_E_DQS_D<13>" )
			)
			( differentialPair "@sapphirecity_baseboard_lib.sapphirecity_baseboard(sch_1):\M_E_DQS_D\(3)"
				( memberType ( signal ) )
				( electricalCSetRef "@crescent_city_bb_fab1_lib.crescent_city_bb_fab1(sch_1):\DDR_DQS_A\" )
				( member ( signalRef "@baseboard_fab2_lib.baseboard_fab2(sch_1):m_e_dqs_dn(3)") )
				( member ( signalRef "@baseboard_fab2_lib.baseboard_fab2(sch_1):m_e_dqs_dp(3)") )
				( objectStatus "M_E_DQS_D<3>" )
			)
			( differentialPair "@sapphirecity_baseboard_lib.sapphirecity_baseboard(sch_1):\M_E_DQS_D\(12)"
				( memberType ( signal ) )
				( electricalCSetRef "@crescent_city_bb_fab1_lib.crescent_city_bb_fab1(sch_1):\DDR_DQS_A\" )
				( member ( signalRef "@baseboard_fab2_lib.baseboard_fab2(sch_1):m_e_dqs_dn(12)") )
				( member ( signalRef "@baseboard_fab2_lib.baseboard_fab2(sch_1):m_e_dqs_dp(12)") )
				( objectStatus "M_E_DQS_D<12>" )
			)
			( differentialPair "@sapphirecity_baseboard_lib.sapphirecity_baseboard(sch_1):\M_E_DQS_D\(2)"
				( memberType ( signal ) )
				( electricalCSetRef "@crescent_city_bb_fab1_lib.crescent_city_bb_fab1(sch_1):\DDR_DQS_A\" )
				( member ( signalRef "@baseboard_fab2_lib.baseboard_fab2(sch_1):m_e_dqs_dn(2)") )
				( member ( signalRef "@baseboard_fab2_lib.baseboard_fab2(sch_1):m_e_dqs_dp(2)") )
				( objectStatus "M_E_DQS_D<2>" )
			)
			( differentialPair "@sapphirecity_baseboard_lib.sapphirecity_baseboard(sch_1):\M_E_DQS_D\(11)"
				( memberType ( signal ) )
				( electricalCSetRef "@crescent_city_bb_fab1_lib.crescent_city_bb_fab1(sch_1):\DDR_DQS_A\" )
				( member ( signalRef "@baseboard_fab2_lib.baseboard_fab2(sch_1):m_e_dqs_dn(11)") )
				( member ( signalRef "@baseboard_fab2_lib.baseboard_fab2(sch_1):m_e_dqs_dp(11)") )
				( objectStatus "M_E_DQS_D<11>" )
			)
			( differentialPair "@sapphirecity_baseboard_lib.sapphirecity_baseboard(sch_1):\M_E_DQS_D\(1)"
				( memberType ( signal ) )
				( electricalCSetRef "@crescent_city_bb_fab1_lib.crescent_city_bb_fab1(sch_1):\DDR_DQS_A\" )
				( member ( signalRef "@baseboard_fab2_lib.baseboard_fab2(sch_1):m_e_dqs_dn(1)") )
				( member ( signalRef "@baseboard_fab2_lib.baseboard_fab2(sch_1):m_e_dqs_dp(1)") )
				( objectStatus "M_E_DQS_D<1>" )
			)
			( differentialPair "@sapphirecity_baseboard_lib.sapphirecity_baseboard(sch_1):\M_E_DQS_D\(10)"
				( memberType ( signal ) )
				( electricalCSetRef "@crescent_city_bb_fab1_lib.crescent_city_bb_fab1(sch_1):\DDR_DQS_A\" )
				( member ( signalRef "@baseboard_fab2_lib.baseboard_fab2(sch_1):m_e_dqs_dn(10)") )
				( member ( signalRef "@baseboard_fab2_lib.baseboard_fab2(sch_1):m_e_dqs_dp(10)") )
				( objectStatus "M_E_DQS_D<10>" )
			)
			( differentialPair "@sapphirecity_baseboard_lib.sapphirecity_baseboard(sch_1):\M_E_DQS_D\(0)"
				( memberType ( signal ) )
				( electricalCSetRef "@crescent_city_bb_fab1_lib.crescent_city_bb_fab1(sch_1):\DDR_DQS_A\" )
				( member ( signalRef "@baseboard_fab2_lib.baseboard_fab2(sch_1):m_e_dqs_dn(0)") )
				( member ( signalRef "@baseboard_fab2_lib.baseboard_fab2(sch_1):m_e_dqs_dp(0)") )
				( objectStatus "M_E_DQS_D<0>" )
			)
			( differentialPair "@sapphirecity_baseboard_lib.sapphirecity_baseboard(sch_1):\M_E_DQS_D\(9)"
				( memberType ( signal ) )
				( electricalCSetRef "@crescent_city_bb_fab1_lib.crescent_city_bb_fab1(sch_1):\DDR_DQS_A\" )
				( member ( signalRef "@baseboard_fab2_lib.baseboard_fab2(sch_1):m_e_dqs_dn(9)") )
				( member ( signalRef "@baseboard_fab2_lib.baseboard_fab2(sch_1):m_e_dqs_dp(9)") )
				( objectStatus "M_E_DQS_D<9>" )
			)
			( differentialPair "@sapphirecity_baseboard_lib.sapphirecity_baseboard(sch_1):\M_D_DQS_D\(8)"
				( memberType ( signal ) )
				( electricalCSetRef "@crescent_city_bb_fab1_lib.crescent_city_bb_fab1(sch_1):\DDR_DQS_A\" )
				( member ( signalRef "@baseboard_fab2_lib.baseboard_fab2(sch_1):m_d_dqs_dn(8)") )
				( member ( signalRef "@baseboard_fab2_lib.baseboard_fab2(sch_1):m_d_dqs_dp(8)") )
				( objectStatus "M_D_DQS_D<8>" )
			)
			( differentialPair "@sapphirecity_baseboard_lib.sapphirecity_baseboard(sch_1):\M_D_DQS_D\(17)"
				( memberType ( signal ) )
				( electricalCSetRef "@crescent_city_bb_fab1_lib.crescent_city_bb_fab1(sch_1):\DDR_DQS_A\" )
				( member ( signalRef "@baseboard_fab2_lib.baseboard_fab2(sch_1):m_d_dqs_dn(17)") )
				( member ( signalRef "@baseboard_fab2_lib.baseboard_fab2(sch_1):m_d_dqs_dp(17)") )
				( objectStatus "M_D_DQS_D<17>" )
			)
			( differentialPair "@sapphirecity_baseboard_lib.sapphirecity_baseboard(sch_1):\M_C_DQS_D\(8)"
				( memberType ( signal ) )
				( electricalCSetRef "@crescent_city_bb_fab1_lib.crescent_city_bb_fab1(sch_1):\DDR_DQS_A\" )
				( member ( signalRef "@baseboard_fab2_lib.baseboard_fab2(sch_1):m_c_dqs_dn(8)") )
				( member ( signalRef "@baseboard_fab2_lib.baseboard_fab2(sch_1):m_c_dqs_dp(8)") )
				( objectStatus "M_C_DQS_D<8>" )
			)
			( differentialPair "@sapphirecity_baseboard_lib.sapphirecity_baseboard(sch_1):\M_C_DQS_D\(17)"
				( memberType ( signal ) )
				( electricalCSetRef "@crescent_city_bb_fab1_lib.crescent_city_bb_fab1(sch_1):\DDR_DQS_A\" )
				( member ( signalRef "@baseboard_fab2_lib.baseboard_fab2(sch_1):m_c_dqs_dn(17)") )
				( member ( signalRef "@baseboard_fab2_lib.baseboard_fab2(sch_1):m_c_dqs_dp(17)") )
				( objectStatus "M_C_DQS_D<17>" )
			)
			( differentialPair "@sapphirecity_baseboard_lib.sapphirecity_baseboard(sch_1):\M_B_DQS_D\(8)"
				( memberType ( signal ) )
				( electricalCSetRef "@crescent_city_bb_fab1_lib.crescent_city_bb_fab1(sch_1):\DDR_DQS_A\" )
				( member ( signalRef "@baseboard_fab2_lib.baseboard_fab2(sch_1):m_b_dqs_dn(8)") )
				( member ( signalRef "@baseboard_fab2_lib.baseboard_fab2(sch_1):m_b_dqs_dp(8)") )
				( objectStatus "M_B_DQS_D<8>" )
			)
			( differentialPair "@sapphirecity_baseboard_lib.sapphirecity_baseboard(sch_1):\M_B_DQS_D\(17)"
				( memberType ( signal ) )
				( electricalCSetRef "@crescent_city_bb_fab1_lib.crescent_city_bb_fab1(sch_1):\DDR_DQS_A\" )
				( member ( signalRef "@baseboard_fab2_lib.baseboard_fab2(sch_1):m_b_dqs_dn(17)") )
				( member ( signalRef "@baseboard_fab2_lib.baseboard_fab2(sch_1):m_b_dqs_dp(17)") )
				( objectStatus "M_B_DQS_D<17>" )
			)
			( differentialPair "@sapphirecity_baseboard_lib.sapphirecity_baseboard(sch_1):\M_A_DQS_D\(8)"
				( memberType ( signal ) )
				( electricalCSetRef "@crescent_city_bb_fab1_lib.crescent_city_bb_fab1(sch_1):\DDR_DQS_A\" )
				( member ( signalRef "@baseboard_fab2_lib.baseboard_fab2(sch_1):m_a_dqs_dn(8)") )
				( member ( signalRef "@baseboard_fab2_lib.baseboard_fab2(sch_1):m_a_dqs_dp(8)") )
				( objectStatus "M_A_DQS_D<8>" )
			)
			( differentialPair "@sapphirecity_baseboard_lib.sapphirecity_baseboard(sch_1):\M_A_DQS_D\(17)"
				( memberType ( signal ) )
				( electricalCSetRef "@crescent_city_bb_fab1_lib.crescent_city_bb_fab1(sch_1):\DDR_DQS_A\" )
				( member ( signalRef "@baseboard_fab2_lib.baseboard_fab2(sch_1):m_a_dqs_dn(17)") )
				( member ( signalRef "@baseboard_fab2_lib.baseboard_fab2(sch_1):m_a_dqs_dp(17)") )
				( objectStatus "M_A_DQS_D<17>" )
			)
			( bus "@baseboard_fab2_lib.baseboard_fab2(sch_1):tp_rsvd"
				( memberType ( signal ) )
				( member ( signalRef "@baseboard_fab2_lib.baseboard_fab2(sch_1):tp_rsvd(0)") )
				( objectStatus "TP_RSVD" )
			)
			( bus "@crescent_city_bb_fab1_lib.crescent_city_bb_fab1(sch_1):p3e_ocp_cpu0_pe3_c_txn"
				( memberType ( signal ) )
				( member ( electricalNetRef "@crescent_city_bb_fab1_lib.crescent_city_bb_fab1(sch_1):p3e_cpu0_pe3_ocp_txn(3)") )
				( member ( electricalNetRef "@crescent_city_bb_fab1_lib.crescent_city_bb_fab1(sch_1):p3e_cpu0_pe3_ocp_txn(2)") )
				( member ( electricalNetRef "@crescent_city_bb_fab1_lib.crescent_city_bb_fab1(sch_1):p3e_cpu0_pe3_ocp_txn(1)") )
				( member ( electricalNetRef "@crescent_city_bb_fab1_lib.crescent_city_bb_fab1(sch_1):p3e_cpu0_pe3_ocp_txn(0)") )
				( member ( electricalNetRef "@crescent_city_bb_fab1_lib.crescent_city_bb_fab1(sch_1):p3e_cpu0_pe3_ocp_txn(7)") )
				( member ( electricalNetRef "@crescent_city_bb_fab1_lib.crescent_city_bb_fab1(sch_1):p3e_cpu0_pe3_ocp_txn(6)") )
				( member ( electricalNetRef "@crescent_city_bb_fab1_lib.crescent_city_bb_fab1(sch_1):p3e_cpu0_pe3_ocp_txn(5)") )
				( member ( electricalNetRef "@crescent_city_bb_fab1_lib.crescent_city_bb_fab1(sch_1):p3e_cpu0_pe3_ocp_txn(4)") )
				( member ( electricalNetRef "@crescent_city_bb_fab1_lib.crescent_city_bb_fab1(sch_1):p3e_cpu0_pe3_ocp_txn(9)") )
				( member ( electricalNetRef "@crescent_city_bb_fab1_lib.crescent_city_bb_fab1(sch_1):p3e_cpu0_pe3_ocp_txn(8)") )
				( member ( electricalNetRef "@crescent_city_bb_fab1_lib.crescent_city_bb_fab1(sch_1):p3e_cpu0_pe3_ocp_txn(15)") )
				( member ( electricalNetRef "@crescent_city_bb_fab1_lib.crescent_city_bb_fab1(sch_1):p3e_cpu0_pe3_ocp_txn(14)") )
				( member ( electricalNetRef "@crescent_city_bb_fab1_lib.crescent_city_bb_fab1(sch_1):p3e_cpu0_pe3_ocp_txn(13)") )
				( member ( electricalNetRef "@crescent_city_bb_fab1_lib.crescent_city_bb_fab1(sch_1):p3e_cpu0_pe3_ocp_txn(12)") )
				( member ( electricalNetRef "@crescent_city_bb_fab1_lib.crescent_city_bb_fab1(sch_1):p3e_cpu0_pe3_ocp_txn(11)") )
				( member ( electricalNetRef "@crescent_city_bb_fab1_lib.crescent_city_bb_fab1(sch_1):p3e_cpu0_pe3_ocp_txn(10)") )
				( objectStatus "P3E_OCP_CPU0_PE3_C_TXN" )
			)
			( bus "@crescent_city_bb_fab1_lib.crescent_city_bb_fab1(sch_1):p3e_ocp_cpu0_pe3_c_txp"
				( memberType ( signal ) )
				( member ( electricalNetRef "@crescent_city_bb_fab1_lib.crescent_city_bb_fab1(sch_1):p3e_cpu0_pe3_ocp_txp(3)") )
				( member ( electricalNetRef "@crescent_city_bb_fab1_lib.crescent_city_bb_fab1(sch_1):p3e_cpu0_pe3_ocp_txp(2)") )
				( member ( electricalNetRef "@crescent_city_bb_fab1_lib.crescent_city_bb_fab1(sch_1):p3e_cpu0_pe3_ocp_txp(1)") )
				( member ( electricalNetRef "@crescent_city_bb_fab1_lib.crescent_city_bb_fab1(sch_1):p3e_cpu0_pe3_ocp_txp(0)") )
				( member ( electricalNetRef "@crescent_city_bb_fab1_lib.crescent_city_bb_fab1(sch_1):p3e_cpu0_pe3_ocp_txp(7)") )
				( member ( electricalNetRef "@crescent_city_bb_fab1_lib.crescent_city_bb_fab1(sch_1):p3e_cpu0_pe3_ocp_txp(6)") )
				( member ( electricalNetRef "@crescent_city_bb_fab1_lib.crescent_city_bb_fab1(sch_1):p3e_cpu0_pe3_ocp_txp(5)") )
				( member ( electricalNetRef "@crescent_city_bb_fab1_lib.crescent_city_bb_fab1(sch_1):p3e_cpu0_pe3_ocp_txp(4)") )
				( member ( electricalNetRef "@crescent_city_bb_fab1_lib.crescent_city_bb_fab1(sch_1):p3e_cpu0_pe3_ocp_txp(9)") )
				( member ( electricalNetRef "@crescent_city_bb_fab1_lib.crescent_city_bb_fab1(sch_1):p3e_cpu0_pe3_ocp_txp(8)") )
				( member ( electricalNetRef "@crescent_city_bb_fab1_lib.crescent_city_bb_fab1(sch_1):p3e_cpu0_pe3_ocp_txp(15)") )
				( member ( electricalNetRef "@crescent_city_bb_fab1_lib.crescent_city_bb_fab1(sch_1):p3e_cpu0_pe3_ocp_txp(14)") )
				( member ( electricalNetRef "@crescent_city_bb_fab1_lib.crescent_city_bb_fab1(sch_1):p3e_cpu0_pe3_ocp_txp(13)") )
				( member ( electricalNetRef "@crescent_city_bb_fab1_lib.crescent_city_bb_fab1(sch_1):p3e_cpu0_pe3_ocp_txp(12)") )
				( member ( electricalNetRef "@crescent_city_bb_fab1_lib.crescent_city_bb_fab1(sch_1):p3e_cpu0_pe3_ocp_txp(11)") )
				( member ( electricalNetRef "@crescent_city_bb_fab1_lib.crescent_city_bb_fab1(sch_1):p3e_cpu0_pe3_ocp_txp(10)") )
				( objectStatus "P3E_OCP_CPU0_PE3_C_TXP" )
			)
			( bus "@crescent_city_bb_fab1_lib.crescent_city_bb_fab1(sch_1):dmi_cpu0_pch_rx_c_dn"
				( memberType ( signal ) )
				( member ( electricalNetRef "@crescent_city_bb_fab1_lib.crescent_city_bb_fab1(sch_1):dmi_cpu0_pch_rx_c_dn(3)") )
				( member ( electricalNetRef "@crescent_city_bb_fab1_lib.crescent_city_bb_fab1(sch_1):dmi_cpu0_pch_rx_c_dn(2)") )
				( member ( electricalNetRef "@crescent_city_bb_fab1_lib.crescent_city_bb_fab1(sch_1):dmi_cpu0_pch_rx_c_dn(1)") )
				( member ( electricalNetRef "@crescent_city_bb_fab1_lib.crescent_city_bb_fab1(sch_1):dmi_cpu0_pch_rx_c_dn(0)") )
				( objectStatus "DMI_CPU0_PCH_RX_C_DN" )
			)
			( bus "@crescent_city_bb_fab1_lib.crescent_city_bb_fab1(sch_1):dmi_cpu0_pch_rx_c_dp"
				( memberType ( signal ) )
				( member ( electricalNetRef "@crescent_city_bb_fab1_lib.crescent_city_bb_fab1(sch_1):dmi_cpu0_pch_rx_c_dp(3)") )
				( member ( electricalNetRef "@crescent_city_bb_fab1_lib.crescent_city_bb_fab1(sch_1):dmi_cpu0_pch_rx_c_dp(2)") )
				( member ( electricalNetRef "@crescent_city_bb_fab1_lib.crescent_city_bb_fab1(sch_1):dmi_cpu0_pch_rx_c_dp(1)") )
				( member ( electricalNetRef "@crescent_city_bb_fab1_lib.crescent_city_bb_fab1(sch_1):dmi_cpu0_pch_rx_c_dp(0)") )
				( objectStatus "DMI_CPU0_PCH_RX_C_DP" )
			)
			( bus "@crescent_city_bb_fab1_lib.crescent_city_bb_fab1(sch_1):dmi_cpu0_pch_tx_c_dn"
				( memberType ( signal ) )
				( member ( electricalNetRef "@crescent_city_bb_fab1_lib.crescent_city_bb_fab1(sch_1):dmi_cpu0_pch_tx_c_dn(3)") )
				( member ( electricalNetRef "@crescent_city_bb_fab1_lib.crescent_city_bb_fab1(sch_1):dmi_cpu0_pch_tx_c_dn(2)") )
				( member ( electricalNetRef "@crescent_city_bb_fab1_lib.crescent_city_bb_fab1(sch_1):dmi_cpu0_pch_tx_c_dn(1)") )
				( member ( electricalNetRef "@crescent_city_bb_fab1_lib.crescent_city_bb_fab1(sch_1):dmi_cpu0_pch_tx_c_dn(0)") )
				( objectStatus "DMI_CPU0_PCH_TX_C_DN" )
			)
			( bus "@crescent_city_bb_fab1_lib.crescent_city_bb_fab1(sch_1):nc_m2"
				( memberType ( signal ) )
				( member ( signalRef "@baseboard_fab2_lib.baseboard_fab2(sch_1):nc_m2(0)") )
				( member ( signalRef "@baseboard_fab2_lib.baseboard_fab2(sch_1):nc_m2(1)") )
				( member ( signalRef "@baseboard_fab2_lib.baseboard_fab2(sch_1):nc_m2(2)") )
				( member ( signalRef "@baseboard_fab2_lib.baseboard_fab2(sch_1):nc_m2(3)") )
				( member ( signalRef "@baseboard_fab2_lib.baseboard_fab2(sch_1):nc_m2(4)") )
				( member ( signalRef "@baseboard_fab2_lib.baseboard_fab2(sch_1):nc_m2(5)") )
				( member ( signalRef "@baseboard_fab2_lib.baseboard_fab2(sch_1):nc_m2(6)") )
				( member ( signalRef "@baseboard_fab2_lib.baseboard_fab2(sch_1):nc_m2(7)") )
				( member ( signalRef "@baseboard_fab2_lib.baseboard_fab2(sch_1):nc_m2(8)") )
				( member ( signalRef "@baseboard_fab2_lib.baseboard_fab2(sch_1):nc_m2(9)") )
				( member ( signalRef "@baseboard_fab2_lib.baseboard_fab2(sch_1):nc_m2(10)") )
				( member ( signalRef "@baseboard_fab2_lib.baseboard_fab2(sch_1):nc_m2(11)") )
				( member ( signalRef "@baseboard_fab2_lib.baseboard_fab2(sch_1):nc_m2(12)") )
				( member ( signalRef "@baseboard_fab2_lib.baseboard_fab2(sch_1):nc_m2(13)") )
				( member ( signalRef "@baseboard_fab2_lib.baseboard_fab2(sch_1):nc_m2(14)") )
				( member ( signalRef "@baseboard_fab2_lib.baseboard_fab2(sch_1):nc_m2(15)") )
				( member ( signalRef "@baseboard_fab2_lib.baseboard_fab2(sch_1):nc_m2(16)") )
				( member ( signalRef "@baseboard_fab2_lib.baseboard_fab2(sch_1):nc_m2(17)") )
				( member ( signalRef "@baseboard_fab2_lib.baseboard_fab2(sch_1):nc_m2(18)") )
				( objectStatus "NC_M2" )
			)
			( bus "@crescent_city_bb_fab1_lib.crescent_city_bb_fab1(sch_1):nc_db1200zl"
				( memberType ( signal ) )
				( member ( signalRef "@baseboard_fab2_lib.baseboard_fab2(sch_1):nc_db1200zl(0)") )
				( member ( signalRef "@baseboard_fab2_lib.baseboard_fab2(sch_1):nc_db1200zl(1)") )
				( member ( signalRef "@baseboard_fab2_lib.baseboard_fab2(sch_1):nc_db1200zl(2)") )
				( objectStatus "NC_DB1200ZL" )
			)
			( bus "@crescent_city_bb_fab1_lib.crescent_city_bb_fab1(sch_1):lpc_lad_io"
				( memberType ( signal ) )
				( member ( electricalNetRef "@crescent_city_bb_fab1_lib.crescent_city_bb_fab1(sch_1):lpc_lad2_io2") )
				( member ( electricalNetRef "@crescent_city_bb_fab1_lib.crescent_city_bb_fab1(sch_1):lpc_lad1_io1") )
				( member ( electricalNetRef "@crescent_city_bb_fab1_lib.crescent_city_bb_fab1(sch_1):lpc_lad0_io0") )
				( member ( electricalNetRef "@crescent_city_bb_fab1_lib.crescent_city_bb_fab1(sch_1):lpc_lad3_io3") )
				( objectStatus "LPC_LAD_IO" )
			)
			( bus "@crescent_city_bb_fab1_lib.crescent_city_bb_fab1(sch_1):p3e_cpu0_pe1_pch_c_txp"
				( memberType ( signal ) )
				( member ( electricalNetRef "@crescent_city_bb_fab1_lib.crescent_city_bb_fab1(sch_1):p3e_cpu0_pe1_pch_c_txp(9)") )
				( member ( electricalNetRef "@crescent_city_bb_fab1_lib.crescent_city_bb_fab1(sch_1):p3e_cpu0_pe1_pch_c_txp(8)") )
				( member ( electricalNetRef "@crescent_city_bb_fab1_lib.crescent_city_bb_fab1(sch_1):p3e_cpu0_pe1_pch_c_txp(15)") )
				( member ( electricalNetRef "@crescent_city_bb_fab1_lib.crescent_city_bb_fab1(sch_1):p3e_cpu0_pe1_pch_c_txp(14)") )
				( member ( electricalNetRef "@crescent_city_bb_fab1_lib.crescent_city_bb_fab1(sch_1):p3e_cpu0_pe1_pch_c_txp(13)") )
				( member ( electricalNetRef "@crescent_city_bb_fab1_lib.crescent_city_bb_fab1(sch_1):p3e_cpu0_pe1_pch_c_txp(12)") )
				( member ( electricalNetRef "@crescent_city_bb_fab1_lib.crescent_city_bb_fab1(sch_1):p3e_cpu0_pe1_pch_c_txp(11)") )
				( member ( electricalNetRef "@crescent_city_bb_fab1_lib.crescent_city_bb_fab1(sch_1):p3e_cpu0_pe1_pch_c_txp(10)") )
				( objectStatus "P3E_CPU0_PE1_PCH_C_TXP" )
			)
			( bus "@crescent_city_bb_fab1_lib.crescent_city_bb_fab1(sch_1):p3e_cpu0_pe1_pch_c_txn"
				( memberType ( signal ) )
				( member ( electricalNetRef "@crescent_city_bb_fab1_lib.crescent_city_bb_fab1(sch_1):p3e_cpu0_pe1_pch_c_txn(9)") )
				( member ( electricalNetRef "@crescent_city_bb_fab1_lib.crescent_city_bb_fab1(sch_1):p3e_cpu0_pe1_pch_c_txn(8)") )
				( member ( electricalNetRef "@crescent_city_bb_fab1_lib.crescent_city_bb_fab1(sch_1):p3e_cpu0_pe1_pch_c_txn(15)") )
				( member ( electricalNetRef "@crescent_city_bb_fab1_lib.crescent_city_bb_fab1(sch_1):p3e_cpu0_pe1_pch_c_txn(14)") )
				( member ( electricalNetRef "@crescent_city_bb_fab1_lib.crescent_city_bb_fab1(sch_1):p3e_cpu0_pe1_pch_c_txn(13)") )
				( member ( electricalNetRef "@crescent_city_bb_fab1_lib.crescent_city_bb_fab1(sch_1):p3e_cpu0_pe1_pch_c_txn(12)") )
				( member ( electricalNetRef "@crescent_city_bb_fab1_lib.crescent_city_bb_fab1(sch_1):p3e_cpu0_pe1_pch_c_txn(11)") )
				( member ( electricalNetRef "@crescent_city_bb_fab1_lib.crescent_city_bb_fab1(sch_1):p3e_cpu0_pe1_pch_c_txn(10)") )
				( objectStatus "P3E_CPU0_PE1_PCH_C_TXN" )
			)
			( bus "@crescent_city_bb_fab1_lib.crescent_city_bb_fab1(sch_1):p3e_cpu0_pe1_pch_txp"
				( memberType ( signal ) )
				( member ( electricalNetRef "@crescent_city_bb_fab1_lib.crescent_city_bb_fab1(sch_1):p3e_cpu0_pe1_pch_txp(7)") )
				( member ( electricalNetRef "@crescent_city_bb_fab1_lib.crescent_city_bb_fab1(sch_1):p3e_cpu0_pe1_pch_txp(6)") )
				( member ( electricalNetRef "@crescent_city_bb_fab1_lib.crescent_city_bb_fab1(sch_1):p3e_cpu0_pe1_pch_txp(5)") )
				( member ( electricalNetRef "@crescent_city_bb_fab1_lib.crescent_city_bb_fab1(sch_1):p3e_cpu0_pe1_pch_txp(4)") )
				( member ( electricalNetRef "@crescent_city_bb_fab1_lib.crescent_city_bb_fab1(sch_1):p3e_cpu0_pe1_pch_txp(3)") )
				( member ( electricalNetRef "@crescent_city_bb_fab1_lib.crescent_city_bb_fab1(sch_1):p3e_cpu0_pe1_pch_txp(2)") )
				( member ( electricalNetRef "@crescent_city_bb_fab1_lib.crescent_city_bb_fab1(sch_1):p3e_cpu0_pe1_pch_txp(1)") )
				( member ( electricalNetRef "@crescent_city_bb_fab1_lib.crescent_city_bb_fab1(sch_1):p3e_cpu0_pe1_pch_txp(0)") )
				( objectStatus "P3E_CPU0_PE1_PCH_TXP" )
			)
			( bus "@crescent_city_bb_fab1_lib.crescent_city_bb_fab1(sch_1):p3e_cpu0_pe1_pch_txn"
				( memberType ( signal ) )
				( member ( electricalNetRef "@crescent_city_bb_fab1_lib.crescent_city_bb_fab1(sch_1):p3e_cpu0_pe1_pch_txn(7)") )
				( member ( electricalNetRef "@crescent_city_bb_fab1_lib.crescent_city_bb_fab1(sch_1):p3e_cpu0_pe1_pch_txn(6)") )
				( member ( electricalNetRef "@crescent_city_bb_fab1_lib.crescent_city_bb_fab1(sch_1):p3e_cpu0_pe1_pch_txn(5)") )
				( member ( electricalNetRef "@crescent_city_bb_fab1_lib.crescent_city_bb_fab1(sch_1):p3e_cpu0_pe1_pch_txn(4)") )
				( member ( electricalNetRef "@crescent_city_bb_fab1_lib.crescent_city_bb_fab1(sch_1):p3e_cpu0_pe1_pch_txn(3)") )
				( member ( electricalNetRef "@crescent_city_bb_fab1_lib.crescent_city_bb_fab1(sch_1):p3e_cpu0_pe1_pch_txn(2)") )
				( member ( electricalNetRef "@crescent_city_bb_fab1_lib.crescent_city_bb_fab1(sch_1):p3e_cpu0_pe1_pch_txn(1)") )
				( member ( electricalNetRef "@crescent_city_bb_fab1_lib.crescent_city_bb_fab1(sch_1):p3e_cpu0_pe1_pch_txn(0)") )
				( objectStatus "P3E_CPU0_PE1_PCH_TXN" )
			)
			( bus "@crescent_city_bb_fab1_lib.crescent_city_bb_fab1(sch_1):p3e_cpu0_pe1_pch_rxp"
				( memberType ( signal ) )
				( member ( electricalNetRef "@crescent_city_bb_fab1_lib.crescent_city_bb_fab1(sch_1):p3e_cpu0_pe1_ss_rxp(7)") )
				( member ( electricalNetRef "@crescent_city_bb_fab1_lib.crescent_city_bb_fab1(sch_1):p3e_cpu0_pe1_ss_rxp(6)") )
				( member ( electricalNetRef "@crescent_city_bb_fab1_lib.crescent_city_bb_fab1(sch_1):p3e_cpu0_pe1_ss_rxp(5)") )
				( member ( electricalNetRef "@crescent_city_bb_fab1_lib.crescent_city_bb_fab1(sch_1):p3e_cpu0_pe1_ss_rxp(4)") )
				( member ( electricalNetRef "@crescent_city_bb_fab1_lib.crescent_city_bb_fab1(sch_1):p3e_cpu0_pe1_ss_rxp(3)") )
				( member ( electricalNetRef "@crescent_city_bb_fab1_lib.crescent_city_bb_fab1(sch_1):p3e_cpu0_pe1_ss_rxp(2)") )
				( member ( electricalNetRef "@crescent_city_bb_fab1_lib.crescent_city_bb_fab1(sch_1):p3e_cpu0_pe1_ss_rxp(1)") )
				( member ( electricalNetRef "@crescent_city_bb_fab1_lib.crescent_city_bb_fab1(sch_1):p3e_cpu0_pe1_ss_rxp(0)") )
				( member ( electricalNetRef "@crescent_city_bb_fab1_lib.crescent_city_bb_fab1(sch_1):p3e_cpu0_pe1_pch_rxp(9)") )
				( member ( electricalNetRef "@crescent_city_bb_fab1_lib.crescent_city_bb_fab1(sch_1):p3e_cpu0_pe1_pch_rxp(8)") )
				( member ( electricalNetRef "@crescent_city_bb_fab1_lib.crescent_city_bb_fab1(sch_1):p3e_cpu0_pe1_pch_rxp(15)") )
				( member ( electricalNetRef "@crescent_city_bb_fab1_lib.crescent_city_bb_fab1(sch_1):p3e_cpu0_pe1_pch_rxp(14)") )
				( member ( electricalNetRef "@crescent_city_bb_fab1_lib.crescent_city_bb_fab1(sch_1):p3e_cpu0_pe1_pch_rxp(13)") )
				( member ( electricalNetRef "@crescent_city_bb_fab1_lib.crescent_city_bb_fab1(sch_1):p3e_cpu0_pe1_pch_rxp(12)") )
				( member ( electricalNetRef "@crescent_city_bb_fab1_lib.crescent_city_bb_fab1(sch_1):p3e_cpu0_pe1_pch_rxp(11)") )
				( member ( electricalNetRef "@crescent_city_bb_fab1_lib.crescent_city_bb_fab1(sch_1):p3e_cpu0_pe1_pch_rxp(10)") )
				( objectStatus "P3E_CPU0_PE1_PCH_RXP" )
			)
			( bus "@crescent_city_bb_fab1_lib.crescent_city_bb_fab1(sch_1):p3e_cpu0_pe1_pch_rxn"
				( memberType ( signal ) )
				( member ( electricalNetRef "@crescent_city_bb_fab1_lib.crescent_city_bb_fab1(sch_1):p3e_cpu0_pe1_ss_rxn(7)") )
				( member ( electricalNetRef "@crescent_city_bb_fab1_lib.crescent_city_bb_fab1(sch_1):p3e_cpu0_pe1_ss_rxn(6)") )
				( member ( electricalNetRef "@crescent_city_bb_fab1_lib.crescent_city_bb_fab1(sch_1):p3e_cpu0_pe1_ss_rxn(5)") )
				( member ( electricalNetRef "@crescent_city_bb_fab1_lib.crescent_city_bb_fab1(sch_1):p3e_cpu0_pe1_ss_rxn(4)") )
				( member ( electricalNetRef "@crescent_city_bb_fab1_lib.crescent_city_bb_fab1(sch_1):p3e_cpu0_pe1_ss_rxn(3)") )
				( member ( electricalNetRef "@crescent_city_bb_fab1_lib.crescent_city_bb_fab1(sch_1):p3e_cpu0_pe1_ss_rxn(2)") )
				( member ( electricalNetRef "@crescent_city_bb_fab1_lib.crescent_city_bb_fab1(sch_1):p3e_cpu0_pe1_ss_rxn(1)") )
				( member ( electricalNetRef "@crescent_city_bb_fab1_lib.crescent_city_bb_fab1(sch_1):p3e_cpu0_pe1_ss_rxn(0)") )
				( member ( electricalNetRef "@crescent_city_bb_fab1_lib.crescent_city_bb_fab1(sch_1):p3e_cpu0_pe1_pch_rxn(9)") )
				( member ( electricalNetRef "@crescent_city_bb_fab1_lib.crescent_city_bb_fab1(sch_1):p3e_cpu0_pe1_pch_rxn(8)") )
				( member ( electricalNetRef "@crescent_city_bb_fab1_lib.crescent_city_bb_fab1(sch_1):p3e_cpu0_pe1_pch_rxn(15)") )
				( member ( electricalNetRef "@crescent_city_bb_fab1_lib.crescent_city_bb_fab1(sch_1):p3e_cpu0_pe1_pch_rxn(14)") )
				( member ( electricalNetRef "@crescent_city_bb_fab1_lib.crescent_city_bb_fab1(sch_1):p3e_cpu0_pe1_pch_rxn(13)") )
				( member ( electricalNetRef "@crescent_city_bb_fab1_lib.crescent_city_bb_fab1(sch_1):p3e_cpu0_pe1_pch_rxn(12)") )
				( member ( electricalNetRef "@crescent_city_bb_fab1_lib.crescent_city_bb_fab1(sch_1):p3e_cpu0_pe1_pch_rxn(11)") )
				( member ( electricalNetRef "@crescent_city_bb_fab1_lib.crescent_city_bb_fab1(sch_1):p3e_cpu0_pe1_pch_rxn(10)") )
				( objectStatus "P3E_CPU0_PE1_PCH_RXN" )
			)
			( bus "@crescent_city_bb_fab1_lib.crescent_city_bb_fab1(sch_1):sata6g_pch_pcie_up_sata_txp"
				( memberType ( signal ) )
				( member ( electricalNetRef "@crescent_city_bb_fab1_lib.crescent_city_bb_fab1(sch_1):sata6g_p7_tx_c_dp") )
				( member ( electricalNetRef "@crescent_city_bb_fab1_lib.crescent_city_bb_fab1(sch_1):sata6g_p6_tx_c_dp") )
				( member ( electricalNetRef "@crescent_city_bb_fab1_lib.crescent_city_bb_fab1(sch_1):sata6g_p5_tx_c_dp") )
				( member ( electricalNetRef "@crescent_city_bb_fab1_lib.crescent_city_bb_fab1(sch_1):sata6g_p4_tx_c_dp") )
				( member ( electricalNetRef "@crescent_city_bb_fab1_lib.crescent_city_bb_fab1(sch_1):sata6g_p3_tx_c_dp") )
				( member ( electricalNetRef "@crescent_city_bb_fab1_lib.crescent_city_bb_fab1(sch_1):sata6g_p2_tx_c_dp") )
				( member ( electricalNetRef "@crescent_city_bb_fab1_lib.crescent_city_bb_fab1(sch_1):sata6g_p1_tx_c_dp") )
				( member ( electricalNetRef "@crescent_city_bb_fab1_lib.crescent_city_bb_fab1(sch_1):sata6g_p0_tx_c_dp") )
				( objectStatus "SATA6G_PCH_PCIE_UP_SATA_TXP" )
			)
			( bus "@crescent_city_bb_fab1_lib.crescent_city_bb_fab1(sch_1):sata6g_pch_pcie_up_sata_txn"
				( memberType ( signal ) )
				( member ( electricalNetRef "@crescent_city_bb_fab1_lib.crescent_city_bb_fab1(sch_1):sata6g_p7_tx_c_dn") )
				( member ( electricalNetRef "@crescent_city_bb_fab1_lib.crescent_city_bb_fab1(sch_1):sata6g_p6_tx_c_dn") )
				( member ( electricalNetRef "@crescent_city_bb_fab1_lib.crescent_city_bb_fab1(sch_1):sata6g_p5_tx_c_dn") )
				( member ( electricalNetRef "@crescent_city_bb_fab1_lib.crescent_city_bb_fab1(sch_1):sata6g_p4_tx_c_dn") )
				( member ( electricalNetRef "@crescent_city_bb_fab1_lib.crescent_city_bb_fab1(sch_1):sata6g_p3_tx_c_dn") )
				( member ( electricalNetRef "@crescent_city_bb_fab1_lib.crescent_city_bb_fab1(sch_1):sata6g_p2_tx_c_dn") )
				( member ( electricalNetRef "@crescent_city_bb_fab1_lib.crescent_city_bb_fab1(sch_1):sata6g_p1_tx_c_dn") )
				( member ( electricalNetRef "@crescent_city_bb_fab1_lib.crescent_city_bb_fab1(sch_1):sata6g_p0_tx_c_dn") )
				( objectStatus "SATA6G_PCH_PCIE_UP_SATA_TXN" )
			)
			( bus "@crescent_city_bb_fab1_lib.crescent_city_bb_fab1(sch_1):sata6g_pch_pcie_up_sata_rxp"
				( memberType ( signal ) )
				( member ( electricalNetRef "@crescent_city_bb_fab1_lib.crescent_city_bb_fab1(sch_1):sata6g_p7_rx_c_dp") )
				( member ( electricalNetRef "@crescent_city_bb_fab1_lib.crescent_city_bb_fab1(sch_1):sata6g_p6_rx_c_dp") )
				( member ( electricalNetRef "@crescent_city_bb_fab1_lib.crescent_city_bb_fab1(sch_1):sata6g_p5_rx_c_dp") )
				( member ( electricalNetRef "@crescent_city_bb_fab1_lib.crescent_city_bb_fab1(sch_1):sata6g_p4_rx_c_dp") )
				( member ( electricalNetRef "@crescent_city_bb_fab1_lib.crescent_city_bb_fab1(sch_1):sata6g_p3_rx_c_dp") )
				( member ( electricalNetRef "@crescent_city_bb_fab1_lib.crescent_city_bb_fab1(sch_1):sata6g_p2_rx_c_dp") )
				( member ( electricalNetRef "@crescent_city_bb_fab1_lib.crescent_city_bb_fab1(sch_1):sata6g_p1_rx_c_dp") )
				( member ( electricalNetRef "@crescent_city_bb_fab1_lib.crescent_city_bb_fab1(sch_1):sata6g_p0_rx_c_dp") )
				( objectStatus "SATA6G_PCH_PCIE_UP_SATA_RXP" )
			)
			( bus "@crescent_city_bb_fab1_lib.crescent_city_bb_fab1(sch_1):sata6g_pch_pcie_up_sata_rxn"
				( memberType ( signal ) )
				( member ( electricalNetRef "@crescent_city_bb_fab1_lib.crescent_city_bb_fab1(sch_1):sata6g_p7_rx_c_dn") )
				( member ( electricalNetRef "@crescent_city_bb_fab1_lib.crescent_city_bb_fab1(sch_1):sata6g_p6_rx_c_dn") )
				( member ( electricalNetRef "@crescent_city_bb_fab1_lib.crescent_city_bb_fab1(sch_1):sata6g_p5_rx_c_dn") )
				( member ( electricalNetRef "@crescent_city_bb_fab1_lib.crescent_city_bb_fab1(sch_1):sata6g_p4_rx_c_dn") )
				( member ( electricalNetRef "@crescent_city_bb_fab1_lib.crescent_city_bb_fab1(sch_1):sata6g_p3_rx_c_dn") )
				( member ( electricalNetRef "@crescent_city_bb_fab1_lib.crescent_city_bb_fab1(sch_1):sata6g_p2_rx_c_dn") )
				( member ( electricalNetRef "@crescent_city_bb_fab1_lib.crescent_city_bb_fab1(sch_1):sata6g_p1_rx_c_dn") )
				( member ( electricalNetRef "@crescent_city_bb_fab1_lib.crescent_city_bb_fab1(sch_1):sata6g_p0_rx_c_dn") )
				( objectStatus "SATA6G_PCH_PCIE_UP_SATA_RXN" )
			)
			( bus "@crescent_city_bb_fab1_lib.crescent_city_bb_fab1(sch_1):tp_p3e_cpu1_pe1_mp_txp"
				( memberType ( signal ) )
				( member ( signalRef "@baseboard_fab2_lib.baseboard_fab2(sch_1):tp_p3e_cpu1_pe1_mp_txp(0)") )
				( member ( signalRef "@baseboard_fab2_lib.baseboard_fab2(sch_1):tp_p3e_cpu1_pe1_mp_txp(1)") )
				( member ( signalRef "@baseboard_fab2_lib.baseboard_fab2(sch_1):tp_p3e_cpu1_pe1_mp_txp(2)") )
				( member ( signalRef "@baseboard_fab2_lib.baseboard_fab2(sch_1):tp_p3e_cpu1_pe1_mp_txp(3)") )
				( member ( signalRef "@baseboard_fab2_lib.baseboard_fab2(sch_1):tp_p3e_cpu1_pe1_mp_txp(4)") )
				( member ( signalRef "@baseboard_fab2_lib.baseboard_fab2(sch_1):tp_p3e_cpu1_pe1_mp_txp(5)") )
				( member ( signalRef "@baseboard_fab2_lib.baseboard_fab2(sch_1):tp_p3e_cpu1_pe1_mp_txp(6)") )
				( member ( signalRef "@baseboard_fab2_lib.baseboard_fab2(sch_1):tp_p3e_cpu1_pe1_mp_txp(7)") )
				( objectStatus "TP_P3E_CPU1_PE1_MP_TXP" )
			)
			( bus "@crescent_city_bb_fab1_lib.crescent_city_bb_fab1(sch_1):tp_p3e_cpu1_pe1_mp_txn"
				( memberType ( signal ) )
				( member ( signalRef "@baseboard_fab2_lib.baseboard_fab2(sch_1):tp_p3e_cpu1_pe1_mp_txn(0)") )
				( member ( signalRef "@baseboard_fab2_lib.baseboard_fab2(sch_1):tp_p3e_cpu1_pe1_mp_txn(1)") )
				( member ( signalRef "@baseboard_fab2_lib.baseboard_fab2(sch_1):tp_p3e_cpu1_pe1_mp_txn(2)") )
				( member ( signalRef "@baseboard_fab2_lib.baseboard_fab2(sch_1):tp_p3e_cpu1_pe1_mp_txn(3)") )
				( member ( signalRef "@baseboard_fab2_lib.baseboard_fab2(sch_1):tp_p3e_cpu1_pe1_mp_txn(4)") )
				( member ( signalRef "@baseboard_fab2_lib.baseboard_fab2(sch_1):tp_p3e_cpu1_pe1_mp_txn(5)") )
				( member ( signalRef "@baseboard_fab2_lib.baseboard_fab2(sch_1):tp_p3e_cpu1_pe1_mp_txn(6)") )
				( member ( signalRef "@baseboard_fab2_lib.baseboard_fab2(sch_1):tp_p3e_cpu1_pe1_mp_txn(7)") )
				( objectStatus "TP_P3E_CPU1_PE1_MP_TXN" )
			)
			( bus "@crescent_city_bb_fab1_lib.crescent_city_bb_fab1(sch_1):tp_p3e_cpu1_pe1_mp_rxp"
				( memberType ( signal ) )
				( member ( signalRef "@baseboard_fab2_lib.baseboard_fab2(sch_1):tp_p3e_cpu1_pe1_mp_rxp(0)") )
				( member ( signalRef "@baseboard_fab2_lib.baseboard_fab2(sch_1):tp_p3e_cpu1_pe1_mp_rxp(1)") )
				( member ( signalRef "@baseboard_fab2_lib.baseboard_fab2(sch_1):tp_p3e_cpu1_pe1_mp_rxp(2)") )
				( member ( signalRef "@baseboard_fab2_lib.baseboard_fab2(sch_1):tp_p3e_cpu1_pe1_mp_rxp(3)") )
				( member ( signalRef "@baseboard_fab2_lib.baseboard_fab2(sch_1):tp_p3e_cpu1_pe1_mp_rxp(4)") )
				( member ( signalRef "@baseboard_fab2_lib.baseboard_fab2(sch_1):tp_p3e_cpu1_pe1_mp_rxp(5)") )
				( member ( signalRef "@baseboard_fab2_lib.baseboard_fab2(sch_1):tp_p3e_cpu1_pe1_mp_rxp(6)") )
				( member ( signalRef "@baseboard_fab2_lib.baseboard_fab2(sch_1):tp_p3e_cpu1_pe1_mp_rxp(7)") )
				( objectStatus "TP_P3E_CPU1_PE1_MP_RXP" )
			)
			( bus "@crescent_city_bb_fab1_lib.crescent_city_bb_fab1(sch_1):tp_p3e_cpu1_pe1_mp_rxn"
				( memberType ( signal ) )
				( member ( signalRef "@baseboard_fab2_lib.baseboard_fab2(sch_1):tp_p3e_cpu1_pe1_mp_rxn(0)") )
				( member ( signalRef "@baseboard_fab2_lib.baseboard_fab2(sch_1):tp_p3e_cpu1_pe1_mp_rxn(1)") )
				( member ( signalRef "@baseboard_fab2_lib.baseboard_fab2(sch_1):tp_p3e_cpu1_pe1_mp_rxn(2)") )
				( member ( signalRef "@baseboard_fab2_lib.baseboard_fab2(sch_1):tp_p3e_cpu1_pe1_mp_rxn(3)") )
				( member ( signalRef "@baseboard_fab2_lib.baseboard_fab2(sch_1):tp_p3e_cpu1_pe1_mp_rxn(4)") )
				( member ( signalRef "@baseboard_fab2_lib.baseboard_fab2(sch_1):tp_p3e_cpu1_pe1_mp_rxn(5)") )
				( member ( signalRef "@baseboard_fab2_lib.baseboard_fab2(sch_1):tp_p3e_cpu1_pe1_mp_rxn(6)") )
				( member ( signalRef "@baseboard_fab2_lib.baseboard_fab2(sch_1):tp_p3e_cpu1_pe1_mp_rxn(7)") )
				( objectStatus "TP_P3E_CPU1_PE1_MP_RXN" )
			)
			( bus "@crescent_city_bb_fab1_lib.crescent_city_bb_fab1(sch_1):p3e_cpu0_pe2_ss_c_txn"
				( memberType ( signal ) )
				( electricalCSetRef "@crescent_city_bb_fab1_lib.crescent_city_bb_fab1(sch_1):\PCIE_SLOT\" )
				( member ( electricalNetRef "@crescent_city_bb_fab1_lib.crescent_city_bb_fab1(sch_1):p3e_cpu0_pe2_ss_c_txn(9)") )
				( member ( electricalNetRef "@crescent_city_bb_fab1_lib.crescent_city_bb_fab1(sch_1):p3e_cpu0_pe2_ss_c_txn(8)") )
				( member ( electricalNetRef "@crescent_city_bb_fab1_lib.crescent_city_bb_fab1(sch_1):p3e_cpu0_pe2_ss_c_txn(7)") )
				( member ( electricalNetRef "@crescent_city_bb_fab1_lib.crescent_city_bb_fab1(sch_1):p3e_cpu0_pe2_ss_c_txn(6)") )
				( member ( electricalNetRef "@crescent_city_bb_fab1_lib.crescent_city_bb_fab1(sch_1):p3e_cpu0_pe2_ss_c_txn(5)") )
				( member ( electricalNetRef "@crescent_city_bb_fab1_lib.crescent_city_bb_fab1(sch_1):p3e_cpu0_pe2_ss_c_txn(4)") )
				( member ( electricalNetRef "@crescent_city_bb_fab1_lib.crescent_city_bb_fab1(sch_1):p3e_cpu0_pe2_ss_c_txn(3)") )
				( member ( electricalNetRef "@crescent_city_bb_fab1_lib.crescent_city_bb_fab1(sch_1):p3e_cpu0_pe2_ss_c_txn(2)") )
				( member ( electricalNetRef "@crescent_city_bb_fab1_lib.crescent_city_bb_fab1(sch_1):p3e_cpu0_pe2_ss_c_txn(1)") )
				( member ( electricalNetRef "@crescent_city_bb_fab1_lib.crescent_city_bb_fab1(sch_1):p3e_cpu0_pe2_ss_c_txn(15)") )
				( member ( electricalNetRef "@crescent_city_bb_fab1_lib.crescent_city_bb_fab1(sch_1):p3e_cpu0_pe2_ss_c_txn(14)") )
				( member ( electricalNetRef "@crescent_city_bb_fab1_lib.crescent_city_bb_fab1(sch_1):p3e_cpu0_pe2_ss_c_txn(13)") )
				( member ( electricalNetRef "@crescent_city_bb_fab1_lib.crescent_city_bb_fab1(sch_1):p3e_cpu0_pe2_ss_c_txn(12)") )
				( member ( electricalNetRef "@crescent_city_bb_fab1_lib.crescent_city_bb_fab1(sch_1):p3e_cpu0_pe2_ss_c_txn(11)") )
				( member ( electricalNetRef "@crescent_city_bb_fab1_lib.crescent_city_bb_fab1(sch_1):p3e_cpu0_pe2_ss_c_txn(10)") )
				( member ( electricalNetRef "@crescent_city_bb_fab1_lib.crescent_city_bb_fab1(sch_1):p3e_cpu0_pe2_ss_c_txn(0)") )
				( objectStatus "P3E_CPU0_PE2_SS_C_TXN" )
			)
			( bus "@crescent_city_bb_fab1_lib.crescent_city_bb_fab1(sch_1):p3e_cpu0_pe2_ss_c_txp"
				( memberType ( signal ) )
				( electricalCSetRef "@crescent_city_bb_fab1_lib.crescent_city_bb_fab1(sch_1):\PCIE_SLOT\" )
				( member ( electricalNetRef "@crescent_city_bb_fab1_lib.crescent_city_bb_fab1(sch_1):p3e_cpu0_pe2_ss_c_txp(9)") )
				( member ( electricalNetRef "@crescent_city_bb_fab1_lib.crescent_city_bb_fab1(sch_1):p3e_cpu0_pe2_ss_c_txp(8)") )
				( member ( electricalNetRef "@crescent_city_bb_fab1_lib.crescent_city_bb_fab1(sch_1):p3e_cpu0_pe2_ss_c_txp(7)") )
				( member ( electricalNetRef "@crescent_city_bb_fab1_lib.crescent_city_bb_fab1(sch_1):p3e_cpu0_pe2_ss_c_txp(6)") )
				( member ( electricalNetRef "@crescent_city_bb_fab1_lib.crescent_city_bb_fab1(sch_1):p3e_cpu0_pe2_ss_c_txp(5)") )
				( member ( electricalNetRef "@crescent_city_bb_fab1_lib.crescent_city_bb_fab1(sch_1):p3e_cpu0_pe2_ss_c_txp(4)") )
				( member ( electricalNetRef "@crescent_city_bb_fab1_lib.crescent_city_bb_fab1(sch_1):p3e_cpu0_pe2_ss_c_txp(3)") )
				( member ( electricalNetRef "@crescent_city_bb_fab1_lib.crescent_city_bb_fab1(sch_1):p3e_cpu0_pe2_ss_c_txp(2)") )
				( member ( electricalNetRef "@crescent_city_bb_fab1_lib.crescent_city_bb_fab1(sch_1):p3e_cpu0_pe2_ss_c_txp(1)") )
				( member ( electricalNetRef "@crescent_city_bb_fab1_lib.crescent_city_bb_fab1(sch_1):p3e_cpu0_pe2_ss_c_txp(15)") )
				( member ( electricalNetRef "@crescent_city_bb_fab1_lib.crescent_city_bb_fab1(sch_1):p3e_cpu0_pe2_ss_c_txp(14)") )
				( member ( electricalNetRef "@crescent_city_bb_fab1_lib.crescent_city_bb_fab1(sch_1):p3e_cpu0_pe2_ss_c_txp(13)") )
				( member ( electricalNetRef "@crescent_city_bb_fab1_lib.crescent_city_bb_fab1(sch_1):p3e_cpu0_pe2_ss_c_txp(12)") )
				( member ( electricalNetRef "@crescent_city_bb_fab1_lib.crescent_city_bb_fab1(sch_1):p3e_cpu0_pe2_ss_c_txp(11)") )
				( member ( electricalNetRef "@crescent_city_bb_fab1_lib.crescent_city_bb_fab1(sch_1):p3e_cpu0_pe2_ss_c_txp(10)") )
				( member ( electricalNetRef "@crescent_city_bb_fab1_lib.crescent_city_bb_fab1(sch_1):p3e_cpu0_pe2_ss_c_txp(0)") )
				( objectStatus "P3E_CPU0_PE2_SS_C_TXP" )
			)
			( bus "@crescent_city_bb_fab1_lib.crescent_city_bb_fab1(sch_1):p3e_cpu0_pe3_ocp_rxp"
				( memberType ( signal ) )
				( electricalCSetRef "@crescent_city_bb_fab1_lib.crescent_city_bb_fab1(sch_1):\PCIE_SLOT_1\" )
				( member ( signalRef "@baseboard_fab2_lib.baseboard_fab2(sch_1):p3e_cpu0_pe3_ocp_rxp(8)") )
				( member ( signalRef "@baseboard_fab2_lib.baseboard_fab2(sch_1):p3e_cpu0_pe3_ocp_rxp(9)") )
				( member ( signalRef "@baseboard_fab2_lib.baseboard_fab2(sch_1):p3e_cpu0_pe3_ocp_rxp(10)") )
				( member ( signalRef "@baseboard_fab2_lib.baseboard_fab2(sch_1):p3e_cpu0_pe3_ocp_rxp(11)") )
				( member ( signalRef "@baseboard_fab2_lib.baseboard_fab2(sch_1):p3e_cpu0_pe3_ocp_rxp(12)") )
				( member ( signalRef "@baseboard_fab2_lib.baseboard_fab2(sch_1):p3e_cpu0_pe3_ocp_rxp(13)") )
				( member ( signalRef "@baseboard_fab2_lib.baseboard_fab2(sch_1):p3e_cpu0_pe3_ocp_rxp(14)") )
				( member ( signalRef "@baseboard_fab2_lib.baseboard_fab2(sch_1):p3e_cpu0_pe3_ocp_rxp(15)") )
				( member ( signalRef "@baseboard_fab2_lib.baseboard_fab2(sch_1):p3e_cpu0_pe3_ocp_rxp(0)") )
				( member ( signalRef "@baseboard_fab2_lib.baseboard_fab2(sch_1):p3e_cpu0_pe3_ocp_rxp(1)") )
				( member ( signalRef "@baseboard_fab2_lib.baseboard_fab2(sch_1):p3e_cpu0_pe3_ocp_rxp(7)") )
				( member ( signalRef "@baseboard_fab2_lib.baseboard_fab2(sch_1):p3e_cpu0_pe3_ocp_rxp(6)") )
				( member ( signalRef "@baseboard_fab2_lib.baseboard_fab2(sch_1):p3e_cpu0_pe3_ocp_rxp(3)") )
				( member ( signalRef "@baseboard_fab2_lib.baseboard_fab2(sch_1):p3e_cpu0_pe3_ocp_rxp(2)") )
				( member ( signalRef "@baseboard_fab2_lib.baseboard_fab2(sch_1):p3e_cpu0_pe3_ocp_rxp(4)") )
				( member ( signalRef "@baseboard_fab2_lib.baseboard_fab2(sch_1):p3e_cpu0_pe3_ocp_rxp(5)") )
				( objectStatus "P3E_CPU0_PE3_OCP_RXP" )
			)
			( bus "@crescent_city_bb_fab1_lib.crescent_city_bb_fab1(sch_1):p3e_cpu0_pe3_ocp_rxn"
				( memberType ( signal ) )
				( electricalCSetRef "@crescent_city_bb_fab1_lib.crescent_city_bb_fab1(sch_1):\PCIE_SLOT_1\" )
				( member ( signalRef "@baseboard_fab2_lib.baseboard_fab2(sch_1):p3e_cpu0_pe3_ocp_rxn(8)") )
				( member ( signalRef "@baseboard_fab2_lib.baseboard_fab2(sch_1):p3e_cpu0_pe3_ocp_rxn(9)") )
				( member ( signalRef "@baseboard_fab2_lib.baseboard_fab2(sch_1):p3e_cpu0_pe3_ocp_rxn(10)") )
				( member ( signalRef "@baseboard_fab2_lib.baseboard_fab2(sch_1):p3e_cpu0_pe3_ocp_rxn(11)") )
				( member ( signalRef "@baseboard_fab2_lib.baseboard_fab2(sch_1):p3e_cpu0_pe3_ocp_rxn(12)") )
				( member ( signalRef "@baseboard_fab2_lib.baseboard_fab2(sch_1):p3e_cpu0_pe3_ocp_rxn(13)") )
				( member ( signalRef "@baseboard_fab2_lib.baseboard_fab2(sch_1):p3e_cpu0_pe3_ocp_rxn(14)") )
				( member ( signalRef "@baseboard_fab2_lib.baseboard_fab2(sch_1):p3e_cpu0_pe3_ocp_rxn(15)") )
				( member ( signalRef "@baseboard_fab2_lib.baseboard_fab2(sch_1):p3e_cpu0_pe3_ocp_rxn(0)") )
				( member ( signalRef "@baseboard_fab2_lib.baseboard_fab2(sch_1):p3e_cpu0_pe3_ocp_rxn(1)") )
				( member ( signalRef "@baseboard_fab2_lib.baseboard_fab2(sch_1):p3e_cpu0_pe3_ocp_rxn(7)") )
				( member ( signalRef "@baseboard_fab2_lib.baseboard_fab2(sch_1):p3e_cpu0_pe3_ocp_rxn(6)") )
				( member ( signalRef "@baseboard_fab2_lib.baseboard_fab2(sch_1):p3e_cpu0_pe3_ocp_rxn(3)") )
				( member ( signalRef "@baseboard_fab2_lib.baseboard_fab2(sch_1):p3e_cpu0_pe3_ocp_rxn(2)") )
				( member ( signalRef "@baseboard_fab2_lib.baseboard_fab2(sch_1):p3e_cpu0_pe3_ocp_rxn(4)") )
				( member ( signalRef "@baseboard_fab2_lib.baseboard_fab2(sch_1):p3e_cpu0_pe3_ocp_rxn(5)") )
				( objectStatus "P3E_CPU0_PE3_OCP_RXN" )
			)
			( bus "@crescent_city_bb_fab1_lib.crescent_city_bb_fab1(sch_1):p3e_pch_m2_tx_c_dp"
				( memberType ( signal ) )
				( member ( electricalNetRef "@crescent_city_bb_fab1_lib.crescent_city_bb_fab1(sch_1):p3e_pch_m2_tx_c_dp(3)") )
				( member ( electricalNetRef "@crescent_city_bb_fab1_lib.crescent_city_bb_fab1(sch_1):p3e_pch_m2_tx_c_dp(2)") )
				( member ( electricalNetRef "@crescent_city_bb_fab1_lib.crescent_city_bb_fab1(sch_1):p3e_pch_m2_tx_c_dp(1)") )
				( objectStatus "P3E_PCH_M2_TX_C_DP" )
			)
			( bus "@crescent_city_bb_fab1_lib.crescent_city_bb_fab1(sch_1):p3e_pch_m2_tx_c_dn"
				( memberType ( signal ) )
				( electricalCSetRef "@crescent_city_bb_fab1_lib.crescent_city_bb_fab1(sch_1):\PCIE_SLOT_C_A\" )
				( member ( electricalNetRef "@crescent_city_bb_fab1_lib.crescent_city_bb_fab1(sch_1):p3e_pch_m2_tx_c_dn(3)") )
				( member ( electricalNetRef "@crescent_city_bb_fab1_lib.crescent_city_bb_fab1(sch_1):p3e_pch_m2_tx_c_dn(2)") )
				( member ( electricalNetRef "@crescent_city_bb_fab1_lib.crescent_city_bb_fab1(sch_1):p3e_pch_m2_tx_c_dn(1)") )
				( objectStatus "P3E_PCH_M2_TX_C_DN" )
			)
			( bus "@crescent_city_bb_fab1_lib.crescent_city_bb_fab1(sch_1):p3e_pch_m2_rx_dp"
				( memberType ( signal ) )
				( electricalCSetRef "@crescent_city_bb_fab1_lib.crescent_city_bb_fab1(sch_1):\PCIE_SLOT_A\" )
				( member ( signalRef "@baseboard_fab2_lib.baseboard_fab2(sch_1):p3e_pch_m2_rx_dp(1)") )
				( member ( signalRef "@baseboard_fab2_lib.baseboard_fab2(sch_1):p3e_pch_m2_rx_dp(2)") )
				( member ( signalRef "@baseboard_fab2_lib.baseboard_fab2(sch_1):p3e_pch_m2_rx_dp(3)") )
				( objectStatus "P3E_PCH_M2_RX_DP" )
			)
			( bus "@crescent_city_bb_fab1_lib.crescent_city_bb_fab1(sch_1):p3e_pch_m2_rx_dn"
				( memberType ( signal ) )
				( electricalCSetRef "@crescent_city_bb_fab1_lib.crescent_city_bb_fab1(sch_1):\PCIE_SLOT_A\" )
				( member ( signalRef "@baseboard_fab2_lib.baseboard_fab2(sch_1):p3e_pch_m2_rx_dn(1)") )
				( member ( signalRef "@baseboard_fab2_lib.baseboard_fab2(sch_1):p3e_pch_m2_rx_dn(2)") )
				( member ( signalRef "@baseboard_fab2_lib.baseboard_fab2(sch_1):p3e_pch_m2_rx_dn(3)") )
				( objectStatus "P3E_PCH_M2_RX_DN" )
			)
			( bus "@crescent_city_bb_fab1_lib.crescent_city_bb_fab1(sch_1):sata6g_tx_dp"
				( memberType ( signal ) )
				( member ( electricalNetRef "@crescent_city_bb_fab1_lib.crescent_city_bb_fab1(sch_1):sata6g_p9_tx_c_dp") )
				( member ( electricalNetRef "@crescent_city_bb_fab1_lib.crescent_city_bb_fab1(sch_1):sata6g_p8_tx_c_dp") )
				( member ( electricalNetRef "@crescent_city_bb_fab1_lib.crescent_city_bb_fab1(sch_1):sata6g_p11_tx_c_dp") )
				( member ( electricalNetRef "@crescent_city_bb_fab1_lib.crescent_city_bb_fab1(sch_1):sata6g_p10_tx_c_dp") )
				( objectStatus "SATA6G_TX_DP" )
			)
			( bus "@crescent_city_bb_fab1_lib.crescent_city_bb_fab1(sch_1):sata6g_tx_dn"
				( memberType ( signal ) )
				( member ( electricalNetRef "@crescent_city_bb_fab1_lib.crescent_city_bb_fab1(sch_1):sata6g_p9_tx_c_dn") )
				( member ( electricalNetRef "@crescent_city_bb_fab1_lib.crescent_city_bb_fab1(sch_1):sata6g_p8_tx_c_dn") )
				( member ( electricalNetRef "@crescent_city_bb_fab1_lib.crescent_city_bb_fab1(sch_1):sata6g_p11_tx_c_dn") )
				( member ( electricalNetRef "@crescent_city_bb_fab1_lib.crescent_city_bb_fab1(sch_1):sata6g_p10_tx_c_dn") )
				( objectStatus "SATA6G_TX_DN" )
			)
			( bus "@crescent_city_bb_fab1_lib.crescent_city_bb_fab1(sch_1):sata6g_rx_dp"
				( memberType ( signal ) )
				( member ( electricalNetRef "@crescent_city_bb_fab1_lib.crescent_city_bb_fab1(sch_1):sata6g_p9_rx_c_dp") )
				( member ( electricalNetRef "@crescent_city_bb_fab1_lib.crescent_city_bb_fab1(sch_1):sata6g_p8_rx_c_dp") )
				( member ( electricalNetRef "@crescent_city_bb_fab1_lib.crescent_city_bb_fab1(sch_1):sata6g_p11_rx_c_dp") )
				( member ( electricalNetRef "@crescent_city_bb_fab1_lib.crescent_city_bb_fab1(sch_1):sata6g_p10_rx_c_dp") )
				( objectStatus "SATA6G_RX_DP" )
			)
			( bus "@crescent_city_bb_fab1_lib.crescent_city_bb_fab1(sch_1):sata6g_rx_dn"
				( memberType ( signal ) )
				( member ( electricalNetRef "@crescent_city_bb_fab1_lib.crescent_city_bb_fab1(sch_1):sata6g_p9_rx_c_dn") )
				( member ( electricalNetRef "@crescent_city_bb_fab1_lib.crescent_city_bb_fab1(sch_1):sata6g_p8_rx_c_dn") )
				( member ( electricalNetRef "@crescent_city_bb_fab1_lib.crescent_city_bb_fab1(sch_1):sata6g_p11_rx_c_dn") )
				( member ( electricalNetRef "@crescent_city_bb_fab1_lib.crescent_city_bb_fab1(sch_1):sata6g_p10_rx_c_dn") )
				( objectStatus "SATA6G_RX_DN" )
			)
			( bus "@crescent_city_bb_fab1_lib.crescent_city_bb_fab1(sch_1):fm_roma"
				( memberType ( signal ) )
				( member ( signalRef "@baseboard_fab2_lib.baseboard_fab2(sch_1):fm_roma(1)") )
				( member ( signalRef "@baseboard_fab2_lib.baseboard_fab2(sch_1):fm_roma(2)") )
				( member ( signalRef "@baseboard_fab2_lib.baseboard_fab2(sch_1):fm_roma(3)") )
				( member ( signalRef "@baseboard_fab2_lib.baseboard_fab2(sch_1):fm_roma(4)") )
				( member ( signalRef "@baseboard_fab2_lib.baseboard_fab2(sch_1):fm_roma(5)") )
				( member ( signalRef "@baseboard_fab2_lib.baseboard_fab2(sch_1):fm_roma(6)") )
				( member ( signalRef "@baseboard_fab2_lib.baseboard_fab2(sch_1):fm_roma(7)") )
				( member ( signalRef "@baseboard_fab2_lib.baseboard_fab2(sch_1):fm_roma(8)") )
				( member ( signalRef "@baseboard_fab2_lib.baseboard_fab2(sch_1):fm_roma(9)") )
				( member ( signalRef "@baseboard_fab2_lib.baseboard_fab2(sch_1):fm_roma(10)") )
				( member ( signalRef "@baseboard_fab2_lib.baseboard_fab2(sch_1):fm_roma(11)") )
				( member ( signalRef "@baseboard_fab2_lib.baseboard_fab2(sch_1):fm_roma(12)") )
				( member ( signalRef "@baseboard_fab2_lib.baseboard_fab2(sch_1):fm_roma(13)") )
				( member ( signalRef "@baseboard_fab2_lib.baseboard_fab2(sch_1):fm_roma(14)") )
				( member ( signalRef "@baseboard_fab2_lib.baseboard_fab2(sch_1):fm_roma(15)") )
				( member ( signalRef "@baseboard_fab2_lib.baseboard_fab2(sch_1):fm_roma(16)") )
				( member ( signalRef "@baseboard_fab2_lib.baseboard_fab2(sch_1):fm_roma(17)") )
				( member ( signalRef "@baseboard_fab2_lib.baseboard_fab2(sch_1):fm_roma(18)") )
				( member ( signalRef "@baseboard_fab2_lib.baseboard_fab2(sch_1):fm_roma(19)") )
				( member ( signalRef "@baseboard_fab2_lib.baseboard_fab2(sch_1):fm_roma(20)") )
				( member ( signalRef "@baseboard_fab2_lib.baseboard_fab2(sch_1):fm_roma(21)") )
				( member ( signalRef "@baseboard_fab2_lib.baseboard_fab2(sch_1):fm_roma(22)") )
				( member ( signalRef "@baseboard_fab2_lib.baseboard_fab2(sch_1):fm_roma(23)") )
				( member ( electricalNetRef "@crescent_city_bb_fab1_lib.crescent_city_bb_fab1(sch_1):fm_bmc_enable_n") )
				( objectStatus "FM_ROMA" )
			)
			( bus "@crescent_city_bb_fab1_lib.crescent_city_bb_fab1(sch_1):p3e_cpu0_pe2_ss_rxp"
				( memberType ( signal ) )
				( electricalCSetRef "@crescent_city_bb_fab1_lib.crescent_city_bb_fab1(sch_1):\PCIE_SLOT_1\" )
				( member ( signalRef "@baseboard_fab2_lib.baseboard_fab2(sch_1):p3e_cpu0_pe2_ss_rxp(0)") )
				( member ( signalRef "@baseboard_fab2_lib.baseboard_fab2(sch_1):p3e_cpu0_pe2_ss_rxp(1)") )
				( member ( signalRef "@baseboard_fab2_lib.baseboard_fab2(sch_1):p3e_cpu0_pe2_ss_rxp(2)") )
				( member ( signalRef "@baseboard_fab2_lib.baseboard_fab2(sch_1):p3e_cpu0_pe2_ss_rxp(3)") )
				( member ( signalRef "@baseboard_fab2_lib.baseboard_fab2(sch_1):p3e_cpu0_pe2_ss_rxp(4)") )
				( member ( signalRef "@baseboard_fab2_lib.baseboard_fab2(sch_1):p3e_cpu0_pe2_ss_rxp(5)") )
				( member ( signalRef "@baseboard_fab2_lib.baseboard_fab2(sch_1):p3e_cpu0_pe2_ss_rxp(6)") )
				( member ( signalRef "@baseboard_fab2_lib.baseboard_fab2(sch_1):p3e_cpu0_pe2_ss_rxp(7)") )
				( member ( signalRef "@baseboard_fab2_lib.baseboard_fab2(sch_1):p3e_cpu0_pe2_ss_rxp(8)") )
				( member ( signalRef "@baseboard_fab2_lib.baseboard_fab2(sch_1):p3e_cpu0_pe2_ss_rxp(9)") )
				( member ( signalRef "@baseboard_fab2_lib.baseboard_fab2(sch_1):p3e_cpu0_pe2_ss_rxp(10)") )
				( member ( signalRef "@baseboard_fab2_lib.baseboard_fab2(sch_1):p3e_cpu0_pe2_ss_rxp(11)") )
				( member ( signalRef "@baseboard_fab2_lib.baseboard_fab2(sch_1):p3e_cpu0_pe2_ss_rxp(12)") )
				( member ( signalRef "@baseboard_fab2_lib.baseboard_fab2(sch_1):p3e_cpu0_pe2_ss_rxp(13)") )
				( member ( signalRef "@baseboard_fab2_lib.baseboard_fab2(sch_1):p3e_cpu0_pe2_ss_rxp(14)") )
				( member ( signalRef "@baseboard_fab2_lib.baseboard_fab2(sch_1):p3e_cpu0_pe2_ss_rxp(15)") )
				( objectStatus "P3E_CPU0_PE2_SS_RXP" )
			)
			( bus "@crescent_city_bb_fab1_lib.crescent_city_bb_fab1(sch_1):p3e_cpu0_pe2_ss_rxn"
				( memberType ( signal ) )
				( electricalCSetRef "@crescent_city_bb_fab1_lib.crescent_city_bb_fab1(sch_1):\PCIE_SLOT_1\" )
				( member ( signalRef "@baseboard_fab2_lib.baseboard_fab2(sch_1):p3e_cpu0_pe2_ss_rxn(0)") )
				( member ( signalRef "@baseboard_fab2_lib.baseboard_fab2(sch_1):p3e_cpu0_pe2_ss_rxn(1)") )
				( member ( signalRef "@baseboard_fab2_lib.baseboard_fab2(sch_1):p3e_cpu0_pe2_ss_rxn(2)") )
				( member ( signalRef "@baseboard_fab2_lib.baseboard_fab2(sch_1):p3e_cpu0_pe2_ss_rxn(3)") )
				( member ( signalRef "@baseboard_fab2_lib.baseboard_fab2(sch_1):p3e_cpu0_pe2_ss_rxn(4)") )
				( member ( signalRef "@baseboard_fab2_lib.baseboard_fab2(sch_1):p3e_cpu0_pe2_ss_rxn(5)") )
				( member ( signalRef "@baseboard_fab2_lib.baseboard_fab2(sch_1):p3e_cpu0_pe2_ss_rxn(6)") )
				( member ( signalRef "@baseboard_fab2_lib.baseboard_fab2(sch_1):p3e_cpu0_pe2_ss_rxn(7)") )
				( member ( signalRef "@baseboard_fab2_lib.baseboard_fab2(sch_1):p3e_cpu0_pe2_ss_rxn(8)") )
				( member ( signalRef "@baseboard_fab2_lib.baseboard_fab2(sch_1):p3e_cpu0_pe2_ss_rxn(9)") )
				( member ( signalRef "@baseboard_fab2_lib.baseboard_fab2(sch_1):p3e_cpu0_pe2_ss_rxn(10)") )
				( member ( signalRef "@baseboard_fab2_lib.baseboard_fab2(sch_1):p3e_cpu0_pe2_ss_rxn(11)") )
				( member ( signalRef "@baseboard_fab2_lib.baseboard_fab2(sch_1):p3e_cpu0_pe2_ss_rxn(12)") )
				( member ( signalRef "@baseboard_fab2_lib.baseboard_fab2(sch_1):p3e_cpu0_pe2_ss_rxn(13)") )
				( member ( signalRef "@baseboard_fab2_lib.baseboard_fab2(sch_1):p3e_cpu0_pe2_ss_rxn(14)") )
				( member ( signalRef "@baseboard_fab2_lib.baseboard_fab2(sch_1):p3e_cpu0_pe2_ss_rxn(15)") )
				( objectStatus "P3E_CPU0_PE2_SS_RXN" )
			)
			( bus "@crescent_city_bb_fab1_lib.crescent_city_bb_fab1(sch_1):upi_cpu1_cpu0_p0p0_dp"
				( memberType ( signal ) )
				( member ( signalRef "@baseboard_fab2_lib.baseboard_fab2(sch_1):upi_cpu1_cpu0_p0p0_dp(0)") )
				( member ( signalRef "@baseboard_fab2_lib.baseboard_fab2(sch_1):upi_cpu1_cpu0_p0p0_dp(1)") )
				( member ( signalRef "@baseboard_fab2_lib.baseboard_fab2(sch_1):upi_cpu1_cpu0_p0p0_dp(2)") )
				( member ( signalRef "@baseboard_fab2_lib.baseboard_fab2(sch_1):upi_cpu1_cpu0_p0p0_dp(3)") )
				( member ( signalRef "@baseboard_fab2_lib.baseboard_fab2(sch_1):upi_cpu1_cpu0_p0p0_dp(4)") )
				( member ( signalRef "@baseboard_fab2_lib.baseboard_fab2(sch_1):upi_cpu1_cpu0_p0p0_dp(5)") )
				( member ( signalRef "@baseboard_fab2_lib.baseboard_fab2(sch_1):upi_cpu1_cpu0_p0p0_dp(6)") )
				( member ( signalRef "@baseboard_fab2_lib.baseboard_fab2(sch_1):upi_cpu1_cpu0_p0p0_dp(7)") )
				( member ( signalRef "@baseboard_fab2_lib.baseboard_fab2(sch_1):upi_cpu1_cpu0_p0p0_dp(8)") )
				( member ( signalRef "@baseboard_fab2_lib.baseboard_fab2(sch_1):upi_cpu1_cpu0_p0p0_dp(9)") )
				( member ( signalRef "@baseboard_fab2_lib.baseboard_fab2(sch_1):upi_cpu1_cpu0_p0p0_dp(10)") )
				( member ( signalRef "@baseboard_fab2_lib.baseboard_fab2(sch_1):upi_cpu1_cpu0_p0p0_dp(11)") )
				( member ( signalRef "@baseboard_fab2_lib.baseboard_fab2(sch_1):upi_cpu1_cpu0_p0p0_dp(12)") )
				( member ( signalRef "@baseboard_fab2_lib.baseboard_fab2(sch_1):upi_cpu1_cpu0_p0p0_dp(13)") )
				( member ( signalRef "@baseboard_fab2_lib.baseboard_fab2(sch_1):upi_cpu1_cpu0_p0p0_dp(14)") )
				( member ( signalRef "@baseboard_fab2_lib.baseboard_fab2(sch_1):upi_cpu1_cpu0_p0p0_dp(15)") )
				( member ( signalRef "@baseboard_fab2_lib.baseboard_fab2(sch_1):upi_cpu1_cpu0_p0p0_dp(16)") )
				( member ( signalRef "@baseboard_fab2_lib.baseboard_fab2(sch_1):upi_cpu1_cpu0_p0p0_dp(17)") )
				( member ( signalRef "@baseboard_fab2_lib.baseboard_fab2(sch_1):upi_cpu1_cpu0_p0p0_dp(18)") )
				( member ( signalRef "@baseboard_fab2_lib.baseboard_fab2(sch_1):upi_cpu1_cpu0_p0p0_dp(19)") )
				( objectStatus "UPI_CPU1_CPU0_P0P0_DP" )
			)
			( bus "@crescent_city_bb_fab1_lib.crescent_city_bb_fab1(sch_1):upi_cpu1_cpu0_p0p0_dn"
				( memberType ( signal ) )
				( member ( signalRef "@baseboard_fab2_lib.baseboard_fab2(sch_1):upi_cpu1_cpu0_p0p0_dn(0)") )
				( member ( signalRef "@baseboard_fab2_lib.baseboard_fab2(sch_1):upi_cpu1_cpu0_p0p0_dn(1)") )
				( member ( signalRef "@baseboard_fab2_lib.baseboard_fab2(sch_1):upi_cpu1_cpu0_p0p0_dn(2)") )
				( member ( signalRef "@baseboard_fab2_lib.baseboard_fab2(sch_1):upi_cpu1_cpu0_p0p0_dn(3)") )
				( member ( signalRef "@baseboard_fab2_lib.baseboard_fab2(sch_1):upi_cpu1_cpu0_p0p0_dn(4)") )
				( member ( signalRef "@baseboard_fab2_lib.baseboard_fab2(sch_1):upi_cpu1_cpu0_p0p0_dn(5)") )
				( member ( signalRef "@baseboard_fab2_lib.baseboard_fab2(sch_1):upi_cpu1_cpu0_p0p0_dn(6)") )
				( member ( signalRef "@baseboard_fab2_lib.baseboard_fab2(sch_1):upi_cpu1_cpu0_p0p0_dn(7)") )
				( member ( signalRef "@baseboard_fab2_lib.baseboard_fab2(sch_1):upi_cpu1_cpu0_p0p0_dn(8)") )
				( member ( signalRef "@baseboard_fab2_lib.baseboard_fab2(sch_1):upi_cpu1_cpu0_p0p0_dn(9)") )
				( member ( signalRef "@baseboard_fab2_lib.baseboard_fab2(sch_1):upi_cpu1_cpu0_p0p0_dn(10)") )
				( member ( signalRef "@baseboard_fab2_lib.baseboard_fab2(sch_1):upi_cpu1_cpu0_p0p0_dn(11)") )
				( member ( signalRef "@baseboard_fab2_lib.baseboard_fab2(sch_1):upi_cpu1_cpu0_p0p0_dn(12)") )
				( member ( signalRef "@baseboard_fab2_lib.baseboard_fab2(sch_1):upi_cpu1_cpu0_p0p0_dn(13)") )
				( member ( signalRef "@baseboard_fab2_lib.baseboard_fab2(sch_1):upi_cpu1_cpu0_p0p0_dn(14)") )
				( member ( signalRef "@baseboard_fab2_lib.baseboard_fab2(sch_1):upi_cpu1_cpu0_p0p0_dn(15)") )
				( member ( signalRef "@baseboard_fab2_lib.baseboard_fab2(sch_1):upi_cpu1_cpu0_p0p0_dn(16)") )
				( member ( signalRef "@baseboard_fab2_lib.baseboard_fab2(sch_1):upi_cpu1_cpu0_p0p0_dn(17)") )
				( member ( signalRef "@baseboard_fab2_lib.baseboard_fab2(sch_1):upi_cpu1_cpu0_p0p0_dn(18)") )
				( member ( signalRef "@baseboard_fab2_lib.baseboard_fab2(sch_1):upi_cpu1_cpu0_p0p0_dn(19)") )
				( objectStatus "UPI_CPU1_CPU0_P0P0_DN" )
			)
			( bus "@crescent_city_bb_fab1_lib.crescent_city_bb_fab1(sch_1):upi_cpu0_cpu1_p0p0_dp"
				( memberType ( signal ) )
				( member ( signalRef "@baseboard_fab2_lib.baseboard_fab2(sch_1):upi_cpu0_cpu1_p0p0_dp(0)") )
				( member ( signalRef "@baseboard_fab2_lib.baseboard_fab2(sch_1):upi_cpu0_cpu1_p0p0_dp(1)") )
				( member ( signalRef "@baseboard_fab2_lib.baseboard_fab2(sch_1):upi_cpu0_cpu1_p0p0_dp(2)") )
				( member ( signalRef "@baseboard_fab2_lib.baseboard_fab2(sch_1):upi_cpu0_cpu1_p0p0_dp(3)") )
				( member ( signalRef "@baseboard_fab2_lib.baseboard_fab2(sch_1):upi_cpu0_cpu1_p0p0_dp(4)") )
				( member ( signalRef "@baseboard_fab2_lib.baseboard_fab2(sch_1):upi_cpu0_cpu1_p0p0_dp(5)") )
				( member ( signalRef "@baseboard_fab2_lib.baseboard_fab2(sch_1):upi_cpu0_cpu1_p0p0_dp(6)") )
				( member ( signalRef "@baseboard_fab2_lib.baseboard_fab2(sch_1):upi_cpu0_cpu1_p0p0_dp(7)") )
				( member ( signalRef "@baseboard_fab2_lib.baseboard_fab2(sch_1):upi_cpu0_cpu1_p0p0_dp(8)") )
				( member ( signalRef "@baseboard_fab2_lib.baseboard_fab2(sch_1):upi_cpu0_cpu1_p0p0_dp(9)") )
				( member ( signalRef "@baseboard_fab2_lib.baseboard_fab2(sch_1):upi_cpu0_cpu1_p0p0_dp(10)") )
				( member ( signalRef "@baseboard_fab2_lib.baseboard_fab2(sch_1):upi_cpu0_cpu1_p0p0_dp(11)") )
				( member ( signalRef "@baseboard_fab2_lib.baseboard_fab2(sch_1):upi_cpu0_cpu1_p0p0_dp(12)") )
				( member ( signalRef "@baseboard_fab2_lib.baseboard_fab2(sch_1):upi_cpu0_cpu1_p0p0_dp(13)") )
				( member ( signalRef "@baseboard_fab2_lib.baseboard_fab2(sch_1):upi_cpu0_cpu1_p0p0_dp(14)") )
				( member ( signalRef "@baseboard_fab2_lib.baseboard_fab2(sch_1):upi_cpu0_cpu1_p0p0_dp(15)") )
				( member ( signalRef "@baseboard_fab2_lib.baseboard_fab2(sch_1):upi_cpu0_cpu1_p0p0_dp(16)") )
				( member ( signalRef "@baseboard_fab2_lib.baseboard_fab2(sch_1):upi_cpu0_cpu1_p0p0_dp(17)") )
				( member ( signalRef "@baseboard_fab2_lib.baseboard_fab2(sch_1):upi_cpu0_cpu1_p0p0_dp(18)") )
				( member ( signalRef "@baseboard_fab2_lib.baseboard_fab2(sch_1):upi_cpu0_cpu1_p0p0_dp(19)") )
				( objectStatus "UPI_CPU0_CPU1_P0P0_DP" )
			)
			( bus "@crescent_city_bb_fab1_lib.crescent_city_bb_fab1(sch_1):upi_cpu0_cpu1_p0p0_dn"
				( memberType ( signal ) )
				( member ( signalRef "@baseboard_fab2_lib.baseboard_fab2(sch_1):upi_cpu0_cpu1_p0p0_dn(0)") )
				( member ( signalRef "@baseboard_fab2_lib.baseboard_fab2(sch_1):upi_cpu0_cpu1_p0p0_dn(1)") )
				( member ( signalRef "@baseboard_fab2_lib.baseboard_fab2(sch_1):upi_cpu0_cpu1_p0p0_dn(2)") )
				( member ( signalRef "@baseboard_fab2_lib.baseboard_fab2(sch_1):upi_cpu0_cpu1_p0p0_dn(3)") )
				( member ( signalRef "@baseboard_fab2_lib.baseboard_fab2(sch_1):upi_cpu0_cpu1_p0p0_dn(4)") )
				( member ( signalRef "@baseboard_fab2_lib.baseboard_fab2(sch_1):upi_cpu0_cpu1_p0p0_dn(5)") )
				( member ( signalRef "@baseboard_fab2_lib.baseboard_fab2(sch_1):upi_cpu0_cpu1_p0p0_dn(6)") )
				( member ( signalRef "@baseboard_fab2_lib.baseboard_fab2(sch_1):upi_cpu0_cpu1_p0p0_dn(7)") )
				( member ( signalRef "@baseboard_fab2_lib.baseboard_fab2(sch_1):upi_cpu0_cpu1_p0p0_dn(8)") )
				( member ( signalRef "@baseboard_fab2_lib.baseboard_fab2(sch_1):upi_cpu0_cpu1_p0p0_dn(9)") )
				( member ( signalRef "@baseboard_fab2_lib.baseboard_fab2(sch_1):upi_cpu0_cpu1_p0p0_dn(10)") )
				( member ( signalRef "@baseboard_fab2_lib.baseboard_fab2(sch_1):upi_cpu0_cpu1_p0p0_dn(11)") )
				( member ( signalRef "@baseboard_fab2_lib.baseboard_fab2(sch_1):upi_cpu0_cpu1_p0p0_dn(12)") )
				( member ( signalRef "@baseboard_fab2_lib.baseboard_fab2(sch_1):upi_cpu0_cpu1_p0p0_dn(13)") )
				( member ( signalRef "@baseboard_fab2_lib.baseboard_fab2(sch_1):upi_cpu0_cpu1_p0p0_dn(14)") )
				( member ( signalRef "@baseboard_fab2_lib.baseboard_fab2(sch_1):upi_cpu0_cpu1_p0p0_dn(15)") )
				( member ( signalRef "@baseboard_fab2_lib.baseboard_fab2(sch_1):upi_cpu0_cpu1_p0p0_dn(16)") )
				( member ( signalRef "@baseboard_fab2_lib.baseboard_fab2(sch_1):upi_cpu0_cpu1_p0p0_dn(17)") )
				( member ( signalRef "@baseboard_fab2_lib.baseboard_fab2(sch_1):upi_cpu0_cpu1_p0p0_dn(18)") )
				( member ( signalRef "@baseboard_fab2_lib.baseboard_fab2(sch_1):upi_cpu0_cpu1_p0p0_dn(19)") )
				( objectStatus "UPI_CPU0_CPU1_P0P0_DN" )
			)
			( bus "@crescent_city_bb_fab1_lib.crescent_city_bb_fab1(sch_1):upi_cpu1_cpu0_p1p1_dp"
				( memberType ( signal ) )
				( member ( signalRef "@baseboard_fab2_lib.baseboard_fab2(sch_1):upi_cpu1_cpu0_p1p1_dp(0)") )
				( member ( signalRef "@baseboard_fab2_lib.baseboard_fab2(sch_1):upi_cpu1_cpu0_p1p1_dp(1)") )
				( member ( signalRef "@baseboard_fab2_lib.baseboard_fab2(sch_1):upi_cpu1_cpu0_p1p1_dp(2)") )
				( member ( signalRef "@baseboard_fab2_lib.baseboard_fab2(sch_1):upi_cpu1_cpu0_p1p1_dp(3)") )
				( member ( signalRef "@baseboard_fab2_lib.baseboard_fab2(sch_1):upi_cpu1_cpu0_p1p1_dp(4)") )
				( member ( signalRef "@baseboard_fab2_lib.baseboard_fab2(sch_1):upi_cpu1_cpu0_p1p1_dp(5)") )
				( member ( signalRef "@baseboard_fab2_lib.baseboard_fab2(sch_1):upi_cpu1_cpu0_p1p1_dp(6)") )
				( member ( signalRef "@baseboard_fab2_lib.baseboard_fab2(sch_1):upi_cpu1_cpu0_p1p1_dp(7)") )
				( member ( signalRef "@baseboard_fab2_lib.baseboard_fab2(sch_1):upi_cpu1_cpu0_p1p1_dp(8)") )
				( member ( signalRef "@baseboard_fab2_lib.baseboard_fab2(sch_1):upi_cpu1_cpu0_p1p1_dp(9)") )
				( member ( signalRef "@baseboard_fab2_lib.baseboard_fab2(sch_1):upi_cpu1_cpu0_p1p1_dp(10)") )
				( member ( signalRef "@baseboard_fab2_lib.baseboard_fab2(sch_1):upi_cpu1_cpu0_p1p1_dp(11)") )
				( member ( signalRef "@baseboard_fab2_lib.baseboard_fab2(sch_1):upi_cpu1_cpu0_p1p1_dp(12)") )
				( member ( signalRef "@baseboard_fab2_lib.baseboard_fab2(sch_1):upi_cpu1_cpu0_p1p1_dp(13)") )
				( member ( signalRef "@baseboard_fab2_lib.baseboard_fab2(sch_1):upi_cpu1_cpu0_p1p1_dp(14)") )
				( member ( signalRef "@baseboard_fab2_lib.baseboard_fab2(sch_1):upi_cpu1_cpu0_p1p1_dp(15)") )
				( member ( signalRef "@baseboard_fab2_lib.baseboard_fab2(sch_1):upi_cpu1_cpu0_p1p1_dp(16)") )
				( member ( signalRef "@baseboard_fab2_lib.baseboard_fab2(sch_1):upi_cpu1_cpu0_p1p1_dp(17)") )
				( member ( signalRef "@baseboard_fab2_lib.baseboard_fab2(sch_1):upi_cpu1_cpu0_p1p1_dp(18)") )
				( member ( signalRef "@baseboard_fab2_lib.baseboard_fab2(sch_1):upi_cpu1_cpu0_p1p1_dp(19)") )
				( objectStatus "UPI_CPU1_CPU0_P1P1_DP" )
			)
			( bus "@crescent_city_bb_fab1_lib.crescent_city_bb_fab1(sch_1):upi_cpu1_cpu0_p1p1_dn"
				( memberType ( signal ) )
				( member ( signalRef "@baseboard_fab2_lib.baseboard_fab2(sch_1):upi_cpu1_cpu0_p1p1_dn(0)") )
				( member ( signalRef "@baseboard_fab2_lib.baseboard_fab2(sch_1):upi_cpu1_cpu0_p1p1_dn(1)") )
				( member ( signalRef "@baseboard_fab2_lib.baseboard_fab2(sch_1):upi_cpu1_cpu0_p1p1_dn(2)") )
				( member ( signalRef "@baseboard_fab2_lib.baseboard_fab2(sch_1):upi_cpu1_cpu0_p1p1_dn(3)") )
				( member ( signalRef "@baseboard_fab2_lib.baseboard_fab2(sch_1):upi_cpu1_cpu0_p1p1_dn(4)") )
				( member ( signalRef "@baseboard_fab2_lib.baseboard_fab2(sch_1):upi_cpu1_cpu0_p1p1_dn(5)") )
				( member ( signalRef "@baseboard_fab2_lib.baseboard_fab2(sch_1):upi_cpu1_cpu0_p1p1_dn(6)") )
				( member ( signalRef "@baseboard_fab2_lib.baseboard_fab2(sch_1):upi_cpu1_cpu0_p1p1_dn(7)") )
				( member ( signalRef "@baseboard_fab2_lib.baseboard_fab2(sch_1):upi_cpu1_cpu0_p1p1_dn(8)") )
				( member ( signalRef "@baseboard_fab2_lib.baseboard_fab2(sch_1):upi_cpu1_cpu0_p1p1_dn(9)") )
				( member ( signalRef "@baseboard_fab2_lib.baseboard_fab2(sch_1):upi_cpu1_cpu0_p1p1_dn(10)") )
				( member ( signalRef "@baseboard_fab2_lib.baseboard_fab2(sch_1):upi_cpu1_cpu0_p1p1_dn(11)") )
				( member ( signalRef "@baseboard_fab2_lib.baseboard_fab2(sch_1):upi_cpu1_cpu0_p1p1_dn(12)") )
				( member ( signalRef "@baseboard_fab2_lib.baseboard_fab2(sch_1):upi_cpu1_cpu0_p1p1_dn(13)") )
				( member ( signalRef "@baseboard_fab2_lib.baseboard_fab2(sch_1):upi_cpu1_cpu0_p1p1_dn(14)") )
				( member ( signalRef "@baseboard_fab2_lib.baseboard_fab2(sch_1):upi_cpu1_cpu0_p1p1_dn(15)") )
				( member ( signalRef "@baseboard_fab2_lib.baseboard_fab2(sch_1):upi_cpu1_cpu0_p1p1_dn(16)") )
				( member ( signalRef "@baseboard_fab2_lib.baseboard_fab2(sch_1):upi_cpu1_cpu0_p1p1_dn(17)") )
				( member ( signalRef "@baseboard_fab2_lib.baseboard_fab2(sch_1):upi_cpu1_cpu0_p1p1_dn(18)") )
				( member ( signalRef "@baseboard_fab2_lib.baseboard_fab2(sch_1):upi_cpu1_cpu0_p1p1_dn(19)") )
				( objectStatus "UPI_CPU1_CPU0_P1P1_DN" )
			)
			( bus "@crescent_city_bb_fab1_lib.crescent_city_bb_fab1(sch_1):upi_cpu0_cpu1_p1p1_dp"
				( memberType ( signal ) )
				( member ( signalRef "@baseboard_fab2_lib.baseboard_fab2(sch_1):upi_cpu0_cpu1_p1p1_dp(0)") )
				( member ( signalRef "@baseboard_fab2_lib.baseboard_fab2(sch_1):upi_cpu0_cpu1_p1p1_dp(1)") )
				( member ( signalRef "@baseboard_fab2_lib.baseboard_fab2(sch_1):upi_cpu0_cpu1_p1p1_dp(2)") )
				( member ( signalRef "@baseboard_fab2_lib.baseboard_fab2(sch_1):upi_cpu0_cpu1_p1p1_dp(3)") )
				( member ( signalRef "@baseboard_fab2_lib.baseboard_fab2(sch_1):upi_cpu0_cpu1_p1p1_dp(4)") )
				( member ( signalRef "@baseboard_fab2_lib.baseboard_fab2(sch_1):upi_cpu0_cpu1_p1p1_dp(5)") )
				( member ( signalRef "@baseboard_fab2_lib.baseboard_fab2(sch_1):upi_cpu0_cpu1_p1p1_dp(6)") )
				( member ( signalRef "@baseboard_fab2_lib.baseboard_fab2(sch_1):upi_cpu0_cpu1_p1p1_dp(7)") )
				( member ( signalRef "@baseboard_fab2_lib.baseboard_fab2(sch_1):upi_cpu0_cpu1_p1p1_dp(8)") )
				( member ( signalRef "@baseboard_fab2_lib.baseboard_fab2(sch_1):upi_cpu0_cpu1_p1p1_dp(9)") )
				( member ( signalRef "@baseboard_fab2_lib.baseboard_fab2(sch_1):upi_cpu0_cpu1_p1p1_dp(10)") )
				( member ( signalRef "@baseboard_fab2_lib.baseboard_fab2(sch_1):upi_cpu0_cpu1_p1p1_dp(11)") )
				( member ( signalRef "@baseboard_fab2_lib.baseboard_fab2(sch_1):upi_cpu0_cpu1_p1p1_dp(12)") )
				( member ( signalRef "@baseboard_fab2_lib.baseboard_fab2(sch_1):upi_cpu0_cpu1_p1p1_dp(13)") )
				( member ( signalRef "@baseboard_fab2_lib.baseboard_fab2(sch_1):upi_cpu0_cpu1_p1p1_dp(14)") )
				( member ( signalRef "@baseboard_fab2_lib.baseboard_fab2(sch_1):upi_cpu0_cpu1_p1p1_dp(15)") )
				( member ( signalRef "@baseboard_fab2_lib.baseboard_fab2(sch_1):upi_cpu0_cpu1_p1p1_dp(16)") )
				( member ( signalRef "@baseboard_fab2_lib.baseboard_fab2(sch_1):upi_cpu0_cpu1_p1p1_dp(17)") )
				( member ( signalRef "@baseboard_fab2_lib.baseboard_fab2(sch_1):upi_cpu0_cpu1_p1p1_dp(18)") )
				( member ( signalRef "@baseboard_fab2_lib.baseboard_fab2(sch_1):upi_cpu0_cpu1_p1p1_dp(19)") )
				( objectStatus "UPI_CPU0_CPU1_P1P1_DP" )
			)
			( bus "@crescent_city_bb_fab1_lib.crescent_city_bb_fab1(sch_1):upi_cpu0_cpu1_p1p1_dn"
				( memberType ( signal ) )
				( member ( signalRef "@baseboard_fab2_lib.baseboard_fab2(sch_1):upi_cpu0_cpu1_p1p1_dn(0)") )
				( member ( signalRef "@baseboard_fab2_lib.baseboard_fab2(sch_1):upi_cpu0_cpu1_p1p1_dn(1)") )
				( member ( signalRef "@baseboard_fab2_lib.baseboard_fab2(sch_1):upi_cpu0_cpu1_p1p1_dn(2)") )
				( member ( signalRef "@baseboard_fab2_lib.baseboard_fab2(sch_1):upi_cpu0_cpu1_p1p1_dn(3)") )
				( member ( signalRef "@baseboard_fab2_lib.baseboard_fab2(sch_1):upi_cpu0_cpu1_p1p1_dn(4)") )
				( member ( signalRef "@baseboard_fab2_lib.baseboard_fab2(sch_1):upi_cpu0_cpu1_p1p1_dn(5)") )
				( member ( signalRef "@baseboard_fab2_lib.baseboard_fab2(sch_1):upi_cpu0_cpu1_p1p1_dn(6)") )
				( member ( signalRef "@baseboard_fab2_lib.baseboard_fab2(sch_1):upi_cpu0_cpu1_p1p1_dn(7)") )
				( member ( signalRef "@baseboard_fab2_lib.baseboard_fab2(sch_1):upi_cpu0_cpu1_p1p1_dn(8)") )
				( member ( signalRef "@baseboard_fab2_lib.baseboard_fab2(sch_1):upi_cpu0_cpu1_p1p1_dn(9)") )
				( member ( signalRef "@baseboard_fab2_lib.baseboard_fab2(sch_1):upi_cpu0_cpu1_p1p1_dn(10)") )
				( member ( signalRef "@baseboard_fab2_lib.baseboard_fab2(sch_1):upi_cpu0_cpu1_p1p1_dn(11)") )
				( member ( signalRef "@baseboard_fab2_lib.baseboard_fab2(sch_1):upi_cpu0_cpu1_p1p1_dn(12)") )
				( member ( signalRef "@baseboard_fab2_lib.baseboard_fab2(sch_1):upi_cpu0_cpu1_p1p1_dn(13)") )
				( member ( signalRef "@baseboard_fab2_lib.baseboard_fab2(sch_1):upi_cpu0_cpu1_p1p1_dn(14)") )
				( member ( signalRef "@baseboard_fab2_lib.baseboard_fab2(sch_1):upi_cpu0_cpu1_p1p1_dn(15)") )
				( member ( signalRef "@baseboard_fab2_lib.baseboard_fab2(sch_1):upi_cpu0_cpu1_p1p1_dn(16)") )
				( member ( signalRef "@baseboard_fab2_lib.baseboard_fab2(sch_1):upi_cpu0_cpu1_p1p1_dn(17)") )
				( member ( signalRef "@baseboard_fab2_lib.baseboard_fab2(sch_1):upi_cpu0_cpu1_p1p1_dn(18)") )
				( member ( signalRef "@baseboard_fab2_lib.baseboard_fab2(sch_1):upi_cpu0_cpu1_p1p1_dn(19)") )
				( objectStatus "UPI_CPU0_CPU1_P1P1_DN" )
			)
			( bus "@crescent_city_bb_fab1_lib.crescent_city_bb_fab1(sch_1):m_bmc_ddr3_ma"
				( memberType ( signal ) )
				( member ( signalRef "@baseboard_fab2_lib.baseboard_fab2(sch_1):m_bmc_ddr3_ma(0)") )
				( member ( signalRef "@baseboard_fab2_lib.baseboard_fab2(sch_1):m_bmc_ddr3_ma(1)") )
				( member ( signalRef "@baseboard_fab2_lib.baseboard_fab2(sch_1):m_bmc_ddr3_ma(2)") )
				( member ( signalRef "@baseboard_fab2_lib.baseboard_fab2(sch_1):m_bmc_ddr3_ma(3)") )
				( member ( signalRef "@baseboard_fab2_lib.baseboard_fab2(sch_1):m_bmc_ddr3_ma(4)") )
				( member ( signalRef "@baseboard_fab2_lib.baseboard_fab2(sch_1):m_bmc_ddr3_ma(5)") )
				( member ( signalRef "@baseboard_fab2_lib.baseboard_fab2(sch_1):m_bmc_ddr3_ma(6)") )
				( member ( signalRef "@baseboard_fab2_lib.baseboard_fab2(sch_1):m_bmc_ddr3_ma(7)") )
				( member ( signalRef "@baseboard_fab2_lib.baseboard_fab2(sch_1):m_bmc_ddr3_ma(8)") )
				( member ( signalRef "@baseboard_fab2_lib.baseboard_fab2(sch_1):m_bmc_ddr3_ma(9)") )
				( member ( signalRef "@baseboard_fab2_lib.baseboard_fab2(sch_1):m_bmc_ddr3_ma(10)") )
				( member ( signalRef "@baseboard_fab2_lib.baseboard_fab2(sch_1):m_bmc_ddr3_ma(11)") )
				( member ( signalRef "@baseboard_fab2_lib.baseboard_fab2(sch_1):m_bmc_ddr3_ma(12)") )
				( member ( signalRef "@baseboard_fab2_lib.baseboard_fab2(sch_1):m_bmc_ddr3_ma(13)") )
				( member ( signalRef "@baseboard_fab2_lib.baseboard_fab2(sch_1):m_bmc_ddr3_ma(14)") )
				( objectStatus "M_BMC_DDR3_MA" )
			)
			( bus "@crescent_city_bb_fab1_lib.crescent_city_bb_fab1(sch_1):m_bmc_ddr3_dq"
				( memberType ( signal ) )
				( member ( signalRef "@baseboard_fab2_lib.baseboard_fab2(sch_1):m_bmc_ddr3_dq(0)") )
				( member ( signalRef "@baseboard_fab2_lib.baseboard_fab2(sch_1):m_bmc_ddr3_dq(1)") )
				( member ( signalRef "@baseboard_fab2_lib.baseboard_fab2(sch_1):m_bmc_ddr3_dq(2)") )
				( member ( signalRef "@baseboard_fab2_lib.baseboard_fab2(sch_1):m_bmc_ddr3_dq(3)") )
				( member ( signalRef "@baseboard_fab2_lib.baseboard_fab2(sch_1):m_bmc_ddr3_dq(4)") )
				( member ( signalRef "@baseboard_fab2_lib.baseboard_fab2(sch_1):m_bmc_ddr3_dq(5)") )
				( member ( signalRef "@baseboard_fab2_lib.baseboard_fab2(sch_1):m_bmc_ddr3_dq(6)") )
				( member ( signalRef "@baseboard_fab2_lib.baseboard_fab2(sch_1):m_bmc_ddr3_dq(7)") )
				( member ( signalRef "@baseboard_fab2_lib.baseboard_fab2(sch_1):m_bmc_ddr3_dq(8)") )
				( member ( signalRef "@baseboard_fab2_lib.baseboard_fab2(sch_1):m_bmc_ddr3_dq(9)") )
				( member ( signalRef "@baseboard_fab2_lib.baseboard_fab2(sch_1):m_bmc_ddr3_dq(10)") )
				( member ( signalRef "@baseboard_fab2_lib.baseboard_fab2(sch_1):m_bmc_ddr3_dq(11)") )
				( member ( signalRef "@baseboard_fab2_lib.baseboard_fab2(sch_1):m_bmc_ddr3_dq(12)") )
				( member ( signalRef "@baseboard_fab2_lib.baseboard_fab2(sch_1):m_bmc_ddr3_dq(13)") )
				( member ( signalRef "@baseboard_fab2_lib.baseboard_fab2(sch_1):m_bmc_ddr3_dq(14)") )
				( member ( signalRef "@baseboard_fab2_lib.baseboard_fab2(sch_1):m_bmc_ddr3_dq(15)") )
				( objectStatus "M_BMC_DDR3_DQ" )
			)
			( bus "@crescent_city_bb_fab1_lib.crescent_city_bb_fab1(sch_1):p3e_cpu1_pe3_mp_c_txp"
				( memberType ( signal ) )
				( electricalCSetRef "@crescent_city_bb_fab1_lib.crescent_city_bb_fab1(sch_1):\PCIE_SLOT\" )
				( member ( electricalNetRef "@crescent_city_bb_fab1_lib.crescent_city_bb_fab1(sch_1):p3e_cpu1_pe3_mp_c_txp(9)") )
				( member ( electricalNetRef "@crescent_city_bb_fab1_lib.crescent_city_bb_fab1(sch_1):p3e_cpu1_pe3_mp_c_txp(8)") )
				( member ( electricalNetRef "@crescent_city_bb_fab1_lib.crescent_city_bb_fab1(sch_1):p3e_cpu1_pe3_mp_c_txp(14)") )
				( member ( electricalNetRef "@crescent_city_bb_fab1_lib.crescent_city_bb_fab1(sch_1):p3e_cpu1_pe3_mp_c_txp(12)") )
				( member ( electricalNetRef "@crescent_city_bb_fab1_lib.crescent_city_bb_fab1(sch_1):p3e_cpu1_pe3_mp_c_txp(11)") )
				( member ( electricalNetRef "@crescent_city_bb_fab1_lib.crescent_city_bb_fab1(sch_1):p3e_cpu1_pe3_mp_c_txp(15)") )
				( member ( electricalNetRef "@crescent_city_bb_fab1_lib.crescent_city_bb_fab1(sch_1):p3e_cpu1_pe3_mp_c_txp(13)") )
				( member ( electricalNetRef "@crescent_city_bb_fab1_lib.crescent_city_bb_fab1(sch_1):p3e_cpu1_pe3_mp_c_txp(10)") )
				( member ( electricalNetRef "@crescent_city_bb_fab1_lib.crescent_city_bb_fab1(sch_1):p3e_cpu1_pe3_mp_c_txp(7)") )
				( member ( electricalNetRef "@crescent_city_bb_fab1_lib.crescent_city_bb_fab1(sch_1):p3e_cpu1_pe3_mp_c_txp(6)") )
				( member ( electricalNetRef "@crescent_city_bb_fab1_lib.crescent_city_bb_fab1(sch_1):p3e_cpu1_pe3_mp_c_txp(5)") )
				( member ( electricalNetRef "@crescent_city_bb_fab1_lib.crescent_city_bb_fab1(sch_1):p3e_cpu1_pe3_mp_c_txp(4)") )
				( member ( electricalNetRef "@crescent_city_bb_fab1_lib.crescent_city_bb_fab1(sch_1):p3e_cpu1_pe3_mp_c_txp(3)") )
				( member ( electricalNetRef "@crescent_city_bb_fab1_lib.crescent_city_bb_fab1(sch_1):p3e_cpu1_pe3_mp_c_txp(2)") )
				( member ( electricalNetRef "@crescent_city_bb_fab1_lib.crescent_city_bb_fab1(sch_1):p3e_cpu1_pe3_mp_c_txp(1)") )
				( member ( electricalNetRef "@crescent_city_bb_fab1_lib.crescent_city_bb_fab1(sch_1):p3e_cpu1_pe3_mp_c_txp(0)") )
				( objectStatus "P3E_CPU1_PE3_MP_C_TXP" )
			)
			( bus "@crescent_city_bb_fab1_lib.crescent_city_bb_fab1(sch_1):p3e_cpu1_pe3_mp_c_txn"
				( memberType ( signal ) )
				( electricalCSetRef "@crescent_city_bb_fab1_lib.crescent_city_bb_fab1(sch_1):\PCIE_SLOT\" )
				( member ( electricalNetRef "@crescent_city_bb_fab1_lib.crescent_city_bb_fab1(sch_1):p3e_cpu1_pe3_mp_c_txn(9)") )
				( member ( electricalNetRef "@crescent_city_bb_fab1_lib.crescent_city_bb_fab1(sch_1):p3e_cpu1_pe3_mp_c_txn(8)") )
				( member ( electricalNetRef "@crescent_city_bb_fab1_lib.crescent_city_bb_fab1(sch_1):p3e_cpu1_pe3_mp_c_txn(14)") )
				( member ( electricalNetRef "@crescent_city_bb_fab1_lib.crescent_city_bb_fab1(sch_1):p3e_cpu1_pe3_mp_c_txn(12)") )
				( member ( electricalNetRef "@crescent_city_bb_fab1_lib.crescent_city_bb_fab1(sch_1):p3e_cpu1_pe3_mp_c_txn(11)") )
				( member ( electricalNetRef "@crescent_city_bb_fab1_lib.crescent_city_bb_fab1(sch_1):p3e_cpu1_pe3_mp_c_txn(15)") )
				( member ( electricalNetRef "@crescent_city_bb_fab1_lib.crescent_city_bb_fab1(sch_1):p3e_cpu1_pe3_mp_c_txn(13)") )
				( member ( electricalNetRef "@crescent_city_bb_fab1_lib.crescent_city_bb_fab1(sch_1):p3e_cpu1_pe3_mp_c_txn(10)") )
				( member ( electricalNetRef "@crescent_city_bb_fab1_lib.crescent_city_bb_fab1(sch_1):p3e_cpu1_pe3_mp_c_txn(7)") )
				( member ( electricalNetRef "@crescent_city_bb_fab1_lib.crescent_city_bb_fab1(sch_1):p3e_cpu1_pe3_mp_c_txn(6)") )
				( member ( electricalNetRef "@crescent_city_bb_fab1_lib.crescent_city_bb_fab1(sch_1):p3e_cpu1_pe3_mp_c_txn(5)") )
				( member ( electricalNetRef "@crescent_city_bb_fab1_lib.crescent_city_bb_fab1(sch_1):p3e_cpu1_pe3_mp_c_txn(4)") )
				( member ( electricalNetRef "@crescent_city_bb_fab1_lib.crescent_city_bb_fab1(sch_1):p3e_cpu1_pe3_mp_c_txn(3)") )
				( member ( electricalNetRef "@crescent_city_bb_fab1_lib.crescent_city_bb_fab1(sch_1):p3e_cpu1_pe3_mp_c_txn(2)") )
				( member ( electricalNetRef "@crescent_city_bb_fab1_lib.crescent_city_bb_fab1(sch_1):p3e_cpu1_pe3_mp_c_txn(1)") )
				( member ( electricalNetRef "@crescent_city_bb_fab1_lib.crescent_city_bb_fab1(sch_1):p3e_cpu1_pe3_mp_c_txn(0)") )
				( objectStatus "P3E_CPU1_PE3_MP_C_TXN" )
			)
			( bus "@crescent_city_bb_fab1_lib.crescent_city_bb_fab1(sch_1):p3e_cpu1_pe3_mp_rxp"
				( memberType ( signal ) )
				( electricalCSetRef "@crescent_city_bb_fab1_lib.crescent_city_bb_fab1(sch_1):\PCIE_SLOT_1\" )
				( member ( signalRef "@baseboard_fab2_lib.baseboard_fab2(sch_1):p3e_cpu1_pe3_mp_rxp(0)") )
				( member ( signalRef "@baseboard_fab2_lib.baseboard_fab2(sch_1):p3e_cpu1_pe3_mp_rxp(1)") )
				( member ( signalRef "@baseboard_fab2_lib.baseboard_fab2(sch_1):p3e_cpu1_pe3_mp_rxp(2)") )
				( member ( signalRef "@baseboard_fab2_lib.baseboard_fab2(sch_1):p3e_cpu1_pe3_mp_rxp(3)") )
				( member ( signalRef "@baseboard_fab2_lib.baseboard_fab2(sch_1):p3e_cpu1_pe3_mp_rxp(4)") )
				( member ( signalRef "@baseboard_fab2_lib.baseboard_fab2(sch_1):p3e_cpu1_pe3_mp_rxp(5)") )
				( member ( signalRef "@baseboard_fab2_lib.baseboard_fab2(sch_1):p3e_cpu1_pe3_mp_rxp(6)") )
				( member ( signalRef "@baseboard_fab2_lib.baseboard_fab2(sch_1):p3e_cpu1_pe3_mp_rxp(7)") )
				( member ( signalRef "@baseboard_fab2_lib.baseboard_fab2(sch_1):p3e_cpu1_pe3_mp_rxp(8)") )
				( member ( signalRef "@baseboard_fab2_lib.baseboard_fab2(sch_1):p3e_cpu1_pe3_mp_rxp(9)") )
				( member ( signalRef "@baseboard_fab2_lib.baseboard_fab2(sch_1):p3e_cpu1_pe3_mp_rxp(10)") )
				( member ( signalRef "@baseboard_fab2_lib.baseboard_fab2(sch_1):p3e_cpu1_pe3_mp_rxp(11)") )
				( member ( signalRef "@baseboard_fab2_lib.baseboard_fab2(sch_1):p3e_cpu1_pe3_mp_rxp(12)") )
				( member ( signalRef "@baseboard_fab2_lib.baseboard_fab2(sch_1):p3e_cpu1_pe3_mp_rxp(13)") )
				( member ( signalRef "@baseboard_fab2_lib.baseboard_fab2(sch_1):p3e_cpu1_pe3_mp_rxp(14)") )
				( member ( signalRef "@baseboard_fab2_lib.baseboard_fab2(sch_1):p3e_cpu1_pe3_mp_rxp(15)") )
				( objectStatus "P3E_CPU1_PE3_MP_RXP" )
			)
			( bus "@crescent_city_bb_fab1_lib.crescent_city_bb_fab1(sch_1):p3e_cpu1_pe3_mp_rxn"
				( memberType ( signal ) )
				( electricalCSetRef "@crescent_city_bb_fab1_lib.crescent_city_bb_fab1(sch_1):\PCIE_SLOT_1\" )
				( member ( signalRef "@baseboard_fab2_lib.baseboard_fab2(sch_1):p3e_cpu1_pe3_mp_rxn(0)") )
				( member ( signalRef "@baseboard_fab2_lib.baseboard_fab2(sch_1):p3e_cpu1_pe3_mp_rxn(1)") )
				( member ( signalRef "@baseboard_fab2_lib.baseboard_fab2(sch_1):p3e_cpu1_pe3_mp_rxn(2)") )
				( member ( signalRef "@baseboard_fab2_lib.baseboard_fab2(sch_1):p3e_cpu1_pe3_mp_rxn(3)") )
				( member ( signalRef "@baseboard_fab2_lib.baseboard_fab2(sch_1):p3e_cpu1_pe3_mp_rxn(4)") )
				( member ( signalRef "@baseboard_fab2_lib.baseboard_fab2(sch_1):p3e_cpu1_pe3_mp_rxn(5)") )
				( member ( signalRef "@baseboard_fab2_lib.baseboard_fab2(sch_1):p3e_cpu1_pe3_mp_rxn(6)") )
				( member ( signalRef "@baseboard_fab2_lib.baseboard_fab2(sch_1):p3e_cpu1_pe3_mp_rxn(7)") )
				( member ( signalRef "@baseboard_fab2_lib.baseboard_fab2(sch_1):p3e_cpu1_pe3_mp_rxn(8)") )
				( member ( signalRef "@baseboard_fab2_lib.baseboard_fab2(sch_1):p3e_cpu1_pe3_mp_rxn(9)") )
				( member ( signalRef "@baseboard_fab2_lib.baseboard_fab2(sch_1):p3e_cpu1_pe3_mp_rxn(10)") )
				( member ( signalRef "@baseboard_fab2_lib.baseboard_fab2(sch_1):p3e_cpu1_pe3_mp_rxn(11)") )
				( member ( signalRef "@baseboard_fab2_lib.baseboard_fab2(sch_1):p3e_cpu1_pe3_mp_rxn(12)") )
				( member ( signalRef "@baseboard_fab2_lib.baseboard_fab2(sch_1):p3e_cpu1_pe3_mp_rxn(13)") )
				( member ( signalRef "@baseboard_fab2_lib.baseboard_fab2(sch_1):p3e_cpu1_pe3_mp_rxn(14)") )
				( member ( signalRef "@baseboard_fab2_lib.baseboard_fab2(sch_1):p3e_cpu1_pe3_mp_rxn(15)") )
				( objectStatus "P3E_CPU1_PE3_MP_RXN" )
			)
			( bus "@crescent_city_bb_fab1_lib.crescent_city_bb_fab1(sch_1):tp_p3e_cpu1_pe2_rsr_txp"
				( memberType ( signal ) )
				( member ( signalRef "@baseboard_fab2_lib.baseboard_fab2(sch_1):tp_p3e_cpu1_pe2_rsr_txp(0)") )
				( member ( signalRef "@baseboard_fab2_lib.baseboard_fab2(sch_1):tp_p3e_cpu1_pe2_rsr_txp(1)") )
				( member ( signalRef "@baseboard_fab2_lib.baseboard_fab2(sch_1):tp_p3e_cpu1_pe2_rsr_txp(2)") )
				( member ( signalRef "@baseboard_fab2_lib.baseboard_fab2(sch_1):tp_p3e_cpu1_pe2_rsr_txp(3)") )
				( member ( signalRef "@baseboard_fab2_lib.baseboard_fab2(sch_1):tp_p3e_cpu1_pe2_rsr_txp(4)") )
				( member ( signalRef "@baseboard_fab2_lib.baseboard_fab2(sch_1):tp_p3e_cpu1_pe2_rsr_txp(5)") )
				( member ( signalRef "@baseboard_fab2_lib.baseboard_fab2(sch_1):tp_p3e_cpu1_pe2_rsr_txp(6)") )
				( member ( signalRef "@baseboard_fab2_lib.baseboard_fab2(sch_1):tp_p3e_cpu1_pe2_rsr_txp(7)") )
				( member ( signalRef "@baseboard_fab2_lib.baseboard_fab2(sch_1):tp_p3e_cpu1_pe2_rsr_txp(8)") )
				( member ( signalRef "@baseboard_fab2_lib.baseboard_fab2(sch_1):tp_p3e_cpu1_pe2_rsr_txp(9)") )
				( member ( signalRef "@baseboard_fab2_lib.baseboard_fab2(sch_1):tp_p3e_cpu1_pe2_rsr_txp(10)") )
				( member ( signalRef "@baseboard_fab2_lib.baseboard_fab2(sch_1):tp_p3e_cpu1_pe2_rsr_txp(11)") )
				( member ( signalRef "@baseboard_fab2_lib.baseboard_fab2(sch_1):tp_p3e_cpu1_pe2_rsr_txp(12)") )
				( member ( signalRef "@baseboard_fab2_lib.baseboard_fab2(sch_1):tp_p3e_cpu1_pe2_rsr_txp(13)") )
				( member ( signalRef "@baseboard_fab2_lib.baseboard_fab2(sch_1):tp_p3e_cpu1_pe2_rsr_txp(14)") )
				( member ( signalRef "@baseboard_fab2_lib.baseboard_fab2(sch_1):tp_p3e_cpu1_pe2_rsr_txp(15)") )
				( objectStatus "TP_P3E_CPU1_PE2_RSR_TXP" )
			)
			( bus "@crescent_city_bb_fab1_lib.crescent_city_bb_fab1(sch_1):tp_p3e_cpu1_pe2_rsr_txn"
				( memberType ( signal ) )
				( member ( signalRef "@baseboard_fab2_lib.baseboard_fab2(sch_1):tp_p3e_cpu1_pe2_rsr_txn(0)") )
				( member ( signalRef "@baseboard_fab2_lib.baseboard_fab2(sch_1):tp_p3e_cpu1_pe2_rsr_txn(1)") )
				( member ( signalRef "@baseboard_fab2_lib.baseboard_fab2(sch_1):tp_p3e_cpu1_pe2_rsr_txn(2)") )
				( member ( signalRef "@baseboard_fab2_lib.baseboard_fab2(sch_1):tp_p3e_cpu1_pe2_rsr_txn(3)") )
				( member ( signalRef "@baseboard_fab2_lib.baseboard_fab2(sch_1):tp_p3e_cpu1_pe2_rsr_txn(4)") )
				( member ( signalRef "@baseboard_fab2_lib.baseboard_fab2(sch_1):tp_p3e_cpu1_pe2_rsr_txn(5)") )
				( member ( signalRef "@baseboard_fab2_lib.baseboard_fab2(sch_1):tp_p3e_cpu1_pe2_rsr_txn(6)") )
				( member ( signalRef "@baseboard_fab2_lib.baseboard_fab2(sch_1):tp_p3e_cpu1_pe2_rsr_txn(7)") )
				( member ( signalRef "@baseboard_fab2_lib.baseboard_fab2(sch_1):tp_p3e_cpu1_pe2_rsr_txn(8)") )
				( member ( signalRef "@baseboard_fab2_lib.baseboard_fab2(sch_1):tp_p3e_cpu1_pe2_rsr_txn(9)") )
				( member ( signalRef "@baseboard_fab2_lib.baseboard_fab2(sch_1):tp_p3e_cpu1_pe2_rsr_txn(10)") )
				( member ( signalRef "@baseboard_fab2_lib.baseboard_fab2(sch_1):tp_p3e_cpu1_pe2_rsr_txn(11)") )
				( member ( signalRef "@baseboard_fab2_lib.baseboard_fab2(sch_1):tp_p3e_cpu1_pe2_rsr_txn(12)") )
				( member ( signalRef "@baseboard_fab2_lib.baseboard_fab2(sch_1):tp_p3e_cpu1_pe2_rsr_txn(13)") )
				( member ( signalRef "@baseboard_fab2_lib.baseboard_fab2(sch_1):tp_p3e_cpu1_pe2_rsr_txn(14)") )
				( member ( signalRef "@baseboard_fab2_lib.baseboard_fab2(sch_1):tp_p3e_cpu1_pe2_rsr_txn(15)") )
				( objectStatus "TP_P3E_CPU1_PE2_RSR_TXN" )
			)
			( bus "@crescent_city_bb_fab1_lib.crescent_city_bb_fab1(sch_1):tp_p3e_cpu1_pe2_rsr_rxp"
				( memberType ( signal ) )
				( member ( signalRef "@baseboard_fab2_lib.baseboard_fab2(sch_1):tp_p3e_cpu1_pe2_rsr_rxp(0)") )
				( member ( signalRef "@baseboard_fab2_lib.baseboard_fab2(sch_1):tp_p3e_cpu1_pe2_rsr_rxp(1)") )
				( member ( signalRef "@baseboard_fab2_lib.baseboard_fab2(sch_1):tp_p3e_cpu1_pe2_rsr_rxp(2)") )
				( member ( signalRef "@baseboard_fab2_lib.baseboard_fab2(sch_1):tp_p3e_cpu1_pe2_rsr_rxp(3)") )
				( member ( signalRef "@baseboard_fab2_lib.baseboard_fab2(sch_1):tp_p3e_cpu1_pe2_rsr_rxp(4)") )
				( member ( signalRef "@baseboard_fab2_lib.baseboard_fab2(sch_1):tp_p3e_cpu1_pe2_rsr_rxp(5)") )
				( member ( signalRef "@baseboard_fab2_lib.baseboard_fab2(sch_1):tp_p3e_cpu1_pe2_rsr_rxp(6)") )
				( member ( signalRef "@baseboard_fab2_lib.baseboard_fab2(sch_1):tp_p3e_cpu1_pe2_rsr_rxp(7)") )
				( member ( signalRef "@baseboard_fab2_lib.baseboard_fab2(sch_1):tp_p3e_cpu1_pe2_rsr_rxp(8)") )
				( member ( signalRef "@baseboard_fab2_lib.baseboard_fab2(sch_1):tp_p3e_cpu1_pe2_rsr_rxp(9)") )
				( member ( signalRef "@baseboard_fab2_lib.baseboard_fab2(sch_1):tp_p3e_cpu1_pe2_rsr_rxp(10)") )
				( member ( signalRef "@baseboard_fab2_lib.baseboard_fab2(sch_1):tp_p3e_cpu1_pe2_rsr_rxp(11)") )
				( member ( signalRef "@baseboard_fab2_lib.baseboard_fab2(sch_1):tp_p3e_cpu1_pe2_rsr_rxp(12)") )
				( member ( signalRef "@baseboard_fab2_lib.baseboard_fab2(sch_1):tp_p3e_cpu1_pe2_rsr_rxp(13)") )
				( member ( signalRef "@baseboard_fab2_lib.baseboard_fab2(sch_1):tp_p3e_cpu1_pe2_rsr_rxp(14)") )
				( member ( signalRef "@baseboard_fab2_lib.baseboard_fab2(sch_1):tp_p3e_cpu1_pe2_rsr_rxp(15)") )
				( objectStatus "TP_P3E_CPU1_PE2_RSR_RXP" )
			)
			( bus "@crescent_city_bb_fab1_lib.crescent_city_bb_fab1(sch_1):tp_p3e_cpu1_pe2_rsr_rxn"
				( memberType ( signal ) )
				( member ( signalRef "@baseboard_fab2_lib.baseboard_fab2(sch_1):tp_p3e_cpu1_pe2_rsr_rxn(0)") )
				( member ( signalRef "@baseboard_fab2_lib.baseboard_fab2(sch_1):tp_p3e_cpu1_pe2_rsr_rxn(1)") )
				( member ( signalRef "@baseboard_fab2_lib.baseboard_fab2(sch_1):tp_p3e_cpu1_pe2_rsr_rxn(2)") )
				( member ( signalRef "@baseboard_fab2_lib.baseboard_fab2(sch_1):tp_p3e_cpu1_pe2_rsr_rxn(3)") )
				( member ( signalRef "@baseboard_fab2_lib.baseboard_fab2(sch_1):tp_p3e_cpu1_pe2_rsr_rxn(4)") )
				( member ( signalRef "@baseboard_fab2_lib.baseboard_fab2(sch_1):tp_p3e_cpu1_pe2_rsr_rxn(5)") )
				( member ( signalRef "@baseboard_fab2_lib.baseboard_fab2(sch_1):tp_p3e_cpu1_pe2_rsr_rxn(6)") )
				( member ( signalRef "@baseboard_fab2_lib.baseboard_fab2(sch_1):tp_p3e_cpu1_pe2_rsr_rxn(7)") )
				( member ( signalRef "@baseboard_fab2_lib.baseboard_fab2(sch_1):tp_p3e_cpu1_pe2_rsr_rxn(8)") )
				( member ( signalRef "@baseboard_fab2_lib.baseboard_fab2(sch_1):tp_p3e_cpu1_pe2_rsr_rxn(9)") )
				( member ( signalRef "@baseboard_fab2_lib.baseboard_fab2(sch_1):tp_p3e_cpu1_pe2_rsr_rxn(10)") )
				( member ( signalRef "@baseboard_fab2_lib.baseboard_fab2(sch_1):tp_p3e_cpu1_pe2_rsr_rxn(11)") )
				( member ( signalRef "@baseboard_fab2_lib.baseboard_fab2(sch_1):tp_p3e_cpu1_pe2_rsr_rxn(12)") )
				( member ( signalRef "@baseboard_fab2_lib.baseboard_fab2(sch_1):tp_p3e_cpu1_pe2_rsr_rxn(13)") )
				( member ( signalRef "@baseboard_fab2_lib.baseboard_fab2(sch_1):tp_p3e_cpu1_pe2_rsr_rxn(14)") )
				( member ( signalRef "@baseboard_fab2_lib.baseboard_fab2(sch_1):tp_p3e_cpu1_pe2_rsr_rxn(15)") )
				( objectStatus "TP_P3E_CPU1_PE2_RSR_RXN" )
			)
			( bus "@crescent_city_bb_fab1_lib.crescent_city_bb_fab1(sch_1):tp_p3e_cpu1_pe1_rsr3_txp"
				( memberType ( signal ) )
				( member ( signalRef "@baseboard_fab2_lib.baseboard_fab2(sch_1):tp_p3e_cpu1_pe1_rsr3_txp(8)") )
				( member ( signalRef "@baseboard_fab2_lib.baseboard_fab2(sch_1):tp_p3e_cpu1_pe1_rsr3_txp(9)") )
				( member ( signalRef "@baseboard_fab2_lib.baseboard_fab2(sch_1):tp_p3e_cpu1_pe1_rsr3_txp(10)") )
				( member ( signalRef "@baseboard_fab2_lib.baseboard_fab2(sch_1):tp_p3e_cpu1_pe1_rsr3_txp(11)") )
				( member ( signalRef "@baseboard_fab2_lib.baseboard_fab2(sch_1):tp_p3e_cpu1_pe1_rsr3_txp(12)") )
				( member ( signalRef "@baseboard_fab2_lib.baseboard_fab2(sch_1):tp_p3e_cpu1_pe1_rsr3_txp(13)") )
				( member ( signalRef "@baseboard_fab2_lib.baseboard_fab2(sch_1):tp_p3e_cpu1_pe1_rsr3_txp(14)") )
				( member ( signalRef "@baseboard_fab2_lib.baseboard_fab2(sch_1):tp_p3e_cpu1_pe1_rsr3_txp(15)") )
				( objectStatus "TP_P3E_CPU1_PE1_RSR3_TXP" )
			)
			( bus "@crescent_city_bb_fab1_lib.crescent_city_bb_fab1(sch_1):tp_p3e_cpu1_pe1_rsr3_txn"
				( memberType ( signal ) )
				( member ( signalRef "@baseboard_fab2_lib.baseboard_fab2(sch_1):tp_p3e_cpu1_pe1_rsr3_txn(8)") )
				( member ( signalRef "@baseboard_fab2_lib.baseboard_fab2(sch_1):tp_p3e_cpu1_pe1_rsr3_txn(9)") )
				( member ( signalRef "@baseboard_fab2_lib.baseboard_fab2(sch_1):tp_p3e_cpu1_pe1_rsr3_txn(10)") )
				( member ( signalRef "@baseboard_fab2_lib.baseboard_fab2(sch_1):tp_p3e_cpu1_pe1_rsr3_txn(11)") )
				( member ( signalRef "@baseboard_fab2_lib.baseboard_fab2(sch_1):tp_p3e_cpu1_pe1_rsr3_txn(12)") )
				( member ( signalRef "@baseboard_fab2_lib.baseboard_fab2(sch_1):tp_p3e_cpu1_pe1_rsr3_txn(13)") )
				( member ( signalRef "@baseboard_fab2_lib.baseboard_fab2(sch_1):tp_p3e_cpu1_pe1_rsr3_txn(14)") )
				( member ( signalRef "@baseboard_fab2_lib.baseboard_fab2(sch_1):tp_p3e_cpu1_pe1_rsr3_txn(15)") )
				( objectStatus "TP_P3E_CPU1_PE1_RSR3_TXN" )
			)
			( bus "@crescent_city_bb_fab1_lib.crescent_city_bb_fab1(sch_1):tp_p3e_cpu1_pe1_rsr3_rxp"
				( memberType ( signal ) )
				( member ( signalRef "@baseboard_fab2_lib.baseboard_fab2(sch_1):tp_p3e_cpu1_pe1_rsr3_rxp(8)") )
				( member ( signalRef "@baseboard_fab2_lib.baseboard_fab2(sch_1):tp_p3e_cpu1_pe1_rsr3_rxp(9)") )
				( member ( signalRef "@baseboard_fab2_lib.baseboard_fab2(sch_1):tp_p3e_cpu1_pe1_rsr3_rxp(10)") )
				( member ( signalRef "@baseboard_fab2_lib.baseboard_fab2(sch_1):tp_p3e_cpu1_pe1_rsr3_rxp(11)") )
				( member ( signalRef "@baseboard_fab2_lib.baseboard_fab2(sch_1):tp_p3e_cpu1_pe1_rsr3_rxp(12)") )
				( member ( signalRef "@baseboard_fab2_lib.baseboard_fab2(sch_1):tp_p3e_cpu1_pe1_rsr3_rxp(13)") )
				( member ( signalRef "@baseboard_fab2_lib.baseboard_fab2(sch_1):tp_p3e_cpu1_pe1_rsr3_rxp(14)") )
				( member ( signalRef "@baseboard_fab2_lib.baseboard_fab2(sch_1):tp_p3e_cpu1_pe1_rsr3_rxp(15)") )
				( objectStatus "TP_P3E_CPU1_PE1_RSR3_RXP" )
			)
			( bus "@crescent_city_bb_fab1_lib.crescent_city_bb_fab1(sch_1):tp_p3e_cpu1_pe1_rsr3_rxn"
				( memberType ( signal ) )
				( member ( signalRef "@baseboard_fab2_lib.baseboard_fab2(sch_1):tp_p3e_cpu1_pe1_rsr3_rxn(8)") )
				( member ( signalRef "@baseboard_fab2_lib.baseboard_fab2(sch_1):tp_p3e_cpu1_pe1_rsr3_rxn(9)") )
				( member ( signalRef "@baseboard_fab2_lib.baseboard_fab2(sch_1):tp_p3e_cpu1_pe1_rsr3_rxn(10)") )
				( member ( signalRef "@baseboard_fab2_lib.baseboard_fab2(sch_1):tp_p3e_cpu1_pe1_rsr3_rxn(11)") )
				( member ( signalRef "@baseboard_fab2_lib.baseboard_fab2(sch_1):tp_p3e_cpu1_pe1_rsr3_rxn(12)") )
				( member ( signalRef "@baseboard_fab2_lib.baseboard_fab2(sch_1):tp_p3e_cpu1_pe1_rsr3_rxn(13)") )
				( member ( signalRef "@baseboard_fab2_lib.baseboard_fab2(sch_1):tp_p3e_cpu1_pe1_rsr3_rxn(14)") )
				( member ( signalRef "@baseboard_fab2_lib.baseboard_fab2(sch_1):tp_p3e_cpu1_pe1_rsr3_rxn(15)") )
				( objectStatus "TP_P3E_CPU1_PE1_RSR3_RXN" )
			)
			( bus "@crescent_city_bb_fab1_lib.crescent_city_bb_fab1(sch_1):dmi_cpu0_pch_tx_c_dp"
				( memberType ( signal ) )
				( electricalCSetRef "@crescent_city_bb_fab1_lib.crescent_city_bb_fab1(sch_1):\DMI_CPU0_PCH_RX_C_DN_0_\" )
				( member ( electricalNetRef "@crescent_city_bb_fab1_lib.crescent_city_bb_fab1(sch_1):dmi_cpu0_pch_tx_c_dp(3)") )
				( member ( electricalNetRef "@crescent_city_bb_fab1_lib.crescent_city_bb_fab1(sch_1):dmi_cpu0_pch_tx_c_dp(2)") )
				( member ( electricalNetRef "@crescent_city_bb_fab1_lib.crescent_city_bb_fab1(sch_1):dmi_cpu0_pch_tx_c_dp(1)") )
				( member ( electricalNetRef "@crescent_city_bb_fab1_lib.crescent_city_bb_fab1(sch_1):dmi_cpu0_pch_tx_c_dp(0)") )
				( objectStatus "DMI_CPU0_PCH_TX_C_DP" )
			)
			( bus "@crescent_city_bb_fab1_lib.crescent_city_bb_fab1(sch_1):m_m_odt"
				( memberType ( signal ) )
				( member ( signalRef "@baseboard_fab2_lib.baseboard_fab2(sch_1):m_m_odt(0)") )
				( member ( signalRef "@baseboard_fab2_lib.baseboard_fab2(sch_1):m_m_odt(1)") )
				( member ( signalRef "@baseboard_fab2_lib.baseboard_fab2(sch_1):m_m_odt(2)") )
				( member ( signalRef "@baseboard_fab2_lib.baseboard_fab2(sch_1):m_m_odt(3)") )
				( objectStatus "M_M_ODT" )
			)
			( bus "@crescent_city_bb_fab1_lib.crescent_city_bb_fab1(sch_1):m_m_ma"
				( memberType ( signal ) )
				( member ( signalRef "@baseboard_fab2_lib.baseboard_fab2(sch_1):m_m_ma(0)") )
				( member ( signalRef "@baseboard_fab2_lib.baseboard_fab2(sch_1):m_m_ma(1)") )
				( member ( signalRef "@baseboard_fab2_lib.baseboard_fab2(sch_1):m_m_ma(2)") )
				( member ( signalRef "@baseboard_fab2_lib.baseboard_fab2(sch_1):m_m_ma(3)") )
				( member ( signalRef "@baseboard_fab2_lib.baseboard_fab2(sch_1):m_m_ma(4)") )
				( member ( signalRef "@baseboard_fab2_lib.baseboard_fab2(sch_1):m_m_ma(5)") )
				( member ( signalRef "@baseboard_fab2_lib.baseboard_fab2(sch_1):m_m_ma(6)") )
				( member ( signalRef "@baseboard_fab2_lib.baseboard_fab2(sch_1):m_m_ma(7)") )
				( member ( signalRef "@baseboard_fab2_lib.baseboard_fab2(sch_1):m_m_ma(8)") )
				( member ( signalRef "@baseboard_fab2_lib.baseboard_fab2(sch_1):m_m_ma(9)") )
				( member ( signalRef "@baseboard_fab2_lib.baseboard_fab2(sch_1):m_m_ma(10)") )
				( member ( signalRef "@baseboard_fab2_lib.baseboard_fab2(sch_1):m_m_ma(11)") )
				( member ( signalRef "@baseboard_fab2_lib.baseboard_fab2(sch_1):m_m_ma(12)") )
				( member ( signalRef "@baseboard_fab2_lib.baseboard_fab2(sch_1):m_m_ma(13)") )
				( member ( signalRef "@baseboard_fab2_lib.baseboard_fab2(sch_1):m_m_ma(14)") )
				( member ( signalRef "@baseboard_fab2_lib.baseboard_fab2(sch_1):m_m_ma(15)") )
				( member ( signalRef "@baseboard_fab2_lib.baseboard_fab2(sch_1):m_m_ma(16)") )
				( member ( signalRef "@baseboard_fab2_lib.baseboard_fab2(sch_1):m_m_ma(17)") )
				( objectStatus "M_M_MA" )
			)
			( bus "@crescent_city_bb_fab1_lib.crescent_city_bb_fab1(sch_1):m_m_ecc"
				( memberType ( signal ) )
				( member ( signalRef "@baseboard_fab2_lib.baseboard_fab2(sch_1):m_m_ecc(0)") )
				( member ( signalRef "@baseboard_fab2_lib.baseboard_fab2(sch_1):m_m_ecc(1)") )
				( member ( signalRef "@baseboard_fab2_lib.baseboard_fab2(sch_1):m_m_ecc(2)") )
				( member ( signalRef "@baseboard_fab2_lib.baseboard_fab2(sch_1):m_m_ecc(3)") )
				( member ( signalRef "@baseboard_fab2_lib.baseboard_fab2(sch_1):m_m_ecc(4)") )
				( member ( signalRef "@baseboard_fab2_lib.baseboard_fab2(sch_1):m_m_ecc(5)") )
				( member ( signalRef "@baseboard_fab2_lib.baseboard_fab2(sch_1):m_m_ecc(6)") )
				( member ( signalRef "@baseboard_fab2_lib.baseboard_fab2(sch_1):m_m_ecc(7)") )
				( objectStatus "M_M_ECC" )
			)
			( bus "@crescent_city_bb_fab1_lib.crescent_city_bb_fab1(sch_1):m_m_dqs_dp"
				( memberType ( signal ) )
				( member ( signalRef "@baseboard_fab2_lib.baseboard_fab2(sch_1):m_m_dqs_dp(0)") )
				( member ( signalRef "@baseboard_fab2_lib.baseboard_fab2(sch_1):m_m_dqs_dp(1)") )
				( member ( signalRef "@baseboard_fab2_lib.baseboard_fab2(sch_1):m_m_dqs_dp(2)") )
				( member ( signalRef "@baseboard_fab2_lib.baseboard_fab2(sch_1):m_m_dqs_dp(3)") )
				( member ( signalRef "@baseboard_fab2_lib.baseboard_fab2(sch_1):m_m_dqs_dp(4)") )
				( member ( signalRef "@baseboard_fab2_lib.baseboard_fab2(sch_1):m_m_dqs_dp(5)") )
				( member ( signalRef "@baseboard_fab2_lib.baseboard_fab2(sch_1):m_m_dqs_dp(6)") )
				( member ( signalRef "@baseboard_fab2_lib.baseboard_fab2(sch_1):m_m_dqs_dp(7)") )
				( member ( signalRef "@baseboard_fab2_lib.baseboard_fab2(sch_1):m_m_dqs_dp(8)") )
				( member ( signalRef "@baseboard_fab2_lib.baseboard_fab2(sch_1):m_m_dqs_dp(9)") )
				( member ( signalRef "@baseboard_fab2_lib.baseboard_fab2(sch_1):m_m_dqs_dp(10)") )
				( member ( signalRef "@baseboard_fab2_lib.baseboard_fab2(sch_1):m_m_dqs_dp(11)") )
				( member ( signalRef "@baseboard_fab2_lib.baseboard_fab2(sch_1):m_m_dqs_dp(12)") )
				( member ( signalRef "@baseboard_fab2_lib.baseboard_fab2(sch_1):m_m_dqs_dp(13)") )
				( member ( signalRef "@baseboard_fab2_lib.baseboard_fab2(sch_1):m_m_dqs_dp(14)") )
				( member ( signalRef "@baseboard_fab2_lib.baseboard_fab2(sch_1):m_m_dqs_dp(15)") )
				( member ( signalRef "@baseboard_fab2_lib.baseboard_fab2(sch_1):m_m_dqs_dp(16)") )
				( member ( signalRef "@baseboard_fab2_lib.baseboard_fab2(sch_1):m_m_dqs_dp(17)") )
				( objectStatus "M_M_DQS_DP" )
			)
			( bus "@crescent_city_bb_fab1_lib.crescent_city_bb_fab1(sch_1):m_m_dqs_dn"
				( memberType ( signal ) )
				( member ( signalRef "@baseboard_fab2_lib.baseboard_fab2(sch_1):m_m_dqs_dn(0)") )
				( member ( signalRef "@baseboard_fab2_lib.baseboard_fab2(sch_1):m_m_dqs_dn(1)") )
				( member ( signalRef "@baseboard_fab2_lib.baseboard_fab2(sch_1):m_m_dqs_dn(2)") )
				( member ( signalRef "@baseboard_fab2_lib.baseboard_fab2(sch_1):m_m_dqs_dn(3)") )
				( member ( signalRef "@baseboard_fab2_lib.baseboard_fab2(sch_1):m_m_dqs_dn(4)") )
				( member ( signalRef "@baseboard_fab2_lib.baseboard_fab2(sch_1):m_m_dqs_dn(5)") )
				( member ( signalRef "@baseboard_fab2_lib.baseboard_fab2(sch_1):m_m_dqs_dn(6)") )
				( member ( signalRef "@baseboard_fab2_lib.baseboard_fab2(sch_1):m_m_dqs_dn(7)") )
				( member ( signalRef "@baseboard_fab2_lib.baseboard_fab2(sch_1):m_m_dqs_dn(8)") )
				( member ( signalRef "@baseboard_fab2_lib.baseboard_fab2(sch_1):m_m_dqs_dn(9)") )
				( member ( signalRef "@baseboard_fab2_lib.baseboard_fab2(sch_1):m_m_dqs_dn(10)") )
				( member ( signalRef "@baseboard_fab2_lib.baseboard_fab2(sch_1):m_m_dqs_dn(11)") )
				( member ( signalRef "@baseboard_fab2_lib.baseboard_fab2(sch_1):m_m_dqs_dn(12)") )
				( member ( signalRef "@baseboard_fab2_lib.baseboard_fab2(sch_1):m_m_dqs_dn(13)") )
				( member ( signalRef "@baseboard_fab2_lib.baseboard_fab2(sch_1):m_m_dqs_dn(14)") )
				( member ( signalRef "@baseboard_fab2_lib.baseboard_fab2(sch_1):m_m_dqs_dn(15)") )
				( member ( signalRef "@baseboard_fab2_lib.baseboard_fab2(sch_1):m_m_dqs_dn(16)") )
				( member ( signalRef "@baseboard_fab2_lib.baseboard_fab2(sch_1):m_m_dqs_dn(17)") )
				( objectStatus "M_M_DQS_DN" )
			)
			( bus "@crescent_city_bb_fab1_lib.crescent_city_bb_fab1(sch_1):m_m_dq"
				( memberType ( signal ) )
				( member ( signalRef "@baseboard_fab2_lib.baseboard_fab2(sch_1):m_m_dq(0)") )
				( member ( signalRef "@baseboard_fab2_lib.baseboard_fab2(sch_1):m_m_dq(1)") )
				( member ( signalRef "@baseboard_fab2_lib.baseboard_fab2(sch_1):m_m_dq(2)") )
				( member ( signalRef "@baseboard_fab2_lib.baseboard_fab2(sch_1):m_m_dq(3)") )
				( member ( signalRef "@baseboard_fab2_lib.baseboard_fab2(sch_1):m_m_dq(4)") )
				( member ( signalRef "@baseboard_fab2_lib.baseboard_fab2(sch_1):m_m_dq(5)") )
				( member ( signalRef "@baseboard_fab2_lib.baseboard_fab2(sch_1):m_m_dq(6)") )
				( member ( signalRef "@baseboard_fab2_lib.baseboard_fab2(sch_1):m_m_dq(7)") )
				( member ( signalRef "@baseboard_fab2_lib.baseboard_fab2(sch_1):m_m_dq(8)") )
				( member ( signalRef "@baseboard_fab2_lib.baseboard_fab2(sch_1):m_m_dq(9)") )
				( member ( signalRef "@baseboard_fab2_lib.baseboard_fab2(sch_1):m_m_dq(10)") )
				( member ( signalRef "@baseboard_fab2_lib.baseboard_fab2(sch_1):m_m_dq(11)") )
				( member ( signalRef "@baseboard_fab2_lib.baseboard_fab2(sch_1):m_m_dq(12)") )
				( member ( signalRef "@baseboard_fab2_lib.baseboard_fab2(sch_1):m_m_dq(13)") )
				( member ( signalRef "@baseboard_fab2_lib.baseboard_fab2(sch_1):m_m_dq(14)") )
				( member ( signalRef "@baseboard_fab2_lib.baseboard_fab2(sch_1):m_m_dq(15)") )
				( member ( signalRef "@baseboard_fab2_lib.baseboard_fab2(sch_1):m_m_dq(16)") )
				( member ( signalRef "@baseboard_fab2_lib.baseboard_fab2(sch_1):m_m_dq(17)") )
				( member ( signalRef "@baseboard_fab2_lib.baseboard_fab2(sch_1):m_m_dq(18)") )
				( member ( signalRef "@baseboard_fab2_lib.baseboard_fab2(sch_1):m_m_dq(19)") )
				( member ( signalRef "@baseboard_fab2_lib.baseboard_fab2(sch_1):m_m_dq(20)") )
				( member ( signalRef "@baseboard_fab2_lib.baseboard_fab2(sch_1):m_m_dq(21)") )
				( member ( signalRef "@baseboard_fab2_lib.baseboard_fab2(sch_1):m_m_dq(22)") )
				( member ( signalRef "@baseboard_fab2_lib.baseboard_fab2(sch_1):m_m_dq(23)") )
				( member ( signalRef "@baseboard_fab2_lib.baseboard_fab2(sch_1):m_m_dq(24)") )
				( member ( signalRef "@baseboard_fab2_lib.baseboard_fab2(sch_1):m_m_dq(25)") )
				( member ( signalRef "@baseboard_fab2_lib.baseboard_fab2(sch_1):m_m_dq(26)") )
				( member ( signalRef "@baseboard_fab2_lib.baseboard_fab2(sch_1):m_m_dq(27)") )
				( member ( signalRef "@baseboard_fab2_lib.baseboard_fab2(sch_1):m_m_dq(28)") )
				( member ( signalRef "@baseboard_fab2_lib.baseboard_fab2(sch_1):m_m_dq(29)") )
				( member ( signalRef "@baseboard_fab2_lib.baseboard_fab2(sch_1):m_m_dq(30)") )
				( member ( signalRef "@baseboard_fab2_lib.baseboard_fab2(sch_1):m_m_dq(31)") )
				( member ( signalRef "@baseboard_fab2_lib.baseboard_fab2(sch_1):m_m_dq(32)") )
				( member ( signalRef "@baseboard_fab2_lib.baseboard_fab2(sch_1):m_m_dq(33)") )
				( member ( signalRef "@baseboard_fab2_lib.baseboard_fab2(sch_1):m_m_dq(34)") )
				( member ( signalRef "@baseboard_fab2_lib.baseboard_fab2(sch_1):m_m_dq(35)") )
				( member ( signalRef "@baseboard_fab2_lib.baseboard_fab2(sch_1):m_m_dq(36)") )
				( member ( signalRef "@baseboard_fab2_lib.baseboard_fab2(sch_1):m_m_dq(37)") )
				( member ( signalRef "@baseboard_fab2_lib.baseboard_fab2(sch_1):m_m_dq(38)") )
				( member ( signalRef "@baseboard_fab2_lib.baseboard_fab2(sch_1):m_m_dq(39)") )
				( member ( signalRef "@baseboard_fab2_lib.baseboard_fab2(sch_1):m_m_dq(40)") )
				( member ( signalRef "@baseboard_fab2_lib.baseboard_fab2(sch_1):m_m_dq(41)") )
				( member ( signalRef "@baseboard_fab2_lib.baseboard_fab2(sch_1):m_m_dq(42)") )
				( member ( signalRef "@baseboard_fab2_lib.baseboard_fab2(sch_1):m_m_dq(43)") )
				( member ( signalRef "@baseboard_fab2_lib.baseboard_fab2(sch_1):m_m_dq(44)") )
				( member ( signalRef "@baseboard_fab2_lib.baseboard_fab2(sch_1):m_m_dq(45)") )
				( member ( signalRef "@baseboard_fab2_lib.baseboard_fab2(sch_1):m_m_dq(46)") )
				( member ( signalRef "@baseboard_fab2_lib.baseboard_fab2(sch_1):m_m_dq(47)") )
				( member ( signalRef "@baseboard_fab2_lib.baseboard_fab2(sch_1):m_m_dq(48)") )
				( member ( signalRef "@baseboard_fab2_lib.baseboard_fab2(sch_1):m_m_dq(49)") )
				( member ( signalRef "@baseboard_fab2_lib.baseboard_fab2(sch_1):m_m_dq(50)") )
				( member ( signalRef "@baseboard_fab2_lib.baseboard_fab2(sch_1):m_m_dq(51)") )
				( member ( signalRef "@baseboard_fab2_lib.baseboard_fab2(sch_1):m_m_dq(52)") )
				( member ( signalRef "@baseboard_fab2_lib.baseboard_fab2(sch_1):m_m_dq(53)") )
				( member ( signalRef "@baseboard_fab2_lib.baseboard_fab2(sch_1):m_m_dq(54)") )
				( member ( signalRef "@baseboard_fab2_lib.baseboard_fab2(sch_1):m_m_dq(55)") )
				( member ( signalRef "@baseboard_fab2_lib.baseboard_fab2(sch_1):m_m_dq(56)") )
				( member ( signalRef "@baseboard_fab2_lib.baseboard_fab2(sch_1):m_m_dq(57)") )
				( member ( signalRef "@baseboard_fab2_lib.baseboard_fab2(sch_1):m_m_dq(58)") )
				( member ( signalRef "@baseboard_fab2_lib.baseboard_fab2(sch_1):m_m_dq(59)") )
				( member ( signalRef "@baseboard_fab2_lib.baseboard_fab2(sch_1):m_m_dq(60)") )
				( member ( signalRef "@baseboard_fab2_lib.baseboard_fab2(sch_1):m_m_dq(61)") )
				( member ( signalRef "@baseboard_fab2_lib.baseboard_fab2(sch_1):m_m_dq(62)") )
				( member ( signalRef "@baseboard_fab2_lib.baseboard_fab2(sch_1):m_m_dq(63)") )
				( objectStatus "M_M_DQ" )
			)
			( bus "@crescent_city_bb_fab1_lib.crescent_city_bb_fab1(sch_1):m_m_cs_n"
				( memberType ( signal ) )
				( member ( signalRef "@baseboard_fab2_lib.baseboard_fab2(sch_1):m_m_cs_n(0)") )
				( member ( signalRef "@baseboard_fab2_lib.baseboard_fab2(sch_1):m_m_cs_n(1)") )
				( member ( signalRef "@baseboard_fab2_lib.baseboard_fab2(sch_1):m_m_cs_n(2)") )
				( member ( signalRef "@baseboard_fab2_lib.baseboard_fab2(sch_1):m_m_cs_n(3)") )
				( member ( signalRef "@baseboard_fab2_lib.baseboard_fab2(sch_1):m_m_cs_n(4)") )
				( member ( signalRef "@baseboard_fab2_lib.baseboard_fab2(sch_1):m_m_cs_n(5)") )
				( member ( signalRef "@baseboard_fab2_lib.baseboard_fab2(sch_1):m_m_cs_n(6)") )
				( member ( signalRef "@baseboard_fab2_lib.baseboard_fab2(sch_1):m_m_cs_n(7)") )
				( objectStatus "M_M_CS_N" )
			)
			( bus "@crescent_city_bb_fab1_lib.crescent_city_bb_fab1(sch_1):m_m_clk_dp"
				( memberType ( signal ) )
				( member ( signalRef "@baseboard_fab2_lib.baseboard_fab2(sch_1):m_m_clk_dp(0)") )
				( member ( signalRef "@baseboard_fab2_lib.baseboard_fab2(sch_1):m_m_clk_dp(1)") )
				( member ( signalRef "@baseboard_fab2_lib.baseboard_fab2(sch_1):m_m_clk_dp(2)") )
				( member ( signalRef "@baseboard_fab2_lib.baseboard_fab2(sch_1):m_m_clk_dp(3)") )
				( objectStatus "M_M_CLK_DP" )
			)
			( bus "@crescent_city_bb_fab1_lib.crescent_city_bb_fab1(sch_1):m_m_clk_dn"
				( memberType ( signal ) )
				( member ( signalRef "@baseboard_fab2_lib.baseboard_fab2(sch_1):m_m_clk_dn(0)") )
				( member ( signalRef "@baseboard_fab2_lib.baseboard_fab2(sch_1):m_m_clk_dn(1)") )
				( member ( signalRef "@baseboard_fab2_lib.baseboard_fab2(sch_1):m_m_clk_dn(2)") )
				( member ( signalRef "@baseboard_fab2_lib.baseboard_fab2(sch_1):m_m_clk_dn(3)") )
				( objectStatus "M_M_CLK_DN" )
			)
			( bus "@crescent_city_bb_fab1_lib.crescent_city_bb_fab1(sch_1):m_m_cke"
				( memberType ( signal ) )
				( member ( signalRef "@baseboard_fab2_lib.baseboard_fab2(sch_1):m_m_cke(0)") )
				( member ( signalRef "@baseboard_fab2_lib.baseboard_fab2(sch_1):m_m_cke(1)") )
				( member ( signalRef "@baseboard_fab2_lib.baseboard_fab2(sch_1):m_m_cke(2)") )
				( member ( signalRef "@baseboard_fab2_lib.baseboard_fab2(sch_1):m_m_cke(3)") )
				( objectStatus "M_M_CKE" )
			)
			( bus "@crescent_city_bb_fab1_lib.crescent_city_bb_fab1(sch_1):m_m_c"
				( memberType ( signal ) )
				( member ( signalRef "@baseboard_fab2_lib.baseboard_fab2(sch_1):m_m_c(2)") )
				( objectStatus "M_M_C" )
			)
			( bus "@crescent_city_bb_fab1_lib.crescent_city_bb_fab1(sch_1):m_m_bg"
				( memberType ( signal ) )
				( member ( signalRef "@baseboard_fab2_lib.baseboard_fab2(sch_1):m_m_bg(0)") )
				( member ( signalRef "@baseboard_fab2_lib.baseboard_fab2(sch_1):m_m_bg(1)") )
				( objectStatus "M_M_BG" )
			)
			( bus "@crescent_city_bb_fab1_lib.crescent_city_bb_fab1(sch_1):m_m_ba"
				( memberType ( signal ) )
				( member ( signalRef "@baseboard_fab2_lib.baseboard_fab2(sch_1):m_m_ba(0)") )
				( member ( signalRef "@baseboard_fab2_lib.baseboard_fab2(sch_1):m_m_ba(1)") )
				( objectStatus "M_M_BA" )
			)
			( bus "@crescent_city_bb_fab1_lib.crescent_city_bb_fab1(sch_1):m_l_odt"
				( memberType ( signal ) )
				( member ( signalRef "@baseboard_fab2_lib.baseboard_fab2(sch_1):m_l_odt(0)") )
				( member ( signalRef "@baseboard_fab2_lib.baseboard_fab2(sch_1):m_l_odt(1)") )
				( member ( signalRef "@baseboard_fab2_lib.baseboard_fab2(sch_1):m_l_odt(2)") )
				( member ( signalRef "@baseboard_fab2_lib.baseboard_fab2(sch_1):m_l_odt(3)") )
				( objectStatus "M_L_ODT" )
			)
			( bus "@crescent_city_bb_fab1_lib.crescent_city_bb_fab1(sch_1):m_l_ma"
				( memberType ( signal ) )
				( member ( signalRef "@baseboard_fab2_lib.baseboard_fab2(sch_1):m_l_ma(0)") )
				( member ( signalRef "@baseboard_fab2_lib.baseboard_fab2(sch_1):m_l_ma(1)") )
				( member ( signalRef "@baseboard_fab2_lib.baseboard_fab2(sch_1):m_l_ma(2)") )
				( member ( signalRef "@baseboard_fab2_lib.baseboard_fab2(sch_1):m_l_ma(3)") )
				( member ( signalRef "@baseboard_fab2_lib.baseboard_fab2(sch_1):m_l_ma(4)") )
				( member ( signalRef "@baseboard_fab2_lib.baseboard_fab2(sch_1):m_l_ma(5)") )
				( member ( signalRef "@baseboard_fab2_lib.baseboard_fab2(sch_1):m_l_ma(6)") )
				( member ( signalRef "@baseboard_fab2_lib.baseboard_fab2(sch_1):m_l_ma(7)") )
				( member ( signalRef "@baseboard_fab2_lib.baseboard_fab2(sch_1):m_l_ma(8)") )
				( member ( signalRef "@baseboard_fab2_lib.baseboard_fab2(sch_1):m_l_ma(9)") )
				( member ( signalRef "@baseboard_fab2_lib.baseboard_fab2(sch_1):m_l_ma(10)") )
				( member ( signalRef "@baseboard_fab2_lib.baseboard_fab2(sch_1):m_l_ma(11)") )
				( member ( signalRef "@baseboard_fab2_lib.baseboard_fab2(sch_1):m_l_ma(12)") )
				( member ( signalRef "@baseboard_fab2_lib.baseboard_fab2(sch_1):m_l_ma(13)") )
				( member ( signalRef "@baseboard_fab2_lib.baseboard_fab2(sch_1):m_l_ma(14)") )
				( member ( signalRef "@baseboard_fab2_lib.baseboard_fab2(sch_1):m_l_ma(15)") )
				( member ( signalRef "@baseboard_fab2_lib.baseboard_fab2(sch_1):m_l_ma(16)") )
				( member ( signalRef "@baseboard_fab2_lib.baseboard_fab2(sch_1):m_l_ma(17)") )
				( objectStatus "M_L_MA" )
			)
			( bus "@crescent_city_bb_fab1_lib.crescent_city_bb_fab1(sch_1):m_l_ecc"
				( memberType ( signal ) )
				( member ( signalRef "@baseboard_fab2_lib.baseboard_fab2(sch_1):m_l_ecc(0)") )
				( member ( signalRef "@baseboard_fab2_lib.baseboard_fab2(sch_1):m_l_ecc(1)") )
				( member ( signalRef "@baseboard_fab2_lib.baseboard_fab2(sch_1):m_l_ecc(2)") )
				( member ( signalRef "@baseboard_fab2_lib.baseboard_fab2(sch_1):m_l_ecc(3)") )
				( member ( signalRef "@baseboard_fab2_lib.baseboard_fab2(sch_1):m_l_ecc(4)") )
				( member ( signalRef "@baseboard_fab2_lib.baseboard_fab2(sch_1):m_l_ecc(5)") )
				( member ( signalRef "@baseboard_fab2_lib.baseboard_fab2(sch_1):m_l_ecc(6)") )
				( member ( signalRef "@baseboard_fab2_lib.baseboard_fab2(sch_1):m_l_ecc(7)") )
				( objectStatus "M_L_ECC" )
			)
			( bus "@crescent_city_bb_fab1_lib.crescent_city_bb_fab1(sch_1):m_l_dqs_dp"
				( memberType ( signal ) )
				( member ( signalRef "@baseboard_fab2_lib.baseboard_fab2(sch_1):m_l_dqs_dp(0)") )
				( member ( signalRef "@baseboard_fab2_lib.baseboard_fab2(sch_1):m_l_dqs_dp(1)") )
				( member ( signalRef "@baseboard_fab2_lib.baseboard_fab2(sch_1):m_l_dqs_dp(2)") )
				( member ( signalRef "@baseboard_fab2_lib.baseboard_fab2(sch_1):m_l_dqs_dp(3)") )
				( member ( signalRef "@baseboard_fab2_lib.baseboard_fab2(sch_1):m_l_dqs_dp(4)") )
				( member ( signalRef "@baseboard_fab2_lib.baseboard_fab2(sch_1):m_l_dqs_dp(5)") )
				( member ( signalRef "@baseboard_fab2_lib.baseboard_fab2(sch_1):m_l_dqs_dp(6)") )
				( member ( signalRef "@baseboard_fab2_lib.baseboard_fab2(sch_1):m_l_dqs_dp(7)") )
				( member ( signalRef "@baseboard_fab2_lib.baseboard_fab2(sch_1):m_l_dqs_dp(8)") )
				( member ( signalRef "@baseboard_fab2_lib.baseboard_fab2(sch_1):m_l_dqs_dp(9)") )
				( member ( signalRef "@baseboard_fab2_lib.baseboard_fab2(sch_1):m_l_dqs_dp(10)") )
				( member ( signalRef "@baseboard_fab2_lib.baseboard_fab2(sch_1):m_l_dqs_dp(11)") )
				( member ( signalRef "@baseboard_fab2_lib.baseboard_fab2(sch_1):m_l_dqs_dp(12)") )
				( member ( signalRef "@baseboard_fab2_lib.baseboard_fab2(sch_1):m_l_dqs_dp(13)") )
				( member ( signalRef "@baseboard_fab2_lib.baseboard_fab2(sch_1):m_l_dqs_dp(14)") )
				( member ( signalRef "@baseboard_fab2_lib.baseboard_fab2(sch_1):m_l_dqs_dp(15)") )
				( member ( signalRef "@baseboard_fab2_lib.baseboard_fab2(sch_1):m_l_dqs_dp(16)") )
				( member ( signalRef "@baseboard_fab2_lib.baseboard_fab2(sch_1):m_l_dqs_dp(17)") )
				( objectStatus "M_L_DQS_DP" )
			)
			( bus "@crescent_city_bb_fab1_lib.crescent_city_bb_fab1(sch_1):m_l_dqs_dn"
				( memberType ( signal ) )
				( member ( signalRef "@baseboard_fab2_lib.baseboard_fab2(sch_1):m_l_dqs_dn(0)") )
				( member ( signalRef "@baseboard_fab2_lib.baseboard_fab2(sch_1):m_l_dqs_dn(1)") )
				( member ( signalRef "@baseboard_fab2_lib.baseboard_fab2(sch_1):m_l_dqs_dn(2)") )
				( member ( signalRef "@baseboard_fab2_lib.baseboard_fab2(sch_1):m_l_dqs_dn(3)") )
				( member ( signalRef "@baseboard_fab2_lib.baseboard_fab2(sch_1):m_l_dqs_dn(4)") )
				( member ( signalRef "@baseboard_fab2_lib.baseboard_fab2(sch_1):m_l_dqs_dn(5)") )
				( member ( signalRef "@baseboard_fab2_lib.baseboard_fab2(sch_1):m_l_dqs_dn(6)") )
				( member ( signalRef "@baseboard_fab2_lib.baseboard_fab2(sch_1):m_l_dqs_dn(7)") )
				( member ( signalRef "@baseboard_fab2_lib.baseboard_fab2(sch_1):m_l_dqs_dn(8)") )
				( member ( signalRef "@baseboard_fab2_lib.baseboard_fab2(sch_1):m_l_dqs_dn(9)") )
				( member ( signalRef "@baseboard_fab2_lib.baseboard_fab2(sch_1):m_l_dqs_dn(10)") )
				( member ( signalRef "@baseboard_fab2_lib.baseboard_fab2(sch_1):m_l_dqs_dn(11)") )
				( member ( signalRef "@baseboard_fab2_lib.baseboard_fab2(sch_1):m_l_dqs_dn(12)") )
				( member ( signalRef "@baseboard_fab2_lib.baseboard_fab2(sch_1):m_l_dqs_dn(13)") )
				( member ( signalRef "@baseboard_fab2_lib.baseboard_fab2(sch_1):m_l_dqs_dn(14)") )
				( member ( signalRef "@baseboard_fab2_lib.baseboard_fab2(sch_1):m_l_dqs_dn(15)") )
				( member ( signalRef "@baseboard_fab2_lib.baseboard_fab2(sch_1):m_l_dqs_dn(16)") )
				( member ( signalRef "@baseboard_fab2_lib.baseboard_fab2(sch_1):m_l_dqs_dn(17)") )
				( objectStatus "M_L_DQS_DN" )
			)
			( bus "@crescent_city_bb_fab1_lib.crescent_city_bb_fab1(sch_1):m_l_dq"
				( memberType ( signal ) )
				( member ( signalRef "@baseboard_fab2_lib.baseboard_fab2(sch_1):m_l_dq(0)") )
				( member ( signalRef "@baseboard_fab2_lib.baseboard_fab2(sch_1):m_l_dq(1)") )
				( member ( signalRef "@baseboard_fab2_lib.baseboard_fab2(sch_1):m_l_dq(2)") )
				( member ( signalRef "@baseboard_fab2_lib.baseboard_fab2(sch_1):m_l_dq(3)") )
				( member ( signalRef "@baseboard_fab2_lib.baseboard_fab2(sch_1):m_l_dq(4)") )
				( member ( signalRef "@baseboard_fab2_lib.baseboard_fab2(sch_1):m_l_dq(5)") )
				( member ( signalRef "@baseboard_fab2_lib.baseboard_fab2(sch_1):m_l_dq(6)") )
				( member ( signalRef "@baseboard_fab2_lib.baseboard_fab2(sch_1):m_l_dq(7)") )
				( member ( signalRef "@baseboard_fab2_lib.baseboard_fab2(sch_1):m_l_dq(8)") )
				( member ( signalRef "@baseboard_fab2_lib.baseboard_fab2(sch_1):m_l_dq(9)") )
				( member ( signalRef "@baseboard_fab2_lib.baseboard_fab2(sch_1):m_l_dq(10)") )
				( member ( signalRef "@baseboard_fab2_lib.baseboard_fab2(sch_1):m_l_dq(11)") )
				( member ( signalRef "@baseboard_fab2_lib.baseboard_fab2(sch_1):m_l_dq(12)") )
				( member ( signalRef "@baseboard_fab2_lib.baseboard_fab2(sch_1):m_l_dq(13)") )
				( member ( signalRef "@baseboard_fab2_lib.baseboard_fab2(sch_1):m_l_dq(14)") )
				( member ( signalRef "@baseboard_fab2_lib.baseboard_fab2(sch_1):m_l_dq(15)") )
				( member ( signalRef "@baseboard_fab2_lib.baseboard_fab2(sch_1):m_l_dq(16)") )
				( member ( signalRef "@baseboard_fab2_lib.baseboard_fab2(sch_1):m_l_dq(17)") )
				( member ( signalRef "@baseboard_fab2_lib.baseboard_fab2(sch_1):m_l_dq(18)") )
				( member ( signalRef "@baseboard_fab2_lib.baseboard_fab2(sch_1):m_l_dq(19)") )
				( member ( signalRef "@baseboard_fab2_lib.baseboard_fab2(sch_1):m_l_dq(20)") )
				( member ( signalRef "@baseboard_fab2_lib.baseboard_fab2(sch_1):m_l_dq(21)") )
				( member ( signalRef "@baseboard_fab2_lib.baseboard_fab2(sch_1):m_l_dq(22)") )
				( member ( signalRef "@baseboard_fab2_lib.baseboard_fab2(sch_1):m_l_dq(23)") )
				( member ( signalRef "@baseboard_fab2_lib.baseboard_fab2(sch_1):m_l_dq(24)") )
				( member ( signalRef "@baseboard_fab2_lib.baseboard_fab2(sch_1):m_l_dq(25)") )
				( member ( signalRef "@baseboard_fab2_lib.baseboard_fab2(sch_1):m_l_dq(26)") )
				( member ( signalRef "@baseboard_fab2_lib.baseboard_fab2(sch_1):m_l_dq(27)") )
				( member ( signalRef "@baseboard_fab2_lib.baseboard_fab2(sch_1):m_l_dq(28)") )
				( member ( signalRef "@baseboard_fab2_lib.baseboard_fab2(sch_1):m_l_dq(29)") )
				( member ( signalRef "@baseboard_fab2_lib.baseboard_fab2(sch_1):m_l_dq(30)") )
				( member ( signalRef "@baseboard_fab2_lib.baseboard_fab2(sch_1):m_l_dq(31)") )
				( member ( signalRef "@baseboard_fab2_lib.baseboard_fab2(sch_1):m_l_dq(32)") )
				( member ( signalRef "@baseboard_fab2_lib.baseboard_fab2(sch_1):m_l_dq(33)") )
				( member ( signalRef "@baseboard_fab2_lib.baseboard_fab2(sch_1):m_l_dq(34)") )
				( member ( signalRef "@baseboard_fab2_lib.baseboard_fab2(sch_1):m_l_dq(35)") )
				( member ( signalRef "@baseboard_fab2_lib.baseboard_fab2(sch_1):m_l_dq(36)") )
				( member ( signalRef "@baseboard_fab2_lib.baseboard_fab2(sch_1):m_l_dq(37)") )
				( member ( signalRef "@baseboard_fab2_lib.baseboard_fab2(sch_1):m_l_dq(38)") )
				( member ( signalRef "@baseboard_fab2_lib.baseboard_fab2(sch_1):m_l_dq(39)") )
				( member ( signalRef "@baseboard_fab2_lib.baseboard_fab2(sch_1):m_l_dq(40)") )
				( member ( signalRef "@baseboard_fab2_lib.baseboard_fab2(sch_1):m_l_dq(41)") )
				( member ( signalRef "@baseboard_fab2_lib.baseboard_fab2(sch_1):m_l_dq(42)") )
				( member ( signalRef "@baseboard_fab2_lib.baseboard_fab2(sch_1):m_l_dq(43)") )
				( member ( signalRef "@baseboard_fab2_lib.baseboard_fab2(sch_1):m_l_dq(44)") )
				( member ( signalRef "@baseboard_fab2_lib.baseboard_fab2(sch_1):m_l_dq(45)") )
				( member ( signalRef "@baseboard_fab2_lib.baseboard_fab2(sch_1):m_l_dq(46)") )
				( member ( signalRef "@baseboard_fab2_lib.baseboard_fab2(sch_1):m_l_dq(47)") )
				( member ( signalRef "@baseboard_fab2_lib.baseboard_fab2(sch_1):m_l_dq(48)") )
				( member ( signalRef "@baseboard_fab2_lib.baseboard_fab2(sch_1):m_l_dq(49)") )
				( member ( signalRef "@baseboard_fab2_lib.baseboard_fab2(sch_1):m_l_dq(50)") )
				( member ( signalRef "@baseboard_fab2_lib.baseboard_fab2(sch_1):m_l_dq(51)") )
				( member ( signalRef "@baseboard_fab2_lib.baseboard_fab2(sch_1):m_l_dq(52)") )
				( member ( signalRef "@baseboard_fab2_lib.baseboard_fab2(sch_1):m_l_dq(53)") )
				( member ( signalRef "@baseboard_fab2_lib.baseboard_fab2(sch_1):m_l_dq(54)") )
				( member ( signalRef "@baseboard_fab2_lib.baseboard_fab2(sch_1):m_l_dq(55)") )
				( member ( signalRef "@baseboard_fab2_lib.baseboard_fab2(sch_1):m_l_dq(56)") )
				( member ( signalRef "@baseboard_fab2_lib.baseboard_fab2(sch_1):m_l_dq(57)") )
				( member ( signalRef "@baseboard_fab2_lib.baseboard_fab2(sch_1):m_l_dq(58)") )
				( member ( signalRef "@baseboard_fab2_lib.baseboard_fab2(sch_1):m_l_dq(59)") )
				( member ( signalRef "@baseboard_fab2_lib.baseboard_fab2(sch_1):m_l_dq(60)") )
				( member ( signalRef "@baseboard_fab2_lib.baseboard_fab2(sch_1):m_l_dq(61)") )
				( member ( signalRef "@baseboard_fab2_lib.baseboard_fab2(sch_1):m_l_dq(62)") )
				( member ( signalRef "@baseboard_fab2_lib.baseboard_fab2(sch_1):m_l_dq(63)") )
				( objectStatus "M_L_DQ" )
			)
			( bus "@crescent_city_bb_fab1_lib.crescent_city_bb_fab1(sch_1):m_l_cs_n"
				( memberType ( signal ) )
				( member ( signalRef "@baseboard_fab2_lib.baseboard_fab2(sch_1):m_l_cs_n(0)") )
				( member ( signalRef "@baseboard_fab2_lib.baseboard_fab2(sch_1):m_l_cs_n(1)") )
				( member ( signalRef "@baseboard_fab2_lib.baseboard_fab2(sch_1):m_l_cs_n(2)") )
				( member ( signalRef "@baseboard_fab2_lib.baseboard_fab2(sch_1):m_l_cs_n(3)") )
				( member ( signalRef "@baseboard_fab2_lib.baseboard_fab2(sch_1):m_l_cs_n(6)") )
				( member ( signalRef "@baseboard_fab2_lib.baseboard_fab2(sch_1):m_l_cs_n(7)") )
				( member ( signalRef "@baseboard_fab2_lib.baseboard_fab2(sch_1):m_l_cs_n(4)") )
				( member ( signalRef "@baseboard_fab2_lib.baseboard_fab2(sch_1):m_l_cs_n(5)") )
				( objectStatus "M_L_CS_N" )
			)
			( bus "@crescent_city_bb_fab1_lib.crescent_city_bb_fab1(sch_1):m_l_clk_dp"
				( memberType ( signal ) )
				( member ( signalRef "@baseboard_fab2_lib.baseboard_fab2(sch_1):m_l_clk_dp(0)") )
				( member ( signalRef "@baseboard_fab2_lib.baseboard_fab2(sch_1):m_l_clk_dp(1)") )
				( member ( signalRef "@baseboard_fab2_lib.baseboard_fab2(sch_1):m_l_clk_dp(2)") )
				( member ( signalRef "@baseboard_fab2_lib.baseboard_fab2(sch_1):m_l_clk_dp(3)") )
				( objectStatus "M_L_CLK_DP" )
			)
			( bus "@crescent_city_bb_fab1_lib.crescent_city_bb_fab1(sch_1):m_l_clk_dn"
				( memberType ( signal ) )
				( member ( signalRef "@baseboard_fab2_lib.baseboard_fab2(sch_1):m_l_clk_dn(0)") )
				( member ( signalRef "@baseboard_fab2_lib.baseboard_fab2(sch_1):m_l_clk_dn(1)") )
				( member ( signalRef "@baseboard_fab2_lib.baseboard_fab2(sch_1):m_l_clk_dn(2)") )
				( member ( signalRef "@baseboard_fab2_lib.baseboard_fab2(sch_1):m_l_clk_dn(3)") )
				( objectStatus "M_L_CLK_DN" )
			)
			( bus "@crescent_city_bb_fab1_lib.crescent_city_bb_fab1(sch_1):m_l_cke"
				( memberType ( signal ) )
				( member ( signalRef "@baseboard_fab2_lib.baseboard_fab2(sch_1):m_l_cke(0)") )
				( member ( signalRef "@baseboard_fab2_lib.baseboard_fab2(sch_1):m_l_cke(1)") )
				( member ( signalRef "@baseboard_fab2_lib.baseboard_fab2(sch_1):m_l_cke(2)") )
				( member ( signalRef "@baseboard_fab2_lib.baseboard_fab2(sch_1):m_l_cke(3)") )
				( objectStatus "M_L_CKE" )
			)
			( bus "@crescent_city_bb_fab1_lib.crescent_city_bb_fab1(sch_1):m_l_c"
				( memberType ( signal ) )
				( member ( signalRef "@baseboard_fab2_lib.baseboard_fab2(sch_1):m_l_c(2)") )
				( objectStatus "M_L_C" )
			)
			( bus "@crescent_city_bb_fab1_lib.crescent_city_bb_fab1(sch_1):m_l_bg"
				( memberType ( signal ) )
				( member ( signalRef "@baseboard_fab2_lib.baseboard_fab2(sch_1):m_l_bg(0)") )
				( member ( signalRef "@baseboard_fab2_lib.baseboard_fab2(sch_1):m_l_bg(1)") )
				( objectStatus "M_L_BG" )
			)
			( bus "@crescent_city_bb_fab1_lib.crescent_city_bb_fab1(sch_1):m_l_ba"
				( memberType ( signal ) )
				( member ( signalRef "@baseboard_fab2_lib.baseboard_fab2(sch_1):m_l_ba(0)") )
				( member ( signalRef "@baseboard_fab2_lib.baseboard_fab2(sch_1):m_l_ba(1)") )
				( objectStatus "M_L_BA" )
			)
			( bus "@crescent_city_bb_fab1_lib.crescent_city_bb_fab1(sch_1):m_k_odt"
				( memberType ( signal ) )
				( member ( signalRef "@baseboard_fab2_lib.baseboard_fab2(sch_1):m_k_odt(0)") )
				( member ( signalRef "@baseboard_fab2_lib.baseboard_fab2(sch_1):m_k_odt(1)") )
				( member ( signalRef "@baseboard_fab2_lib.baseboard_fab2(sch_1):m_k_odt(2)") )
				( member ( signalRef "@baseboard_fab2_lib.baseboard_fab2(sch_1):m_k_odt(3)") )
				( objectStatus "M_K_ODT" )
			)
			( bus "@crescent_city_bb_fab1_lib.crescent_city_bb_fab1(sch_1):m_k_ma"
				( memberType ( signal ) )
				( member ( signalRef "@baseboard_fab2_lib.baseboard_fab2(sch_1):m_k_ma(0)") )
				( member ( signalRef "@baseboard_fab2_lib.baseboard_fab2(sch_1):m_k_ma(1)") )
				( member ( signalRef "@baseboard_fab2_lib.baseboard_fab2(sch_1):m_k_ma(2)") )
				( member ( signalRef "@baseboard_fab2_lib.baseboard_fab2(sch_1):m_k_ma(3)") )
				( member ( signalRef "@baseboard_fab2_lib.baseboard_fab2(sch_1):m_k_ma(4)") )
				( member ( signalRef "@baseboard_fab2_lib.baseboard_fab2(sch_1):m_k_ma(5)") )
				( member ( signalRef "@baseboard_fab2_lib.baseboard_fab2(sch_1):m_k_ma(6)") )
				( member ( signalRef "@baseboard_fab2_lib.baseboard_fab2(sch_1):m_k_ma(7)") )
				( member ( signalRef "@baseboard_fab2_lib.baseboard_fab2(sch_1):m_k_ma(8)") )
				( member ( signalRef "@baseboard_fab2_lib.baseboard_fab2(sch_1):m_k_ma(9)") )
				( member ( signalRef "@baseboard_fab2_lib.baseboard_fab2(sch_1):m_k_ma(10)") )
				( member ( signalRef "@baseboard_fab2_lib.baseboard_fab2(sch_1):m_k_ma(11)") )
				( member ( signalRef "@baseboard_fab2_lib.baseboard_fab2(sch_1):m_k_ma(12)") )
				( member ( signalRef "@baseboard_fab2_lib.baseboard_fab2(sch_1):m_k_ma(13)") )
				( member ( signalRef "@baseboard_fab2_lib.baseboard_fab2(sch_1):m_k_ma(14)") )
				( member ( signalRef "@baseboard_fab2_lib.baseboard_fab2(sch_1):m_k_ma(15)") )
				( member ( signalRef "@baseboard_fab2_lib.baseboard_fab2(sch_1):m_k_ma(16)") )
				( member ( signalRef "@baseboard_fab2_lib.baseboard_fab2(sch_1):m_k_ma(17)") )
				( objectStatus "M_K_MA" )
			)
			( bus "@crescent_city_bb_fab1_lib.crescent_city_bb_fab1(sch_1):m_k_ecc"
				( memberType ( signal ) )
				( member ( signalRef "@baseboard_fab2_lib.baseboard_fab2(sch_1):m_k_ecc(0)") )
				( member ( signalRef "@baseboard_fab2_lib.baseboard_fab2(sch_1):m_k_ecc(1)") )
				( member ( signalRef "@baseboard_fab2_lib.baseboard_fab2(sch_1):m_k_ecc(2)") )
				( member ( signalRef "@baseboard_fab2_lib.baseboard_fab2(sch_1):m_k_ecc(3)") )
				( member ( signalRef "@baseboard_fab2_lib.baseboard_fab2(sch_1):m_k_ecc(4)") )
				( member ( signalRef "@baseboard_fab2_lib.baseboard_fab2(sch_1):m_k_ecc(5)") )
				( member ( signalRef "@baseboard_fab2_lib.baseboard_fab2(sch_1):m_k_ecc(6)") )
				( member ( signalRef "@baseboard_fab2_lib.baseboard_fab2(sch_1):m_k_ecc(7)") )
				( objectStatus "M_K_ECC" )
			)
			( bus "@crescent_city_bb_fab1_lib.crescent_city_bb_fab1(sch_1):m_k_dqs_dp"
				( memberType ( signal ) )
				( member ( signalRef "@baseboard_fab2_lib.baseboard_fab2(sch_1):m_k_dqs_dp(0)") )
				( member ( signalRef "@baseboard_fab2_lib.baseboard_fab2(sch_1):m_k_dqs_dp(1)") )
				( member ( signalRef "@baseboard_fab2_lib.baseboard_fab2(sch_1):m_k_dqs_dp(2)") )
				( member ( signalRef "@baseboard_fab2_lib.baseboard_fab2(sch_1):m_k_dqs_dp(3)") )
				( member ( signalRef "@baseboard_fab2_lib.baseboard_fab2(sch_1):m_k_dqs_dp(4)") )
				( member ( signalRef "@baseboard_fab2_lib.baseboard_fab2(sch_1):m_k_dqs_dp(5)") )
				( member ( signalRef "@baseboard_fab2_lib.baseboard_fab2(sch_1):m_k_dqs_dp(6)") )
				( member ( signalRef "@baseboard_fab2_lib.baseboard_fab2(sch_1):m_k_dqs_dp(7)") )
				( member ( signalRef "@baseboard_fab2_lib.baseboard_fab2(sch_1):m_k_dqs_dp(8)") )
				( member ( signalRef "@baseboard_fab2_lib.baseboard_fab2(sch_1):m_k_dqs_dp(9)") )
				( member ( signalRef "@baseboard_fab2_lib.baseboard_fab2(sch_1):m_k_dqs_dp(10)") )
				( member ( signalRef "@baseboard_fab2_lib.baseboard_fab2(sch_1):m_k_dqs_dp(11)") )
				( member ( signalRef "@baseboard_fab2_lib.baseboard_fab2(sch_1):m_k_dqs_dp(12)") )
				( member ( signalRef "@baseboard_fab2_lib.baseboard_fab2(sch_1):m_k_dqs_dp(13)") )
				( member ( signalRef "@baseboard_fab2_lib.baseboard_fab2(sch_1):m_k_dqs_dp(14)") )
				( member ( signalRef "@baseboard_fab2_lib.baseboard_fab2(sch_1):m_k_dqs_dp(15)") )
				( member ( signalRef "@baseboard_fab2_lib.baseboard_fab2(sch_1):m_k_dqs_dp(16)") )
				( member ( signalRef "@baseboard_fab2_lib.baseboard_fab2(sch_1):m_k_dqs_dp(17)") )
				( objectStatus "M_K_DQS_DP" )
			)
			( bus "@crescent_city_bb_fab1_lib.crescent_city_bb_fab1(sch_1):m_k_dqs_dn"
				( memberType ( signal ) )
				( member ( signalRef "@baseboard_fab2_lib.baseboard_fab2(sch_1):m_k_dqs_dn(0)") )
				( member ( signalRef "@baseboard_fab2_lib.baseboard_fab2(sch_1):m_k_dqs_dn(1)") )
				( member ( signalRef "@baseboard_fab2_lib.baseboard_fab2(sch_1):m_k_dqs_dn(2)") )
				( member ( signalRef "@baseboard_fab2_lib.baseboard_fab2(sch_1):m_k_dqs_dn(3)") )
				( member ( signalRef "@baseboard_fab2_lib.baseboard_fab2(sch_1):m_k_dqs_dn(4)") )
				( member ( signalRef "@baseboard_fab2_lib.baseboard_fab2(sch_1):m_k_dqs_dn(5)") )
				( member ( signalRef "@baseboard_fab2_lib.baseboard_fab2(sch_1):m_k_dqs_dn(6)") )
				( member ( signalRef "@baseboard_fab2_lib.baseboard_fab2(sch_1):m_k_dqs_dn(7)") )
				( member ( signalRef "@baseboard_fab2_lib.baseboard_fab2(sch_1):m_k_dqs_dn(8)") )
				( member ( signalRef "@baseboard_fab2_lib.baseboard_fab2(sch_1):m_k_dqs_dn(9)") )
				( member ( signalRef "@baseboard_fab2_lib.baseboard_fab2(sch_1):m_k_dqs_dn(10)") )
				( member ( signalRef "@baseboard_fab2_lib.baseboard_fab2(sch_1):m_k_dqs_dn(11)") )
				( member ( signalRef "@baseboard_fab2_lib.baseboard_fab2(sch_1):m_k_dqs_dn(12)") )
				( member ( signalRef "@baseboard_fab2_lib.baseboard_fab2(sch_1):m_k_dqs_dn(13)") )
				( member ( signalRef "@baseboard_fab2_lib.baseboard_fab2(sch_1):m_k_dqs_dn(14)") )
				( member ( signalRef "@baseboard_fab2_lib.baseboard_fab2(sch_1):m_k_dqs_dn(15)") )
				( member ( signalRef "@baseboard_fab2_lib.baseboard_fab2(sch_1):m_k_dqs_dn(16)") )
				( member ( signalRef "@baseboard_fab2_lib.baseboard_fab2(sch_1):m_k_dqs_dn(17)") )
				( objectStatus "M_K_DQS_DN" )
			)
			( bus "@crescent_city_bb_fab1_lib.crescent_city_bb_fab1(sch_1):m_k_dq"
				( memberType ( signal ) )
				( member ( signalRef "@baseboard_fab2_lib.baseboard_fab2(sch_1):m_k_dq(0)") )
				( member ( signalRef "@baseboard_fab2_lib.baseboard_fab2(sch_1):m_k_dq(1)") )
				( member ( signalRef "@baseboard_fab2_lib.baseboard_fab2(sch_1):m_k_dq(2)") )
				( member ( signalRef "@baseboard_fab2_lib.baseboard_fab2(sch_1):m_k_dq(3)") )
				( member ( signalRef "@baseboard_fab2_lib.baseboard_fab2(sch_1):m_k_dq(4)") )
				( member ( signalRef "@baseboard_fab2_lib.baseboard_fab2(sch_1):m_k_dq(5)") )
				( member ( signalRef "@baseboard_fab2_lib.baseboard_fab2(sch_1):m_k_dq(6)") )
				( member ( signalRef "@baseboard_fab2_lib.baseboard_fab2(sch_1):m_k_dq(7)") )
				( member ( signalRef "@baseboard_fab2_lib.baseboard_fab2(sch_1):m_k_dq(8)") )
				( member ( signalRef "@baseboard_fab2_lib.baseboard_fab2(sch_1):m_k_dq(9)") )
				( member ( signalRef "@baseboard_fab2_lib.baseboard_fab2(sch_1):m_k_dq(10)") )
				( member ( signalRef "@baseboard_fab2_lib.baseboard_fab2(sch_1):m_k_dq(11)") )
				( member ( signalRef "@baseboard_fab2_lib.baseboard_fab2(sch_1):m_k_dq(12)") )
				( member ( signalRef "@baseboard_fab2_lib.baseboard_fab2(sch_1):m_k_dq(13)") )
				( member ( signalRef "@baseboard_fab2_lib.baseboard_fab2(sch_1):m_k_dq(14)") )
				( member ( signalRef "@baseboard_fab2_lib.baseboard_fab2(sch_1):m_k_dq(15)") )
				( member ( signalRef "@baseboard_fab2_lib.baseboard_fab2(sch_1):m_k_dq(16)") )
				( member ( signalRef "@baseboard_fab2_lib.baseboard_fab2(sch_1):m_k_dq(17)") )
				( member ( signalRef "@baseboard_fab2_lib.baseboard_fab2(sch_1):m_k_dq(18)") )
				( member ( signalRef "@baseboard_fab2_lib.baseboard_fab2(sch_1):m_k_dq(19)") )
				( member ( signalRef "@baseboard_fab2_lib.baseboard_fab2(sch_1):m_k_dq(20)") )
				( member ( signalRef "@baseboard_fab2_lib.baseboard_fab2(sch_1):m_k_dq(21)") )
				( member ( signalRef "@baseboard_fab2_lib.baseboard_fab2(sch_1):m_k_dq(22)") )
				( member ( signalRef "@baseboard_fab2_lib.baseboard_fab2(sch_1):m_k_dq(23)") )
				( member ( signalRef "@baseboard_fab2_lib.baseboard_fab2(sch_1):m_k_dq(24)") )
				( member ( signalRef "@baseboard_fab2_lib.baseboard_fab2(sch_1):m_k_dq(25)") )
				( member ( signalRef "@baseboard_fab2_lib.baseboard_fab2(sch_1):m_k_dq(26)") )
				( member ( signalRef "@baseboard_fab2_lib.baseboard_fab2(sch_1):m_k_dq(27)") )
				( member ( signalRef "@baseboard_fab2_lib.baseboard_fab2(sch_1):m_k_dq(28)") )
				( member ( signalRef "@baseboard_fab2_lib.baseboard_fab2(sch_1):m_k_dq(29)") )
				( member ( signalRef "@baseboard_fab2_lib.baseboard_fab2(sch_1):m_k_dq(30)") )
				( member ( signalRef "@baseboard_fab2_lib.baseboard_fab2(sch_1):m_k_dq(31)") )
				( member ( signalRef "@baseboard_fab2_lib.baseboard_fab2(sch_1):m_k_dq(32)") )
				( member ( signalRef "@baseboard_fab2_lib.baseboard_fab2(sch_1):m_k_dq(33)") )
				( member ( signalRef "@baseboard_fab2_lib.baseboard_fab2(sch_1):m_k_dq(34)") )
				( member ( signalRef "@baseboard_fab2_lib.baseboard_fab2(sch_1):m_k_dq(35)") )
				( member ( signalRef "@baseboard_fab2_lib.baseboard_fab2(sch_1):m_k_dq(36)") )
				( member ( signalRef "@baseboard_fab2_lib.baseboard_fab2(sch_1):m_k_dq(37)") )
				( member ( signalRef "@baseboard_fab2_lib.baseboard_fab2(sch_1):m_k_dq(38)") )
				( member ( signalRef "@baseboard_fab2_lib.baseboard_fab2(sch_1):m_k_dq(39)") )
				( member ( signalRef "@baseboard_fab2_lib.baseboard_fab2(sch_1):m_k_dq(40)") )
				( member ( signalRef "@baseboard_fab2_lib.baseboard_fab2(sch_1):m_k_dq(41)") )
				( member ( signalRef "@baseboard_fab2_lib.baseboard_fab2(sch_1):m_k_dq(42)") )
				( member ( signalRef "@baseboard_fab2_lib.baseboard_fab2(sch_1):m_k_dq(43)") )
				( member ( signalRef "@baseboard_fab2_lib.baseboard_fab2(sch_1):m_k_dq(44)") )
				( member ( signalRef "@baseboard_fab2_lib.baseboard_fab2(sch_1):m_k_dq(45)") )
				( member ( signalRef "@baseboard_fab2_lib.baseboard_fab2(sch_1):m_k_dq(46)") )
				( member ( signalRef "@baseboard_fab2_lib.baseboard_fab2(sch_1):m_k_dq(47)") )
				( member ( signalRef "@baseboard_fab2_lib.baseboard_fab2(sch_1):m_k_dq(48)") )
				( member ( signalRef "@baseboard_fab2_lib.baseboard_fab2(sch_1):m_k_dq(49)") )
				( member ( signalRef "@baseboard_fab2_lib.baseboard_fab2(sch_1):m_k_dq(50)") )
				( member ( signalRef "@baseboard_fab2_lib.baseboard_fab2(sch_1):m_k_dq(51)") )
				( member ( signalRef "@baseboard_fab2_lib.baseboard_fab2(sch_1):m_k_dq(52)") )
				( member ( signalRef "@baseboard_fab2_lib.baseboard_fab2(sch_1):m_k_dq(53)") )
				( member ( signalRef "@baseboard_fab2_lib.baseboard_fab2(sch_1):m_k_dq(54)") )
				( member ( signalRef "@baseboard_fab2_lib.baseboard_fab2(sch_1):m_k_dq(55)") )
				( member ( signalRef "@baseboard_fab2_lib.baseboard_fab2(sch_1):m_k_dq(56)") )
				( member ( signalRef "@baseboard_fab2_lib.baseboard_fab2(sch_1):m_k_dq(57)") )
				( member ( signalRef "@baseboard_fab2_lib.baseboard_fab2(sch_1):m_k_dq(58)") )
				( member ( signalRef "@baseboard_fab2_lib.baseboard_fab2(sch_1):m_k_dq(59)") )
				( member ( signalRef "@baseboard_fab2_lib.baseboard_fab2(sch_1):m_k_dq(60)") )
				( member ( signalRef "@baseboard_fab2_lib.baseboard_fab2(sch_1):m_k_dq(61)") )
				( member ( signalRef "@baseboard_fab2_lib.baseboard_fab2(sch_1):m_k_dq(62)") )
				( member ( signalRef "@baseboard_fab2_lib.baseboard_fab2(sch_1):m_k_dq(63)") )
				( objectStatus "M_K_DQ" )
			)
			( bus "@crescent_city_bb_fab1_lib.crescent_city_bb_fab1(sch_1):m_k_cs_n"
				( memberType ( signal ) )
				( member ( signalRef "@baseboard_fab2_lib.baseboard_fab2(sch_1):m_k_cs_n(0)") )
				( member ( signalRef "@baseboard_fab2_lib.baseboard_fab2(sch_1):m_k_cs_n(1)") )
				( member ( signalRef "@baseboard_fab2_lib.baseboard_fab2(sch_1):m_k_cs_n(2)") )
				( member ( signalRef "@baseboard_fab2_lib.baseboard_fab2(sch_1):m_k_cs_n(3)") )
				( member ( signalRef "@baseboard_fab2_lib.baseboard_fab2(sch_1):m_k_cs_n(4)") )
				( member ( signalRef "@baseboard_fab2_lib.baseboard_fab2(sch_1):m_k_cs_n(5)") )
				( member ( signalRef "@baseboard_fab2_lib.baseboard_fab2(sch_1):m_k_cs_n(6)") )
				( member ( signalRef "@baseboard_fab2_lib.baseboard_fab2(sch_1):m_k_cs_n(7)") )
				( objectStatus "M_K_CS_N" )
			)
			( bus "@crescent_city_bb_fab1_lib.crescent_city_bb_fab1(sch_1):m_k_clk_dp"
				( memberType ( signal ) )
				( member ( signalRef "@baseboard_fab2_lib.baseboard_fab2(sch_1):m_k_clk_dp(0)") )
				( member ( signalRef "@baseboard_fab2_lib.baseboard_fab2(sch_1):m_k_clk_dp(2)") )
				( member ( signalRef "@baseboard_fab2_lib.baseboard_fab2(sch_1):m_k_clk_dp(1)") )
				( member ( signalRef "@baseboard_fab2_lib.baseboard_fab2(sch_1):m_k_clk_dp(3)") )
				( objectStatus "M_K_CLK_DP" )
			)
			( bus "@crescent_city_bb_fab1_lib.crescent_city_bb_fab1(sch_1):m_k_clk_dn"
				( memberType ( signal ) )
				( member ( signalRef "@baseboard_fab2_lib.baseboard_fab2(sch_1):m_k_clk_dn(0)") )
				( member ( signalRef "@baseboard_fab2_lib.baseboard_fab2(sch_1):m_k_clk_dn(2)") )
				( member ( signalRef "@baseboard_fab2_lib.baseboard_fab2(sch_1):m_k_clk_dn(1)") )
				( member ( signalRef "@baseboard_fab2_lib.baseboard_fab2(sch_1):m_k_clk_dn(3)") )
				( objectStatus "M_K_CLK_DN" )
			)
			( bus "@crescent_city_bb_fab1_lib.crescent_city_bb_fab1(sch_1):m_k_cke"
				( memberType ( signal ) )
				( member ( signalRef "@baseboard_fab2_lib.baseboard_fab2(sch_1):m_k_cke(0)") )
				( member ( signalRef "@baseboard_fab2_lib.baseboard_fab2(sch_1):m_k_cke(1)") )
				( member ( signalRef "@baseboard_fab2_lib.baseboard_fab2(sch_1):m_k_cke(2)") )
				( member ( signalRef "@baseboard_fab2_lib.baseboard_fab2(sch_1):m_k_cke(3)") )
				( objectStatus "M_K_CKE" )
			)
			( bus "@crescent_city_bb_fab1_lib.crescent_city_bb_fab1(sch_1):m_k_c"
				( memberType ( signal ) )
				( member ( signalRef "@baseboard_fab2_lib.baseboard_fab2(sch_1):m_k_c(2)") )
				( objectStatus "M_K_C" )
			)
			( bus "@crescent_city_bb_fab1_lib.crescent_city_bb_fab1(sch_1):m_k_bg"
				( memberType ( signal ) )
				( member ( signalRef "@baseboard_fab2_lib.baseboard_fab2(sch_1):m_k_bg(0)") )
				( member ( signalRef "@baseboard_fab2_lib.baseboard_fab2(sch_1):m_k_bg(1)") )
				( objectStatus "M_K_BG" )
			)
			( bus "@crescent_city_bb_fab1_lib.crescent_city_bb_fab1(sch_1):m_k_ba"
				( memberType ( signal ) )
				( member ( signalRef "@baseboard_fab2_lib.baseboard_fab2(sch_1):m_k_ba(0)") )
				( member ( signalRef "@baseboard_fab2_lib.baseboard_fab2(sch_1):m_k_ba(1)") )
				( objectStatus "M_K_BA" )
			)
			( bus "@crescent_city_bb_fab1_lib.crescent_city_bb_fab1(sch_1):m_j_odt"
				( memberType ( signal ) )
				( member ( signalRef "@baseboard_fab2_lib.baseboard_fab2(sch_1):m_j_odt(0)") )
				( member ( signalRef "@baseboard_fab2_lib.baseboard_fab2(sch_1):m_j_odt(1)") )
				( member ( signalRef "@baseboard_fab2_lib.baseboard_fab2(sch_1):m_j_odt(2)") )
				( member ( signalRef "@baseboard_fab2_lib.baseboard_fab2(sch_1):m_j_odt(3)") )
				( objectStatus "M_J_ODT" )
			)
			( bus "@crescent_city_bb_fab1_lib.crescent_city_bb_fab1(sch_1):m_j_ma"
				( memberType ( signal ) )
				( member ( signalRef "@baseboard_fab2_lib.baseboard_fab2(sch_1):m_j_ma(0)") )
				( member ( signalRef "@baseboard_fab2_lib.baseboard_fab2(sch_1):m_j_ma(1)") )
				( member ( signalRef "@baseboard_fab2_lib.baseboard_fab2(sch_1):m_j_ma(2)") )
				( member ( signalRef "@baseboard_fab2_lib.baseboard_fab2(sch_1):m_j_ma(3)") )
				( member ( signalRef "@baseboard_fab2_lib.baseboard_fab2(sch_1):m_j_ma(4)") )
				( member ( signalRef "@baseboard_fab2_lib.baseboard_fab2(sch_1):m_j_ma(5)") )
				( member ( signalRef "@baseboard_fab2_lib.baseboard_fab2(sch_1):m_j_ma(6)") )
				( member ( signalRef "@baseboard_fab2_lib.baseboard_fab2(sch_1):m_j_ma(7)") )
				( member ( signalRef "@baseboard_fab2_lib.baseboard_fab2(sch_1):m_j_ma(8)") )
				( member ( signalRef "@baseboard_fab2_lib.baseboard_fab2(sch_1):m_j_ma(9)") )
				( member ( signalRef "@baseboard_fab2_lib.baseboard_fab2(sch_1):m_j_ma(10)") )
				( member ( signalRef "@baseboard_fab2_lib.baseboard_fab2(sch_1):m_j_ma(11)") )
				( member ( signalRef "@baseboard_fab2_lib.baseboard_fab2(sch_1):m_j_ma(12)") )
				( member ( signalRef "@baseboard_fab2_lib.baseboard_fab2(sch_1):m_j_ma(13)") )
				( member ( signalRef "@baseboard_fab2_lib.baseboard_fab2(sch_1):m_j_ma(14)") )
				( member ( signalRef "@baseboard_fab2_lib.baseboard_fab2(sch_1):m_j_ma(15)") )
				( member ( signalRef "@baseboard_fab2_lib.baseboard_fab2(sch_1):m_j_ma(16)") )
				( member ( signalRef "@baseboard_fab2_lib.baseboard_fab2(sch_1):m_j_ma(17)") )
				( objectStatus "M_J_MA" )
			)
			( bus "@crescent_city_bb_fab1_lib.crescent_city_bb_fab1(sch_1):m_j_ecc"
				( memberType ( signal ) )
				( member ( signalRef "@baseboard_fab2_lib.baseboard_fab2(sch_1):m_j_ecc(0)") )
				( member ( signalRef "@baseboard_fab2_lib.baseboard_fab2(sch_1):m_j_ecc(1)") )
				( member ( signalRef "@baseboard_fab2_lib.baseboard_fab2(sch_1):m_j_ecc(2)") )
				( member ( signalRef "@baseboard_fab2_lib.baseboard_fab2(sch_1):m_j_ecc(3)") )
				( member ( signalRef "@baseboard_fab2_lib.baseboard_fab2(sch_1):m_j_ecc(4)") )
				( member ( signalRef "@baseboard_fab2_lib.baseboard_fab2(sch_1):m_j_ecc(5)") )
				( member ( signalRef "@baseboard_fab2_lib.baseboard_fab2(sch_1):m_j_ecc(6)") )
				( member ( signalRef "@baseboard_fab2_lib.baseboard_fab2(sch_1):m_j_ecc(7)") )
				( objectStatus "M_J_ECC" )
			)
			( bus "@crescent_city_bb_fab1_lib.crescent_city_bb_fab1(sch_1):m_j_dqs_dp"
				( memberType ( signal ) )
				( member ( signalRef "@baseboard_fab2_lib.baseboard_fab2(sch_1):m_j_dqs_dp(0)") )
				( member ( signalRef "@baseboard_fab2_lib.baseboard_fab2(sch_1):m_j_dqs_dp(1)") )
				( member ( signalRef "@baseboard_fab2_lib.baseboard_fab2(sch_1):m_j_dqs_dp(2)") )
				( member ( signalRef "@baseboard_fab2_lib.baseboard_fab2(sch_1):m_j_dqs_dp(3)") )
				( member ( signalRef "@baseboard_fab2_lib.baseboard_fab2(sch_1):m_j_dqs_dp(4)") )
				( member ( signalRef "@baseboard_fab2_lib.baseboard_fab2(sch_1):m_j_dqs_dp(5)") )
				( member ( signalRef "@baseboard_fab2_lib.baseboard_fab2(sch_1):m_j_dqs_dp(6)") )
				( member ( signalRef "@baseboard_fab2_lib.baseboard_fab2(sch_1):m_j_dqs_dp(7)") )
				( member ( signalRef "@baseboard_fab2_lib.baseboard_fab2(sch_1):m_j_dqs_dp(8)") )
				( member ( signalRef "@baseboard_fab2_lib.baseboard_fab2(sch_1):m_j_dqs_dp(9)") )
				( member ( signalRef "@baseboard_fab2_lib.baseboard_fab2(sch_1):m_j_dqs_dp(10)") )
				( member ( signalRef "@baseboard_fab2_lib.baseboard_fab2(sch_1):m_j_dqs_dp(11)") )
				( member ( signalRef "@baseboard_fab2_lib.baseboard_fab2(sch_1):m_j_dqs_dp(12)") )
				( member ( signalRef "@baseboard_fab2_lib.baseboard_fab2(sch_1):m_j_dqs_dp(13)") )
				( member ( signalRef "@baseboard_fab2_lib.baseboard_fab2(sch_1):m_j_dqs_dp(14)") )
				( member ( signalRef "@baseboard_fab2_lib.baseboard_fab2(sch_1):m_j_dqs_dp(15)") )
				( member ( signalRef "@baseboard_fab2_lib.baseboard_fab2(sch_1):m_j_dqs_dp(16)") )
				( member ( signalRef "@baseboard_fab2_lib.baseboard_fab2(sch_1):m_j_dqs_dp(17)") )
				( objectStatus "M_J_DQS_DP" )
			)
			( bus "@crescent_city_bb_fab1_lib.crescent_city_bb_fab1(sch_1):m_j_dqs_dn"
				( memberType ( signal ) )
				( member ( signalRef "@baseboard_fab2_lib.baseboard_fab2(sch_1):m_j_dqs_dn(0)") )
				( member ( signalRef "@baseboard_fab2_lib.baseboard_fab2(sch_1):m_j_dqs_dn(1)") )
				( member ( signalRef "@baseboard_fab2_lib.baseboard_fab2(sch_1):m_j_dqs_dn(2)") )
				( member ( signalRef "@baseboard_fab2_lib.baseboard_fab2(sch_1):m_j_dqs_dn(3)") )
				( member ( signalRef "@baseboard_fab2_lib.baseboard_fab2(sch_1):m_j_dqs_dn(4)") )
				( member ( signalRef "@baseboard_fab2_lib.baseboard_fab2(sch_1):m_j_dqs_dn(5)") )
				( member ( signalRef "@baseboard_fab2_lib.baseboard_fab2(sch_1):m_j_dqs_dn(6)") )
				( member ( signalRef "@baseboard_fab2_lib.baseboard_fab2(sch_1):m_j_dqs_dn(7)") )
				( member ( signalRef "@baseboard_fab2_lib.baseboard_fab2(sch_1):m_j_dqs_dn(8)") )
				( member ( signalRef "@baseboard_fab2_lib.baseboard_fab2(sch_1):m_j_dqs_dn(9)") )
				( member ( signalRef "@baseboard_fab2_lib.baseboard_fab2(sch_1):m_j_dqs_dn(10)") )
				( member ( signalRef "@baseboard_fab2_lib.baseboard_fab2(sch_1):m_j_dqs_dn(11)") )
				( member ( signalRef "@baseboard_fab2_lib.baseboard_fab2(sch_1):m_j_dqs_dn(12)") )
				( member ( signalRef "@baseboard_fab2_lib.baseboard_fab2(sch_1):m_j_dqs_dn(13)") )
				( member ( signalRef "@baseboard_fab2_lib.baseboard_fab2(sch_1):m_j_dqs_dn(14)") )
				( member ( signalRef "@baseboard_fab2_lib.baseboard_fab2(sch_1):m_j_dqs_dn(15)") )
				( member ( signalRef "@baseboard_fab2_lib.baseboard_fab2(sch_1):m_j_dqs_dn(16)") )
				( member ( signalRef "@baseboard_fab2_lib.baseboard_fab2(sch_1):m_j_dqs_dn(17)") )
				( objectStatus "M_J_DQS_DN" )
			)
			( bus "@crescent_city_bb_fab1_lib.crescent_city_bb_fab1(sch_1):m_j_dq"
				( memberType ( signal ) )
				( member ( signalRef "@baseboard_fab2_lib.baseboard_fab2(sch_1):m_j_dq(0)") )
				( member ( signalRef "@baseboard_fab2_lib.baseboard_fab2(sch_1):m_j_dq(1)") )
				( member ( signalRef "@baseboard_fab2_lib.baseboard_fab2(sch_1):m_j_dq(2)") )
				( member ( signalRef "@baseboard_fab2_lib.baseboard_fab2(sch_1):m_j_dq(3)") )
				( member ( signalRef "@baseboard_fab2_lib.baseboard_fab2(sch_1):m_j_dq(4)") )
				( member ( signalRef "@baseboard_fab2_lib.baseboard_fab2(sch_1):m_j_dq(5)") )
				( member ( signalRef "@baseboard_fab2_lib.baseboard_fab2(sch_1):m_j_dq(6)") )
				( member ( signalRef "@baseboard_fab2_lib.baseboard_fab2(sch_1):m_j_dq(7)") )
				( member ( signalRef "@baseboard_fab2_lib.baseboard_fab2(sch_1):m_j_dq(8)") )
				( member ( signalRef "@baseboard_fab2_lib.baseboard_fab2(sch_1):m_j_dq(9)") )
				( member ( signalRef "@baseboard_fab2_lib.baseboard_fab2(sch_1):m_j_dq(10)") )
				( member ( signalRef "@baseboard_fab2_lib.baseboard_fab2(sch_1):m_j_dq(11)") )
				( member ( signalRef "@baseboard_fab2_lib.baseboard_fab2(sch_1):m_j_dq(12)") )
				( member ( signalRef "@baseboard_fab2_lib.baseboard_fab2(sch_1):m_j_dq(13)") )
				( member ( signalRef "@baseboard_fab2_lib.baseboard_fab2(sch_1):m_j_dq(14)") )
				( member ( signalRef "@baseboard_fab2_lib.baseboard_fab2(sch_1):m_j_dq(15)") )
				( member ( signalRef "@baseboard_fab2_lib.baseboard_fab2(sch_1):m_j_dq(16)") )
				( member ( signalRef "@baseboard_fab2_lib.baseboard_fab2(sch_1):m_j_dq(17)") )
				( member ( signalRef "@baseboard_fab2_lib.baseboard_fab2(sch_1):m_j_dq(18)") )
				( member ( signalRef "@baseboard_fab2_lib.baseboard_fab2(sch_1):m_j_dq(19)") )
				( member ( signalRef "@baseboard_fab2_lib.baseboard_fab2(sch_1):m_j_dq(20)") )
				( member ( signalRef "@baseboard_fab2_lib.baseboard_fab2(sch_1):m_j_dq(21)") )
				( member ( signalRef "@baseboard_fab2_lib.baseboard_fab2(sch_1):m_j_dq(22)") )
				( member ( signalRef "@baseboard_fab2_lib.baseboard_fab2(sch_1):m_j_dq(23)") )
				( member ( signalRef "@baseboard_fab2_lib.baseboard_fab2(sch_1):m_j_dq(24)") )
				( member ( signalRef "@baseboard_fab2_lib.baseboard_fab2(sch_1):m_j_dq(25)") )
				( member ( signalRef "@baseboard_fab2_lib.baseboard_fab2(sch_1):m_j_dq(26)") )
				( member ( signalRef "@baseboard_fab2_lib.baseboard_fab2(sch_1):m_j_dq(27)") )
				( member ( signalRef "@baseboard_fab2_lib.baseboard_fab2(sch_1):m_j_dq(28)") )
				( member ( signalRef "@baseboard_fab2_lib.baseboard_fab2(sch_1):m_j_dq(29)") )
				( member ( signalRef "@baseboard_fab2_lib.baseboard_fab2(sch_1):m_j_dq(30)") )
				( member ( signalRef "@baseboard_fab2_lib.baseboard_fab2(sch_1):m_j_dq(31)") )
				( member ( signalRef "@baseboard_fab2_lib.baseboard_fab2(sch_1):m_j_dq(32)") )
				( member ( signalRef "@baseboard_fab2_lib.baseboard_fab2(sch_1):m_j_dq(33)") )
				( member ( signalRef "@baseboard_fab2_lib.baseboard_fab2(sch_1):m_j_dq(34)") )
				( member ( signalRef "@baseboard_fab2_lib.baseboard_fab2(sch_1):m_j_dq(35)") )
				( member ( signalRef "@baseboard_fab2_lib.baseboard_fab2(sch_1):m_j_dq(36)") )
				( member ( signalRef "@baseboard_fab2_lib.baseboard_fab2(sch_1):m_j_dq(37)") )
				( member ( signalRef "@baseboard_fab2_lib.baseboard_fab2(sch_1):m_j_dq(38)") )
				( member ( signalRef "@baseboard_fab2_lib.baseboard_fab2(sch_1):m_j_dq(39)") )
				( member ( signalRef "@baseboard_fab2_lib.baseboard_fab2(sch_1):m_j_dq(40)") )
				( member ( signalRef "@baseboard_fab2_lib.baseboard_fab2(sch_1):m_j_dq(41)") )
				( member ( signalRef "@baseboard_fab2_lib.baseboard_fab2(sch_1):m_j_dq(42)") )
				( member ( signalRef "@baseboard_fab2_lib.baseboard_fab2(sch_1):m_j_dq(43)") )
				( member ( signalRef "@baseboard_fab2_lib.baseboard_fab2(sch_1):m_j_dq(44)") )
				( member ( signalRef "@baseboard_fab2_lib.baseboard_fab2(sch_1):m_j_dq(45)") )
				( member ( signalRef "@baseboard_fab2_lib.baseboard_fab2(sch_1):m_j_dq(46)") )
				( member ( signalRef "@baseboard_fab2_lib.baseboard_fab2(sch_1):m_j_dq(47)") )
				( member ( signalRef "@baseboard_fab2_lib.baseboard_fab2(sch_1):m_j_dq(48)") )
				( member ( signalRef "@baseboard_fab2_lib.baseboard_fab2(sch_1):m_j_dq(49)") )
				( member ( signalRef "@baseboard_fab2_lib.baseboard_fab2(sch_1):m_j_dq(50)") )
				( member ( signalRef "@baseboard_fab2_lib.baseboard_fab2(sch_1):m_j_dq(51)") )
				( member ( signalRef "@baseboard_fab2_lib.baseboard_fab2(sch_1):m_j_dq(52)") )
				( member ( signalRef "@baseboard_fab2_lib.baseboard_fab2(sch_1):m_j_dq(53)") )
				( member ( signalRef "@baseboard_fab2_lib.baseboard_fab2(sch_1):m_j_dq(54)") )
				( member ( signalRef "@baseboard_fab2_lib.baseboard_fab2(sch_1):m_j_dq(55)") )
				( member ( signalRef "@baseboard_fab2_lib.baseboard_fab2(sch_1):m_j_dq(56)") )
				( member ( signalRef "@baseboard_fab2_lib.baseboard_fab2(sch_1):m_j_dq(57)") )
				( member ( signalRef "@baseboard_fab2_lib.baseboard_fab2(sch_1):m_j_dq(58)") )
				( member ( signalRef "@baseboard_fab2_lib.baseboard_fab2(sch_1):m_j_dq(59)") )
				( member ( signalRef "@baseboard_fab2_lib.baseboard_fab2(sch_1):m_j_dq(60)") )
				( member ( signalRef "@baseboard_fab2_lib.baseboard_fab2(sch_1):m_j_dq(61)") )
				( member ( signalRef "@baseboard_fab2_lib.baseboard_fab2(sch_1):m_j_dq(62)") )
				( member ( signalRef "@baseboard_fab2_lib.baseboard_fab2(sch_1):m_j_dq(63)") )
				( objectStatus "M_J_DQ" )
			)
			( bus "@crescent_city_bb_fab1_lib.crescent_city_bb_fab1(sch_1):m_j_cs_n"
				( memberType ( signal ) )
				( member ( signalRef "@baseboard_fab2_lib.baseboard_fab2(sch_1):m_j_cs_n(0)") )
				( member ( signalRef "@baseboard_fab2_lib.baseboard_fab2(sch_1):m_j_cs_n(1)") )
				( member ( signalRef "@baseboard_fab2_lib.baseboard_fab2(sch_1):m_j_cs_n(2)") )
				( member ( signalRef "@baseboard_fab2_lib.baseboard_fab2(sch_1):m_j_cs_n(3)") )
				( member ( signalRef "@baseboard_fab2_lib.baseboard_fab2(sch_1):m_j_cs_n(4)") )
				( member ( signalRef "@baseboard_fab2_lib.baseboard_fab2(sch_1):m_j_cs_n(5)") )
				( member ( signalRef "@baseboard_fab2_lib.baseboard_fab2(sch_1):m_j_cs_n(6)") )
				( member ( signalRef "@baseboard_fab2_lib.baseboard_fab2(sch_1):m_j_cs_n(7)") )
				( objectStatus "M_J_CS_N" )
			)
			( bus "@crescent_city_bb_fab1_lib.crescent_city_bb_fab1(sch_1):m_j_clk_dp"
				( memberType ( signal ) )
				( member ( signalRef "@baseboard_fab2_lib.baseboard_fab2(sch_1):m_j_clk_dp(0)") )
				( member ( signalRef "@baseboard_fab2_lib.baseboard_fab2(sch_1):m_j_clk_dp(1)") )
				( member ( signalRef "@baseboard_fab2_lib.baseboard_fab2(sch_1):m_j_clk_dp(2)") )
				( member ( signalRef "@baseboard_fab2_lib.baseboard_fab2(sch_1):m_j_clk_dp(3)") )
				( objectStatus "M_J_CLK_DP" )
			)
			( bus "@crescent_city_bb_fab1_lib.crescent_city_bb_fab1(sch_1):m_j_clk_dn"
				( memberType ( signal ) )
				( member ( signalRef "@baseboard_fab2_lib.baseboard_fab2(sch_1):m_j_clk_dn(0)") )
				( member ( signalRef "@baseboard_fab2_lib.baseboard_fab2(sch_1):m_j_clk_dn(1)") )
				( member ( signalRef "@baseboard_fab2_lib.baseboard_fab2(sch_1):m_j_clk_dn(2)") )
				( member ( signalRef "@baseboard_fab2_lib.baseboard_fab2(sch_1):m_j_clk_dn(3)") )
				( objectStatus "M_J_CLK_DN" )
			)
			( bus "@crescent_city_bb_fab1_lib.crescent_city_bb_fab1(sch_1):m_j_cke"
				( memberType ( signal ) )
				( member ( signalRef "@baseboard_fab2_lib.baseboard_fab2(sch_1):m_j_cke(0)") )
				( member ( signalRef "@baseboard_fab2_lib.baseboard_fab2(sch_1):m_j_cke(1)") )
				( member ( signalRef "@baseboard_fab2_lib.baseboard_fab2(sch_1):m_j_cke(2)") )
				( member ( signalRef "@baseboard_fab2_lib.baseboard_fab2(sch_1):m_j_cke(3)") )
				( objectStatus "M_J_CKE" )
			)
			( bus "@crescent_city_bb_fab1_lib.crescent_city_bb_fab1(sch_1):m_j_c"
				( memberType ( signal ) )
				( member ( signalRef "@baseboard_fab2_lib.baseboard_fab2(sch_1):m_j_c(2)") )
				( objectStatus "M_J_C" )
			)
			( bus "@crescent_city_bb_fab1_lib.crescent_city_bb_fab1(sch_1):m_j_bg"
				( memberType ( signal ) )
				( member ( signalRef "@baseboard_fab2_lib.baseboard_fab2(sch_1):m_j_bg(0)") )
				( member ( signalRef "@baseboard_fab2_lib.baseboard_fab2(sch_1):m_j_bg(1)") )
				( objectStatus "M_J_BG" )
			)
			( bus "@crescent_city_bb_fab1_lib.crescent_city_bb_fab1(sch_1):m_j_ba"
				( memberType ( signal ) )
				( member ( signalRef "@baseboard_fab2_lib.baseboard_fab2(sch_1):m_j_ba(0)") )
				( member ( signalRef "@baseboard_fab2_lib.baseboard_fab2(sch_1):m_j_ba(1)") )
				( objectStatus "M_J_BA" )
			)
			( bus "@crescent_city_bb_fab1_lib.crescent_city_bb_fab1(sch_1):m_h_odt"
				( memberType ( signal ) )
				( member ( signalRef "@baseboard_fab2_lib.baseboard_fab2(sch_1):m_h_odt(0)") )
				( member ( signalRef "@baseboard_fab2_lib.baseboard_fab2(sch_1):m_h_odt(1)") )
				( member ( signalRef "@baseboard_fab2_lib.baseboard_fab2(sch_1):m_h_odt(2)") )
				( member ( signalRef "@baseboard_fab2_lib.baseboard_fab2(sch_1):m_h_odt(3)") )
				( objectStatus "M_H_ODT" )
			)
			( bus "@crescent_city_bb_fab1_lib.crescent_city_bb_fab1(sch_1):m_h_ma"
				( memberType ( signal ) )
				( member ( signalRef "@baseboard_fab2_lib.baseboard_fab2(sch_1):m_h_ma(0)") )
				( member ( signalRef "@baseboard_fab2_lib.baseboard_fab2(sch_1):m_h_ma(1)") )
				( member ( signalRef "@baseboard_fab2_lib.baseboard_fab2(sch_1):m_h_ma(2)") )
				( member ( signalRef "@baseboard_fab2_lib.baseboard_fab2(sch_1):m_h_ma(3)") )
				( member ( signalRef "@baseboard_fab2_lib.baseboard_fab2(sch_1):m_h_ma(4)") )
				( member ( signalRef "@baseboard_fab2_lib.baseboard_fab2(sch_1):m_h_ma(5)") )
				( member ( signalRef "@baseboard_fab2_lib.baseboard_fab2(sch_1):m_h_ma(6)") )
				( member ( signalRef "@baseboard_fab2_lib.baseboard_fab2(sch_1):m_h_ma(7)") )
				( member ( signalRef "@baseboard_fab2_lib.baseboard_fab2(sch_1):m_h_ma(8)") )
				( member ( signalRef "@baseboard_fab2_lib.baseboard_fab2(sch_1):m_h_ma(9)") )
				( member ( signalRef "@baseboard_fab2_lib.baseboard_fab2(sch_1):m_h_ma(10)") )
				( member ( signalRef "@baseboard_fab2_lib.baseboard_fab2(sch_1):m_h_ma(11)") )
				( member ( signalRef "@baseboard_fab2_lib.baseboard_fab2(sch_1):m_h_ma(12)") )
				( member ( signalRef "@baseboard_fab2_lib.baseboard_fab2(sch_1):m_h_ma(13)") )
				( member ( signalRef "@baseboard_fab2_lib.baseboard_fab2(sch_1):m_h_ma(14)") )
				( member ( signalRef "@baseboard_fab2_lib.baseboard_fab2(sch_1):m_h_ma(15)") )
				( member ( signalRef "@baseboard_fab2_lib.baseboard_fab2(sch_1):m_h_ma(16)") )
				( member ( signalRef "@baseboard_fab2_lib.baseboard_fab2(sch_1):m_h_ma(17)") )
				( objectStatus "M_H_MA" )
			)
			( bus "@crescent_city_bb_fab1_lib.crescent_city_bb_fab1(sch_1):m_h_ecc"
				( memberType ( signal ) )
				( member ( signalRef "@baseboard_fab2_lib.baseboard_fab2(sch_1):m_h_ecc(0)") )
				( member ( signalRef "@baseboard_fab2_lib.baseboard_fab2(sch_1):m_h_ecc(1)") )
				( member ( signalRef "@baseboard_fab2_lib.baseboard_fab2(sch_1):m_h_ecc(2)") )
				( member ( signalRef "@baseboard_fab2_lib.baseboard_fab2(sch_1):m_h_ecc(3)") )
				( member ( signalRef "@baseboard_fab2_lib.baseboard_fab2(sch_1):m_h_ecc(4)") )
				( member ( signalRef "@baseboard_fab2_lib.baseboard_fab2(sch_1):m_h_ecc(5)") )
				( member ( signalRef "@baseboard_fab2_lib.baseboard_fab2(sch_1):m_h_ecc(6)") )
				( member ( signalRef "@baseboard_fab2_lib.baseboard_fab2(sch_1):m_h_ecc(7)") )
				( objectStatus "M_H_ECC" )
			)
			( bus "@crescent_city_bb_fab1_lib.crescent_city_bb_fab1(sch_1):m_h_dqs_dp"
				( memberType ( signal ) )
				( member ( signalRef "@baseboard_fab2_lib.baseboard_fab2(sch_1):m_h_dqs_dp(0)") )
				( member ( signalRef "@baseboard_fab2_lib.baseboard_fab2(sch_1):m_h_dqs_dp(1)") )
				( member ( signalRef "@baseboard_fab2_lib.baseboard_fab2(sch_1):m_h_dqs_dp(2)") )
				( member ( signalRef "@baseboard_fab2_lib.baseboard_fab2(sch_1):m_h_dqs_dp(3)") )
				( member ( signalRef "@baseboard_fab2_lib.baseboard_fab2(sch_1):m_h_dqs_dp(4)") )
				( member ( signalRef "@baseboard_fab2_lib.baseboard_fab2(sch_1):m_h_dqs_dp(5)") )
				( member ( signalRef "@baseboard_fab2_lib.baseboard_fab2(sch_1):m_h_dqs_dp(6)") )
				( member ( signalRef "@baseboard_fab2_lib.baseboard_fab2(sch_1):m_h_dqs_dp(7)") )
				( member ( signalRef "@baseboard_fab2_lib.baseboard_fab2(sch_1):m_h_dqs_dp(8)") )
				( member ( signalRef "@baseboard_fab2_lib.baseboard_fab2(sch_1):m_h_dqs_dp(9)") )
				( member ( signalRef "@baseboard_fab2_lib.baseboard_fab2(sch_1):m_h_dqs_dp(10)") )
				( member ( signalRef "@baseboard_fab2_lib.baseboard_fab2(sch_1):m_h_dqs_dp(11)") )
				( member ( signalRef "@baseboard_fab2_lib.baseboard_fab2(sch_1):m_h_dqs_dp(12)") )
				( member ( signalRef "@baseboard_fab2_lib.baseboard_fab2(sch_1):m_h_dqs_dp(13)") )
				( member ( signalRef "@baseboard_fab2_lib.baseboard_fab2(sch_1):m_h_dqs_dp(14)") )
				( member ( signalRef "@baseboard_fab2_lib.baseboard_fab2(sch_1):m_h_dqs_dp(15)") )
				( member ( signalRef "@baseboard_fab2_lib.baseboard_fab2(sch_1):m_h_dqs_dp(16)") )
				( member ( signalRef "@baseboard_fab2_lib.baseboard_fab2(sch_1):m_h_dqs_dp(17)") )
				( objectStatus "M_H_DQS_DP" )
			)
			( bus "@crescent_city_bb_fab1_lib.crescent_city_bb_fab1(sch_1):m_h_dqs_dn"
				( memberType ( signal ) )
				( member ( signalRef "@baseboard_fab2_lib.baseboard_fab2(sch_1):m_h_dqs_dn(0)") )
				( member ( signalRef "@baseboard_fab2_lib.baseboard_fab2(sch_1):m_h_dqs_dn(1)") )
				( member ( signalRef "@baseboard_fab2_lib.baseboard_fab2(sch_1):m_h_dqs_dn(2)") )
				( member ( signalRef "@baseboard_fab2_lib.baseboard_fab2(sch_1):m_h_dqs_dn(3)") )
				( member ( signalRef "@baseboard_fab2_lib.baseboard_fab2(sch_1):m_h_dqs_dn(4)") )
				( member ( signalRef "@baseboard_fab2_lib.baseboard_fab2(sch_1):m_h_dqs_dn(5)") )
				( member ( signalRef "@baseboard_fab2_lib.baseboard_fab2(sch_1):m_h_dqs_dn(6)") )
				( member ( signalRef "@baseboard_fab2_lib.baseboard_fab2(sch_1):m_h_dqs_dn(7)") )
				( member ( signalRef "@baseboard_fab2_lib.baseboard_fab2(sch_1):m_h_dqs_dn(8)") )
				( member ( signalRef "@baseboard_fab2_lib.baseboard_fab2(sch_1):m_h_dqs_dn(9)") )
				( member ( signalRef "@baseboard_fab2_lib.baseboard_fab2(sch_1):m_h_dqs_dn(10)") )
				( member ( signalRef "@baseboard_fab2_lib.baseboard_fab2(sch_1):m_h_dqs_dn(11)") )
				( member ( signalRef "@baseboard_fab2_lib.baseboard_fab2(sch_1):m_h_dqs_dn(12)") )
				( member ( signalRef "@baseboard_fab2_lib.baseboard_fab2(sch_1):m_h_dqs_dn(13)") )
				( member ( signalRef "@baseboard_fab2_lib.baseboard_fab2(sch_1):m_h_dqs_dn(14)") )
				( member ( signalRef "@baseboard_fab2_lib.baseboard_fab2(sch_1):m_h_dqs_dn(15)") )
				( member ( signalRef "@baseboard_fab2_lib.baseboard_fab2(sch_1):m_h_dqs_dn(16)") )
				( member ( signalRef "@baseboard_fab2_lib.baseboard_fab2(sch_1):m_h_dqs_dn(17)") )
				( objectStatus "M_H_DQS_DN" )
			)
			( bus "@crescent_city_bb_fab1_lib.crescent_city_bb_fab1(sch_1):m_h_dq"
				( memberType ( signal ) )
				( member ( signalRef "@baseboard_fab2_lib.baseboard_fab2(sch_1):m_h_dq(0)") )
				( member ( signalRef "@baseboard_fab2_lib.baseboard_fab2(sch_1):m_h_dq(1)") )
				( member ( signalRef "@baseboard_fab2_lib.baseboard_fab2(sch_1):m_h_dq(2)") )
				( member ( signalRef "@baseboard_fab2_lib.baseboard_fab2(sch_1):m_h_dq(3)") )
				( member ( signalRef "@baseboard_fab2_lib.baseboard_fab2(sch_1):m_h_dq(4)") )
				( member ( signalRef "@baseboard_fab2_lib.baseboard_fab2(sch_1):m_h_dq(5)") )
				( member ( signalRef "@baseboard_fab2_lib.baseboard_fab2(sch_1):m_h_dq(6)") )
				( member ( signalRef "@baseboard_fab2_lib.baseboard_fab2(sch_1):m_h_dq(7)") )
				( member ( signalRef "@baseboard_fab2_lib.baseboard_fab2(sch_1):m_h_dq(8)") )
				( member ( signalRef "@baseboard_fab2_lib.baseboard_fab2(sch_1):m_h_dq(9)") )
				( member ( signalRef "@baseboard_fab2_lib.baseboard_fab2(sch_1):m_h_dq(10)") )
				( member ( signalRef "@baseboard_fab2_lib.baseboard_fab2(sch_1):m_h_dq(11)") )
				( member ( signalRef "@baseboard_fab2_lib.baseboard_fab2(sch_1):m_h_dq(12)") )
				( member ( signalRef "@baseboard_fab2_lib.baseboard_fab2(sch_1):m_h_dq(13)") )
				( member ( signalRef "@baseboard_fab2_lib.baseboard_fab2(sch_1):m_h_dq(14)") )
				( member ( signalRef "@baseboard_fab2_lib.baseboard_fab2(sch_1):m_h_dq(15)") )
				( member ( signalRef "@baseboard_fab2_lib.baseboard_fab2(sch_1):m_h_dq(16)") )
				( member ( signalRef "@baseboard_fab2_lib.baseboard_fab2(sch_1):m_h_dq(17)") )
				( member ( signalRef "@baseboard_fab2_lib.baseboard_fab2(sch_1):m_h_dq(18)") )
				( member ( signalRef "@baseboard_fab2_lib.baseboard_fab2(sch_1):m_h_dq(19)") )
				( member ( signalRef "@baseboard_fab2_lib.baseboard_fab2(sch_1):m_h_dq(20)") )
				( member ( signalRef "@baseboard_fab2_lib.baseboard_fab2(sch_1):m_h_dq(21)") )
				( member ( signalRef "@baseboard_fab2_lib.baseboard_fab2(sch_1):m_h_dq(22)") )
				( member ( signalRef "@baseboard_fab2_lib.baseboard_fab2(sch_1):m_h_dq(23)") )
				( member ( signalRef "@baseboard_fab2_lib.baseboard_fab2(sch_1):m_h_dq(24)") )
				( member ( signalRef "@baseboard_fab2_lib.baseboard_fab2(sch_1):m_h_dq(25)") )
				( member ( signalRef "@baseboard_fab2_lib.baseboard_fab2(sch_1):m_h_dq(26)") )
				( member ( signalRef "@baseboard_fab2_lib.baseboard_fab2(sch_1):m_h_dq(27)") )
				( member ( signalRef "@baseboard_fab2_lib.baseboard_fab2(sch_1):m_h_dq(28)") )
				( member ( signalRef "@baseboard_fab2_lib.baseboard_fab2(sch_1):m_h_dq(29)") )
				( member ( signalRef "@baseboard_fab2_lib.baseboard_fab2(sch_1):m_h_dq(30)") )
				( member ( signalRef "@baseboard_fab2_lib.baseboard_fab2(sch_1):m_h_dq(31)") )
				( member ( signalRef "@baseboard_fab2_lib.baseboard_fab2(sch_1):m_h_dq(32)") )
				( member ( signalRef "@baseboard_fab2_lib.baseboard_fab2(sch_1):m_h_dq(33)") )
				( member ( signalRef "@baseboard_fab2_lib.baseboard_fab2(sch_1):m_h_dq(34)") )
				( member ( signalRef "@baseboard_fab2_lib.baseboard_fab2(sch_1):m_h_dq(35)") )
				( member ( signalRef "@baseboard_fab2_lib.baseboard_fab2(sch_1):m_h_dq(36)") )
				( member ( signalRef "@baseboard_fab2_lib.baseboard_fab2(sch_1):m_h_dq(37)") )
				( member ( signalRef "@baseboard_fab2_lib.baseboard_fab2(sch_1):m_h_dq(38)") )
				( member ( signalRef "@baseboard_fab2_lib.baseboard_fab2(sch_1):m_h_dq(39)") )
				( member ( signalRef "@baseboard_fab2_lib.baseboard_fab2(sch_1):m_h_dq(40)") )
				( member ( signalRef "@baseboard_fab2_lib.baseboard_fab2(sch_1):m_h_dq(41)") )
				( member ( signalRef "@baseboard_fab2_lib.baseboard_fab2(sch_1):m_h_dq(42)") )
				( member ( signalRef "@baseboard_fab2_lib.baseboard_fab2(sch_1):m_h_dq(43)") )
				( member ( signalRef "@baseboard_fab2_lib.baseboard_fab2(sch_1):m_h_dq(44)") )
				( member ( signalRef "@baseboard_fab2_lib.baseboard_fab2(sch_1):m_h_dq(45)") )
				( member ( signalRef "@baseboard_fab2_lib.baseboard_fab2(sch_1):m_h_dq(46)") )
				( member ( signalRef "@baseboard_fab2_lib.baseboard_fab2(sch_1):m_h_dq(47)") )
				( member ( signalRef "@baseboard_fab2_lib.baseboard_fab2(sch_1):m_h_dq(48)") )
				( member ( signalRef "@baseboard_fab2_lib.baseboard_fab2(sch_1):m_h_dq(49)") )
				( member ( signalRef "@baseboard_fab2_lib.baseboard_fab2(sch_1):m_h_dq(50)") )
				( member ( signalRef "@baseboard_fab2_lib.baseboard_fab2(sch_1):m_h_dq(51)") )
				( member ( signalRef "@baseboard_fab2_lib.baseboard_fab2(sch_1):m_h_dq(52)") )
				( member ( signalRef "@baseboard_fab2_lib.baseboard_fab2(sch_1):m_h_dq(53)") )
				( member ( signalRef "@baseboard_fab2_lib.baseboard_fab2(sch_1):m_h_dq(54)") )
				( member ( signalRef "@baseboard_fab2_lib.baseboard_fab2(sch_1):m_h_dq(55)") )
				( member ( signalRef "@baseboard_fab2_lib.baseboard_fab2(sch_1):m_h_dq(56)") )
				( member ( signalRef "@baseboard_fab2_lib.baseboard_fab2(sch_1):m_h_dq(57)") )
				( member ( signalRef "@baseboard_fab2_lib.baseboard_fab2(sch_1):m_h_dq(58)") )
				( member ( signalRef "@baseboard_fab2_lib.baseboard_fab2(sch_1):m_h_dq(59)") )
				( member ( signalRef "@baseboard_fab2_lib.baseboard_fab2(sch_1):m_h_dq(60)") )
				( member ( signalRef "@baseboard_fab2_lib.baseboard_fab2(sch_1):m_h_dq(61)") )
				( member ( signalRef "@baseboard_fab2_lib.baseboard_fab2(sch_1):m_h_dq(62)") )
				( member ( signalRef "@baseboard_fab2_lib.baseboard_fab2(sch_1):m_h_dq(63)") )
				( objectStatus "M_H_DQ" )
			)
			( bus "@crescent_city_bb_fab1_lib.crescent_city_bb_fab1(sch_1):m_h_cs_n"
				( memberType ( signal ) )
				( member ( signalRef "@baseboard_fab2_lib.baseboard_fab2(sch_1):m_h_cs_n(0)") )
				( member ( signalRef "@baseboard_fab2_lib.baseboard_fab2(sch_1):m_h_cs_n(1)") )
				( member ( signalRef "@baseboard_fab2_lib.baseboard_fab2(sch_1):m_h_cs_n(2)") )
				( member ( signalRef "@baseboard_fab2_lib.baseboard_fab2(sch_1):m_h_cs_n(3)") )
				( member ( signalRef "@baseboard_fab2_lib.baseboard_fab2(sch_1):m_h_cs_n(4)") )
				( member ( signalRef "@baseboard_fab2_lib.baseboard_fab2(sch_1):m_h_cs_n(5)") )
				( member ( signalRef "@baseboard_fab2_lib.baseboard_fab2(sch_1):m_h_cs_n(6)") )
				( member ( signalRef "@baseboard_fab2_lib.baseboard_fab2(sch_1):m_h_cs_n(7)") )
				( objectStatus "M_H_CS_N" )
			)
			( bus "@crescent_city_bb_fab1_lib.crescent_city_bb_fab1(sch_1):m_h_clk_dp"
				( memberType ( signal ) )
				( member ( signalRef "@baseboard_fab2_lib.baseboard_fab2(sch_1):m_h_clk_dp(0)") )
				( member ( signalRef "@baseboard_fab2_lib.baseboard_fab2(sch_1):m_h_clk_dp(1)") )
				( member ( signalRef "@baseboard_fab2_lib.baseboard_fab2(sch_1):m_h_clk_dp(2)") )
				( member ( signalRef "@baseboard_fab2_lib.baseboard_fab2(sch_1):m_h_clk_dp(3)") )
				( objectStatus "M_H_CLK_DP" )
			)
			( bus "@crescent_city_bb_fab1_lib.crescent_city_bb_fab1(sch_1):m_h_clk_dn"
				( memberType ( signal ) )
				( member ( signalRef "@baseboard_fab2_lib.baseboard_fab2(sch_1):m_h_clk_dn(0)") )
				( member ( signalRef "@baseboard_fab2_lib.baseboard_fab2(sch_1):m_h_clk_dn(1)") )
				( member ( signalRef "@baseboard_fab2_lib.baseboard_fab2(sch_1):m_h_clk_dn(2)") )
				( member ( signalRef "@baseboard_fab2_lib.baseboard_fab2(sch_1):m_h_clk_dn(3)") )
				( objectStatus "M_H_CLK_DN" )
			)
			( bus "@crescent_city_bb_fab1_lib.crescent_city_bb_fab1(sch_1):m_h_cke"
				( memberType ( signal ) )
				( member ( signalRef "@baseboard_fab2_lib.baseboard_fab2(sch_1):m_h_cke(0)") )
				( member ( signalRef "@baseboard_fab2_lib.baseboard_fab2(sch_1):m_h_cke(1)") )
				( member ( signalRef "@baseboard_fab2_lib.baseboard_fab2(sch_1):m_h_cke(2)") )
				( member ( signalRef "@baseboard_fab2_lib.baseboard_fab2(sch_1):m_h_cke(3)") )
				( objectStatus "M_H_CKE" )
			)
			( bus "@crescent_city_bb_fab1_lib.crescent_city_bb_fab1(sch_1):m_h_c"
				( memberType ( signal ) )
				( member ( signalRef "@baseboard_fab2_lib.baseboard_fab2(sch_1):m_h_c(2)") )
				( objectStatus "M_H_C" )
			)
			( bus "@crescent_city_bb_fab1_lib.crescent_city_bb_fab1(sch_1):m_h_bg"
				( memberType ( signal ) )
				( member ( signalRef "@baseboard_fab2_lib.baseboard_fab2(sch_1):m_h_bg(0)") )
				( member ( signalRef "@baseboard_fab2_lib.baseboard_fab2(sch_1):m_h_bg(1)") )
				( objectStatus "M_H_BG" )
			)
			( bus "@crescent_city_bb_fab1_lib.crescent_city_bb_fab1(sch_1):m_h_ba"
				( memberType ( signal ) )
				( member ( signalRef "@baseboard_fab2_lib.baseboard_fab2(sch_1):m_h_ba(0)") )
				( member ( signalRef "@baseboard_fab2_lib.baseboard_fab2(sch_1):m_h_ba(1)") )
				( objectStatus "M_H_BA" )
			)
			( bus "@crescent_city_bb_fab1_lib.crescent_city_bb_fab1(sch_1):m_g_odt"
				( memberType ( signal ) )
				( member ( signalRef "@baseboard_fab2_lib.baseboard_fab2(sch_1):m_g_odt(0)") )
				( member ( signalRef "@baseboard_fab2_lib.baseboard_fab2(sch_1):m_g_odt(1)") )
				( member ( signalRef "@baseboard_fab2_lib.baseboard_fab2(sch_1):m_g_odt(2)") )
				( member ( signalRef "@baseboard_fab2_lib.baseboard_fab2(sch_1):m_g_odt(3)") )
				( objectStatus "M_G_ODT" )
			)
			( bus "@crescent_city_bb_fab1_lib.crescent_city_bb_fab1(sch_1):m_g_ma"
				( memberType ( signal ) )
				( member ( signalRef "@baseboard_fab2_lib.baseboard_fab2(sch_1):m_g_ma(0)") )
				( member ( signalRef "@baseboard_fab2_lib.baseboard_fab2(sch_1):m_g_ma(1)") )
				( member ( signalRef "@baseboard_fab2_lib.baseboard_fab2(sch_1):m_g_ma(2)") )
				( member ( signalRef "@baseboard_fab2_lib.baseboard_fab2(sch_1):m_g_ma(3)") )
				( member ( signalRef "@baseboard_fab2_lib.baseboard_fab2(sch_1):m_g_ma(4)") )
				( member ( signalRef "@baseboard_fab2_lib.baseboard_fab2(sch_1):m_g_ma(5)") )
				( member ( signalRef "@baseboard_fab2_lib.baseboard_fab2(sch_1):m_g_ma(6)") )
				( member ( signalRef "@baseboard_fab2_lib.baseboard_fab2(sch_1):m_g_ma(7)") )
				( member ( signalRef "@baseboard_fab2_lib.baseboard_fab2(sch_1):m_g_ma(8)") )
				( member ( signalRef "@baseboard_fab2_lib.baseboard_fab2(sch_1):m_g_ma(9)") )
				( member ( signalRef "@baseboard_fab2_lib.baseboard_fab2(sch_1):m_g_ma(10)") )
				( member ( signalRef "@baseboard_fab2_lib.baseboard_fab2(sch_1):m_g_ma(11)") )
				( member ( signalRef "@baseboard_fab2_lib.baseboard_fab2(sch_1):m_g_ma(12)") )
				( member ( signalRef "@baseboard_fab2_lib.baseboard_fab2(sch_1):m_g_ma(13)") )
				( member ( signalRef "@baseboard_fab2_lib.baseboard_fab2(sch_1):m_g_ma(14)") )
				( member ( signalRef "@baseboard_fab2_lib.baseboard_fab2(sch_1):m_g_ma(15)") )
				( member ( signalRef "@baseboard_fab2_lib.baseboard_fab2(sch_1):m_g_ma(16)") )
				( member ( signalRef "@baseboard_fab2_lib.baseboard_fab2(sch_1):m_g_ma(17)") )
				( objectStatus "M_G_MA" )
			)
			( bus "@crescent_city_bb_fab1_lib.crescent_city_bb_fab1(sch_1):m_g_ecc"
				( memberType ( signal ) )
				( member ( signalRef "@baseboard_fab2_lib.baseboard_fab2(sch_1):m_g_ecc(0)") )
				( member ( signalRef "@baseboard_fab2_lib.baseboard_fab2(sch_1):m_g_ecc(1)") )
				( member ( signalRef "@baseboard_fab2_lib.baseboard_fab2(sch_1):m_g_ecc(2)") )
				( member ( signalRef "@baseboard_fab2_lib.baseboard_fab2(sch_1):m_g_ecc(3)") )
				( member ( signalRef "@baseboard_fab2_lib.baseboard_fab2(sch_1):m_g_ecc(4)") )
				( member ( signalRef "@baseboard_fab2_lib.baseboard_fab2(sch_1):m_g_ecc(5)") )
				( member ( signalRef "@baseboard_fab2_lib.baseboard_fab2(sch_1):m_g_ecc(6)") )
				( member ( signalRef "@baseboard_fab2_lib.baseboard_fab2(sch_1):m_g_ecc(7)") )
				( objectStatus "M_G_ECC" )
			)
			( bus "@crescent_city_bb_fab1_lib.crescent_city_bb_fab1(sch_1):m_g_dqs_dp"
				( memberType ( signal ) )
				( member ( signalRef "@baseboard_fab2_lib.baseboard_fab2(sch_1):m_g_dqs_dp(0)") )
				( member ( signalRef "@baseboard_fab2_lib.baseboard_fab2(sch_1):m_g_dqs_dp(1)") )
				( member ( signalRef "@baseboard_fab2_lib.baseboard_fab2(sch_1):m_g_dqs_dp(2)") )
				( member ( signalRef "@baseboard_fab2_lib.baseboard_fab2(sch_1):m_g_dqs_dp(3)") )
				( member ( signalRef "@baseboard_fab2_lib.baseboard_fab2(sch_1):m_g_dqs_dp(4)") )
				( member ( signalRef "@baseboard_fab2_lib.baseboard_fab2(sch_1):m_g_dqs_dp(5)") )
				( member ( signalRef "@baseboard_fab2_lib.baseboard_fab2(sch_1):m_g_dqs_dp(6)") )
				( member ( signalRef "@baseboard_fab2_lib.baseboard_fab2(sch_1):m_g_dqs_dp(7)") )
				( member ( signalRef "@baseboard_fab2_lib.baseboard_fab2(sch_1):m_g_dqs_dp(8)") )
				( member ( signalRef "@baseboard_fab2_lib.baseboard_fab2(sch_1):m_g_dqs_dp(9)") )
				( member ( signalRef "@baseboard_fab2_lib.baseboard_fab2(sch_1):m_g_dqs_dp(10)") )
				( member ( signalRef "@baseboard_fab2_lib.baseboard_fab2(sch_1):m_g_dqs_dp(11)") )
				( member ( signalRef "@baseboard_fab2_lib.baseboard_fab2(sch_1):m_g_dqs_dp(12)") )
				( member ( signalRef "@baseboard_fab2_lib.baseboard_fab2(sch_1):m_g_dqs_dp(13)") )
				( member ( signalRef "@baseboard_fab2_lib.baseboard_fab2(sch_1):m_g_dqs_dp(14)") )
				( member ( signalRef "@baseboard_fab2_lib.baseboard_fab2(sch_1):m_g_dqs_dp(15)") )
				( member ( signalRef "@baseboard_fab2_lib.baseboard_fab2(sch_1):m_g_dqs_dp(16)") )
				( member ( signalRef "@baseboard_fab2_lib.baseboard_fab2(sch_1):m_g_dqs_dp(17)") )
				( objectStatus "M_G_DQS_DP" )
			)
			( bus "@crescent_city_bb_fab1_lib.crescent_city_bb_fab1(sch_1):m_g_dqs_dn"
				( memberType ( signal ) )
				( member ( signalRef "@baseboard_fab2_lib.baseboard_fab2(sch_1):m_g_dqs_dn(0)") )
				( member ( signalRef "@baseboard_fab2_lib.baseboard_fab2(sch_1):m_g_dqs_dn(1)") )
				( member ( signalRef "@baseboard_fab2_lib.baseboard_fab2(sch_1):m_g_dqs_dn(2)") )
				( member ( signalRef "@baseboard_fab2_lib.baseboard_fab2(sch_1):m_g_dqs_dn(3)") )
				( member ( signalRef "@baseboard_fab2_lib.baseboard_fab2(sch_1):m_g_dqs_dn(4)") )
				( member ( signalRef "@baseboard_fab2_lib.baseboard_fab2(sch_1):m_g_dqs_dn(5)") )
				( member ( signalRef "@baseboard_fab2_lib.baseboard_fab2(sch_1):m_g_dqs_dn(6)") )
				( member ( signalRef "@baseboard_fab2_lib.baseboard_fab2(sch_1):m_g_dqs_dn(7)") )
				( member ( signalRef "@baseboard_fab2_lib.baseboard_fab2(sch_1):m_g_dqs_dn(8)") )
				( member ( signalRef "@baseboard_fab2_lib.baseboard_fab2(sch_1):m_g_dqs_dn(9)") )
				( member ( signalRef "@baseboard_fab2_lib.baseboard_fab2(sch_1):m_g_dqs_dn(10)") )
				( member ( signalRef "@baseboard_fab2_lib.baseboard_fab2(sch_1):m_g_dqs_dn(11)") )
				( member ( signalRef "@baseboard_fab2_lib.baseboard_fab2(sch_1):m_g_dqs_dn(12)") )
				( member ( signalRef "@baseboard_fab2_lib.baseboard_fab2(sch_1):m_g_dqs_dn(13)") )
				( member ( signalRef "@baseboard_fab2_lib.baseboard_fab2(sch_1):m_g_dqs_dn(14)") )
				( member ( signalRef "@baseboard_fab2_lib.baseboard_fab2(sch_1):m_g_dqs_dn(15)") )
				( member ( signalRef "@baseboard_fab2_lib.baseboard_fab2(sch_1):m_g_dqs_dn(16)") )
				( member ( signalRef "@baseboard_fab2_lib.baseboard_fab2(sch_1):m_g_dqs_dn(17)") )
				( objectStatus "M_G_DQS_DN" )
			)
			( bus "@crescent_city_bb_fab1_lib.crescent_city_bb_fab1(sch_1):m_g_dq"
				( memberType ( signal ) )
				( member ( signalRef "@baseboard_fab2_lib.baseboard_fab2(sch_1):m_g_dq(0)") )
				( member ( signalRef "@baseboard_fab2_lib.baseboard_fab2(sch_1):m_g_dq(1)") )
				( member ( signalRef "@baseboard_fab2_lib.baseboard_fab2(sch_1):m_g_dq(2)") )
				( member ( signalRef "@baseboard_fab2_lib.baseboard_fab2(sch_1):m_g_dq(3)") )
				( member ( signalRef "@baseboard_fab2_lib.baseboard_fab2(sch_1):m_g_dq(4)") )
				( member ( signalRef "@baseboard_fab2_lib.baseboard_fab2(sch_1):m_g_dq(5)") )
				( member ( signalRef "@baseboard_fab2_lib.baseboard_fab2(sch_1):m_g_dq(6)") )
				( member ( signalRef "@baseboard_fab2_lib.baseboard_fab2(sch_1):m_g_dq(7)") )
				( member ( signalRef "@baseboard_fab2_lib.baseboard_fab2(sch_1):m_g_dq(8)") )
				( member ( signalRef "@baseboard_fab2_lib.baseboard_fab2(sch_1):m_g_dq(9)") )
				( member ( signalRef "@baseboard_fab2_lib.baseboard_fab2(sch_1):m_g_dq(10)") )
				( member ( signalRef "@baseboard_fab2_lib.baseboard_fab2(sch_1):m_g_dq(11)") )
				( member ( signalRef "@baseboard_fab2_lib.baseboard_fab2(sch_1):m_g_dq(12)") )
				( member ( signalRef "@baseboard_fab2_lib.baseboard_fab2(sch_1):m_g_dq(13)") )
				( member ( signalRef "@baseboard_fab2_lib.baseboard_fab2(sch_1):m_g_dq(14)") )
				( member ( signalRef "@baseboard_fab2_lib.baseboard_fab2(sch_1):m_g_dq(15)") )
				( member ( signalRef "@baseboard_fab2_lib.baseboard_fab2(sch_1):m_g_dq(16)") )
				( member ( signalRef "@baseboard_fab2_lib.baseboard_fab2(sch_1):m_g_dq(17)") )
				( member ( signalRef "@baseboard_fab2_lib.baseboard_fab2(sch_1):m_g_dq(18)") )
				( member ( signalRef "@baseboard_fab2_lib.baseboard_fab2(sch_1):m_g_dq(19)") )
				( member ( signalRef "@baseboard_fab2_lib.baseboard_fab2(sch_1):m_g_dq(20)") )
				( member ( signalRef "@baseboard_fab2_lib.baseboard_fab2(sch_1):m_g_dq(21)") )
				( member ( signalRef "@baseboard_fab2_lib.baseboard_fab2(sch_1):m_g_dq(22)") )
				( member ( signalRef "@baseboard_fab2_lib.baseboard_fab2(sch_1):m_g_dq(23)") )
				( member ( signalRef "@baseboard_fab2_lib.baseboard_fab2(sch_1):m_g_dq(24)") )
				( member ( signalRef "@baseboard_fab2_lib.baseboard_fab2(sch_1):m_g_dq(25)") )
				( member ( signalRef "@baseboard_fab2_lib.baseboard_fab2(sch_1):m_g_dq(26)") )
				( member ( signalRef "@baseboard_fab2_lib.baseboard_fab2(sch_1):m_g_dq(27)") )
				( member ( signalRef "@baseboard_fab2_lib.baseboard_fab2(sch_1):m_g_dq(28)") )
				( member ( signalRef "@baseboard_fab2_lib.baseboard_fab2(sch_1):m_g_dq(29)") )
				( member ( signalRef "@baseboard_fab2_lib.baseboard_fab2(sch_1):m_g_dq(30)") )
				( member ( signalRef "@baseboard_fab2_lib.baseboard_fab2(sch_1):m_g_dq(31)") )
				( member ( signalRef "@baseboard_fab2_lib.baseboard_fab2(sch_1):m_g_dq(32)") )
				( member ( signalRef "@baseboard_fab2_lib.baseboard_fab2(sch_1):m_g_dq(33)") )
				( member ( signalRef "@baseboard_fab2_lib.baseboard_fab2(sch_1):m_g_dq(34)") )
				( member ( signalRef "@baseboard_fab2_lib.baseboard_fab2(sch_1):m_g_dq(35)") )
				( member ( signalRef "@baseboard_fab2_lib.baseboard_fab2(sch_1):m_g_dq(36)") )
				( member ( signalRef "@baseboard_fab2_lib.baseboard_fab2(sch_1):m_g_dq(37)") )
				( member ( signalRef "@baseboard_fab2_lib.baseboard_fab2(sch_1):m_g_dq(38)") )
				( member ( signalRef "@baseboard_fab2_lib.baseboard_fab2(sch_1):m_g_dq(39)") )
				( member ( signalRef "@baseboard_fab2_lib.baseboard_fab2(sch_1):m_g_dq(40)") )
				( member ( signalRef "@baseboard_fab2_lib.baseboard_fab2(sch_1):m_g_dq(41)") )
				( member ( signalRef "@baseboard_fab2_lib.baseboard_fab2(sch_1):m_g_dq(42)") )
				( member ( signalRef "@baseboard_fab2_lib.baseboard_fab2(sch_1):m_g_dq(43)") )
				( member ( signalRef "@baseboard_fab2_lib.baseboard_fab2(sch_1):m_g_dq(44)") )
				( member ( signalRef "@baseboard_fab2_lib.baseboard_fab2(sch_1):m_g_dq(45)") )
				( member ( signalRef "@baseboard_fab2_lib.baseboard_fab2(sch_1):m_g_dq(46)") )
				( member ( signalRef "@baseboard_fab2_lib.baseboard_fab2(sch_1):m_g_dq(47)") )
				( member ( signalRef "@baseboard_fab2_lib.baseboard_fab2(sch_1):m_g_dq(48)") )
				( member ( signalRef "@baseboard_fab2_lib.baseboard_fab2(sch_1):m_g_dq(49)") )
				( member ( signalRef "@baseboard_fab2_lib.baseboard_fab2(sch_1):m_g_dq(50)") )
				( member ( signalRef "@baseboard_fab2_lib.baseboard_fab2(sch_1):m_g_dq(51)") )
				( member ( signalRef "@baseboard_fab2_lib.baseboard_fab2(sch_1):m_g_dq(52)") )
				( member ( signalRef "@baseboard_fab2_lib.baseboard_fab2(sch_1):m_g_dq(53)") )
				( member ( signalRef "@baseboard_fab2_lib.baseboard_fab2(sch_1):m_g_dq(54)") )
				( member ( signalRef "@baseboard_fab2_lib.baseboard_fab2(sch_1):m_g_dq(55)") )
				( member ( signalRef "@baseboard_fab2_lib.baseboard_fab2(sch_1):m_g_dq(56)") )
				( member ( signalRef "@baseboard_fab2_lib.baseboard_fab2(sch_1):m_g_dq(57)") )
				( member ( signalRef "@baseboard_fab2_lib.baseboard_fab2(sch_1):m_g_dq(58)") )
				( member ( signalRef "@baseboard_fab2_lib.baseboard_fab2(sch_1):m_g_dq(59)") )
				( member ( signalRef "@baseboard_fab2_lib.baseboard_fab2(sch_1):m_g_dq(60)") )
				( member ( signalRef "@baseboard_fab2_lib.baseboard_fab2(sch_1):m_g_dq(61)") )
				( member ( signalRef "@baseboard_fab2_lib.baseboard_fab2(sch_1):m_g_dq(62)") )
				( member ( signalRef "@baseboard_fab2_lib.baseboard_fab2(sch_1):m_g_dq(63)") )
				( objectStatus "M_G_DQ" )
			)
			( bus "@crescent_city_bb_fab1_lib.crescent_city_bb_fab1(sch_1):m_g_cs_n"
				( memberType ( signal ) )
				( member ( signalRef "@baseboard_fab2_lib.baseboard_fab2(sch_1):m_g_cs_n(0)") )
				( member ( signalRef "@baseboard_fab2_lib.baseboard_fab2(sch_1):m_g_cs_n(1)") )
				( member ( signalRef "@baseboard_fab2_lib.baseboard_fab2(sch_1):m_g_cs_n(2)") )
				( member ( signalRef "@baseboard_fab2_lib.baseboard_fab2(sch_1):m_g_cs_n(3)") )
				( member ( signalRef "@baseboard_fab2_lib.baseboard_fab2(sch_1):m_g_cs_n(4)") )
				( member ( signalRef "@baseboard_fab2_lib.baseboard_fab2(sch_1):m_g_cs_n(5)") )
				( member ( signalRef "@baseboard_fab2_lib.baseboard_fab2(sch_1):m_g_cs_n(6)") )
				( member ( signalRef "@baseboard_fab2_lib.baseboard_fab2(sch_1):m_g_cs_n(7)") )
				( objectStatus "M_G_CS_N" )
			)
			( bus "@crescent_city_bb_fab1_lib.crescent_city_bb_fab1(sch_1):m_g_clk_dp"
				( memberType ( signal ) )
				( member ( signalRef "@baseboard_fab2_lib.baseboard_fab2(sch_1):m_g_clk_dp(0)") )
				( member ( signalRef "@baseboard_fab2_lib.baseboard_fab2(sch_1):m_g_clk_dp(2)") )
				( member ( signalRef "@baseboard_fab2_lib.baseboard_fab2(sch_1):m_g_clk_dp(1)") )
				( member ( signalRef "@baseboard_fab2_lib.baseboard_fab2(sch_1):m_g_clk_dp(3)") )
				( objectStatus "M_G_CLK_DP" )
			)
			( bus "@crescent_city_bb_fab1_lib.crescent_city_bb_fab1(sch_1):m_g_clk_dn"
				( memberType ( signal ) )
				( member ( signalRef "@baseboard_fab2_lib.baseboard_fab2(sch_1):m_g_clk_dn(0)") )
				( member ( signalRef "@baseboard_fab2_lib.baseboard_fab2(sch_1):m_g_clk_dn(2)") )
				( member ( signalRef "@baseboard_fab2_lib.baseboard_fab2(sch_1):m_g_clk_dn(1)") )
				( member ( signalRef "@baseboard_fab2_lib.baseboard_fab2(sch_1):m_g_clk_dn(3)") )
				( objectStatus "M_G_CLK_DN" )
			)
			( bus "@crescent_city_bb_fab1_lib.crescent_city_bb_fab1(sch_1):m_g_cke"
				( memberType ( signal ) )
				( member ( signalRef "@baseboard_fab2_lib.baseboard_fab2(sch_1):m_g_cke(0)") )
				( member ( signalRef "@baseboard_fab2_lib.baseboard_fab2(sch_1):m_g_cke(1)") )
				( member ( signalRef "@baseboard_fab2_lib.baseboard_fab2(sch_1):m_g_cke(2)") )
				( member ( signalRef "@baseboard_fab2_lib.baseboard_fab2(sch_1):m_g_cke(3)") )
				( objectStatus "M_G_CKE" )
			)
			( bus "@crescent_city_bb_fab1_lib.crescent_city_bb_fab1(sch_1):m_g_c"
				( memberType ( signal ) )
				( member ( signalRef "@baseboard_fab2_lib.baseboard_fab2(sch_1):m_g_c(2)") )
				( objectStatus "M_G_C" )
			)
			( bus "@crescent_city_bb_fab1_lib.crescent_city_bb_fab1(sch_1):m_g_bg"
				( memberType ( signal ) )
				( member ( signalRef "@baseboard_fab2_lib.baseboard_fab2(sch_1):m_g_bg(0)") )
				( member ( signalRef "@baseboard_fab2_lib.baseboard_fab2(sch_1):m_g_bg(1)") )
				( objectStatus "M_G_BG" )
			)
			( bus "@crescent_city_bb_fab1_lib.crescent_city_bb_fab1(sch_1):m_g_ba"
				( memberType ( signal ) )
				( member ( signalRef "@baseboard_fab2_lib.baseboard_fab2(sch_1):m_g_ba(0)") )
				( member ( signalRef "@baseboard_fab2_lib.baseboard_fab2(sch_1):m_g_ba(1)") )
				( objectStatus "M_G_BA" )
			)
			( bus "@crescent_city_bb_fab1_lib.crescent_city_bb_fab1(sch_1):m_f_odt"
				( memberType ( signal ) )
				( member ( signalRef "@baseboard_fab2_lib.baseboard_fab2(sch_1):m_f_odt(0)") )
				( member ( signalRef "@baseboard_fab2_lib.baseboard_fab2(sch_1):m_f_odt(1)") )
				( member ( signalRef "@baseboard_fab2_lib.baseboard_fab2(sch_1):m_f_odt(2)") )
				( member ( signalRef "@baseboard_fab2_lib.baseboard_fab2(sch_1):m_f_odt(3)") )
				( objectStatus "M_F_ODT" )
			)
			( bus "@crescent_city_bb_fab1_lib.crescent_city_bb_fab1(sch_1):m_f_ma"
				( memberType ( signal ) )
				( member ( signalRef "@baseboard_fab2_lib.baseboard_fab2(sch_1):m_f_ma(0)") )
				( member ( signalRef "@baseboard_fab2_lib.baseboard_fab2(sch_1):m_f_ma(1)") )
				( member ( signalRef "@baseboard_fab2_lib.baseboard_fab2(sch_1):m_f_ma(2)") )
				( member ( signalRef "@baseboard_fab2_lib.baseboard_fab2(sch_1):m_f_ma(3)") )
				( member ( signalRef "@baseboard_fab2_lib.baseboard_fab2(sch_1):m_f_ma(4)") )
				( member ( signalRef "@baseboard_fab2_lib.baseboard_fab2(sch_1):m_f_ma(5)") )
				( member ( signalRef "@baseboard_fab2_lib.baseboard_fab2(sch_1):m_f_ma(6)") )
				( member ( signalRef "@baseboard_fab2_lib.baseboard_fab2(sch_1):m_f_ma(7)") )
				( member ( signalRef "@baseboard_fab2_lib.baseboard_fab2(sch_1):m_f_ma(8)") )
				( member ( signalRef "@baseboard_fab2_lib.baseboard_fab2(sch_1):m_f_ma(9)") )
				( member ( signalRef "@baseboard_fab2_lib.baseboard_fab2(sch_1):m_f_ma(10)") )
				( member ( signalRef "@baseboard_fab2_lib.baseboard_fab2(sch_1):m_f_ma(11)") )
				( member ( signalRef "@baseboard_fab2_lib.baseboard_fab2(sch_1):m_f_ma(12)") )
				( member ( signalRef "@baseboard_fab2_lib.baseboard_fab2(sch_1):m_f_ma(13)") )
				( member ( signalRef "@baseboard_fab2_lib.baseboard_fab2(sch_1):m_f_ma(14)") )
				( member ( signalRef "@baseboard_fab2_lib.baseboard_fab2(sch_1):m_f_ma(15)") )
				( member ( signalRef "@baseboard_fab2_lib.baseboard_fab2(sch_1):m_f_ma(16)") )
				( member ( signalRef "@baseboard_fab2_lib.baseboard_fab2(sch_1):m_f_ma(17)") )
				( objectStatus "M_F_MA" )
			)
			( bus "@crescent_city_bb_fab1_lib.crescent_city_bb_fab1(sch_1):m_f_ecc"
				( memberType ( signal ) )
				( member ( signalRef "@baseboard_fab2_lib.baseboard_fab2(sch_1):m_f_ecc(0)") )
				( member ( signalRef "@baseboard_fab2_lib.baseboard_fab2(sch_1):m_f_ecc(1)") )
				( member ( signalRef "@baseboard_fab2_lib.baseboard_fab2(sch_1):m_f_ecc(2)") )
				( member ( signalRef "@baseboard_fab2_lib.baseboard_fab2(sch_1):m_f_ecc(3)") )
				( member ( signalRef "@baseboard_fab2_lib.baseboard_fab2(sch_1):m_f_ecc(4)") )
				( member ( signalRef "@baseboard_fab2_lib.baseboard_fab2(sch_1):m_f_ecc(5)") )
				( member ( signalRef "@baseboard_fab2_lib.baseboard_fab2(sch_1):m_f_ecc(6)") )
				( member ( signalRef "@baseboard_fab2_lib.baseboard_fab2(sch_1):m_f_ecc(7)") )
				( objectStatus "M_F_ECC" )
			)
			( bus "@crescent_city_bb_fab1_lib.crescent_city_bb_fab1(sch_1):m_f_dqs_dp"
				( memberType ( signal ) )
				( member ( signalRef "@baseboard_fab2_lib.baseboard_fab2(sch_1):m_f_dqs_dp(0)") )
				( member ( signalRef "@baseboard_fab2_lib.baseboard_fab2(sch_1):m_f_dqs_dp(1)") )
				( member ( signalRef "@baseboard_fab2_lib.baseboard_fab2(sch_1):m_f_dqs_dp(2)") )
				( member ( signalRef "@baseboard_fab2_lib.baseboard_fab2(sch_1):m_f_dqs_dp(3)") )
				( member ( signalRef "@baseboard_fab2_lib.baseboard_fab2(sch_1):m_f_dqs_dp(4)") )
				( member ( signalRef "@baseboard_fab2_lib.baseboard_fab2(sch_1):m_f_dqs_dp(5)") )
				( member ( signalRef "@baseboard_fab2_lib.baseboard_fab2(sch_1):m_f_dqs_dp(6)") )
				( member ( signalRef "@baseboard_fab2_lib.baseboard_fab2(sch_1):m_f_dqs_dp(7)") )
				( member ( signalRef "@baseboard_fab2_lib.baseboard_fab2(sch_1):m_f_dqs_dp(8)") )
				( member ( signalRef "@baseboard_fab2_lib.baseboard_fab2(sch_1):m_f_dqs_dp(9)") )
				( member ( signalRef "@baseboard_fab2_lib.baseboard_fab2(sch_1):m_f_dqs_dp(10)") )
				( member ( signalRef "@baseboard_fab2_lib.baseboard_fab2(sch_1):m_f_dqs_dp(11)") )
				( member ( signalRef "@baseboard_fab2_lib.baseboard_fab2(sch_1):m_f_dqs_dp(12)") )
				( member ( signalRef "@baseboard_fab2_lib.baseboard_fab2(sch_1):m_f_dqs_dp(13)") )
				( member ( signalRef "@baseboard_fab2_lib.baseboard_fab2(sch_1):m_f_dqs_dp(14)") )
				( member ( signalRef "@baseboard_fab2_lib.baseboard_fab2(sch_1):m_f_dqs_dp(15)") )
				( member ( signalRef "@baseboard_fab2_lib.baseboard_fab2(sch_1):m_f_dqs_dp(16)") )
				( member ( signalRef "@baseboard_fab2_lib.baseboard_fab2(sch_1):m_f_dqs_dp(17)") )
				( objectStatus "M_F_DQS_DP" )
			)
			( bus "@crescent_city_bb_fab1_lib.crescent_city_bb_fab1(sch_1):m_f_dqs_dn"
				( memberType ( signal ) )
				( member ( signalRef "@baseboard_fab2_lib.baseboard_fab2(sch_1):m_f_dqs_dn(0)") )
				( member ( signalRef "@baseboard_fab2_lib.baseboard_fab2(sch_1):m_f_dqs_dn(1)") )
				( member ( signalRef "@baseboard_fab2_lib.baseboard_fab2(sch_1):m_f_dqs_dn(2)") )
				( member ( signalRef "@baseboard_fab2_lib.baseboard_fab2(sch_1):m_f_dqs_dn(3)") )
				( member ( signalRef "@baseboard_fab2_lib.baseboard_fab2(sch_1):m_f_dqs_dn(4)") )
				( member ( signalRef "@baseboard_fab2_lib.baseboard_fab2(sch_1):m_f_dqs_dn(5)") )
				( member ( signalRef "@baseboard_fab2_lib.baseboard_fab2(sch_1):m_f_dqs_dn(6)") )
				( member ( signalRef "@baseboard_fab2_lib.baseboard_fab2(sch_1):m_f_dqs_dn(7)") )
				( member ( signalRef "@baseboard_fab2_lib.baseboard_fab2(sch_1):m_f_dqs_dn(8)") )
				( member ( signalRef "@baseboard_fab2_lib.baseboard_fab2(sch_1):m_f_dqs_dn(9)") )
				( member ( signalRef "@baseboard_fab2_lib.baseboard_fab2(sch_1):m_f_dqs_dn(10)") )
				( member ( signalRef "@baseboard_fab2_lib.baseboard_fab2(sch_1):m_f_dqs_dn(11)") )
				( member ( signalRef "@baseboard_fab2_lib.baseboard_fab2(sch_1):m_f_dqs_dn(12)") )
				( member ( signalRef "@baseboard_fab2_lib.baseboard_fab2(sch_1):m_f_dqs_dn(13)") )
				( member ( signalRef "@baseboard_fab2_lib.baseboard_fab2(sch_1):m_f_dqs_dn(14)") )
				( member ( signalRef "@baseboard_fab2_lib.baseboard_fab2(sch_1):m_f_dqs_dn(15)") )
				( member ( signalRef "@baseboard_fab2_lib.baseboard_fab2(sch_1):m_f_dqs_dn(16)") )
				( member ( signalRef "@baseboard_fab2_lib.baseboard_fab2(sch_1):m_f_dqs_dn(17)") )
				( objectStatus "M_F_DQS_DN" )
			)
			( bus "@crescent_city_bb_fab1_lib.crescent_city_bb_fab1(sch_1):m_f_dq"
				( memberType ( signal ) )
				( member ( signalRef "@baseboard_fab2_lib.baseboard_fab2(sch_1):m_f_dq(0)") )
				( member ( signalRef "@baseboard_fab2_lib.baseboard_fab2(sch_1):m_f_dq(1)") )
				( member ( signalRef "@baseboard_fab2_lib.baseboard_fab2(sch_1):m_f_dq(2)") )
				( member ( signalRef "@baseboard_fab2_lib.baseboard_fab2(sch_1):m_f_dq(3)") )
				( member ( signalRef "@baseboard_fab2_lib.baseboard_fab2(sch_1):m_f_dq(4)") )
				( member ( signalRef "@baseboard_fab2_lib.baseboard_fab2(sch_1):m_f_dq(5)") )
				( member ( signalRef "@baseboard_fab2_lib.baseboard_fab2(sch_1):m_f_dq(6)") )
				( member ( signalRef "@baseboard_fab2_lib.baseboard_fab2(sch_1):m_f_dq(7)") )
				( member ( signalRef "@baseboard_fab2_lib.baseboard_fab2(sch_1):m_f_dq(8)") )
				( member ( signalRef "@baseboard_fab2_lib.baseboard_fab2(sch_1):m_f_dq(9)") )
				( member ( signalRef "@baseboard_fab2_lib.baseboard_fab2(sch_1):m_f_dq(10)") )
				( member ( signalRef "@baseboard_fab2_lib.baseboard_fab2(sch_1):m_f_dq(11)") )
				( member ( signalRef "@baseboard_fab2_lib.baseboard_fab2(sch_1):m_f_dq(12)") )
				( member ( signalRef "@baseboard_fab2_lib.baseboard_fab2(sch_1):m_f_dq(13)") )
				( member ( signalRef "@baseboard_fab2_lib.baseboard_fab2(sch_1):m_f_dq(14)") )
				( member ( signalRef "@baseboard_fab2_lib.baseboard_fab2(sch_1):m_f_dq(15)") )
				( member ( signalRef "@baseboard_fab2_lib.baseboard_fab2(sch_1):m_f_dq(16)") )
				( member ( signalRef "@baseboard_fab2_lib.baseboard_fab2(sch_1):m_f_dq(17)") )
				( member ( signalRef "@baseboard_fab2_lib.baseboard_fab2(sch_1):m_f_dq(18)") )
				( member ( signalRef "@baseboard_fab2_lib.baseboard_fab2(sch_1):m_f_dq(19)") )
				( member ( signalRef "@baseboard_fab2_lib.baseboard_fab2(sch_1):m_f_dq(20)") )
				( member ( signalRef "@baseboard_fab2_lib.baseboard_fab2(sch_1):m_f_dq(21)") )
				( member ( signalRef "@baseboard_fab2_lib.baseboard_fab2(sch_1):m_f_dq(22)") )
				( member ( signalRef "@baseboard_fab2_lib.baseboard_fab2(sch_1):m_f_dq(23)") )
				( member ( signalRef "@baseboard_fab2_lib.baseboard_fab2(sch_1):m_f_dq(24)") )
				( member ( signalRef "@baseboard_fab2_lib.baseboard_fab2(sch_1):m_f_dq(25)") )
				( member ( signalRef "@baseboard_fab2_lib.baseboard_fab2(sch_1):m_f_dq(26)") )
				( member ( signalRef "@baseboard_fab2_lib.baseboard_fab2(sch_1):m_f_dq(27)") )
				( member ( signalRef "@baseboard_fab2_lib.baseboard_fab2(sch_1):m_f_dq(28)") )
				( member ( signalRef "@baseboard_fab2_lib.baseboard_fab2(sch_1):m_f_dq(29)") )
				( member ( signalRef "@baseboard_fab2_lib.baseboard_fab2(sch_1):m_f_dq(30)") )
				( member ( signalRef "@baseboard_fab2_lib.baseboard_fab2(sch_1):m_f_dq(31)") )
				( member ( signalRef "@baseboard_fab2_lib.baseboard_fab2(sch_1):m_f_dq(32)") )
				( member ( signalRef "@baseboard_fab2_lib.baseboard_fab2(sch_1):m_f_dq(33)") )
				( member ( signalRef "@baseboard_fab2_lib.baseboard_fab2(sch_1):m_f_dq(34)") )
				( member ( signalRef "@baseboard_fab2_lib.baseboard_fab2(sch_1):m_f_dq(35)") )
				( member ( signalRef "@baseboard_fab2_lib.baseboard_fab2(sch_1):m_f_dq(36)") )
				( member ( signalRef "@baseboard_fab2_lib.baseboard_fab2(sch_1):m_f_dq(37)") )
				( member ( signalRef "@baseboard_fab2_lib.baseboard_fab2(sch_1):m_f_dq(38)") )
				( member ( signalRef "@baseboard_fab2_lib.baseboard_fab2(sch_1):m_f_dq(39)") )
				( member ( signalRef "@baseboard_fab2_lib.baseboard_fab2(sch_1):m_f_dq(40)") )
				( member ( signalRef "@baseboard_fab2_lib.baseboard_fab2(sch_1):m_f_dq(41)") )
				( member ( signalRef "@baseboard_fab2_lib.baseboard_fab2(sch_1):m_f_dq(42)") )
				( member ( signalRef "@baseboard_fab2_lib.baseboard_fab2(sch_1):m_f_dq(43)") )
				( member ( signalRef "@baseboard_fab2_lib.baseboard_fab2(sch_1):m_f_dq(44)") )
				( member ( signalRef "@baseboard_fab2_lib.baseboard_fab2(sch_1):m_f_dq(45)") )
				( member ( signalRef "@baseboard_fab2_lib.baseboard_fab2(sch_1):m_f_dq(46)") )
				( member ( signalRef "@baseboard_fab2_lib.baseboard_fab2(sch_1):m_f_dq(47)") )
				( member ( signalRef "@baseboard_fab2_lib.baseboard_fab2(sch_1):m_f_dq(48)") )
				( member ( signalRef "@baseboard_fab2_lib.baseboard_fab2(sch_1):m_f_dq(49)") )
				( member ( signalRef "@baseboard_fab2_lib.baseboard_fab2(sch_1):m_f_dq(50)") )
				( member ( signalRef "@baseboard_fab2_lib.baseboard_fab2(sch_1):m_f_dq(51)") )
				( member ( signalRef "@baseboard_fab2_lib.baseboard_fab2(sch_1):m_f_dq(52)") )
				( member ( signalRef "@baseboard_fab2_lib.baseboard_fab2(sch_1):m_f_dq(53)") )
				( member ( signalRef "@baseboard_fab2_lib.baseboard_fab2(sch_1):m_f_dq(54)") )
				( member ( signalRef "@baseboard_fab2_lib.baseboard_fab2(sch_1):m_f_dq(55)") )
				( member ( signalRef "@baseboard_fab2_lib.baseboard_fab2(sch_1):m_f_dq(56)") )
				( member ( signalRef "@baseboard_fab2_lib.baseboard_fab2(sch_1):m_f_dq(57)") )
				( member ( signalRef "@baseboard_fab2_lib.baseboard_fab2(sch_1):m_f_dq(58)") )
				( member ( signalRef "@baseboard_fab2_lib.baseboard_fab2(sch_1):m_f_dq(59)") )
				( member ( signalRef "@baseboard_fab2_lib.baseboard_fab2(sch_1):m_f_dq(60)") )
				( member ( signalRef "@baseboard_fab2_lib.baseboard_fab2(sch_1):m_f_dq(61)") )
				( member ( signalRef "@baseboard_fab2_lib.baseboard_fab2(sch_1):m_f_dq(62)") )
				( member ( signalRef "@baseboard_fab2_lib.baseboard_fab2(sch_1):m_f_dq(63)") )
				( objectStatus "M_F_DQ" )
			)
			( bus "@crescent_city_bb_fab1_lib.crescent_city_bb_fab1(sch_1):m_f_cs_n"
				( memberType ( signal ) )
				( member ( signalRef "@baseboard_fab2_lib.baseboard_fab2(sch_1):m_f_cs_n(0)") )
				( member ( signalRef "@baseboard_fab2_lib.baseboard_fab2(sch_1):m_f_cs_n(1)") )
				( member ( signalRef "@baseboard_fab2_lib.baseboard_fab2(sch_1):m_f_cs_n(2)") )
				( member ( signalRef "@baseboard_fab2_lib.baseboard_fab2(sch_1):m_f_cs_n(3)") )
				( member ( signalRef "@baseboard_fab2_lib.baseboard_fab2(sch_1):m_f_cs_n(4)") )
				( member ( signalRef "@baseboard_fab2_lib.baseboard_fab2(sch_1):m_f_cs_n(5)") )
				( member ( signalRef "@baseboard_fab2_lib.baseboard_fab2(sch_1):m_f_cs_n(6)") )
				( member ( signalRef "@baseboard_fab2_lib.baseboard_fab2(sch_1):m_f_cs_n(7)") )
				( objectStatus "M_F_CS_N" )
			)
			( bus "@crescent_city_bb_fab1_lib.crescent_city_bb_fab1(sch_1):m_f_clk_dp"
				( memberType ( signal ) )
				( member ( signalRef "@baseboard_fab2_lib.baseboard_fab2(sch_1):m_f_clk_dp(0)") )
				( member ( signalRef "@baseboard_fab2_lib.baseboard_fab2(sch_1):m_f_clk_dp(1)") )
				( member ( signalRef "@baseboard_fab2_lib.baseboard_fab2(sch_1):m_f_clk_dp(2)") )
				( member ( signalRef "@baseboard_fab2_lib.baseboard_fab2(sch_1):m_f_clk_dp(3)") )
				( objectStatus "M_F_CLK_DP" )
			)
			( bus "@crescent_city_bb_fab1_lib.crescent_city_bb_fab1(sch_1):m_f_clk_dn"
				( memberType ( signal ) )
				( member ( signalRef "@baseboard_fab2_lib.baseboard_fab2(sch_1):m_f_clk_dn(0)") )
				( member ( signalRef "@baseboard_fab2_lib.baseboard_fab2(sch_1):m_f_clk_dn(1)") )
				( member ( signalRef "@baseboard_fab2_lib.baseboard_fab2(sch_1):m_f_clk_dn(2)") )
				( member ( signalRef "@baseboard_fab2_lib.baseboard_fab2(sch_1):m_f_clk_dn(3)") )
				( objectStatus "M_F_CLK_DN" )
			)
			( bus "@crescent_city_bb_fab1_lib.crescent_city_bb_fab1(sch_1):m_f_cke"
				( memberType ( signal ) )
				( member ( signalRef "@baseboard_fab2_lib.baseboard_fab2(sch_1):m_f_cke(0)") )
				( member ( signalRef "@baseboard_fab2_lib.baseboard_fab2(sch_1):m_f_cke(1)") )
				( member ( signalRef "@baseboard_fab2_lib.baseboard_fab2(sch_1):m_f_cke(2)") )
				( member ( signalRef "@baseboard_fab2_lib.baseboard_fab2(sch_1):m_f_cke(3)") )
				( objectStatus "M_F_CKE" )
			)
			( bus "@crescent_city_bb_fab1_lib.crescent_city_bb_fab1(sch_1):m_f_c"
				( memberType ( signal ) )
				( member ( signalRef "@baseboard_fab2_lib.baseboard_fab2(sch_1):m_f_c(2)") )
				( objectStatus "M_F_C" )
			)
			( bus "@crescent_city_bb_fab1_lib.crescent_city_bb_fab1(sch_1):m_f_bg"
				( memberType ( signal ) )
				( member ( signalRef "@baseboard_fab2_lib.baseboard_fab2(sch_1):m_f_bg(0)") )
				( member ( signalRef "@baseboard_fab2_lib.baseboard_fab2(sch_1):m_f_bg(1)") )
				( objectStatus "M_F_BG" )
			)
			( bus "@crescent_city_bb_fab1_lib.crescent_city_bb_fab1(sch_1):m_f_ba"
				( memberType ( signal ) )
				( member ( signalRef "@baseboard_fab2_lib.baseboard_fab2(sch_1):m_f_ba(0)") )
				( member ( signalRef "@baseboard_fab2_lib.baseboard_fab2(sch_1):m_f_ba(1)") )
				( objectStatus "M_F_BA" )
			)
			( bus "@crescent_city_bb_fab1_lib.crescent_city_bb_fab1(sch_1):m_e_odt"
				( memberType ( signal ) )
				( member ( signalRef "@baseboard_fab2_lib.baseboard_fab2(sch_1):m_e_odt(0)") )
				( member ( signalRef "@baseboard_fab2_lib.baseboard_fab2(sch_1):m_e_odt(1)") )
				( member ( signalRef "@baseboard_fab2_lib.baseboard_fab2(sch_1):m_e_odt(2)") )
				( member ( signalRef "@baseboard_fab2_lib.baseboard_fab2(sch_1):m_e_odt(3)") )
				( objectStatus "M_E_ODT" )
			)
			( bus "@crescent_city_bb_fab1_lib.crescent_city_bb_fab1(sch_1):m_e_ma"
				( memberType ( signal ) )
				( member ( signalRef "@baseboard_fab2_lib.baseboard_fab2(sch_1):m_e_ma(0)") )
				( member ( signalRef "@baseboard_fab2_lib.baseboard_fab2(sch_1):m_e_ma(1)") )
				( member ( signalRef "@baseboard_fab2_lib.baseboard_fab2(sch_1):m_e_ma(2)") )
				( member ( signalRef "@baseboard_fab2_lib.baseboard_fab2(sch_1):m_e_ma(3)") )
				( member ( signalRef "@baseboard_fab2_lib.baseboard_fab2(sch_1):m_e_ma(4)") )
				( member ( signalRef "@baseboard_fab2_lib.baseboard_fab2(sch_1):m_e_ma(5)") )
				( member ( signalRef "@baseboard_fab2_lib.baseboard_fab2(sch_1):m_e_ma(6)") )
				( member ( signalRef "@baseboard_fab2_lib.baseboard_fab2(sch_1):m_e_ma(7)") )
				( member ( signalRef "@baseboard_fab2_lib.baseboard_fab2(sch_1):m_e_ma(8)") )
				( member ( signalRef "@baseboard_fab2_lib.baseboard_fab2(sch_1):m_e_ma(9)") )
				( member ( signalRef "@baseboard_fab2_lib.baseboard_fab2(sch_1):m_e_ma(10)") )
				( member ( signalRef "@baseboard_fab2_lib.baseboard_fab2(sch_1):m_e_ma(11)") )
				( member ( signalRef "@baseboard_fab2_lib.baseboard_fab2(sch_1):m_e_ma(12)") )
				( member ( signalRef "@baseboard_fab2_lib.baseboard_fab2(sch_1):m_e_ma(13)") )
				( member ( signalRef "@baseboard_fab2_lib.baseboard_fab2(sch_1):m_e_ma(14)") )
				( member ( signalRef "@baseboard_fab2_lib.baseboard_fab2(sch_1):m_e_ma(15)") )
				( member ( signalRef "@baseboard_fab2_lib.baseboard_fab2(sch_1):m_e_ma(16)") )
				( member ( signalRef "@baseboard_fab2_lib.baseboard_fab2(sch_1):m_e_ma(17)") )
				( objectStatus "M_E_MA" )
			)
			( bus "@crescent_city_bb_fab1_lib.crescent_city_bb_fab1(sch_1):m_e_ecc"
				( memberType ( signal ) )
				( member ( signalRef "@baseboard_fab2_lib.baseboard_fab2(sch_1):m_e_ecc(0)") )
				( member ( signalRef "@baseboard_fab2_lib.baseboard_fab2(sch_1):m_e_ecc(1)") )
				( member ( signalRef "@baseboard_fab2_lib.baseboard_fab2(sch_1):m_e_ecc(2)") )
				( member ( signalRef "@baseboard_fab2_lib.baseboard_fab2(sch_1):m_e_ecc(3)") )
				( member ( signalRef "@baseboard_fab2_lib.baseboard_fab2(sch_1):m_e_ecc(4)") )
				( member ( signalRef "@baseboard_fab2_lib.baseboard_fab2(sch_1):m_e_ecc(5)") )
				( member ( signalRef "@baseboard_fab2_lib.baseboard_fab2(sch_1):m_e_ecc(6)") )
				( member ( signalRef "@baseboard_fab2_lib.baseboard_fab2(sch_1):m_e_ecc(7)") )
				( objectStatus "M_E_ECC" )
			)
			( bus "@crescent_city_bb_fab1_lib.crescent_city_bb_fab1(sch_1):m_e_dqs_dp"
				( memberType ( signal ) )
				( member ( signalRef "@baseboard_fab2_lib.baseboard_fab2(sch_1):m_e_dqs_dp(0)") )
				( member ( signalRef "@baseboard_fab2_lib.baseboard_fab2(sch_1):m_e_dqs_dp(1)") )
				( member ( signalRef "@baseboard_fab2_lib.baseboard_fab2(sch_1):m_e_dqs_dp(2)") )
				( member ( signalRef "@baseboard_fab2_lib.baseboard_fab2(sch_1):m_e_dqs_dp(3)") )
				( member ( signalRef "@baseboard_fab2_lib.baseboard_fab2(sch_1):m_e_dqs_dp(4)") )
				( member ( signalRef "@baseboard_fab2_lib.baseboard_fab2(sch_1):m_e_dqs_dp(5)") )
				( member ( signalRef "@baseboard_fab2_lib.baseboard_fab2(sch_1):m_e_dqs_dp(6)") )
				( member ( signalRef "@baseboard_fab2_lib.baseboard_fab2(sch_1):m_e_dqs_dp(7)") )
				( member ( signalRef "@baseboard_fab2_lib.baseboard_fab2(sch_1):m_e_dqs_dp(8)") )
				( member ( signalRef "@baseboard_fab2_lib.baseboard_fab2(sch_1):m_e_dqs_dp(9)") )
				( member ( signalRef "@baseboard_fab2_lib.baseboard_fab2(sch_1):m_e_dqs_dp(10)") )
				( member ( signalRef "@baseboard_fab2_lib.baseboard_fab2(sch_1):m_e_dqs_dp(11)") )
				( member ( signalRef "@baseboard_fab2_lib.baseboard_fab2(sch_1):m_e_dqs_dp(12)") )
				( member ( signalRef "@baseboard_fab2_lib.baseboard_fab2(sch_1):m_e_dqs_dp(13)") )
				( member ( signalRef "@baseboard_fab2_lib.baseboard_fab2(sch_1):m_e_dqs_dp(14)") )
				( member ( signalRef "@baseboard_fab2_lib.baseboard_fab2(sch_1):m_e_dqs_dp(15)") )
				( member ( signalRef "@baseboard_fab2_lib.baseboard_fab2(sch_1):m_e_dqs_dp(16)") )
				( member ( signalRef "@baseboard_fab2_lib.baseboard_fab2(sch_1):m_e_dqs_dp(17)") )
				( objectStatus "M_E_DQS_DP" )
			)
			( bus "@crescent_city_bb_fab1_lib.crescent_city_bb_fab1(sch_1):m_e_dqs_dn"
				( memberType ( signal ) )
				( member ( signalRef "@baseboard_fab2_lib.baseboard_fab2(sch_1):m_e_dqs_dn(0)") )
				( member ( signalRef "@baseboard_fab2_lib.baseboard_fab2(sch_1):m_e_dqs_dn(1)") )
				( member ( signalRef "@baseboard_fab2_lib.baseboard_fab2(sch_1):m_e_dqs_dn(2)") )
				( member ( signalRef "@baseboard_fab2_lib.baseboard_fab2(sch_1):m_e_dqs_dn(3)") )
				( member ( signalRef "@baseboard_fab2_lib.baseboard_fab2(sch_1):m_e_dqs_dn(4)") )
				( member ( signalRef "@baseboard_fab2_lib.baseboard_fab2(sch_1):m_e_dqs_dn(5)") )
				( member ( signalRef "@baseboard_fab2_lib.baseboard_fab2(sch_1):m_e_dqs_dn(6)") )
				( member ( signalRef "@baseboard_fab2_lib.baseboard_fab2(sch_1):m_e_dqs_dn(7)") )
				( member ( signalRef "@baseboard_fab2_lib.baseboard_fab2(sch_1):m_e_dqs_dn(8)") )
				( member ( signalRef "@baseboard_fab2_lib.baseboard_fab2(sch_1):m_e_dqs_dn(9)") )
				( member ( signalRef "@baseboard_fab2_lib.baseboard_fab2(sch_1):m_e_dqs_dn(10)") )
				( member ( signalRef "@baseboard_fab2_lib.baseboard_fab2(sch_1):m_e_dqs_dn(11)") )
				( member ( signalRef "@baseboard_fab2_lib.baseboard_fab2(sch_1):m_e_dqs_dn(12)") )
				( member ( signalRef "@baseboard_fab2_lib.baseboard_fab2(sch_1):m_e_dqs_dn(13)") )
				( member ( signalRef "@baseboard_fab2_lib.baseboard_fab2(sch_1):m_e_dqs_dn(14)") )
				( member ( signalRef "@baseboard_fab2_lib.baseboard_fab2(sch_1):m_e_dqs_dn(15)") )
				( member ( signalRef "@baseboard_fab2_lib.baseboard_fab2(sch_1):m_e_dqs_dn(16)") )
				( member ( signalRef "@baseboard_fab2_lib.baseboard_fab2(sch_1):m_e_dqs_dn(17)") )
				( objectStatus "M_E_DQS_DN" )
			)
			( bus "@crescent_city_bb_fab1_lib.crescent_city_bb_fab1(sch_1):m_e_dq"
				( memberType ( signal ) )
				( member ( signalRef "@baseboard_fab2_lib.baseboard_fab2(sch_1):m_e_dq(0)") )
				( member ( signalRef "@baseboard_fab2_lib.baseboard_fab2(sch_1):m_e_dq(1)") )
				( member ( signalRef "@baseboard_fab2_lib.baseboard_fab2(sch_1):m_e_dq(2)") )
				( member ( signalRef "@baseboard_fab2_lib.baseboard_fab2(sch_1):m_e_dq(3)") )
				( member ( signalRef "@baseboard_fab2_lib.baseboard_fab2(sch_1):m_e_dq(4)") )
				( member ( signalRef "@baseboard_fab2_lib.baseboard_fab2(sch_1):m_e_dq(5)") )
				( member ( signalRef "@baseboard_fab2_lib.baseboard_fab2(sch_1):m_e_dq(6)") )
				( member ( signalRef "@baseboard_fab2_lib.baseboard_fab2(sch_1):m_e_dq(7)") )
				( member ( signalRef "@baseboard_fab2_lib.baseboard_fab2(sch_1):m_e_dq(8)") )
				( member ( signalRef "@baseboard_fab2_lib.baseboard_fab2(sch_1):m_e_dq(9)") )
				( member ( signalRef "@baseboard_fab2_lib.baseboard_fab2(sch_1):m_e_dq(10)") )
				( member ( signalRef "@baseboard_fab2_lib.baseboard_fab2(sch_1):m_e_dq(11)") )
				( member ( signalRef "@baseboard_fab2_lib.baseboard_fab2(sch_1):m_e_dq(12)") )
				( member ( signalRef "@baseboard_fab2_lib.baseboard_fab2(sch_1):m_e_dq(13)") )
				( member ( signalRef "@baseboard_fab2_lib.baseboard_fab2(sch_1):m_e_dq(14)") )
				( member ( signalRef "@baseboard_fab2_lib.baseboard_fab2(sch_1):m_e_dq(15)") )
				( member ( signalRef "@baseboard_fab2_lib.baseboard_fab2(sch_1):m_e_dq(16)") )
				( member ( signalRef "@baseboard_fab2_lib.baseboard_fab2(sch_1):m_e_dq(17)") )
				( member ( signalRef "@baseboard_fab2_lib.baseboard_fab2(sch_1):m_e_dq(18)") )
				( member ( signalRef "@baseboard_fab2_lib.baseboard_fab2(sch_1):m_e_dq(19)") )
				( member ( signalRef "@baseboard_fab2_lib.baseboard_fab2(sch_1):m_e_dq(20)") )
				( member ( signalRef "@baseboard_fab2_lib.baseboard_fab2(sch_1):m_e_dq(21)") )
				( member ( signalRef "@baseboard_fab2_lib.baseboard_fab2(sch_1):m_e_dq(22)") )
				( member ( signalRef "@baseboard_fab2_lib.baseboard_fab2(sch_1):m_e_dq(23)") )
				( member ( signalRef "@baseboard_fab2_lib.baseboard_fab2(sch_1):m_e_dq(24)") )
				( member ( signalRef "@baseboard_fab2_lib.baseboard_fab2(sch_1):m_e_dq(25)") )
				( member ( signalRef "@baseboard_fab2_lib.baseboard_fab2(sch_1):m_e_dq(26)") )
				( member ( signalRef "@baseboard_fab2_lib.baseboard_fab2(sch_1):m_e_dq(27)") )
				( member ( signalRef "@baseboard_fab2_lib.baseboard_fab2(sch_1):m_e_dq(28)") )
				( member ( signalRef "@baseboard_fab2_lib.baseboard_fab2(sch_1):m_e_dq(29)") )
				( member ( signalRef "@baseboard_fab2_lib.baseboard_fab2(sch_1):m_e_dq(30)") )
				( member ( signalRef "@baseboard_fab2_lib.baseboard_fab2(sch_1):m_e_dq(31)") )
				( member ( signalRef "@baseboard_fab2_lib.baseboard_fab2(sch_1):m_e_dq(32)") )
				( member ( signalRef "@baseboard_fab2_lib.baseboard_fab2(sch_1):m_e_dq(33)") )
				( member ( signalRef "@baseboard_fab2_lib.baseboard_fab2(sch_1):m_e_dq(34)") )
				( member ( signalRef "@baseboard_fab2_lib.baseboard_fab2(sch_1):m_e_dq(35)") )
				( member ( signalRef "@baseboard_fab2_lib.baseboard_fab2(sch_1):m_e_dq(36)") )
				( member ( signalRef "@baseboard_fab2_lib.baseboard_fab2(sch_1):m_e_dq(37)") )
				( member ( signalRef "@baseboard_fab2_lib.baseboard_fab2(sch_1):m_e_dq(38)") )
				( member ( signalRef "@baseboard_fab2_lib.baseboard_fab2(sch_1):m_e_dq(39)") )
				( member ( signalRef "@baseboard_fab2_lib.baseboard_fab2(sch_1):m_e_dq(40)") )
				( member ( signalRef "@baseboard_fab2_lib.baseboard_fab2(sch_1):m_e_dq(41)") )
				( member ( signalRef "@baseboard_fab2_lib.baseboard_fab2(sch_1):m_e_dq(42)") )
				( member ( signalRef "@baseboard_fab2_lib.baseboard_fab2(sch_1):m_e_dq(43)") )
				( member ( signalRef "@baseboard_fab2_lib.baseboard_fab2(sch_1):m_e_dq(44)") )
				( member ( signalRef "@baseboard_fab2_lib.baseboard_fab2(sch_1):m_e_dq(45)") )
				( member ( signalRef "@baseboard_fab2_lib.baseboard_fab2(sch_1):m_e_dq(46)") )
				( member ( signalRef "@baseboard_fab2_lib.baseboard_fab2(sch_1):m_e_dq(47)") )
				( member ( signalRef "@baseboard_fab2_lib.baseboard_fab2(sch_1):m_e_dq(48)") )
				( member ( signalRef "@baseboard_fab2_lib.baseboard_fab2(sch_1):m_e_dq(49)") )
				( member ( signalRef "@baseboard_fab2_lib.baseboard_fab2(sch_1):m_e_dq(50)") )
				( member ( signalRef "@baseboard_fab2_lib.baseboard_fab2(sch_1):m_e_dq(51)") )
				( member ( signalRef "@baseboard_fab2_lib.baseboard_fab2(sch_1):m_e_dq(52)") )
				( member ( signalRef "@baseboard_fab2_lib.baseboard_fab2(sch_1):m_e_dq(53)") )
				( member ( signalRef "@baseboard_fab2_lib.baseboard_fab2(sch_1):m_e_dq(54)") )
				( member ( signalRef "@baseboard_fab2_lib.baseboard_fab2(sch_1):m_e_dq(55)") )
				( member ( signalRef "@baseboard_fab2_lib.baseboard_fab2(sch_1):m_e_dq(56)") )
				( member ( signalRef "@baseboard_fab2_lib.baseboard_fab2(sch_1):m_e_dq(57)") )
				( member ( signalRef "@baseboard_fab2_lib.baseboard_fab2(sch_1):m_e_dq(58)") )
				( member ( signalRef "@baseboard_fab2_lib.baseboard_fab2(sch_1):m_e_dq(59)") )
				( member ( signalRef "@baseboard_fab2_lib.baseboard_fab2(sch_1):m_e_dq(60)") )
				( member ( signalRef "@baseboard_fab2_lib.baseboard_fab2(sch_1):m_e_dq(61)") )
				( member ( signalRef "@baseboard_fab2_lib.baseboard_fab2(sch_1):m_e_dq(62)") )
				( member ( signalRef "@baseboard_fab2_lib.baseboard_fab2(sch_1):m_e_dq(63)") )
				( objectStatus "M_E_DQ" )
			)
			( bus "@crescent_city_bb_fab1_lib.crescent_city_bb_fab1(sch_1):m_e_cs_n"
				( memberType ( signal ) )
				( member ( signalRef "@baseboard_fab2_lib.baseboard_fab2(sch_1):m_e_cs_n(0)") )
				( member ( signalRef "@baseboard_fab2_lib.baseboard_fab2(sch_1):m_e_cs_n(1)") )
				( member ( signalRef "@baseboard_fab2_lib.baseboard_fab2(sch_1):m_e_cs_n(2)") )
				( member ( signalRef "@baseboard_fab2_lib.baseboard_fab2(sch_1):m_e_cs_n(3)") )
				( member ( signalRef "@baseboard_fab2_lib.baseboard_fab2(sch_1):m_e_cs_n(6)") )
				( member ( signalRef "@baseboard_fab2_lib.baseboard_fab2(sch_1):m_e_cs_n(7)") )
				( member ( signalRef "@baseboard_fab2_lib.baseboard_fab2(sch_1):m_e_cs_n(4)") )
				( member ( signalRef "@baseboard_fab2_lib.baseboard_fab2(sch_1):m_e_cs_n(5)") )
				( objectStatus "M_E_CS_N" )
			)
			( bus "@crescent_city_bb_fab1_lib.crescent_city_bb_fab1(sch_1):m_e_clk_dp"
				( memberType ( signal ) )
				( member ( signalRef "@baseboard_fab2_lib.baseboard_fab2(sch_1):m_e_clk_dp(0)") )
				( member ( signalRef "@baseboard_fab2_lib.baseboard_fab2(sch_1):m_e_clk_dp(2)") )
				( member ( signalRef "@baseboard_fab2_lib.baseboard_fab2(sch_1):m_e_clk_dp(1)") )
				( member ( signalRef "@baseboard_fab2_lib.baseboard_fab2(sch_1):m_e_clk_dp(3)") )
				( objectStatus "M_E_CLK_DP" )
			)
			( bus "@crescent_city_bb_fab1_lib.crescent_city_bb_fab1(sch_1):m_e_clk_dn"
				( memberType ( signal ) )
				( member ( signalRef "@baseboard_fab2_lib.baseboard_fab2(sch_1):m_e_clk_dn(0)") )
				( member ( signalRef "@baseboard_fab2_lib.baseboard_fab2(sch_1):m_e_clk_dn(2)") )
				( member ( signalRef "@baseboard_fab2_lib.baseboard_fab2(sch_1):m_e_clk_dn(1)") )
				( member ( signalRef "@baseboard_fab2_lib.baseboard_fab2(sch_1):m_e_clk_dn(3)") )
				( objectStatus "M_E_CLK_DN" )
			)
			( bus "@crescent_city_bb_fab1_lib.crescent_city_bb_fab1(sch_1):m_e_cke"
				( memberType ( signal ) )
				( member ( signalRef "@baseboard_fab2_lib.baseboard_fab2(sch_1):m_e_cke(0)") )
				( member ( signalRef "@baseboard_fab2_lib.baseboard_fab2(sch_1):m_e_cke(1)") )
				( member ( signalRef "@baseboard_fab2_lib.baseboard_fab2(sch_1):m_e_cke(2)") )
				( member ( signalRef "@baseboard_fab2_lib.baseboard_fab2(sch_1):m_e_cke(3)") )
				( objectStatus "M_E_CKE" )
			)
			( bus "@crescent_city_bb_fab1_lib.crescent_city_bb_fab1(sch_1):m_e_c"
				( memberType ( signal ) )
				( member ( signalRef "@baseboard_fab2_lib.baseboard_fab2(sch_1):m_e_c(2)") )
				( objectStatus "M_E_C" )
			)
			( bus "@crescent_city_bb_fab1_lib.crescent_city_bb_fab1(sch_1):m_e_bg"
				( memberType ( signal ) )
				( member ( signalRef "@baseboard_fab2_lib.baseboard_fab2(sch_1):m_e_bg(0)") )
				( member ( signalRef "@baseboard_fab2_lib.baseboard_fab2(sch_1):m_e_bg(1)") )
				( objectStatus "M_E_BG" )
			)
			( bus "@crescent_city_bb_fab1_lib.crescent_city_bb_fab1(sch_1):m_e_ba"
				( memberType ( signal ) )
				( member ( signalRef "@baseboard_fab2_lib.baseboard_fab2(sch_1):m_e_ba(0)") )
				( member ( signalRef "@baseboard_fab2_lib.baseboard_fab2(sch_1):m_e_ba(1)") )
				( objectStatus "M_E_BA" )
			)
			( bus "@crescent_city_bb_fab1_lib.crescent_city_bb_fab1(sch_1):m_d_odt"
				( memberType ( signal ) )
				( member ( signalRef "@baseboard_fab2_lib.baseboard_fab2(sch_1):m_d_odt(0)") )
				( member ( signalRef "@baseboard_fab2_lib.baseboard_fab2(sch_1):m_d_odt(1)") )
				( member ( signalRef "@baseboard_fab2_lib.baseboard_fab2(sch_1):m_d_odt(2)") )
				( member ( signalRef "@baseboard_fab2_lib.baseboard_fab2(sch_1):m_d_odt(3)") )
				( objectStatus "M_D_ODT" )
			)
			( bus "@crescent_city_bb_fab1_lib.crescent_city_bb_fab1(sch_1):m_d_ma"
				( memberType ( signal ) )
				( member ( signalRef "@baseboard_fab2_lib.baseboard_fab2(sch_1):m_d_ma(0)") )
				( member ( signalRef "@baseboard_fab2_lib.baseboard_fab2(sch_1):m_d_ma(1)") )
				( member ( signalRef "@baseboard_fab2_lib.baseboard_fab2(sch_1):m_d_ma(2)") )
				( member ( signalRef "@baseboard_fab2_lib.baseboard_fab2(sch_1):m_d_ma(3)") )
				( member ( signalRef "@baseboard_fab2_lib.baseboard_fab2(sch_1):m_d_ma(4)") )
				( member ( signalRef "@baseboard_fab2_lib.baseboard_fab2(sch_1):m_d_ma(5)") )
				( member ( signalRef "@baseboard_fab2_lib.baseboard_fab2(sch_1):m_d_ma(6)") )
				( member ( signalRef "@baseboard_fab2_lib.baseboard_fab2(sch_1):m_d_ma(7)") )
				( member ( signalRef "@baseboard_fab2_lib.baseboard_fab2(sch_1):m_d_ma(8)") )
				( member ( signalRef "@baseboard_fab2_lib.baseboard_fab2(sch_1):m_d_ma(9)") )
				( member ( signalRef "@baseboard_fab2_lib.baseboard_fab2(sch_1):m_d_ma(10)") )
				( member ( signalRef "@baseboard_fab2_lib.baseboard_fab2(sch_1):m_d_ma(11)") )
				( member ( signalRef "@baseboard_fab2_lib.baseboard_fab2(sch_1):m_d_ma(12)") )
				( member ( signalRef "@baseboard_fab2_lib.baseboard_fab2(sch_1):m_d_ma(13)") )
				( member ( signalRef "@baseboard_fab2_lib.baseboard_fab2(sch_1):m_d_ma(14)") )
				( member ( signalRef "@baseboard_fab2_lib.baseboard_fab2(sch_1):m_d_ma(15)") )
				( member ( signalRef "@baseboard_fab2_lib.baseboard_fab2(sch_1):m_d_ma(16)") )
				( member ( signalRef "@baseboard_fab2_lib.baseboard_fab2(sch_1):m_d_ma(17)") )
				( objectStatus "M_D_MA" )
			)
			( bus "@crescent_city_bb_fab1_lib.crescent_city_bb_fab1(sch_1):m_d_ecc"
				( memberType ( signal ) )
				( member ( signalRef "@baseboard_fab2_lib.baseboard_fab2(sch_1):m_d_ecc(0)") )
				( member ( signalRef "@baseboard_fab2_lib.baseboard_fab2(sch_1):m_d_ecc(1)") )
				( member ( signalRef "@baseboard_fab2_lib.baseboard_fab2(sch_1):m_d_ecc(2)") )
				( member ( signalRef "@baseboard_fab2_lib.baseboard_fab2(sch_1):m_d_ecc(3)") )
				( member ( signalRef "@baseboard_fab2_lib.baseboard_fab2(sch_1):m_d_ecc(4)") )
				( member ( signalRef "@baseboard_fab2_lib.baseboard_fab2(sch_1):m_d_ecc(5)") )
				( member ( signalRef "@baseboard_fab2_lib.baseboard_fab2(sch_1):m_d_ecc(6)") )
				( member ( signalRef "@baseboard_fab2_lib.baseboard_fab2(sch_1):m_d_ecc(7)") )
				( objectStatus "M_D_ECC" )
			)
			( bus "@crescent_city_bb_fab1_lib.crescent_city_bb_fab1(sch_1):m_d_dqs_dp"
				( memberType ( signal ) )
				( member ( signalRef "@baseboard_fab2_lib.baseboard_fab2(sch_1):m_d_dqs_dp(0)") )
				( member ( signalRef "@baseboard_fab2_lib.baseboard_fab2(sch_1):m_d_dqs_dp(1)") )
				( member ( signalRef "@baseboard_fab2_lib.baseboard_fab2(sch_1):m_d_dqs_dp(2)") )
				( member ( signalRef "@baseboard_fab2_lib.baseboard_fab2(sch_1):m_d_dqs_dp(3)") )
				( member ( signalRef "@baseboard_fab2_lib.baseboard_fab2(sch_1):m_d_dqs_dp(4)") )
				( member ( signalRef "@baseboard_fab2_lib.baseboard_fab2(sch_1):m_d_dqs_dp(5)") )
				( member ( signalRef "@baseboard_fab2_lib.baseboard_fab2(sch_1):m_d_dqs_dp(6)") )
				( member ( signalRef "@baseboard_fab2_lib.baseboard_fab2(sch_1):m_d_dqs_dp(7)") )
				( member ( signalRef "@baseboard_fab2_lib.baseboard_fab2(sch_1):m_d_dqs_dp(8)") )
				( member ( signalRef "@baseboard_fab2_lib.baseboard_fab2(sch_1):m_d_dqs_dp(9)") )
				( member ( signalRef "@baseboard_fab2_lib.baseboard_fab2(sch_1):m_d_dqs_dp(10)") )
				( member ( signalRef "@baseboard_fab2_lib.baseboard_fab2(sch_1):m_d_dqs_dp(11)") )
				( member ( signalRef "@baseboard_fab2_lib.baseboard_fab2(sch_1):m_d_dqs_dp(12)") )
				( member ( signalRef "@baseboard_fab2_lib.baseboard_fab2(sch_1):m_d_dqs_dp(13)") )
				( member ( signalRef "@baseboard_fab2_lib.baseboard_fab2(sch_1):m_d_dqs_dp(14)") )
				( member ( signalRef "@baseboard_fab2_lib.baseboard_fab2(sch_1):m_d_dqs_dp(15)") )
				( member ( signalRef "@baseboard_fab2_lib.baseboard_fab2(sch_1):m_d_dqs_dp(16)") )
				( member ( signalRef "@baseboard_fab2_lib.baseboard_fab2(sch_1):m_d_dqs_dp(17)") )
				( objectStatus "M_D_DQS_DP" )
			)
			( bus "@crescent_city_bb_fab1_lib.crescent_city_bb_fab1(sch_1):m_d_dqs_dn"
				( memberType ( signal ) )
				( member ( signalRef "@baseboard_fab2_lib.baseboard_fab2(sch_1):m_d_dqs_dn(0)") )
				( member ( signalRef "@baseboard_fab2_lib.baseboard_fab2(sch_1):m_d_dqs_dn(1)") )
				( member ( signalRef "@baseboard_fab2_lib.baseboard_fab2(sch_1):m_d_dqs_dn(2)") )
				( member ( signalRef "@baseboard_fab2_lib.baseboard_fab2(sch_1):m_d_dqs_dn(3)") )
				( member ( signalRef "@baseboard_fab2_lib.baseboard_fab2(sch_1):m_d_dqs_dn(4)") )
				( member ( signalRef "@baseboard_fab2_lib.baseboard_fab2(sch_1):m_d_dqs_dn(5)") )
				( member ( signalRef "@baseboard_fab2_lib.baseboard_fab2(sch_1):m_d_dqs_dn(6)") )
				( member ( signalRef "@baseboard_fab2_lib.baseboard_fab2(sch_1):m_d_dqs_dn(7)") )
				( member ( signalRef "@baseboard_fab2_lib.baseboard_fab2(sch_1):m_d_dqs_dn(8)") )
				( member ( signalRef "@baseboard_fab2_lib.baseboard_fab2(sch_1):m_d_dqs_dn(9)") )
				( member ( signalRef "@baseboard_fab2_lib.baseboard_fab2(sch_1):m_d_dqs_dn(10)") )
				( member ( signalRef "@baseboard_fab2_lib.baseboard_fab2(sch_1):m_d_dqs_dn(11)") )
				( member ( signalRef "@baseboard_fab2_lib.baseboard_fab2(sch_1):m_d_dqs_dn(12)") )
				( member ( signalRef "@baseboard_fab2_lib.baseboard_fab2(sch_1):m_d_dqs_dn(13)") )
				( member ( signalRef "@baseboard_fab2_lib.baseboard_fab2(sch_1):m_d_dqs_dn(14)") )
				( member ( signalRef "@baseboard_fab2_lib.baseboard_fab2(sch_1):m_d_dqs_dn(15)") )
				( member ( signalRef "@baseboard_fab2_lib.baseboard_fab2(sch_1):m_d_dqs_dn(16)") )
				( member ( signalRef "@baseboard_fab2_lib.baseboard_fab2(sch_1):m_d_dqs_dn(17)") )
				( objectStatus "M_D_DQS_DN" )
			)
			( bus "@crescent_city_bb_fab1_lib.crescent_city_bb_fab1(sch_1):m_d_dq"
				( memberType ( signal ) )
				( member ( signalRef "@baseboard_fab2_lib.baseboard_fab2(sch_1):m_d_dq(0)") )
				( member ( signalRef "@baseboard_fab2_lib.baseboard_fab2(sch_1):m_d_dq(1)") )
				( member ( signalRef "@baseboard_fab2_lib.baseboard_fab2(sch_1):m_d_dq(2)") )
				( member ( signalRef "@baseboard_fab2_lib.baseboard_fab2(sch_1):m_d_dq(3)") )
				( member ( signalRef "@baseboard_fab2_lib.baseboard_fab2(sch_1):m_d_dq(4)") )
				( member ( signalRef "@baseboard_fab2_lib.baseboard_fab2(sch_1):m_d_dq(5)") )
				( member ( signalRef "@baseboard_fab2_lib.baseboard_fab2(sch_1):m_d_dq(6)") )
				( member ( signalRef "@baseboard_fab2_lib.baseboard_fab2(sch_1):m_d_dq(7)") )
				( member ( signalRef "@baseboard_fab2_lib.baseboard_fab2(sch_1):m_d_dq(8)") )
				( member ( signalRef "@baseboard_fab2_lib.baseboard_fab2(sch_1):m_d_dq(9)") )
				( member ( signalRef "@baseboard_fab2_lib.baseboard_fab2(sch_1):m_d_dq(10)") )
				( member ( signalRef "@baseboard_fab2_lib.baseboard_fab2(sch_1):m_d_dq(11)") )
				( member ( signalRef "@baseboard_fab2_lib.baseboard_fab2(sch_1):m_d_dq(12)") )
				( member ( signalRef "@baseboard_fab2_lib.baseboard_fab2(sch_1):m_d_dq(13)") )
				( member ( signalRef "@baseboard_fab2_lib.baseboard_fab2(sch_1):m_d_dq(14)") )
				( member ( signalRef "@baseboard_fab2_lib.baseboard_fab2(sch_1):m_d_dq(15)") )
				( member ( signalRef "@baseboard_fab2_lib.baseboard_fab2(sch_1):m_d_dq(16)") )
				( member ( signalRef "@baseboard_fab2_lib.baseboard_fab2(sch_1):m_d_dq(17)") )
				( member ( signalRef "@baseboard_fab2_lib.baseboard_fab2(sch_1):m_d_dq(18)") )
				( member ( signalRef "@baseboard_fab2_lib.baseboard_fab2(sch_1):m_d_dq(19)") )
				( member ( signalRef "@baseboard_fab2_lib.baseboard_fab2(sch_1):m_d_dq(20)") )
				( member ( signalRef "@baseboard_fab2_lib.baseboard_fab2(sch_1):m_d_dq(21)") )
				( member ( signalRef "@baseboard_fab2_lib.baseboard_fab2(sch_1):m_d_dq(22)") )
				( member ( signalRef "@baseboard_fab2_lib.baseboard_fab2(sch_1):m_d_dq(23)") )
				( member ( signalRef "@baseboard_fab2_lib.baseboard_fab2(sch_1):m_d_dq(24)") )
				( member ( signalRef "@baseboard_fab2_lib.baseboard_fab2(sch_1):m_d_dq(25)") )
				( member ( signalRef "@baseboard_fab2_lib.baseboard_fab2(sch_1):m_d_dq(26)") )
				( member ( signalRef "@baseboard_fab2_lib.baseboard_fab2(sch_1):m_d_dq(27)") )
				( member ( signalRef "@baseboard_fab2_lib.baseboard_fab2(sch_1):m_d_dq(28)") )
				( member ( signalRef "@baseboard_fab2_lib.baseboard_fab2(sch_1):m_d_dq(29)") )
				( member ( signalRef "@baseboard_fab2_lib.baseboard_fab2(sch_1):m_d_dq(30)") )
				( member ( signalRef "@baseboard_fab2_lib.baseboard_fab2(sch_1):m_d_dq(31)") )
				( member ( signalRef "@baseboard_fab2_lib.baseboard_fab2(sch_1):m_d_dq(32)") )
				( member ( signalRef "@baseboard_fab2_lib.baseboard_fab2(sch_1):m_d_dq(33)") )
				( member ( signalRef "@baseboard_fab2_lib.baseboard_fab2(sch_1):m_d_dq(34)") )
				( member ( signalRef "@baseboard_fab2_lib.baseboard_fab2(sch_1):m_d_dq(35)") )
				( member ( signalRef "@baseboard_fab2_lib.baseboard_fab2(sch_1):m_d_dq(36)") )
				( member ( signalRef "@baseboard_fab2_lib.baseboard_fab2(sch_1):m_d_dq(37)") )
				( member ( signalRef "@baseboard_fab2_lib.baseboard_fab2(sch_1):m_d_dq(38)") )
				( member ( signalRef "@baseboard_fab2_lib.baseboard_fab2(sch_1):m_d_dq(39)") )
				( member ( signalRef "@baseboard_fab2_lib.baseboard_fab2(sch_1):m_d_dq(40)") )
				( member ( signalRef "@baseboard_fab2_lib.baseboard_fab2(sch_1):m_d_dq(41)") )
				( member ( signalRef "@baseboard_fab2_lib.baseboard_fab2(sch_1):m_d_dq(42)") )
				( member ( signalRef "@baseboard_fab2_lib.baseboard_fab2(sch_1):m_d_dq(43)") )
				( member ( signalRef "@baseboard_fab2_lib.baseboard_fab2(sch_1):m_d_dq(44)") )
				( member ( signalRef "@baseboard_fab2_lib.baseboard_fab2(sch_1):m_d_dq(45)") )
				( member ( signalRef "@baseboard_fab2_lib.baseboard_fab2(sch_1):m_d_dq(46)") )
				( member ( signalRef "@baseboard_fab2_lib.baseboard_fab2(sch_1):m_d_dq(47)") )
				( member ( signalRef "@baseboard_fab2_lib.baseboard_fab2(sch_1):m_d_dq(48)") )
				( member ( signalRef "@baseboard_fab2_lib.baseboard_fab2(sch_1):m_d_dq(49)") )
				( member ( signalRef "@baseboard_fab2_lib.baseboard_fab2(sch_1):m_d_dq(50)") )
				( member ( signalRef "@baseboard_fab2_lib.baseboard_fab2(sch_1):m_d_dq(51)") )
				( member ( signalRef "@baseboard_fab2_lib.baseboard_fab2(sch_1):m_d_dq(52)") )
				( member ( signalRef "@baseboard_fab2_lib.baseboard_fab2(sch_1):m_d_dq(53)") )
				( member ( signalRef "@baseboard_fab2_lib.baseboard_fab2(sch_1):m_d_dq(54)") )
				( member ( signalRef "@baseboard_fab2_lib.baseboard_fab2(sch_1):m_d_dq(55)") )
				( member ( signalRef "@baseboard_fab2_lib.baseboard_fab2(sch_1):m_d_dq(56)") )
				( member ( signalRef "@baseboard_fab2_lib.baseboard_fab2(sch_1):m_d_dq(57)") )
				( member ( signalRef "@baseboard_fab2_lib.baseboard_fab2(sch_1):m_d_dq(58)") )
				( member ( signalRef "@baseboard_fab2_lib.baseboard_fab2(sch_1):m_d_dq(59)") )
				( member ( signalRef "@baseboard_fab2_lib.baseboard_fab2(sch_1):m_d_dq(60)") )
				( member ( signalRef "@baseboard_fab2_lib.baseboard_fab2(sch_1):m_d_dq(61)") )
				( member ( signalRef "@baseboard_fab2_lib.baseboard_fab2(sch_1):m_d_dq(62)") )
				( member ( signalRef "@baseboard_fab2_lib.baseboard_fab2(sch_1):m_d_dq(63)") )
				( objectStatus "M_D_DQ" )
			)
			( bus "@crescent_city_bb_fab1_lib.crescent_city_bb_fab1(sch_1):m_d_cs_n"
				( memberType ( signal ) )
				( member ( signalRef "@baseboard_fab2_lib.baseboard_fab2(sch_1):m_d_cs_n(0)") )
				( member ( signalRef "@baseboard_fab2_lib.baseboard_fab2(sch_1):m_d_cs_n(1)") )
				( member ( signalRef "@baseboard_fab2_lib.baseboard_fab2(sch_1):m_d_cs_n(2)") )
				( member ( signalRef "@baseboard_fab2_lib.baseboard_fab2(sch_1):m_d_cs_n(3)") )
				( member ( signalRef "@baseboard_fab2_lib.baseboard_fab2(sch_1):m_d_cs_n(4)") )
				( member ( signalRef "@baseboard_fab2_lib.baseboard_fab2(sch_1):m_d_cs_n(5)") )
				( member ( signalRef "@baseboard_fab2_lib.baseboard_fab2(sch_1):m_d_cs_n(6)") )
				( member ( signalRef "@baseboard_fab2_lib.baseboard_fab2(sch_1):m_d_cs_n(7)") )
				( objectStatus "M_D_CS_N" )
			)
			( bus "@crescent_city_bb_fab1_lib.crescent_city_bb_fab1(sch_1):m_d_clk_dp"
				( memberType ( signal ) )
				( member ( signalRef "@baseboard_fab2_lib.baseboard_fab2(sch_1):m_d_clk_dp(0)") )
				( member ( signalRef "@baseboard_fab2_lib.baseboard_fab2(sch_1):m_d_clk_dp(2)") )
				( member ( signalRef "@baseboard_fab2_lib.baseboard_fab2(sch_1):m_d_clk_dp(1)") )
				( member ( signalRef "@baseboard_fab2_lib.baseboard_fab2(sch_1):m_d_clk_dp(3)") )
				( objectStatus "M_D_CLK_DP" )
			)
			( bus "@crescent_city_bb_fab1_lib.crescent_city_bb_fab1(sch_1):m_d_clk_dn"
				( memberType ( signal ) )
				( member ( signalRef "@baseboard_fab2_lib.baseboard_fab2(sch_1):m_d_clk_dn(0)") )
				( member ( signalRef "@baseboard_fab2_lib.baseboard_fab2(sch_1):m_d_clk_dn(2)") )
				( member ( signalRef "@baseboard_fab2_lib.baseboard_fab2(sch_1):m_d_clk_dn(1)") )
				( member ( signalRef "@baseboard_fab2_lib.baseboard_fab2(sch_1):m_d_clk_dn(3)") )
				( objectStatus "M_D_CLK_DN" )
			)
			( bus "@crescent_city_bb_fab1_lib.crescent_city_bb_fab1(sch_1):m_d_cke"
				( memberType ( signal ) )
				( member ( signalRef "@baseboard_fab2_lib.baseboard_fab2(sch_1):m_d_cke(0)") )
				( member ( signalRef "@baseboard_fab2_lib.baseboard_fab2(sch_1):m_d_cke(1)") )
				( member ( signalRef "@baseboard_fab2_lib.baseboard_fab2(sch_1):m_d_cke(2)") )
				( member ( signalRef "@baseboard_fab2_lib.baseboard_fab2(sch_1):m_d_cke(3)") )
				( objectStatus "M_D_CKE" )
			)
			( bus "@crescent_city_bb_fab1_lib.crescent_city_bb_fab1(sch_1):m_d_c"
				( memberType ( signal ) )
				( member ( signalRef "@baseboard_fab2_lib.baseboard_fab2(sch_1):m_d_c(2)") )
				( objectStatus "M_D_C" )
			)
			( bus "@crescent_city_bb_fab1_lib.crescent_city_bb_fab1(sch_1):m_d_bg"
				( memberType ( signal ) )
				( member ( signalRef "@baseboard_fab2_lib.baseboard_fab2(sch_1):m_d_bg(0)") )
				( member ( signalRef "@baseboard_fab2_lib.baseboard_fab2(sch_1):m_d_bg(1)") )
				( objectStatus "M_D_BG" )
			)
			( bus "@crescent_city_bb_fab1_lib.crescent_city_bb_fab1(sch_1):m_d_ba"
				( memberType ( signal ) )
				( member ( signalRef "@baseboard_fab2_lib.baseboard_fab2(sch_1):m_d_ba(0)") )
				( member ( signalRef "@baseboard_fab2_lib.baseboard_fab2(sch_1):m_d_ba(1)") )
				( objectStatus "M_D_BA" )
			)
			( bus "@crescent_city_bb_fab1_lib.crescent_city_bb_fab1(sch_1):m_c_odt"
				( memberType ( signal ) )
				( member ( signalRef "@baseboard_fab2_lib.baseboard_fab2(sch_1):m_c_odt(0)") )
				( member ( signalRef "@baseboard_fab2_lib.baseboard_fab2(sch_1):m_c_odt(1)") )
				( member ( signalRef "@baseboard_fab2_lib.baseboard_fab2(sch_1):m_c_odt(2)") )
				( member ( signalRef "@baseboard_fab2_lib.baseboard_fab2(sch_1):m_c_odt(3)") )
				( objectStatus "M_C_ODT" )
			)
			( bus "@crescent_city_bb_fab1_lib.crescent_city_bb_fab1(sch_1):m_c_ma"
				( memberType ( signal ) )
				( member ( signalRef "@baseboard_fab2_lib.baseboard_fab2(sch_1):m_c_ma(0)") )
				( member ( signalRef "@baseboard_fab2_lib.baseboard_fab2(sch_1):m_c_ma(1)") )
				( member ( signalRef "@baseboard_fab2_lib.baseboard_fab2(sch_1):m_c_ma(2)") )
				( member ( signalRef "@baseboard_fab2_lib.baseboard_fab2(sch_1):m_c_ma(3)") )
				( member ( signalRef "@baseboard_fab2_lib.baseboard_fab2(sch_1):m_c_ma(4)") )
				( member ( signalRef "@baseboard_fab2_lib.baseboard_fab2(sch_1):m_c_ma(5)") )
				( member ( signalRef "@baseboard_fab2_lib.baseboard_fab2(sch_1):m_c_ma(6)") )
				( member ( signalRef "@baseboard_fab2_lib.baseboard_fab2(sch_1):m_c_ma(7)") )
				( member ( signalRef "@baseboard_fab2_lib.baseboard_fab2(sch_1):m_c_ma(8)") )
				( member ( signalRef "@baseboard_fab2_lib.baseboard_fab2(sch_1):m_c_ma(9)") )
				( member ( signalRef "@baseboard_fab2_lib.baseboard_fab2(sch_1):m_c_ma(10)") )
				( member ( signalRef "@baseboard_fab2_lib.baseboard_fab2(sch_1):m_c_ma(11)") )
				( member ( signalRef "@baseboard_fab2_lib.baseboard_fab2(sch_1):m_c_ma(12)") )
				( member ( signalRef "@baseboard_fab2_lib.baseboard_fab2(sch_1):m_c_ma(13)") )
				( member ( signalRef "@baseboard_fab2_lib.baseboard_fab2(sch_1):m_c_ma(14)") )
				( member ( signalRef "@baseboard_fab2_lib.baseboard_fab2(sch_1):m_c_ma(15)") )
				( member ( signalRef "@baseboard_fab2_lib.baseboard_fab2(sch_1):m_c_ma(16)") )
				( member ( signalRef "@baseboard_fab2_lib.baseboard_fab2(sch_1):m_c_ma(17)") )
				( objectStatus "M_C_MA" )
			)
			( bus "@crescent_city_bb_fab1_lib.crescent_city_bb_fab1(sch_1):m_c_ecc"
				( memberType ( signal ) )
				( member ( signalRef "@baseboard_fab2_lib.baseboard_fab2(sch_1):m_c_ecc(0)") )
				( member ( signalRef "@baseboard_fab2_lib.baseboard_fab2(sch_1):m_c_ecc(1)") )
				( member ( signalRef "@baseboard_fab2_lib.baseboard_fab2(sch_1):m_c_ecc(2)") )
				( member ( signalRef "@baseboard_fab2_lib.baseboard_fab2(sch_1):m_c_ecc(3)") )
				( member ( signalRef "@baseboard_fab2_lib.baseboard_fab2(sch_1):m_c_ecc(4)") )
				( member ( signalRef "@baseboard_fab2_lib.baseboard_fab2(sch_1):m_c_ecc(5)") )
				( member ( signalRef "@baseboard_fab2_lib.baseboard_fab2(sch_1):m_c_ecc(6)") )
				( member ( signalRef "@baseboard_fab2_lib.baseboard_fab2(sch_1):m_c_ecc(7)") )
				( objectStatus "M_C_ECC" )
			)
			( bus "@crescent_city_bb_fab1_lib.crescent_city_bb_fab1(sch_1):m_c_dqs_dp"
				( memberType ( signal ) )
				( member ( signalRef "@baseboard_fab2_lib.baseboard_fab2(sch_1):m_c_dqs_dp(0)") )
				( member ( signalRef "@baseboard_fab2_lib.baseboard_fab2(sch_1):m_c_dqs_dp(1)") )
				( member ( signalRef "@baseboard_fab2_lib.baseboard_fab2(sch_1):m_c_dqs_dp(2)") )
				( member ( signalRef "@baseboard_fab2_lib.baseboard_fab2(sch_1):m_c_dqs_dp(3)") )
				( member ( signalRef "@baseboard_fab2_lib.baseboard_fab2(sch_1):m_c_dqs_dp(4)") )
				( member ( signalRef "@baseboard_fab2_lib.baseboard_fab2(sch_1):m_c_dqs_dp(5)") )
				( member ( signalRef "@baseboard_fab2_lib.baseboard_fab2(sch_1):m_c_dqs_dp(6)") )
				( member ( signalRef "@baseboard_fab2_lib.baseboard_fab2(sch_1):m_c_dqs_dp(7)") )
				( member ( signalRef "@baseboard_fab2_lib.baseboard_fab2(sch_1):m_c_dqs_dp(8)") )
				( member ( signalRef "@baseboard_fab2_lib.baseboard_fab2(sch_1):m_c_dqs_dp(9)") )
				( member ( signalRef "@baseboard_fab2_lib.baseboard_fab2(sch_1):m_c_dqs_dp(10)") )
				( member ( signalRef "@baseboard_fab2_lib.baseboard_fab2(sch_1):m_c_dqs_dp(11)") )
				( member ( signalRef "@baseboard_fab2_lib.baseboard_fab2(sch_1):m_c_dqs_dp(12)") )
				( member ( signalRef "@baseboard_fab2_lib.baseboard_fab2(sch_1):m_c_dqs_dp(13)") )
				( member ( signalRef "@baseboard_fab2_lib.baseboard_fab2(sch_1):m_c_dqs_dp(14)") )
				( member ( signalRef "@baseboard_fab2_lib.baseboard_fab2(sch_1):m_c_dqs_dp(15)") )
				( member ( signalRef "@baseboard_fab2_lib.baseboard_fab2(sch_1):m_c_dqs_dp(16)") )
				( member ( signalRef "@baseboard_fab2_lib.baseboard_fab2(sch_1):m_c_dqs_dp(17)") )
				( objectStatus "M_C_DQS_DP" )
			)
			( bus "@crescent_city_bb_fab1_lib.crescent_city_bb_fab1(sch_1):m_c_dqs_dn"
				( memberType ( signal ) )
				( member ( signalRef "@baseboard_fab2_lib.baseboard_fab2(sch_1):m_c_dqs_dn(0)") )
				( member ( signalRef "@baseboard_fab2_lib.baseboard_fab2(sch_1):m_c_dqs_dn(1)") )
				( member ( signalRef "@baseboard_fab2_lib.baseboard_fab2(sch_1):m_c_dqs_dn(2)") )
				( member ( signalRef "@baseboard_fab2_lib.baseboard_fab2(sch_1):m_c_dqs_dn(3)") )
				( member ( signalRef "@baseboard_fab2_lib.baseboard_fab2(sch_1):m_c_dqs_dn(4)") )
				( member ( signalRef "@baseboard_fab2_lib.baseboard_fab2(sch_1):m_c_dqs_dn(5)") )
				( member ( signalRef "@baseboard_fab2_lib.baseboard_fab2(sch_1):m_c_dqs_dn(6)") )
				( member ( signalRef "@baseboard_fab2_lib.baseboard_fab2(sch_1):m_c_dqs_dn(7)") )
				( member ( signalRef "@baseboard_fab2_lib.baseboard_fab2(sch_1):m_c_dqs_dn(8)") )
				( member ( signalRef "@baseboard_fab2_lib.baseboard_fab2(sch_1):m_c_dqs_dn(9)") )
				( member ( signalRef "@baseboard_fab2_lib.baseboard_fab2(sch_1):m_c_dqs_dn(10)") )
				( member ( signalRef "@baseboard_fab2_lib.baseboard_fab2(sch_1):m_c_dqs_dn(11)") )
				( member ( signalRef "@baseboard_fab2_lib.baseboard_fab2(sch_1):m_c_dqs_dn(12)") )
				( member ( signalRef "@baseboard_fab2_lib.baseboard_fab2(sch_1):m_c_dqs_dn(13)") )
				( member ( signalRef "@baseboard_fab2_lib.baseboard_fab2(sch_1):m_c_dqs_dn(14)") )
				( member ( signalRef "@baseboard_fab2_lib.baseboard_fab2(sch_1):m_c_dqs_dn(15)") )
				( member ( signalRef "@baseboard_fab2_lib.baseboard_fab2(sch_1):m_c_dqs_dn(16)") )
				( member ( signalRef "@baseboard_fab2_lib.baseboard_fab2(sch_1):m_c_dqs_dn(17)") )
				( objectStatus "M_C_DQS_DN" )
			)
			( bus "@crescent_city_bb_fab1_lib.crescent_city_bb_fab1(sch_1):m_c_dq"
				( memberType ( signal ) )
				( member ( signalRef "@baseboard_fab2_lib.baseboard_fab2(sch_1):m_c_dq(0)") )
				( member ( signalRef "@baseboard_fab2_lib.baseboard_fab2(sch_1):m_c_dq(1)") )
				( member ( signalRef "@baseboard_fab2_lib.baseboard_fab2(sch_1):m_c_dq(2)") )
				( member ( signalRef "@baseboard_fab2_lib.baseboard_fab2(sch_1):m_c_dq(3)") )
				( member ( signalRef "@baseboard_fab2_lib.baseboard_fab2(sch_1):m_c_dq(4)") )
				( member ( signalRef "@baseboard_fab2_lib.baseboard_fab2(sch_1):m_c_dq(5)") )
				( member ( signalRef "@baseboard_fab2_lib.baseboard_fab2(sch_1):m_c_dq(6)") )
				( member ( signalRef "@baseboard_fab2_lib.baseboard_fab2(sch_1):m_c_dq(7)") )
				( member ( signalRef "@baseboard_fab2_lib.baseboard_fab2(sch_1):m_c_dq(8)") )
				( member ( signalRef "@baseboard_fab2_lib.baseboard_fab2(sch_1):m_c_dq(9)") )
				( member ( signalRef "@baseboard_fab2_lib.baseboard_fab2(sch_1):m_c_dq(10)") )
				( member ( signalRef "@baseboard_fab2_lib.baseboard_fab2(sch_1):m_c_dq(11)") )
				( member ( signalRef "@baseboard_fab2_lib.baseboard_fab2(sch_1):m_c_dq(12)") )
				( member ( signalRef "@baseboard_fab2_lib.baseboard_fab2(sch_1):m_c_dq(13)") )
				( member ( signalRef "@baseboard_fab2_lib.baseboard_fab2(sch_1):m_c_dq(14)") )
				( member ( signalRef "@baseboard_fab2_lib.baseboard_fab2(sch_1):m_c_dq(15)") )
				( member ( signalRef "@baseboard_fab2_lib.baseboard_fab2(sch_1):m_c_dq(16)") )
				( member ( signalRef "@baseboard_fab2_lib.baseboard_fab2(sch_1):m_c_dq(17)") )
				( member ( signalRef "@baseboard_fab2_lib.baseboard_fab2(sch_1):m_c_dq(18)") )
				( member ( signalRef "@baseboard_fab2_lib.baseboard_fab2(sch_1):m_c_dq(19)") )
				( member ( signalRef "@baseboard_fab2_lib.baseboard_fab2(sch_1):m_c_dq(20)") )
				( member ( signalRef "@baseboard_fab2_lib.baseboard_fab2(sch_1):m_c_dq(21)") )
				( member ( signalRef "@baseboard_fab2_lib.baseboard_fab2(sch_1):m_c_dq(22)") )
				( member ( signalRef "@baseboard_fab2_lib.baseboard_fab2(sch_1):m_c_dq(23)") )
				( member ( signalRef "@baseboard_fab2_lib.baseboard_fab2(sch_1):m_c_dq(24)") )
				( member ( signalRef "@baseboard_fab2_lib.baseboard_fab2(sch_1):m_c_dq(25)") )
				( member ( signalRef "@baseboard_fab2_lib.baseboard_fab2(sch_1):m_c_dq(26)") )
				( member ( signalRef "@baseboard_fab2_lib.baseboard_fab2(sch_1):m_c_dq(27)") )
				( member ( signalRef "@baseboard_fab2_lib.baseboard_fab2(sch_1):m_c_dq(28)") )
				( member ( signalRef "@baseboard_fab2_lib.baseboard_fab2(sch_1):m_c_dq(29)") )
				( member ( signalRef "@baseboard_fab2_lib.baseboard_fab2(sch_1):m_c_dq(30)") )
				( member ( signalRef "@baseboard_fab2_lib.baseboard_fab2(sch_1):m_c_dq(31)") )
				( member ( signalRef "@baseboard_fab2_lib.baseboard_fab2(sch_1):m_c_dq(32)") )
				( member ( signalRef "@baseboard_fab2_lib.baseboard_fab2(sch_1):m_c_dq(33)") )
				( member ( signalRef "@baseboard_fab2_lib.baseboard_fab2(sch_1):m_c_dq(34)") )
				( member ( signalRef "@baseboard_fab2_lib.baseboard_fab2(sch_1):m_c_dq(35)") )
				( member ( signalRef "@baseboard_fab2_lib.baseboard_fab2(sch_1):m_c_dq(36)") )
				( member ( signalRef "@baseboard_fab2_lib.baseboard_fab2(sch_1):m_c_dq(37)") )
				( member ( signalRef "@baseboard_fab2_lib.baseboard_fab2(sch_1):m_c_dq(38)") )
				( member ( signalRef "@baseboard_fab2_lib.baseboard_fab2(sch_1):m_c_dq(39)") )
				( member ( signalRef "@baseboard_fab2_lib.baseboard_fab2(sch_1):m_c_dq(40)") )
				( member ( signalRef "@baseboard_fab2_lib.baseboard_fab2(sch_1):m_c_dq(41)") )
				( member ( signalRef "@baseboard_fab2_lib.baseboard_fab2(sch_1):m_c_dq(42)") )
				( member ( signalRef "@baseboard_fab2_lib.baseboard_fab2(sch_1):m_c_dq(43)") )
				( member ( signalRef "@baseboard_fab2_lib.baseboard_fab2(sch_1):m_c_dq(44)") )
				( member ( signalRef "@baseboard_fab2_lib.baseboard_fab2(sch_1):m_c_dq(45)") )
				( member ( signalRef "@baseboard_fab2_lib.baseboard_fab2(sch_1):m_c_dq(46)") )
				( member ( signalRef "@baseboard_fab2_lib.baseboard_fab2(sch_1):m_c_dq(47)") )
				( member ( signalRef "@baseboard_fab2_lib.baseboard_fab2(sch_1):m_c_dq(48)") )
				( member ( signalRef "@baseboard_fab2_lib.baseboard_fab2(sch_1):m_c_dq(49)") )
				( member ( signalRef "@baseboard_fab2_lib.baseboard_fab2(sch_1):m_c_dq(50)") )
				( member ( signalRef "@baseboard_fab2_lib.baseboard_fab2(sch_1):m_c_dq(51)") )
				( member ( signalRef "@baseboard_fab2_lib.baseboard_fab2(sch_1):m_c_dq(52)") )
				( member ( signalRef "@baseboard_fab2_lib.baseboard_fab2(sch_1):m_c_dq(53)") )
				( member ( signalRef "@baseboard_fab2_lib.baseboard_fab2(sch_1):m_c_dq(54)") )
				( member ( signalRef "@baseboard_fab2_lib.baseboard_fab2(sch_1):m_c_dq(55)") )
				( member ( signalRef "@baseboard_fab2_lib.baseboard_fab2(sch_1):m_c_dq(56)") )
				( member ( signalRef "@baseboard_fab2_lib.baseboard_fab2(sch_1):m_c_dq(57)") )
				( member ( signalRef "@baseboard_fab2_lib.baseboard_fab2(sch_1):m_c_dq(58)") )
				( member ( signalRef "@baseboard_fab2_lib.baseboard_fab2(sch_1):m_c_dq(59)") )
				( member ( signalRef "@baseboard_fab2_lib.baseboard_fab2(sch_1):m_c_dq(60)") )
				( member ( signalRef "@baseboard_fab2_lib.baseboard_fab2(sch_1):m_c_dq(61)") )
				( member ( signalRef "@baseboard_fab2_lib.baseboard_fab2(sch_1):m_c_dq(62)") )
				( member ( signalRef "@baseboard_fab2_lib.baseboard_fab2(sch_1):m_c_dq(63)") )
				( objectStatus "M_C_DQ" )
			)
			( bus "@crescent_city_bb_fab1_lib.crescent_city_bb_fab1(sch_1):m_c_cs_n"
				( memberType ( signal ) )
				( member ( signalRef "@baseboard_fab2_lib.baseboard_fab2(sch_1):m_c_cs_n(0)") )
				( member ( signalRef "@baseboard_fab2_lib.baseboard_fab2(sch_1):m_c_cs_n(1)") )
				( member ( signalRef "@baseboard_fab2_lib.baseboard_fab2(sch_1):m_c_cs_n(2)") )
				( member ( signalRef "@baseboard_fab2_lib.baseboard_fab2(sch_1):m_c_cs_n(3)") )
				( member ( signalRef "@baseboard_fab2_lib.baseboard_fab2(sch_1):m_c_cs_n(4)") )
				( member ( signalRef "@baseboard_fab2_lib.baseboard_fab2(sch_1):m_c_cs_n(5)") )
				( member ( signalRef "@baseboard_fab2_lib.baseboard_fab2(sch_1):m_c_cs_n(6)") )
				( member ( signalRef "@baseboard_fab2_lib.baseboard_fab2(sch_1):m_c_cs_n(7)") )
				( objectStatus "M_C_CS_N" )
			)
			( bus "@crescent_city_bb_fab1_lib.crescent_city_bb_fab1(sch_1):m_c_clk_dp"
				( memberType ( signal ) )
				( member ( signalRef "@baseboard_fab2_lib.baseboard_fab2(sch_1):m_c_clk_dp(0)") )
				( member ( signalRef "@baseboard_fab2_lib.baseboard_fab2(sch_1):m_c_clk_dp(1)") )
				( member ( signalRef "@baseboard_fab2_lib.baseboard_fab2(sch_1):m_c_clk_dp(2)") )
				( member ( signalRef "@baseboard_fab2_lib.baseboard_fab2(sch_1):m_c_clk_dp(3)") )
				( objectStatus "M_C_CLK_DP" )
			)
			( bus "@crescent_city_bb_fab1_lib.crescent_city_bb_fab1(sch_1):m_c_clk_dn"
				( memberType ( signal ) )
				( member ( signalRef "@baseboard_fab2_lib.baseboard_fab2(sch_1):m_c_clk_dn(0)") )
				( member ( signalRef "@baseboard_fab2_lib.baseboard_fab2(sch_1):m_c_clk_dn(1)") )
				( member ( signalRef "@baseboard_fab2_lib.baseboard_fab2(sch_1):m_c_clk_dn(2)") )
				( member ( signalRef "@baseboard_fab2_lib.baseboard_fab2(sch_1):m_c_clk_dn(3)") )
				( objectStatus "M_C_CLK_DN" )
			)
			( bus "@crescent_city_bb_fab1_lib.crescent_city_bb_fab1(sch_1):m_c_cke"
				( memberType ( signal ) )
				( member ( signalRef "@baseboard_fab2_lib.baseboard_fab2(sch_1):m_c_cke(0)") )
				( member ( signalRef "@baseboard_fab2_lib.baseboard_fab2(sch_1):m_c_cke(1)") )
				( member ( signalRef "@baseboard_fab2_lib.baseboard_fab2(sch_1):m_c_cke(2)") )
				( member ( signalRef "@baseboard_fab2_lib.baseboard_fab2(sch_1):m_c_cke(3)") )
				( objectStatus "M_C_CKE" )
			)
			( bus "@crescent_city_bb_fab1_lib.crescent_city_bb_fab1(sch_1):m_c_c"
				( memberType ( signal ) )
				( member ( signalRef "@baseboard_fab2_lib.baseboard_fab2(sch_1):m_c_c(2)") )
				( objectStatus "M_C_C" )
			)
			( bus "@crescent_city_bb_fab1_lib.crescent_city_bb_fab1(sch_1):m_c_bg"
				( memberType ( signal ) )
				( member ( signalRef "@baseboard_fab2_lib.baseboard_fab2(sch_1):m_c_bg(0)") )
				( member ( signalRef "@baseboard_fab2_lib.baseboard_fab2(sch_1):m_c_bg(1)") )
				( objectStatus "M_C_BG" )
			)
			( bus "@crescent_city_bb_fab1_lib.crescent_city_bb_fab1(sch_1):m_c_ba"
				( memberType ( signal ) )
				( member ( signalRef "@baseboard_fab2_lib.baseboard_fab2(sch_1):m_c_ba(0)") )
				( member ( signalRef "@baseboard_fab2_lib.baseboard_fab2(sch_1):m_c_ba(1)") )
				( objectStatus "M_C_BA" )
			)
			( bus "@crescent_city_bb_fab1_lib.crescent_city_bb_fab1(sch_1):m_b_odt"
				( memberType ( signal ) )
				( member ( signalRef "@baseboard_fab2_lib.baseboard_fab2(sch_1):m_b_odt(0)") )
				( member ( signalRef "@baseboard_fab2_lib.baseboard_fab2(sch_1):m_b_odt(1)") )
				( member ( signalRef "@baseboard_fab2_lib.baseboard_fab2(sch_1):m_b_odt(2)") )
				( member ( signalRef "@baseboard_fab2_lib.baseboard_fab2(sch_1):m_b_odt(3)") )
				( objectStatus "M_B_ODT" )
			)
			( bus "@crescent_city_bb_fab1_lib.crescent_city_bb_fab1(sch_1):m_b_ma"
				( memberType ( signal ) )
				( member ( signalRef "@baseboard_fab2_lib.baseboard_fab2(sch_1):m_b_ma(0)") )
				( member ( signalRef "@baseboard_fab2_lib.baseboard_fab2(sch_1):m_b_ma(1)") )
				( member ( signalRef "@baseboard_fab2_lib.baseboard_fab2(sch_1):m_b_ma(2)") )
				( member ( signalRef "@baseboard_fab2_lib.baseboard_fab2(sch_1):m_b_ma(3)") )
				( member ( signalRef "@baseboard_fab2_lib.baseboard_fab2(sch_1):m_b_ma(4)") )
				( member ( signalRef "@baseboard_fab2_lib.baseboard_fab2(sch_1):m_b_ma(5)") )
				( member ( signalRef "@baseboard_fab2_lib.baseboard_fab2(sch_1):m_b_ma(6)") )
				( member ( signalRef "@baseboard_fab2_lib.baseboard_fab2(sch_1):m_b_ma(7)") )
				( member ( signalRef "@baseboard_fab2_lib.baseboard_fab2(sch_1):m_b_ma(8)") )
				( member ( signalRef "@baseboard_fab2_lib.baseboard_fab2(sch_1):m_b_ma(9)") )
				( member ( signalRef "@baseboard_fab2_lib.baseboard_fab2(sch_1):m_b_ma(10)") )
				( member ( signalRef "@baseboard_fab2_lib.baseboard_fab2(sch_1):m_b_ma(11)") )
				( member ( signalRef "@baseboard_fab2_lib.baseboard_fab2(sch_1):m_b_ma(12)") )
				( member ( signalRef "@baseboard_fab2_lib.baseboard_fab2(sch_1):m_b_ma(13)") )
				( member ( signalRef "@baseboard_fab2_lib.baseboard_fab2(sch_1):m_b_ma(14)") )
				( member ( signalRef "@baseboard_fab2_lib.baseboard_fab2(sch_1):m_b_ma(15)") )
				( member ( signalRef "@baseboard_fab2_lib.baseboard_fab2(sch_1):m_b_ma(16)") )
				( member ( signalRef "@baseboard_fab2_lib.baseboard_fab2(sch_1):m_b_ma(17)") )
				( objectStatus "M_B_MA" )
			)
			( bus "@crescent_city_bb_fab1_lib.crescent_city_bb_fab1(sch_1):m_b_ecc"
				( memberType ( signal ) )
				( member ( signalRef "@baseboard_fab2_lib.baseboard_fab2(sch_1):m_b_ecc(0)") )
				( member ( signalRef "@baseboard_fab2_lib.baseboard_fab2(sch_1):m_b_ecc(1)") )
				( member ( signalRef "@baseboard_fab2_lib.baseboard_fab2(sch_1):m_b_ecc(2)") )
				( member ( signalRef "@baseboard_fab2_lib.baseboard_fab2(sch_1):m_b_ecc(3)") )
				( member ( signalRef "@baseboard_fab2_lib.baseboard_fab2(sch_1):m_b_ecc(4)") )
				( member ( signalRef "@baseboard_fab2_lib.baseboard_fab2(sch_1):m_b_ecc(5)") )
				( member ( signalRef "@baseboard_fab2_lib.baseboard_fab2(sch_1):m_b_ecc(6)") )
				( member ( signalRef "@baseboard_fab2_lib.baseboard_fab2(sch_1):m_b_ecc(7)") )
				( objectStatus "M_B_ECC" )
			)
			( bus "@crescent_city_bb_fab1_lib.crescent_city_bb_fab1(sch_1):m_b_dqs_dp"
				( memberType ( signal ) )
				( member ( signalRef "@baseboard_fab2_lib.baseboard_fab2(sch_1):m_b_dqs_dp(0)") )
				( member ( signalRef "@baseboard_fab2_lib.baseboard_fab2(sch_1):m_b_dqs_dp(1)") )
				( member ( signalRef "@baseboard_fab2_lib.baseboard_fab2(sch_1):m_b_dqs_dp(2)") )
				( member ( signalRef "@baseboard_fab2_lib.baseboard_fab2(sch_1):m_b_dqs_dp(3)") )
				( member ( signalRef "@baseboard_fab2_lib.baseboard_fab2(sch_1):m_b_dqs_dp(4)") )
				( member ( signalRef "@baseboard_fab2_lib.baseboard_fab2(sch_1):m_b_dqs_dp(5)") )
				( member ( signalRef "@baseboard_fab2_lib.baseboard_fab2(sch_1):m_b_dqs_dp(6)") )
				( member ( signalRef "@baseboard_fab2_lib.baseboard_fab2(sch_1):m_b_dqs_dp(7)") )
				( member ( signalRef "@baseboard_fab2_lib.baseboard_fab2(sch_1):m_b_dqs_dp(8)") )
				( member ( signalRef "@baseboard_fab2_lib.baseboard_fab2(sch_1):m_b_dqs_dp(9)") )
				( member ( signalRef "@baseboard_fab2_lib.baseboard_fab2(sch_1):m_b_dqs_dp(10)") )
				( member ( signalRef "@baseboard_fab2_lib.baseboard_fab2(sch_1):m_b_dqs_dp(11)") )
				( member ( signalRef "@baseboard_fab2_lib.baseboard_fab2(sch_1):m_b_dqs_dp(12)") )
				( member ( signalRef "@baseboard_fab2_lib.baseboard_fab2(sch_1):m_b_dqs_dp(13)") )
				( member ( signalRef "@baseboard_fab2_lib.baseboard_fab2(sch_1):m_b_dqs_dp(14)") )
				( member ( signalRef "@baseboard_fab2_lib.baseboard_fab2(sch_1):m_b_dqs_dp(15)") )
				( member ( signalRef "@baseboard_fab2_lib.baseboard_fab2(sch_1):m_b_dqs_dp(16)") )
				( member ( signalRef "@baseboard_fab2_lib.baseboard_fab2(sch_1):m_b_dqs_dp(17)") )
				( objectStatus "M_B_DQS_DP" )
			)
			( bus "@crescent_city_bb_fab1_lib.crescent_city_bb_fab1(sch_1):m_b_dqs_dn"
				( memberType ( signal ) )
				( member ( signalRef "@baseboard_fab2_lib.baseboard_fab2(sch_1):m_b_dqs_dn(0)") )
				( member ( signalRef "@baseboard_fab2_lib.baseboard_fab2(sch_1):m_b_dqs_dn(1)") )
				( member ( signalRef "@baseboard_fab2_lib.baseboard_fab2(sch_1):m_b_dqs_dn(2)") )
				( member ( signalRef "@baseboard_fab2_lib.baseboard_fab2(sch_1):m_b_dqs_dn(3)") )
				( member ( signalRef "@baseboard_fab2_lib.baseboard_fab2(sch_1):m_b_dqs_dn(4)") )
				( member ( signalRef "@baseboard_fab2_lib.baseboard_fab2(sch_1):m_b_dqs_dn(5)") )
				( member ( signalRef "@baseboard_fab2_lib.baseboard_fab2(sch_1):m_b_dqs_dn(6)") )
				( member ( signalRef "@baseboard_fab2_lib.baseboard_fab2(sch_1):m_b_dqs_dn(7)") )
				( member ( signalRef "@baseboard_fab2_lib.baseboard_fab2(sch_1):m_b_dqs_dn(8)") )
				( member ( signalRef "@baseboard_fab2_lib.baseboard_fab2(sch_1):m_b_dqs_dn(9)") )
				( member ( signalRef "@baseboard_fab2_lib.baseboard_fab2(sch_1):m_b_dqs_dn(10)") )
				( member ( signalRef "@baseboard_fab2_lib.baseboard_fab2(sch_1):m_b_dqs_dn(11)") )
				( member ( signalRef "@baseboard_fab2_lib.baseboard_fab2(sch_1):m_b_dqs_dn(12)") )
				( member ( signalRef "@baseboard_fab2_lib.baseboard_fab2(sch_1):m_b_dqs_dn(13)") )
				( member ( signalRef "@baseboard_fab2_lib.baseboard_fab2(sch_1):m_b_dqs_dn(14)") )
				( member ( signalRef "@baseboard_fab2_lib.baseboard_fab2(sch_1):m_b_dqs_dn(15)") )
				( member ( signalRef "@baseboard_fab2_lib.baseboard_fab2(sch_1):m_b_dqs_dn(16)") )
				( member ( signalRef "@baseboard_fab2_lib.baseboard_fab2(sch_1):m_b_dqs_dn(17)") )
				( objectStatus "M_B_DQS_DN" )
			)
			( bus "@crescent_city_bb_fab1_lib.crescent_city_bb_fab1(sch_1):m_b_dq"
				( memberType ( signal ) )
				( member ( signalRef "@baseboard_fab2_lib.baseboard_fab2(sch_1):m_b_dq(0)") )
				( member ( signalRef "@baseboard_fab2_lib.baseboard_fab2(sch_1):m_b_dq(1)") )
				( member ( signalRef "@baseboard_fab2_lib.baseboard_fab2(sch_1):m_b_dq(2)") )
				( member ( signalRef "@baseboard_fab2_lib.baseboard_fab2(sch_1):m_b_dq(3)") )
				( member ( signalRef "@baseboard_fab2_lib.baseboard_fab2(sch_1):m_b_dq(4)") )
				( member ( signalRef "@baseboard_fab2_lib.baseboard_fab2(sch_1):m_b_dq(5)") )
				( member ( signalRef "@baseboard_fab2_lib.baseboard_fab2(sch_1):m_b_dq(6)") )
				( member ( signalRef "@baseboard_fab2_lib.baseboard_fab2(sch_1):m_b_dq(7)") )
				( member ( signalRef "@baseboard_fab2_lib.baseboard_fab2(sch_1):m_b_dq(8)") )
				( member ( signalRef "@baseboard_fab2_lib.baseboard_fab2(sch_1):m_b_dq(9)") )
				( member ( signalRef "@baseboard_fab2_lib.baseboard_fab2(sch_1):m_b_dq(10)") )
				( member ( signalRef "@baseboard_fab2_lib.baseboard_fab2(sch_1):m_b_dq(11)") )
				( member ( signalRef "@baseboard_fab2_lib.baseboard_fab2(sch_1):m_b_dq(12)") )
				( member ( signalRef "@baseboard_fab2_lib.baseboard_fab2(sch_1):m_b_dq(13)") )
				( member ( signalRef "@baseboard_fab2_lib.baseboard_fab2(sch_1):m_b_dq(14)") )
				( member ( signalRef "@baseboard_fab2_lib.baseboard_fab2(sch_1):m_b_dq(15)") )
				( member ( signalRef "@baseboard_fab2_lib.baseboard_fab2(sch_1):m_b_dq(16)") )
				( member ( signalRef "@baseboard_fab2_lib.baseboard_fab2(sch_1):m_b_dq(17)") )
				( member ( signalRef "@baseboard_fab2_lib.baseboard_fab2(sch_1):m_b_dq(18)") )
				( member ( signalRef "@baseboard_fab2_lib.baseboard_fab2(sch_1):m_b_dq(19)") )
				( member ( signalRef "@baseboard_fab2_lib.baseboard_fab2(sch_1):m_b_dq(20)") )
				( member ( signalRef "@baseboard_fab2_lib.baseboard_fab2(sch_1):m_b_dq(21)") )
				( member ( signalRef "@baseboard_fab2_lib.baseboard_fab2(sch_1):m_b_dq(22)") )
				( member ( signalRef "@baseboard_fab2_lib.baseboard_fab2(sch_1):m_b_dq(23)") )
				( member ( signalRef "@baseboard_fab2_lib.baseboard_fab2(sch_1):m_b_dq(24)") )
				( member ( signalRef "@baseboard_fab2_lib.baseboard_fab2(sch_1):m_b_dq(25)") )
				( member ( signalRef "@baseboard_fab2_lib.baseboard_fab2(sch_1):m_b_dq(26)") )
				( member ( signalRef "@baseboard_fab2_lib.baseboard_fab2(sch_1):m_b_dq(27)") )
				( member ( signalRef "@baseboard_fab2_lib.baseboard_fab2(sch_1):m_b_dq(28)") )
				( member ( signalRef "@baseboard_fab2_lib.baseboard_fab2(sch_1):m_b_dq(29)") )
				( member ( signalRef "@baseboard_fab2_lib.baseboard_fab2(sch_1):m_b_dq(30)") )
				( member ( signalRef "@baseboard_fab2_lib.baseboard_fab2(sch_1):m_b_dq(31)") )
				( member ( signalRef "@baseboard_fab2_lib.baseboard_fab2(sch_1):m_b_dq(32)") )
				( member ( signalRef "@baseboard_fab2_lib.baseboard_fab2(sch_1):m_b_dq(33)") )
				( member ( signalRef "@baseboard_fab2_lib.baseboard_fab2(sch_1):m_b_dq(34)") )
				( member ( signalRef "@baseboard_fab2_lib.baseboard_fab2(sch_1):m_b_dq(35)") )
				( member ( signalRef "@baseboard_fab2_lib.baseboard_fab2(sch_1):m_b_dq(36)") )
				( member ( signalRef "@baseboard_fab2_lib.baseboard_fab2(sch_1):m_b_dq(37)") )
				( member ( signalRef "@baseboard_fab2_lib.baseboard_fab2(sch_1):m_b_dq(38)") )
				( member ( signalRef "@baseboard_fab2_lib.baseboard_fab2(sch_1):m_b_dq(39)") )
				( member ( signalRef "@baseboard_fab2_lib.baseboard_fab2(sch_1):m_b_dq(40)") )
				( member ( signalRef "@baseboard_fab2_lib.baseboard_fab2(sch_1):m_b_dq(41)") )
				( member ( signalRef "@baseboard_fab2_lib.baseboard_fab2(sch_1):m_b_dq(42)") )
				( member ( signalRef "@baseboard_fab2_lib.baseboard_fab2(sch_1):m_b_dq(43)") )
				( member ( signalRef "@baseboard_fab2_lib.baseboard_fab2(sch_1):m_b_dq(44)") )
				( member ( signalRef "@baseboard_fab2_lib.baseboard_fab2(sch_1):m_b_dq(45)") )
				( member ( signalRef "@baseboard_fab2_lib.baseboard_fab2(sch_1):m_b_dq(46)") )
				( member ( signalRef "@baseboard_fab2_lib.baseboard_fab2(sch_1):m_b_dq(47)") )
				( member ( signalRef "@baseboard_fab2_lib.baseboard_fab2(sch_1):m_b_dq(48)") )
				( member ( signalRef "@baseboard_fab2_lib.baseboard_fab2(sch_1):m_b_dq(49)") )
				( member ( signalRef "@baseboard_fab2_lib.baseboard_fab2(sch_1):m_b_dq(50)") )
				( member ( signalRef "@baseboard_fab2_lib.baseboard_fab2(sch_1):m_b_dq(51)") )
				( member ( signalRef "@baseboard_fab2_lib.baseboard_fab2(sch_1):m_b_dq(52)") )
				( member ( signalRef "@baseboard_fab2_lib.baseboard_fab2(sch_1):m_b_dq(53)") )
				( member ( signalRef "@baseboard_fab2_lib.baseboard_fab2(sch_1):m_b_dq(54)") )
				( member ( signalRef "@baseboard_fab2_lib.baseboard_fab2(sch_1):m_b_dq(55)") )
				( member ( signalRef "@baseboard_fab2_lib.baseboard_fab2(sch_1):m_b_dq(56)") )
				( member ( signalRef "@baseboard_fab2_lib.baseboard_fab2(sch_1):m_b_dq(57)") )
				( member ( signalRef "@baseboard_fab2_lib.baseboard_fab2(sch_1):m_b_dq(58)") )
				( member ( signalRef "@baseboard_fab2_lib.baseboard_fab2(sch_1):m_b_dq(59)") )
				( member ( signalRef "@baseboard_fab2_lib.baseboard_fab2(sch_1):m_b_dq(60)") )
				( member ( signalRef "@baseboard_fab2_lib.baseboard_fab2(sch_1):m_b_dq(61)") )
				( member ( signalRef "@baseboard_fab2_lib.baseboard_fab2(sch_1):m_b_dq(62)") )
				( member ( signalRef "@baseboard_fab2_lib.baseboard_fab2(sch_1):m_b_dq(63)") )
				( objectStatus "M_B_DQ" )
			)
			( bus "@crescent_city_bb_fab1_lib.crescent_city_bb_fab1(sch_1):m_b_cs_n"
				( memberType ( signal ) )
				( member ( signalRef "@baseboard_fab2_lib.baseboard_fab2(sch_1):m_b_cs_n(0)") )
				( member ( signalRef "@baseboard_fab2_lib.baseboard_fab2(sch_1):m_b_cs_n(1)") )
				( member ( signalRef "@baseboard_fab2_lib.baseboard_fab2(sch_1):m_b_cs_n(2)") )
				( member ( signalRef "@baseboard_fab2_lib.baseboard_fab2(sch_1):m_b_cs_n(3)") )
				( member ( signalRef "@baseboard_fab2_lib.baseboard_fab2(sch_1):m_b_cs_n(4)") )
				( member ( signalRef "@baseboard_fab2_lib.baseboard_fab2(sch_1):m_b_cs_n(5)") )
				( member ( signalRef "@baseboard_fab2_lib.baseboard_fab2(sch_1):m_b_cs_n(6)") )
				( member ( signalRef "@baseboard_fab2_lib.baseboard_fab2(sch_1):m_b_cs_n(7)") )
				( objectStatus "M_B_CS_N" )
			)
			( bus "@crescent_city_bb_fab1_lib.crescent_city_bb_fab1(sch_1):m_b_clk_dp"
				( memberType ( signal ) )
				( member ( signalRef "@baseboard_fab2_lib.baseboard_fab2(sch_1):m_b_clk_dp(0)") )
				( member ( signalRef "@baseboard_fab2_lib.baseboard_fab2(sch_1):m_b_clk_dp(1)") )
				( member ( signalRef "@baseboard_fab2_lib.baseboard_fab2(sch_1):m_b_clk_dp(2)") )
				( member ( signalRef "@baseboard_fab2_lib.baseboard_fab2(sch_1):m_b_clk_dp(3)") )
				( objectStatus "M_B_CLK_DP" )
			)
			( bus "@crescent_city_bb_fab1_lib.crescent_city_bb_fab1(sch_1):m_b_clk_dn"
				( memberType ( signal ) )
				( member ( signalRef "@baseboard_fab2_lib.baseboard_fab2(sch_1):m_b_clk_dn(0)") )
				( member ( signalRef "@baseboard_fab2_lib.baseboard_fab2(sch_1):m_b_clk_dn(1)") )
				( member ( signalRef "@baseboard_fab2_lib.baseboard_fab2(sch_1):m_b_clk_dn(2)") )
				( member ( signalRef "@baseboard_fab2_lib.baseboard_fab2(sch_1):m_b_clk_dn(3)") )
				( objectStatus "M_B_CLK_DN" )
			)
			( bus "@crescent_city_bb_fab1_lib.crescent_city_bb_fab1(sch_1):m_b_cke"
				( memberType ( signal ) )
				( member ( signalRef "@baseboard_fab2_lib.baseboard_fab2(sch_1):m_b_cke(0)") )
				( member ( signalRef "@baseboard_fab2_lib.baseboard_fab2(sch_1):m_b_cke(1)") )
				( member ( signalRef "@baseboard_fab2_lib.baseboard_fab2(sch_1):m_b_cke(2)") )
				( member ( signalRef "@baseboard_fab2_lib.baseboard_fab2(sch_1):m_b_cke(3)") )
				( objectStatus "M_B_CKE" )
			)
			( bus "@crescent_city_bb_fab1_lib.crescent_city_bb_fab1(sch_1):m_b_c"
				( memberType ( signal ) )
				( member ( signalRef "@baseboard_fab2_lib.baseboard_fab2(sch_1):m_b_c(2)") )
				( objectStatus "M_B_C" )
			)
			( bus "@crescent_city_bb_fab1_lib.crescent_city_bb_fab1(sch_1):m_b_bg"
				( memberType ( signal ) )
				( member ( signalRef "@baseboard_fab2_lib.baseboard_fab2(sch_1):m_b_bg(0)") )
				( member ( signalRef "@baseboard_fab2_lib.baseboard_fab2(sch_1):m_b_bg(1)") )
				( objectStatus "M_B_BG" )
			)
			( bus "@crescent_city_bb_fab1_lib.crescent_city_bb_fab1(sch_1):m_b_ba"
				( memberType ( signal ) )
				( member ( signalRef "@baseboard_fab2_lib.baseboard_fab2(sch_1):m_b_ba(0)") )
				( member ( signalRef "@baseboard_fab2_lib.baseboard_fab2(sch_1):m_b_ba(1)") )
				( objectStatus "M_B_BA" )
			)
			( bus "@crescent_city_bb_fab1_lib.crescent_city_bb_fab1(sch_1):m_a_odt"
				( memberType ( signal ) )
				( member ( signalRef "@baseboard_fab2_lib.baseboard_fab2(sch_1):m_a_odt(0)") )
				( member ( signalRef "@baseboard_fab2_lib.baseboard_fab2(sch_1):m_a_odt(1)") )
				( member ( signalRef "@baseboard_fab2_lib.baseboard_fab2(sch_1):m_a_odt(2)") )
				( member ( signalRef "@baseboard_fab2_lib.baseboard_fab2(sch_1):m_a_odt(3)") )
				( objectStatus "M_A_ODT" )
			)
			( bus "@crescent_city_bb_fab1_lib.crescent_city_bb_fab1(sch_1):m_a_ma"
				( memberType ( signal ) )
				( member ( signalRef "@baseboard_fab2_lib.baseboard_fab2(sch_1):m_a_ma(0)") )
				( member ( signalRef "@baseboard_fab2_lib.baseboard_fab2(sch_1):m_a_ma(1)") )
				( member ( signalRef "@baseboard_fab2_lib.baseboard_fab2(sch_1):m_a_ma(2)") )
				( member ( signalRef "@baseboard_fab2_lib.baseboard_fab2(sch_1):m_a_ma(3)") )
				( member ( signalRef "@baseboard_fab2_lib.baseboard_fab2(sch_1):m_a_ma(4)") )
				( member ( signalRef "@baseboard_fab2_lib.baseboard_fab2(sch_1):m_a_ma(5)") )
				( member ( signalRef "@baseboard_fab2_lib.baseboard_fab2(sch_1):m_a_ma(6)") )
				( member ( signalRef "@baseboard_fab2_lib.baseboard_fab2(sch_1):m_a_ma(7)") )
				( member ( signalRef "@baseboard_fab2_lib.baseboard_fab2(sch_1):m_a_ma(8)") )
				( member ( signalRef "@baseboard_fab2_lib.baseboard_fab2(sch_1):m_a_ma(9)") )
				( member ( signalRef "@baseboard_fab2_lib.baseboard_fab2(sch_1):m_a_ma(10)") )
				( member ( signalRef "@baseboard_fab2_lib.baseboard_fab2(sch_1):m_a_ma(11)") )
				( member ( signalRef "@baseboard_fab2_lib.baseboard_fab2(sch_1):m_a_ma(12)") )
				( member ( signalRef "@baseboard_fab2_lib.baseboard_fab2(sch_1):m_a_ma(13)") )
				( member ( signalRef "@baseboard_fab2_lib.baseboard_fab2(sch_1):m_a_ma(14)") )
				( member ( signalRef "@baseboard_fab2_lib.baseboard_fab2(sch_1):m_a_ma(15)") )
				( member ( signalRef "@baseboard_fab2_lib.baseboard_fab2(sch_1):m_a_ma(16)") )
				( member ( signalRef "@baseboard_fab2_lib.baseboard_fab2(sch_1):m_a_ma(17)") )
				( objectStatus "M_A_MA" )
			)
			( bus "@crescent_city_bb_fab1_lib.crescent_city_bb_fab1(sch_1):m_a_ecc"
				( memberType ( signal ) )
				( member ( signalRef "@baseboard_fab2_lib.baseboard_fab2(sch_1):m_a_ecc(0)") )
				( member ( signalRef "@baseboard_fab2_lib.baseboard_fab2(sch_1):m_a_ecc(1)") )
				( member ( signalRef "@baseboard_fab2_lib.baseboard_fab2(sch_1):m_a_ecc(2)") )
				( member ( signalRef "@baseboard_fab2_lib.baseboard_fab2(sch_1):m_a_ecc(3)") )
				( member ( signalRef "@baseboard_fab2_lib.baseboard_fab2(sch_1):m_a_ecc(4)") )
				( member ( signalRef "@baseboard_fab2_lib.baseboard_fab2(sch_1):m_a_ecc(5)") )
				( member ( signalRef "@baseboard_fab2_lib.baseboard_fab2(sch_1):m_a_ecc(6)") )
				( member ( signalRef "@baseboard_fab2_lib.baseboard_fab2(sch_1):m_a_ecc(7)") )
				( objectStatus "M_A_ECC" )
			)
			( bus "@crescent_city_bb_fab1_lib.crescent_city_bb_fab1(sch_1):m_a_dqs_dp"
				( memberType ( signal ) )
				( member ( signalRef "@baseboard_fab2_lib.baseboard_fab2(sch_1):m_a_dqs_dp(0)") )
				( member ( signalRef "@baseboard_fab2_lib.baseboard_fab2(sch_1):m_a_dqs_dp(1)") )
				( member ( signalRef "@baseboard_fab2_lib.baseboard_fab2(sch_1):m_a_dqs_dp(2)") )
				( member ( signalRef "@baseboard_fab2_lib.baseboard_fab2(sch_1):m_a_dqs_dp(3)") )
				( member ( signalRef "@baseboard_fab2_lib.baseboard_fab2(sch_1):m_a_dqs_dp(4)") )
				( member ( signalRef "@baseboard_fab2_lib.baseboard_fab2(sch_1):m_a_dqs_dp(5)") )
				( member ( signalRef "@baseboard_fab2_lib.baseboard_fab2(sch_1):m_a_dqs_dp(6)") )
				( member ( signalRef "@baseboard_fab2_lib.baseboard_fab2(sch_1):m_a_dqs_dp(7)") )
				( member ( signalRef "@baseboard_fab2_lib.baseboard_fab2(sch_1):m_a_dqs_dp(8)") )
				( member ( signalRef "@baseboard_fab2_lib.baseboard_fab2(sch_1):m_a_dqs_dp(9)") )
				( member ( signalRef "@baseboard_fab2_lib.baseboard_fab2(sch_1):m_a_dqs_dp(10)") )
				( member ( signalRef "@baseboard_fab2_lib.baseboard_fab2(sch_1):m_a_dqs_dp(11)") )
				( member ( signalRef "@baseboard_fab2_lib.baseboard_fab2(sch_1):m_a_dqs_dp(12)") )
				( member ( signalRef "@baseboard_fab2_lib.baseboard_fab2(sch_1):m_a_dqs_dp(13)") )
				( member ( signalRef "@baseboard_fab2_lib.baseboard_fab2(sch_1):m_a_dqs_dp(14)") )
				( member ( signalRef "@baseboard_fab2_lib.baseboard_fab2(sch_1):m_a_dqs_dp(15)") )
				( member ( signalRef "@baseboard_fab2_lib.baseboard_fab2(sch_1):m_a_dqs_dp(16)") )
				( member ( signalRef "@baseboard_fab2_lib.baseboard_fab2(sch_1):m_a_dqs_dp(17)") )
				( objectStatus "M_A_DQS_DP" )
			)
			( bus "@crescent_city_bb_fab1_lib.crescent_city_bb_fab1(sch_1):m_a_dqs_dn"
				( memberType ( signal ) )
				( member ( signalRef "@baseboard_fab2_lib.baseboard_fab2(sch_1):m_a_dqs_dn(0)") )
				( member ( signalRef "@baseboard_fab2_lib.baseboard_fab2(sch_1):m_a_dqs_dn(1)") )
				( member ( signalRef "@baseboard_fab2_lib.baseboard_fab2(sch_1):m_a_dqs_dn(2)") )
				( member ( signalRef "@baseboard_fab2_lib.baseboard_fab2(sch_1):m_a_dqs_dn(3)") )
				( member ( signalRef "@baseboard_fab2_lib.baseboard_fab2(sch_1):m_a_dqs_dn(4)") )
				( member ( signalRef "@baseboard_fab2_lib.baseboard_fab2(sch_1):m_a_dqs_dn(5)") )
				( member ( signalRef "@baseboard_fab2_lib.baseboard_fab2(sch_1):m_a_dqs_dn(6)") )
				( member ( signalRef "@baseboard_fab2_lib.baseboard_fab2(sch_1):m_a_dqs_dn(7)") )
				( member ( signalRef "@baseboard_fab2_lib.baseboard_fab2(sch_1):m_a_dqs_dn(8)") )
				( member ( signalRef "@baseboard_fab2_lib.baseboard_fab2(sch_1):m_a_dqs_dn(9)") )
				( member ( signalRef "@baseboard_fab2_lib.baseboard_fab2(sch_1):m_a_dqs_dn(10)") )
				( member ( signalRef "@baseboard_fab2_lib.baseboard_fab2(sch_1):m_a_dqs_dn(11)") )
				( member ( signalRef "@baseboard_fab2_lib.baseboard_fab2(sch_1):m_a_dqs_dn(12)") )
				( member ( signalRef "@baseboard_fab2_lib.baseboard_fab2(sch_1):m_a_dqs_dn(13)") )
				( member ( signalRef "@baseboard_fab2_lib.baseboard_fab2(sch_1):m_a_dqs_dn(14)") )
				( member ( signalRef "@baseboard_fab2_lib.baseboard_fab2(sch_1):m_a_dqs_dn(15)") )
				( member ( signalRef "@baseboard_fab2_lib.baseboard_fab2(sch_1):m_a_dqs_dn(16)") )
				( member ( signalRef "@baseboard_fab2_lib.baseboard_fab2(sch_1):m_a_dqs_dn(17)") )
				( objectStatus "M_A_DQS_DN" )
			)
			( bus "@crescent_city_bb_fab1_lib.crescent_city_bb_fab1(sch_1):m_a_dq"
				( memberType ( signal ) )
				( member ( signalRef "@baseboard_fab2_lib.baseboard_fab2(sch_1):m_a_dq(0)") )
				( member ( signalRef "@baseboard_fab2_lib.baseboard_fab2(sch_1):m_a_dq(1)") )
				( member ( signalRef "@baseboard_fab2_lib.baseboard_fab2(sch_1):m_a_dq(2)") )
				( member ( signalRef "@baseboard_fab2_lib.baseboard_fab2(sch_1):m_a_dq(3)") )
				( member ( signalRef "@baseboard_fab2_lib.baseboard_fab2(sch_1):m_a_dq(4)") )
				( member ( signalRef "@baseboard_fab2_lib.baseboard_fab2(sch_1):m_a_dq(5)") )
				( member ( signalRef "@baseboard_fab2_lib.baseboard_fab2(sch_1):m_a_dq(6)") )
				( member ( signalRef "@baseboard_fab2_lib.baseboard_fab2(sch_1):m_a_dq(7)") )
				( member ( signalRef "@baseboard_fab2_lib.baseboard_fab2(sch_1):m_a_dq(8)") )
				( member ( signalRef "@baseboard_fab2_lib.baseboard_fab2(sch_1):m_a_dq(9)") )
				( member ( signalRef "@baseboard_fab2_lib.baseboard_fab2(sch_1):m_a_dq(10)") )
				( member ( signalRef "@baseboard_fab2_lib.baseboard_fab2(sch_1):m_a_dq(11)") )
				( member ( signalRef "@baseboard_fab2_lib.baseboard_fab2(sch_1):m_a_dq(12)") )
				( member ( signalRef "@baseboard_fab2_lib.baseboard_fab2(sch_1):m_a_dq(13)") )
				( member ( signalRef "@baseboard_fab2_lib.baseboard_fab2(sch_1):m_a_dq(14)") )
				( member ( signalRef "@baseboard_fab2_lib.baseboard_fab2(sch_1):m_a_dq(15)") )
				( member ( signalRef "@baseboard_fab2_lib.baseboard_fab2(sch_1):m_a_dq(16)") )
				( member ( signalRef "@baseboard_fab2_lib.baseboard_fab2(sch_1):m_a_dq(17)") )
				( member ( signalRef "@baseboard_fab2_lib.baseboard_fab2(sch_1):m_a_dq(18)") )
				( member ( signalRef "@baseboard_fab2_lib.baseboard_fab2(sch_1):m_a_dq(19)") )
				( member ( signalRef "@baseboard_fab2_lib.baseboard_fab2(sch_1):m_a_dq(20)") )
				( member ( signalRef "@baseboard_fab2_lib.baseboard_fab2(sch_1):m_a_dq(21)") )
				( member ( signalRef "@baseboard_fab2_lib.baseboard_fab2(sch_1):m_a_dq(22)") )
				( member ( signalRef "@baseboard_fab2_lib.baseboard_fab2(sch_1):m_a_dq(23)") )
				( member ( signalRef "@baseboard_fab2_lib.baseboard_fab2(sch_1):m_a_dq(24)") )
				( member ( signalRef "@baseboard_fab2_lib.baseboard_fab2(sch_1):m_a_dq(25)") )
				( member ( signalRef "@baseboard_fab2_lib.baseboard_fab2(sch_1):m_a_dq(26)") )
				( member ( signalRef "@baseboard_fab2_lib.baseboard_fab2(sch_1):m_a_dq(27)") )
				( member ( signalRef "@baseboard_fab2_lib.baseboard_fab2(sch_1):m_a_dq(28)") )
				( member ( signalRef "@baseboard_fab2_lib.baseboard_fab2(sch_1):m_a_dq(29)") )
				( member ( signalRef "@baseboard_fab2_lib.baseboard_fab2(sch_1):m_a_dq(30)") )
				( member ( signalRef "@baseboard_fab2_lib.baseboard_fab2(sch_1):m_a_dq(31)") )
				( member ( signalRef "@baseboard_fab2_lib.baseboard_fab2(sch_1):m_a_dq(32)") )
				( member ( signalRef "@baseboard_fab2_lib.baseboard_fab2(sch_1):m_a_dq(33)") )
				( member ( signalRef "@baseboard_fab2_lib.baseboard_fab2(sch_1):m_a_dq(34)") )
				( member ( signalRef "@baseboard_fab2_lib.baseboard_fab2(sch_1):m_a_dq(35)") )
				( member ( signalRef "@baseboard_fab2_lib.baseboard_fab2(sch_1):m_a_dq(36)") )
				( member ( signalRef "@baseboard_fab2_lib.baseboard_fab2(sch_1):m_a_dq(37)") )
				( member ( signalRef "@baseboard_fab2_lib.baseboard_fab2(sch_1):m_a_dq(38)") )
				( member ( signalRef "@baseboard_fab2_lib.baseboard_fab2(sch_1):m_a_dq(39)") )
				( member ( signalRef "@baseboard_fab2_lib.baseboard_fab2(sch_1):m_a_dq(40)") )
				( member ( signalRef "@baseboard_fab2_lib.baseboard_fab2(sch_1):m_a_dq(41)") )
				( member ( signalRef "@baseboard_fab2_lib.baseboard_fab2(sch_1):m_a_dq(42)") )
				( member ( signalRef "@baseboard_fab2_lib.baseboard_fab2(sch_1):m_a_dq(43)") )
				( member ( signalRef "@baseboard_fab2_lib.baseboard_fab2(sch_1):m_a_dq(44)") )
				( member ( signalRef "@baseboard_fab2_lib.baseboard_fab2(sch_1):m_a_dq(45)") )
				( member ( signalRef "@baseboard_fab2_lib.baseboard_fab2(sch_1):m_a_dq(46)") )
				( member ( signalRef "@baseboard_fab2_lib.baseboard_fab2(sch_1):m_a_dq(47)") )
				( member ( signalRef "@baseboard_fab2_lib.baseboard_fab2(sch_1):m_a_dq(48)") )
				( member ( signalRef "@baseboard_fab2_lib.baseboard_fab2(sch_1):m_a_dq(49)") )
				( member ( signalRef "@baseboard_fab2_lib.baseboard_fab2(sch_1):m_a_dq(50)") )
				( member ( signalRef "@baseboard_fab2_lib.baseboard_fab2(sch_1):m_a_dq(51)") )
				( member ( signalRef "@baseboard_fab2_lib.baseboard_fab2(sch_1):m_a_dq(52)") )
				( member ( signalRef "@baseboard_fab2_lib.baseboard_fab2(sch_1):m_a_dq(53)") )
				( member ( signalRef "@baseboard_fab2_lib.baseboard_fab2(sch_1):m_a_dq(54)") )
				( member ( signalRef "@baseboard_fab2_lib.baseboard_fab2(sch_1):m_a_dq(55)") )
				( member ( signalRef "@baseboard_fab2_lib.baseboard_fab2(sch_1):m_a_dq(56)") )
				( member ( signalRef "@baseboard_fab2_lib.baseboard_fab2(sch_1):m_a_dq(57)") )
				( member ( signalRef "@baseboard_fab2_lib.baseboard_fab2(sch_1):m_a_dq(58)") )
				( member ( signalRef "@baseboard_fab2_lib.baseboard_fab2(sch_1):m_a_dq(59)") )
				( member ( signalRef "@baseboard_fab2_lib.baseboard_fab2(sch_1):m_a_dq(60)") )
				( member ( signalRef "@baseboard_fab2_lib.baseboard_fab2(sch_1):m_a_dq(61)") )
				( member ( signalRef "@baseboard_fab2_lib.baseboard_fab2(sch_1):m_a_dq(62)") )
				( member ( signalRef "@baseboard_fab2_lib.baseboard_fab2(sch_1):m_a_dq(63)") )
				( objectStatus "M_A_DQ" )
			)
			( bus "@crescent_city_bb_fab1_lib.crescent_city_bb_fab1(sch_1):m_a_cs_n"
				( memberType ( signal ) )
				( member ( signalRef "@baseboard_fab2_lib.baseboard_fab2(sch_1):m_a_cs_n(0)") )
				( member ( signalRef "@baseboard_fab2_lib.baseboard_fab2(sch_1):m_a_cs_n(1)") )
				( member ( signalRef "@baseboard_fab2_lib.baseboard_fab2(sch_1):m_a_cs_n(2)") )
				( member ( signalRef "@baseboard_fab2_lib.baseboard_fab2(sch_1):m_a_cs_n(3)") )
				( member ( signalRef "@baseboard_fab2_lib.baseboard_fab2(sch_1):m_a_cs_n(4)") )
				( member ( signalRef "@baseboard_fab2_lib.baseboard_fab2(sch_1):m_a_cs_n(5)") )
				( member ( signalRef "@baseboard_fab2_lib.baseboard_fab2(sch_1):m_a_cs_n(6)") )
				( member ( signalRef "@baseboard_fab2_lib.baseboard_fab2(sch_1):m_a_cs_n(7)") )
				( objectStatus "M_A_CS_N" )
			)
			( bus "@crescent_city_bb_fab1_lib.crescent_city_bb_fab1(sch_1):m_a_clk_dp"
				( memberType ( signal ) )
				( member ( signalRef "@baseboard_fab2_lib.baseboard_fab2(sch_1):m_a_clk_dp(0)") )
				( member ( signalRef "@baseboard_fab2_lib.baseboard_fab2(sch_1):m_a_clk_dp(2)") )
				( member ( signalRef "@baseboard_fab2_lib.baseboard_fab2(sch_1):m_a_clk_dp(1)") )
				( member ( signalRef "@baseboard_fab2_lib.baseboard_fab2(sch_1):m_a_clk_dp(3)") )
				( objectStatus "M_A_CLK_DP" )
			)
			( bus "@crescent_city_bb_fab1_lib.crescent_city_bb_fab1(sch_1):m_a_clk_dn"
				( memberType ( signal ) )
				( member ( signalRef "@baseboard_fab2_lib.baseboard_fab2(sch_1):m_a_clk_dn(0)") )
				( member ( signalRef "@baseboard_fab2_lib.baseboard_fab2(sch_1):m_a_clk_dn(2)") )
				( member ( signalRef "@baseboard_fab2_lib.baseboard_fab2(sch_1):m_a_clk_dn(1)") )
				( member ( signalRef "@baseboard_fab2_lib.baseboard_fab2(sch_1):m_a_clk_dn(3)") )
				( objectStatus "M_A_CLK_DN" )
			)
			( bus "@crescent_city_bb_fab1_lib.crescent_city_bb_fab1(sch_1):m_a_cke"
				( memberType ( signal ) )
				( member ( signalRef "@baseboard_fab2_lib.baseboard_fab2(sch_1):m_a_cke(0)") )
				( member ( signalRef "@baseboard_fab2_lib.baseboard_fab2(sch_1):m_a_cke(1)") )
				( member ( signalRef "@baseboard_fab2_lib.baseboard_fab2(sch_1):m_a_cke(2)") )
				( member ( signalRef "@baseboard_fab2_lib.baseboard_fab2(sch_1):m_a_cke(3)") )
				( objectStatus "M_A_CKE" )
			)
			( bus "@crescent_city_bb_fab1_lib.crescent_city_bb_fab1(sch_1):m_a_c"
				( memberType ( signal ) )
				( member ( signalRef "@baseboard_fab2_lib.baseboard_fab2(sch_1):m_a_c(2)") )
				( objectStatus "M_A_C" )
			)
			( bus "@crescent_city_bb_fab1_lib.crescent_city_bb_fab1(sch_1):m_a_bg"
				( memberType ( signal ) )
				( member ( signalRef "@baseboard_fab2_lib.baseboard_fab2(sch_1):m_a_bg(0)") )
				( member ( signalRef "@baseboard_fab2_lib.baseboard_fab2(sch_1):m_a_bg(1)") )
				( objectStatus "M_A_BG" )
			)
			( bus "@crescent_city_bb_fab1_lib.crescent_city_bb_fab1(sch_1):m_a_ba"
				( memberType ( signal ) )
				( member ( signalRef "@baseboard_fab2_lib.baseboard_fab2(sch_1):m_a_ba(0)") )
				( member ( signalRef "@baseboard_fab2_lib.baseboard_fab2(sch_1):m_a_ba(1)") )
				( objectStatus "M_A_BA" )
			)
			( netClass "@sapphirecity_baseboard_lib.sapphirecity_baseboard(sch_1):\GND\"
				( memberType ( signal ) )
				( physicalCSetRef "@sapphirecity_baseboard_lib.sapphirecity_baseboard(sch_1):\10-MILS-POWER\" )
				( spacingCSetRef "@crescent_city_bb_fab1_lib.crescent_city_bb_fab1(sch_1):\DEFAULT\" )
				( sameNetSpacingCSetRef "@crescent_city_bb_fab1_lib.crescent_city_bb_fab1(sch_1):\DEFAULT\" )
				( objectFlag fObjectPhysical )
				( objectFlag fObjectSpacing )
				( objectFlag fObjectSameNetSpacing )
				( member ( signalRef "@baseboard_fab2_lib.baseboard_fab2(sch_1):gnd") )
				( member ( signalRef "@baseboard_fab2_lib.baseboard_fab2(sch_1):agnd_hsc") )
				( member ( signalRef "@baseboard_fab2_lib.baseboard_fab2(sch_1):agnd_pvpp_abc") )
				( member ( signalRef "@baseboard_fab2_lib.baseboard_fab2(sch_1):agnd_pvpp_def") )
				( member ( signalRef "@baseboard_fab2_lib.baseboard_fab2(sch_1):agnd_pvpp_ghj") )
				( member ( signalRef "@baseboard_fab2_lib.baseboard_fab2(sch_1):agnd_pvpp_klm") )
				( member ( signalRef "@baseboard_fab2_lib.baseboard_fab2(sch_1):agnd_p3v3_stby") )
				( member ( signalRef "@baseboard_fab2_lib.baseboard_fab2(sch_1):agnd_p5v_stby") )
				( member ( signalRef "@baseboard_fab2_lib.baseboard_fab2(sch_1):gnd_nic") )
				( member ( signalRef "@baseboard_fab2_lib.baseboard_fab2(sch_1):gnd_signal1") )
				( member ( signalRef "@baseboard_fab2_lib.baseboard_fab2(sch_1):gnd_signal2") )
				( objectStatus "GND" )
			)
			( netClass "@sapphirecity_baseboard_lib.sapphirecity_baseboard(sch_1):\KTI_CPU0_CPU1_P1P0\"
				( memberType ( signal ) )
				( spacingCSetRef "@crescent_city_bb_fab1_lib.crescent_city_bb_fab1(sch_1):\13H_US_AND_7H_SL_VIA+3H_A\" )
				( sameNetSpacingCSetRef "@crescent_city_bb_fab1_lib.crescent_city_bb_fab1(sch_1):\20_MIL\" )
				( objectFlag fObjectSpacing )
				( objectFlag fObjectSameNetSpacing )
				( member ( diffPairRef "@crescent_city_bb_fab1_lib.crescent_city_bb_fab1(sch_1):\KTI_CPU0_CPU1_P0P0\(0)") )
				( member ( diffPairRef "@crescent_city_bb_fab1_lib.crescent_city_bb_fab1(sch_1):\KTI_CPU0_CPU1_P0P0\(1)") )
				( member ( diffPairRef "@crescent_city_bb_fab1_lib.crescent_city_bb_fab1(sch_1):\KTI_CPU0_CPU1_P0P0\(2)") )
				( member ( diffPairRef "@crescent_city_bb_fab1_lib.crescent_city_bb_fab1(sch_1):\KTI_CPU0_CPU1_P0P0\(3)") )
				( member ( diffPairRef "@crescent_city_bb_fab1_lib.crescent_city_bb_fab1(sch_1):\KTI_CPU0_CPU1_P0P0\(4)") )
				( member ( diffPairRef "@crescent_city_bb_fab1_lib.crescent_city_bb_fab1(sch_1):\KTI_CPU0_CPU1_P0P0\(5)") )
				( member ( diffPairRef "@crescent_city_bb_fab1_lib.crescent_city_bb_fab1(sch_1):\KTI_CPU0_CPU1_P0P0\(6)") )
				( member ( diffPairRef "@crescent_city_bb_fab1_lib.crescent_city_bb_fab1(sch_1):\KTI_CPU0_CPU1_P0P0\(7)") )
				( member ( diffPairRef "@crescent_city_bb_fab1_lib.crescent_city_bb_fab1(sch_1):\KTI_CPU0_CPU1_P0P0\(8)") )
				( member ( diffPairRef "@crescent_city_bb_fab1_lib.crescent_city_bb_fab1(sch_1):\KTI_CPU0_CPU1_P0P0\(9)") )
				( member ( diffPairRef "@crescent_city_bb_fab1_lib.crescent_city_bb_fab1(sch_1):\KTI_CPU0_CPU1_P0P0\(10)") )
				( member ( diffPairRef "@crescent_city_bb_fab1_lib.crescent_city_bb_fab1(sch_1):\KTI_CPU0_CPU1_P0P0\(11)") )
				( member ( diffPairRef "@crescent_city_bb_fab1_lib.crescent_city_bb_fab1(sch_1):\KTI_CPU0_CPU1_P0P0\(12)") )
				( member ( diffPairRef "@crescent_city_bb_fab1_lib.crescent_city_bb_fab1(sch_1):\KTI_CPU0_CPU1_P0P0\(13)") )
				( member ( diffPairRef "@crescent_city_bb_fab1_lib.crescent_city_bb_fab1(sch_1):\KTI_CPU0_CPU1_P0P0\(14)") )
				( member ( diffPairRef "@crescent_city_bb_fab1_lib.crescent_city_bb_fab1(sch_1):\KTI_CPU0_CPU1_P0P0\(15)") )
				( member ( diffPairRef "@crescent_city_bb_fab1_lib.crescent_city_bb_fab1(sch_1):\KTI_CPU0_CPU1_P0P0\(16)") )
				( member ( diffPairRef "@crescent_city_bb_fab1_lib.crescent_city_bb_fab1(sch_1):\KTI_CPU0_CPU1_P0P0\(17)") )
				( member ( diffPairRef "@crescent_city_bb_fab1_lib.crescent_city_bb_fab1(sch_1):\KTI_CPU0_CPU1_P0P0\(18)") )
				( member ( diffPairRef "@crescent_city_bb_fab1_lib.crescent_city_bb_fab1(sch_1):\KTI_CPU0_CPU1_P0P0\(19)") )
				( objectStatus "SNCLS_UPI_CPU0_CPU1_P0P0" )
			)
			( netClass "@sapphirecity_baseboard_lib.sapphirecity_baseboard(sch_1):\KTI_CPU0_CPU1_P0P1\"
				( memberType ( signal ) )
				( spacingCSetRef "@crescent_city_bb_fab1_lib.crescent_city_bb_fab1(sch_1):\13H_US_AND_7H_SL_VIA+3H_A\" )
				( sameNetSpacingCSetRef "@crescent_city_bb_fab1_lib.crescent_city_bb_fab1(sch_1):\20_MIL\" )
				( objectFlag fObjectSpacing )
				( objectFlag fObjectSameNetSpacing )
				( member ( diffPairRef "@crescent_city_bb_fab1_lib.crescent_city_bb_fab1(sch_1):\KTI_CPU0_CPU1_P1P1\(0)") )
				( member ( diffPairRef "@crescent_city_bb_fab1_lib.crescent_city_bb_fab1(sch_1):\KTI_CPU0_CPU1_P1P1\(1)") )
				( member ( diffPairRef "@crescent_city_bb_fab1_lib.crescent_city_bb_fab1(sch_1):\KTI_CPU0_CPU1_P1P1\(2)") )
				( member ( diffPairRef "@crescent_city_bb_fab1_lib.crescent_city_bb_fab1(sch_1):\KTI_CPU0_CPU1_P1P1\(3)") )
				( member ( diffPairRef "@crescent_city_bb_fab1_lib.crescent_city_bb_fab1(sch_1):\KTI_CPU0_CPU1_P1P1\(4)") )
				( member ( diffPairRef "@crescent_city_bb_fab1_lib.crescent_city_bb_fab1(sch_1):\KTI_CPU0_CPU1_P1P1\(5)") )
				( member ( diffPairRef "@crescent_city_bb_fab1_lib.crescent_city_bb_fab1(sch_1):\KTI_CPU0_CPU1_P1P1\(6)") )
				( member ( diffPairRef "@crescent_city_bb_fab1_lib.crescent_city_bb_fab1(sch_1):\KTI_CPU0_CPU1_P1P1\(7)") )
				( member ( diffPairRef "@crescent_city_bb_fab1_lib.crescent_city_bb_fab1(sch_1):\KTI_CPU0_CPU1_P1P1\(8)") )
				( member ( diffPairRef "@crescent_city_bb_fab1_lib.crescent_city_bb_fab1(sch_1):\KTI_CPU0_CPU1_P1P1\(9)") )
				( member ( diffPairRef "@crescent_city_bb_fab1_lib.crescent_city_bb_fab1(sch_1):\KTI_CPU0_CPU1_P1P1\(10)") )
				( member ( diffPairRef "@crescent_city_bb_fab1_lib.crescent_city_bb_fab1(sch_1):\KTI_CPU0_CPU1_P1P1\(11)") )
				( member ( diffPairRef "@crescent_city_bb_fab1_lib.crescent_city_bb_fab1(sch_1):\KTI_CPU0_CPU1_P1P1\(12)") )
				( member ( diffPairRef "@crescent_city_bb_fab1_lib.crescent_city_bb_fab1(sch_1):\KTI_CPU0_CPU1_P1P1\(13)") )
				( member ( diffPairRef "@crescent_city_bb_fab1_lib.crescent_city_bb_fab1(sch_1):\KTI_CPU0_CPU1_P1P1\(14)") )
				( member ( diffPairRef "@crescent_city_bb_fab1_lib.crescent_city_bb_fab1(sch_1):\KTI_CPU0_CPU1_P1P1\(15)") )
				( member ( diffPairRef "@crescent_city_bb_fab1_lib.crescent_city_bb_fab1(sch_1):\KTI_CPU0_CPU1_P1P1\(16)") )
				( member ( diffPairRef "@crescent_city_bb_fab1_lib.crescent_city_bb_fab1(sch_1):\KTI_CPU0_CPU1_P1P1\(17)") )
				( member ( diffPairRef "@crescent_city_bb_fab1_lib.crescent_city_bb_fab1(sch_1):\KTI_CPU0_CPU1_P1P1\(18)") )
				( member ( diffPairRef "@crescent_city_bb_fab1_lib.crescent_city_bb_fab1(sch_1):\KTI_CPU0_CPU1_P1P1\(19)") )
				( objectStatus "SNCLS_UPI_CPU0_CPU1_P1P1" )
			)
			( netClass "@sapphirecity_baseboard_lib.sapphirecity_baseboard(sch_1):\KTI_CPU1_CPU0_P1P0\"
				( memberType ( signal ) )
				( spacingCSetRef "@crescent_city_bb_fab1_lib.crescent_city_bb_fab1(sch_1):\13H_US_AND_7H_SL_VIA+3H_A\" )
				( sameNetSpacingCSetRef "@crescent_city_bb_fab1_lib.crescent_city_bb_fab1(sch_1):\20_MIL\" )
				( objectFlag fObjectSpacing )
				( objectFlag fObjectSameNetSpacing )
				( member ( diffPairRef "@crescent_city_bb_fab1_lib.crescent_city_bb_fab1(sch_1):\KTI_CPU1_CPU0_P0P0\(0)") )
				( member ( diffPairRef "@crescent_city_bb_fab1_lib.crescent_city_bb_fab1(sch_1):\KTI_CPU1_CPU0_P0P0\(1)") )
				( member ( diffPairRef "@crescent_city_bb_fab1_lib.crescent_city_bb_fab1(sch_1):\KTI_CPU1_CPU0_P0P0\(2)") )
				( member ( diffPairRef "@crescent_city_bb_fab1_lib.crescent_city_bb_fab1(sch_1):\KTI_CPU1_CPU0_P0P0\(3)") )
				( member ( diffPairRef "@crescent_city_bb_fab1_lib.crescent_city_bb_fab1(sch_1):\KTI_CPU1_CPU0_P0P0\(4)") )
				( member ( diffPairRef "@crescent_city_bb_fab1_lib.crescent_city_bb_fab1(sch_1):\KTI_CPU1_CPU0_P0P0\(5)") )
				( member ( diffPairRef "@crescent_city_bb_fab1_lib.crescent_city_bb_fab1(sch_1):\KTI_CPU1_CPU0_P0P0\(6)") )
				( member ( diffPairRef "@crescent_city_bb_fab1_lib.crescent_city_bb_fab1(sch_1):\KTI_CPU1_CPU0_P0P0\(7)") )
				( member ( diffPairRef "@crescent_city_bb_fab1_lib.crescent_city_bb_fab1(sch_1):\KTI_CPU1_CPU0_P0P0\(8)") )
				( member ( diffPairRef "@crescent_city_bb_fab1_lib.crescent_city_bb_fab1(sch_1):\KTI_CPU1_CPU0_P0P0\(9)") )
				( member ( diffPairRef "@crescent_city_bb_fab1_lib.crescent_city_bb_fab1(sch_1):\KTI_CPU1_CPU0_P0P0\(10)") )
				( member ( diffPairRef "@crescent_city_bb_fab1_lib.crescent_city_bb_fab1(sch_1):\KTI_CPU1_CPU0_P0P0\(11)") )
				( member ( diffPairRef "@crescent_city_bb_fab1_lib.crescent_city_bb_fab1(sch_1):\KTI_CPU1_CPU0_P0P0\(12)") )
				( member ( diffPairRef "@crescent_city_bb_fab1_lib.crescent_city_bb_fab1(sch_1):\KTI_CPU1_CPU0_P0P0\(13)") )
				( member ( diffPairRef "@crescent_city_bb_fab1_lib.crescent_city_bb_fab1(sch_1):\KTI_CPU1_CPU0_P0P0\(14)") )
				( member ( diffPairRef "@crescent_city_bb_fab1_lib.crescent_city_bb_fab1(sch_1):\KTI_CPU1_CPU0_P0P0\(15)") )
				( member ( diffPairRef "@crescent_city_bb_fab1_lib.crescent_city_bb_fab1(sch_1):\KTI_CPU1_CPU0_P0P0\(16)") )
				( member ( diffPairRef "@crescent_city_bb_fab1_lib.crescent_city_bb_fab1(sch_1):\KTI_CPU1_CPU0_P0P0\(17)") )
				( member ( diffPairRef "@crescent_city_bb_fab1_lib.crescent_city_bb_fab1(sch_1):\KTI_CPU1_CPU0_P0P0\(18)") )
				( member ( diffPairRef "@crescent_city_bb_fab1_lib.crescent_city_bb_fab1(sch_1):\KTI_CPU1_CPU0_P0P0\(19)") )
				( objectStatus "SNCLS_UPI_CPU1_CPU0_P0P0" )
			)
			( netClass "@sapphirecity_baseboard_lib.sapphirecity_baseboard(sch_1):\KTI_CPU1_CPU0_P0P1\"
				( memberType ( signal ) )
				( spacingCSetRef "@crescent_city_bb_fab1_lib.crescent_city_bb_fab1(sch_1):\13H_US_AND_7H_SL_VIA+3H_A\" )
				( sameNetSpacingCSetRef "@crescent_city_bb_fab1_lib.crescent_city_bb_fab1(sch_1):\20_MIL\" )
				( objectFlag fObjectSpacing )
				( objectFlag fObjectSameNetSpacing )
				( member ( diffPairRef "@crescent_city_bb_fab1_lib.crescent_city_bb_fab1(sch_1):\KTI_CPU1_CPU0_P1P1\(0)") )
				( member ( diffPairRef "@crescent_city_bb_fab1_lib.crescent_city_bb_fab1(sch_1):\KTI_CPU1_CPU0_P1P1\(1)") )
				( member ( diffPairRef "@crescent_city_bb_fab1_lib.crescent_city_bb_fab1(sch_1):\KTI_CPU1_CPU0_P1P1\(2)") )
				( member ( diffPairRef "@crescent_city_bb_fab1_lib.crescent_city_bb_fab1(sch_1):\KTI_CPU1_CPU0_P1P1\(3)") )
				( member ( diffPairRef "@crescent_city_bb_fab1_lib.crescent_city_bb_fab1(sch_1):\KTI_CPU1_CPU0_P1P1\(4)") )
				( member ( diffPairRef "@crescent_city_bb_fab1_lib.crescent_city_bb_fab1(sch_1):\KTI_CPU1_CPU0_P1P1\(5)") )
				( member ( diffPairRef "@crescent_city_bb_fab1_lib.crescent_city_bb_fab1(sch_1):\KTI_CPU1_CPU0_P1P1\(6)") )
				( member ( diffPairRef "@crescent_city_bb_fab1_lib.crescent_city_bb_fab1(sch_1):\KTI_CPU1_CPU0_P1P1\(7)") )
				( member ( diffPairRef "@crescent_city_bb_fab1_lib.crescent_city_bb_fab1(sch_1):\KTI_CPU1_CPU0_P1P1\(8)") )
				( member ( diffPairRef "@crescent_city_bb_fab1_lib.crescent_city_bb_fab1(sch_1):\KTI_CPU1_CPU0_P1P1\(9)") )
				( member ( diffPairRef "@crescent_city_bb_fab1_lib.crescent_city_bb_fab1(sch_1):\KTI_CPU1_CPU0_P1P1\(10)") )
				( member ( diffPairRef "@crescent_city_bb_fab1_lib.crescent_city_bb_fab1(sch_1):\KTI_CPU1_CPU0_P1P1\(11)") )
				( member ( diffPairRef "@crescent_city_bb_fab1_lib.crescent_city_bb_fab1(sch_1):\KTI_CPU1_CPU0_P1P1\(12)") )
				( member ( diffPairRef "@crescent_city_bb_fab1_lib.crescent_city_bb_fab1(sch_1):\KTI_CPU1_CPU0_P1P1\(13)") )
				( member ( diffPairRef "@crescent_city_bb_fab1_lib.crescent_city_bb_fab1(sch_1):\KTI_CPU1_CPU0_P1P1\(14)") )
				( member ( diffPairRef "@crescent_city_bb_fab1_lib.crescent_city_bb_fab1(sch_1):\KTI_CPU1_CPU0_P1P1\(15)") )
				( member ( diffPairRef "@crescent_city_bb_fab1_lib.crescent_city_bb_fab1(sch_1):\KTI_CPU1_CPU0_P1P1\(16)") )
				( member ( diffPairRef "@crescent_city_bb_fab1_lib.crescent_city_bb_fab1(sch_1):\KTI_CPU1_CPU0_P1P1\(17)") )
				( member ( diffPairRef "@crescent_city_bb_fab1_lib.crescent_city_bb_fab1(sch_1):\KTI_CPU1_CPU0_P1P1\(18)") )
				( member ( diffPairRef "@crescent_city_bb_fab1_lib.crescent_city_bb_fab1(sch_1):\KTI_CPU1_CPU0_P1P1\(19)") )
				( objectStatus "SNCLS_UPI_CPU1_CPU0_P1P1" )
			)
			( netClass "@sapphirecity_baseboard_lib.sapphirecity_baseboard(sch_1):\DDR4_CHN_A_DQ_DQS_BYTE7\"
				( memberType ( signal ) )
				( spacingCSetRef "@sapphirecity_baseboard_lib.sapphirecity_baseboard(sch_1):\10H_SL_12H_MS\" )
				( sameNetSpacingCSetRef "@crescent_city_bb_fab1_lib.crescent_city_bb_fab1(sch_1):\7H_US_AND_5H_SL\" )
				( objectFlag fObjectSpacing )
				( objectFlag fObjectSameNetSpacing )
				( member ( diffPairRef "@sapphirecity_baseboard_lib.sapphirecity_baseboard(sch_1):\M_A_DQS_D\(7)") )
				( member ( diffPairRef "@sapphirecity_baseboard_lib.sapphirecity_baseboard(sch_1):\M_A_DQS_D\(16)") )
				( member ( signalRef "@baseboard_fab2_lib.baseboard_fab2(sch_1):m_a_dq(56)") )
				( member ( signalRef "@baseboard_fab2_lib.baseboard_fab2(sch_1):m_a_dq(57)") )
				( member ( signalRef "@baseboard_fab2_lib.baseboard_fab2(sch_1):m_a_dq(58)") )
				( member ( signalRef "@baseboard_fab2_lib.baseboard_fab2(sch_1):m_a_dq(59)") )
				( member ( signalRef "@baseboard_fab2_lib.baseboard_fab2(sch_1):m_a_dq(60)") )
				( member ( signalRef "@baseboard_fab2_lib.baseboard_fab2(sch_1):m_a_dq(61)") )
				( member ( signalRef "@baseboard_fab2_lib.baseboard_fab2(sch_1):m_a_dq(62)") )
				( member ( signalRef "@baseboard_fab2_lib.baseboard_fab2(sch_1):m_a_dq(63)") )
				( objectStatus "SNCLS_DDR4_CHN_A_DQ_DQS_BYTE7" )
			)
			( netClass "@sapphirecity_baseboard_lib.sapphirecity_baseboard(sch_1):\DDR4_CHN_D_DQ_DQS_BYTE5\"
				( memberType ( signal ) )
				( spacingCSetRef "@sapphirecity_baseboard_lib.sapphirecity_baseboard(sch_1):\DQ_TO_DQ\" )
				( sameNetSpacingCSetRef "@crescent_city_bb_fab1_lib.crescent_city_bb_fab1(sch_1):\7H_US_AND_5H_SL\" )
				( objectFlag fObjectSpacing )
				( objectFlag fObjectSameNetSpacing )
				( member ( diffPairRef "@sapphirecity_baseboard_lib.sapphirecity_baseboard(sch_1):\M_D_DQS_D\(5)") )
				( member ( diffPairRef "@sapphirecity_baseboard_lib.sapphirecity_baseboard(sch_1):\M_D_DQS_D\(14)") )
				( member ( signalRef "@baseboard_fab2_lib.baseboard_fab2(sch_1):m_d_dq(40)") )
				( member ( signalRef "@baseboard_fab2_lib.baseboard_fab2(sch_1):m_d_dq(41)") )
				( member ( signalRef "@baseboard_fab2_lib.baseboard_fab2(sch_1):m_d_dq(42)") )
				( member ( signalRef "@baseboard_fab2_lib.baseboard_fab2(sch_1):m_d_dq(43)") )
				( member ( signalRef "@baseboard_fab2_lib.baseboard_fab2(sch_1):m_d_dq(44)") )
				( member ( signalRef "@baseboard_fab2_lib.baseboard_fab2(sch_1):m_d_dq(45)") )
				( member ( signalRef "@baseboard_fab2_lib.baseboard_fab2(sch_1):m_d_dq(46)") )
				( member ( signalRef "@baseboard_fab2_lib.baseboard_fab2(sch_1):m_d_dq(47)") )
				( objectStatus "SNCLS_DDR4_CHN_D_DQ_DQS_BYTE5" )
			)
			( netClass "@sapphirecity_baseboard_lib.sapphirecity_baseboard(sch_1):\DDR4_CHN_G_CLK\"
				( memberType ( signal ) )
				( spacingCSetRef "@crescent_city_bb_fab1_lib.crescent_city_bb_fab1(sch_1):\8P9_US_&_6H_SL\" )
				( sameNetSpacingCSetRef "@crescent_city_bb_fab1_lib.crescent_city_bb_fab1(sch_1):\7H_US_AND_5H_SL\" )
				( objectFlag fObjectSpacing )
				( objectFlag fObjectSameNetSpacing )
				( member ( diffPairRef "@sapphirecity_baseboard_lib.sapphirecity_baseboard(sch_1):\M_G_CLK_D\(0)") )
				( member ( diffPairRef "@sapphirecity_baseboard_lib.sapphirecity_baseboard(sch_1):\M_G_CLK_D\(2)") )
				( member ( diffPairRef "@crescent_city_bb_fab1_lib.crescent_city_bb_fab1(sch_1):\DP_M_G_CLK\(1)") )
				( member ( diffPairRef "@crescent_city_bb_fab1_lib.crescent_city_bb_fab1(sch_1):\DP_M_G_CLK\(3)") )
				( objectStatus "SNCLS_DDR4_CHN_G_CLK" )
			)
			( netClass "@sapphirecity_baseboard_lib.sapphirecity_baseboard(sch_1):\DDR4_CHN_G_CMD_ADD\"
				( memberType ( signal ) )
				( spacingCSetRef "@crescent_city_bb_fab1_lib.crescent_city_bb_fab1(sch_1):\8P9_US_&_6H_SL\" )
				( sameNetSpacingCSetRef "@crescent_city_bb_fab1_lib.crescent_city_bb_fab1(sch_1):\7H_US_AND_5H_SL\" )
				( objectFlag fObjectSpacing )
				( objectFlag fObjectSameNetSpacing )
				( member ( signalRef "@baseboard_fab2_lib.baseboard_fab2(sch_1):m_g_act_n") )
				( member ( signalRef "@baseboard_fab2_lib.baseboard_fab2(sch_1):m_g_c(2)") )
				( member ( signalRef "@baseboard_fab2_lib.baseboard_fab2(sch_1):m_g_par") )
				( member ( signalRef "@baseboard_fab2_lib.baseboard_fab2(sch_1):m_g_ba(0)") )
				( member ( signalRef "@baseboard_fab2_lib.baseboard_fab2(sch_1):m_g_ba(1)") )
				( member ( signalRef "@baseboard_fab2_lib.baseboard_fab2(sch_1):m_g_bg(0)") )
				( member ( signalRef "@baseboard_fab2_lib.baseboard_fab2(sch_1):m_g_bg(1)") )
				( member ( signalRef "@baseboard_fab2_lib.baseboard_fab2(sch_1):m_g_ma(0)") )
				( member ( signalRef "@baseboard_fab2_lib.baseboard_fab2(sch_1):m_g_ma(1)") )
				( member ( signalRef "@baseboard_fab2_lib.baseboard_fab2(sch_1):m_g_ma(2)") )
				( member ( signalRef "@baseboard_fab2_lib.baseboard_fab2(sch_1):m_g_ma(3)") )
				( member ( signalRef "@baseboard_fab2_lib.baseboard_fab2(sch_1):m_g_ma(4)") )
				( member ( signalRef "@baseboard_fab2_lib.baseboard_fab2(sch_1):m_g_ma(5)") )
				( member ( signalRef "@baseboard_fab2_lib.baseboard_fab2(sch_1):m_g_ma(6)") )
				( member ( signalRef "@baseboard_fab2_lib.baseboard_fab2(sch_1):m_g_ma(7)") )
				( member ( signalRef "@baseboard_fab2_lib.baseboard_fab2(sch_1):m_g_ma(8)") )
				( member ( signalRef "@baseboard_fab2_lib.baseboard_fab2(sch_1):m_g_ma(9)") )
				( member ( signalRef "@baseboard_fab2_lib.baseboard_fab2(sch_1):m_g_ma(10)") )
				( member ( signalRef "@baseboard_fab2_lib.baseboard_fab2(sch_1):m_g_ma(11)") )
				( member ( signalRef "@baseboard_fab2_lib.baseboard_fab2(sch_1):m_g_ma(12)") )
				( member ( signalRef "@baseboard_fab2_lib.baseboard_fab2(sch_1):m_g_ma(13)") )
				( member ( signalRef "@baseboard_fab2_lib.baseboard_fab2(sch_1):m_g_ma(14)") )
				( member ( signalRef "@baseboard_fab2_lib.baseboard_fab2(sch_1):m_g_ma(15)") )
				( member ( signalRef "@baseboard_fab2_lib.baseboard_fab2(sch_1):m_g_ma(16)") )
				( member ( signalRef "@baseboard_fab2_lib.baseboard_fab2(sch_1):m_g_ma(17)") )
				( objectStatus "SNCLS_DDR4_CHN_G_CMD_ADD" )
			)
			( netClass "@sapphirecity_baseboard_lib.sapphirecity_baseboard(sch_1):\DDR4_CHN_G_CTRL\"
				( memberType ( signal ) )
				( spacingCSetRef "@crescent_city_bb_fab1_lib.crescent_city_bb_fab1(sch_1):\8P9_US_&_6H_SL\" )
				( sameNetSpacingCSetRef "@crescent_city_bb_fab1_lib.crescent_city_bb_fab1(sch_1):\7H_US_AND_5H_SL\" )
				( objectFlag fObjectSpacing )
				( objectFlag fObjectSameNetSpacing )
				( member ( signalRef "@baseboard_fab2_lib.baseboard_fab2(sch_1):m_g_cke(0)") )
				( member ( signalRef "@baseboard_fab2_lib.baseboard_fab2(sch_1):m_g_cke(1)") )
				( member ( signalRef "@baseboard_fab2_lib.baseboard_fab2(sch_1):m_g_cke(2)") )
				( member ( signalRef "@baseboard_fab2_lib.baseboard_fab2(sch_1):m_g_cke(3)") )
				( member ( signalRef "@baseboard_fab2_lib.baseboard_fab2(sch_1):m_g_cs_n(0)") )
				( member ( signalRef "@baseboard_fab2_lib.baseboard_fab2(sch_1):m_g_cs_n(1)") )
				( member ( signalRef "@baseboard_fab2_lib.baseboard_fab2(sch_1):m_g_cs_n(2)") )
				( member ( signalRef "@baseboard_fab2_lib.baseboard_fab2(sch_1):m_g_cs_n(3)") )
				( member ( signalRef "@baseboard_fab2_lib.baseboard_fab2(sch_1):m_g_cs_n(4)") )
				( member ( signalRef "@baseboard_fab2_lib.baseboard_fab2(sch_1):m_g_cs_n(5)") )
				( member ( signalRef "@baseboard_fab2_lib.baseboard_fab2(sch_1):m_g_cs_n(6)") )
				( member ( signalRef "@baseboard_fab2_lib.baseboard_fab2(sch_1):m_g_cs_n(7)") )
				( member ( signalRef "@baseboard_fab2_lib.baseboard_fab2(sch_1):m_g_odt(0)") )
				( member ( signalRef "@baseboard_fab2_lib.baseboard_fab2(sch_1):m_g_odt(1)") )
				( member ( signalRef "@baseboard_fab2_lib.baseboard_fab2(sch_1):m_g_odt(2)") )
				( member ( signalRef "@baseboard_fab2_lib.baseboard_fab2(sch_1):m_g_odt(3)") )
				( member ( signalRef "@baseboard_fab2_lib.baseboard_fab2(sch_1):m_g_alert_n") )
				( objectStatus "SNCLS_DDR4_CHN_G_CTRL" )
			)
			( netClass "@sapphirecity_baseboard_lib.sapphirecity_baseboard(sch_1):\DDR4_CHN_J_DQ_DQS_BYTE0\"
				( memberType ( signal ) )
				( spacingCSetRef "@sapphirecity_baseboard_lib.sapphirecity_baseboard(sch_1):\10H_SL_12H_MS\" )
				( sameNetSpacingCSetRef "@crescent_city_bb_fab1_lib.crescent_city_bb_fab1(sch_1):\7H_US_AND_5H_SL\" )
				( objectFlag fObjectSpacing )
				( objectFlag fObjectSameNetSpacing )
				( member ( diffPairRef "@sapphirecity_baseboard_lib.sapphirecity_baseboard(sch_1):\M_J_DQS_D\(0)") )
				( member ( diffPairRef "@sapphirecity_baseboard_lib.sapphirecity_baseboard(sch_1):\M_J_DQS_D\(9)") )
				( member ( signalRef "@baseboard_fab2_lib.baseboard_fab2(sch_1):m_j_dq(0)") )
				( member ( signalRef "@baseboard_fab2_lib.baseboard_fab2(sch_1):m_j_dq(1)") )
				( member ( signalRef "@baseboard_fab2_lib.baseboard_fab2(sch_1):m_j_dq(2)") )
				( member ( signalRef "@baseboard_fab2_lib.baseboard_fab2(sch_1):m_j_dq(3)") )
				( member ( signalRef "@baseboard_fab2_lib.baseboard_fab2(sch_1):m_j_dq(4)") )
				( member ( signalRef "@baseboard_fab2_lib.baseboard_fab2(sch_1):m_j_dq(5)") )
				( member ( signalRef "@baseboard_fab2_lib.baseboard_fab2(sch_1):m_j_dq(6)") )
				( member ( signalRef "@baseboard_fab2_lib.baseboard_fab2(sch_1):m_j_dq(7)") )
				( objectStatus "SNCLS_DDR4_CHN_J_DQ_DQS_BYTE0" )
			)
			( netClass "@sapphirecity_baseboard_lib.sapphirecity_baseboard(sch_1):\DDR4_CHN_K_DQ_DQS_BYTE0\"
				( memberType ( signal ) )
				( spacingCSetRef "@sapphirecity_baseboard_lib.sapphirecity_baseboard(sch_1):\10H_SL_12H_MS\" )
				( sameNetSpacingCSetRef "@crescent_city_bb_fab1_lib.crescent_city_bb_fab1(sch_1):\7H_US_AND_5H_SL\" )
				( objectFlag fObjectSpacing )
				( objectFlag fObjectSameNetSpacing )
				( member ( diffPairRef "@sapphirecity_baseboard_lib.sapphirecity_baseboard(sch_1):\M_K_DQS_D\(0)") )
				( member ( diffPairRef "@sapphirecity_baseboard_lib.sapphirecity_baseboard(sch_1):\M_K_DQS_D\(9)") )
				( member ( signalRef "@baseboard_fab2_lib.baseboard_fab2(sch_1):m_k_dq(0)") )
				( member ( signalRef "@baseboard_fab2_lib.baseboard_fab2(sch_1):m_k_dq(1)") )
				( member ( signalRef "@baseboard_fab2_lib.baseboard_fab2(sch_1):m_k_dq(2)") )
				( member ( signalRef "@baseboard_fab2_lib.baseboard_fab2(sch_1):m_k_dq(3)") )
				( member ( signalRef "@baseboard_fab2_lib.baseboard_fab2(sch_1):m_k_dq(4)") )
				( member ( signalRef "@baseboard_fab2_lib.baseboard_fab2(sch_1):m_k_dq(5)") )
				( member ( signalRef "@baseboard_fab2_lib.baseboard_fab2(sch_1):m_k_dq(6)") )
				( member ( signalRef "@baseboard_fab2_lib.baseboard_fab2(sch_1):m_k_dq(7)") )
				( objectStatus "SNCLS_DDR4_CHN_K_DQ_DQS_BYTE0" )
			)
			( netClass "@sapphirecity_baseboard_lib.sapphirecity_baseboard(sch_1):\DDR4_CHN_J_DQ_DQS_BYTE1\"
				( memberType ( signal ) )
				( spacingCSetRef "@sapphirecity_baseboard_lib.sapphirecity_baseboard(sch_1):\10H_SL_12H_MS\" )
				( sameNetSpacingCSetRef "@crescent_city_bb_fab1_lib.crescent_city_bb_fab1(sch_1):\7H_US_AND_5H_SL\" )
				( objectFlag fObjectSpacing )
				( objectFlag fObjectSameNetSpacing )
				( member ( diffPairRef "@sapphirecity_baseboard_lib.sapphirecity_baseboard(sch_1):\M_J_DQS_D\(1)") )
				( member ( diffPairRef "@sapphirecity_baseboard_lib.sapphirecity_baseboard(sch_1):\M_J_DQS_D\(10)") )
				( member ( signalRef "@baseboard_fab2_lib.baseboard_fab2(sch_1):m_j_dq(8)") )
				( member ( signalRef "@baseboard_fab2_lib.baseboard_fab2(sch_1):m_j_dq(9)") )
				( member ( signalRef "@baseboard_fab2_lib.baseboard_fab2(sch_1):m_j_dq(10)") )
				( member ( signalRef "@baseboard_fab2_lib.baseboard_fab2(sch_1):m_j_dq(11)") )
				( member ( signalRef "@baseboard_fab2_lib.baseboard_fab2(sch_1):m_j_dq(12)") )
				( member ( signalRef "@baseboard_fab2_lib.baseboard_fab2(sch_1):m_j_dq(13)") )
				( member ( signalRef "@baseboard_fab2_lib.baseboard_fab2(sch_1):m_j_dq(14)") )
				( member ( signalRef "@baseboard_fab2_lib.baseboard_fab2(sch_1):m_j_dq(15)") )
				( objectStatus "SNCLS_DDR4_CHN_J_DQ_DQS_BYTE1" )
			)
			( netClass "@sapphirecity_baseboard_lib.sapphirecity_baseboard(sch_1):\DDR4_CHN_J_DQ_DQS_BYTE2\"
				( memberType ( signal ) )
				( spacingCSetRef "@sapphirecity_baseboard_lib.sapphirecity_baseboard(sch_1):\10H_SL_12H_MS\" )
				( sameNetSpacingCSetRef "@crescent_city_bb_fab1_lib.crescent_city_bb_fab1(sch_1):\7H_US_AND_5H_SL\" )
				( objectFlag fObjectSpacing )
				( objectFlag fObjectSameNetSpacing )
				( member ( diffPairRef "@sapphirecity_baseboard_lib.sapphirecity_baseboard(sch_1):\M_J_DQS_D\(2)") )
				( member ( diffPairRef "@sapphirecity_baseboard_lib.sapphirecity_baseboard(sch_1):\M_J_DQS_D\(11)") )
				( member ( signalRef "@baseboard_fab2_lib.baseboard_fab2(sch_1):m_j_dq(16)") )
				( member ( signalRef "@baseboard_fab2_lib.baseboard_fab2(sch_1):m_j_dq(17)") )
				( member ( signalRef "@baseboard_fab2_lib.baseboard_fab2(sch_1):m_j_dq(18)") )
				( member ( signalRef "@baseboard_fab2_lib.baseboard_fab2(sch_1):m_j_dq(19)") )
				( member ( signalRef "@baseboard_fab2_lib.baseboard_fab2(sch_1):m_j_dq(20)") )
				( member ( signalRef "@baseboard_fab2_lib.baseboard_fab2(sch_1):m_j_dq(21)") )
				( member ( signalRef "@baseboard_fab2_lib.baseboard_fab2(sch_1):m_j_dq(22)") )
				( member ( signalRef "@baseboard_fab2_lib.baseboard_fab2(sch_1):m_j_dq(23)") )
				( objectStatus "SNCLS_DDR4_CHN_J_DQ_DQS_BYTE2" )
			)
			( netClass "@sapphirecity_baseboard_lib.sapphirecity_baseboard(sch_1):\DDR4_CHN_J_DQ_DQS_BYTE3\"
				( memberType ( signal ) )
				( spacingCSetRef "@sapphirecity_baseboard_lib.sapphirecity_baseboard(sch_1):\10H_SL_12H_MS\" )
				( sameNetSpacingCSetRef "@crescent_city_bb_fab1_lib.crescent_city_bb_fab1(sch_1):\7H_US_AND_5H_SL\" )
				( objectFlag fObjectSpacing )
				( objectFlag fObjectSameNetSpacing )
				( member ( diffPairRef "@sapphirecity_baseboard_lib.sapphirecity_baseboard(sch_1):\M_J_DQS_D\(3)") )
				( member ( diffPairRef "@sapphirecity_baseboard_lib.sapphirecity_baseboard(sch_1):\M_J_DQS_D\(12)") )
				( member ( signalRef "@baseboard_fab2_lib.baseboard_fab2(sch_1):m_j_dq(24)") )
				( member ( signalRef "@baseboard_fab2_lib.baseboard_fab2(sch_1):m_j_dq(25)") )
				( member ( signalRef "@baseboard_fab2_lib.baseboard_fab2(sch_1):m_j_dq(26)") )
				( member ( signalRef "@baseboard_fab2_lib.baseboard_fab2(sch_1):m_j_dq(27)") )
				( member ( signalRef "@baseboard_fab2_lib.baseboard_fab2(sch_1):m_j_dq(28)") )
				( member ( signalRef "@baseboard_fab2_lib.baseboard_fab2(sch_1):m_j_dq(29)") )
				( member ( signalRef "@baseboard_fab2_lib.baseboard_fab2(sch_1):m_j_dq(30)") )
				( member ( signalRef "@baseboard_fab2_lib.baseboard_fab2(sch_1):m_j_dq(31)") )
				( objectStatus "SNCLS_DDR4_CHN_J_DQ_DQS_BYTE3" )
			)
			( netClass "@sapphirecity_baseboard_lib.sapphirecity_baseboard(sch_1):\DDR4_CHN_J_DQ_DQS_BYTE4\"
				( memberType ( signal ) )
				( spacingCSetRef "@sapphirecity_baseboard_lib.sapphirecity_baseboard(sch_1):\10H_SL_12H_MS\" )
				( sameNetSpacingCSetRef "@crescent_city_bb_fab1_lib.crescent_city_bb_fab1(sch_1):\7H_US_AND_5H_SL\" )
				( objectFlag fObjectSpacing )
				( objectFlag fObjectSameNetSpacing )
				( member ( diffPairRef "@sapphirecity_baseboard_lib.sapphirecity_baseboard(sch_1):\M_J_DQS_D\(4)") )
				( member ( diffPairRef "@sapphirecity_baseboard_lib.sapphirecity_baseboard(sch_1):\M_J_DQS_D\(13)") )
				( member ( signalRef "@baseboard_fab2_lib.baseboard_fab2(sch_1):m_j_dq(32)") )
				( member ( signalRef "@baseboard_fab2_lib.baseboard_fab2(sch_1):m_j_dq(33)") )
				( member ( signalRef "@baseboard_fab2_lib.baseboard_fab2(sch_1):m_j_dq(34)") )
				( member ( signalRef "@baseboard_fab2_lib.baseboard_fab2(sch_1):m_j_dq(35)") )
				( member ( signalRef "@baseboard_fab2_lib.baseboard_fab2(sch_1):m_j_dq(36)") )
				( member ( signalRef "@baseboard_fab2_lib.baseboard_fab2(sch_1):m_j_dq(37)") )
				( member ( signalRef "@baseboard_fab2_lib.baseboard_fab2(sch_1):m_j_dq(38)") )
				( member ( signalRef "@baseboard_fab2_lib.baseboard_fab2(sch_1):m_j_dq(39)") )
				( objectStatus "SNCLS_DDR4_CHN_J_DQ_DQS_BYTE4" )
			)
			( netClass "@sapphirecity_baseboard_lib.sapphirecity_baseboard(sch_1):\DDR4_CHN_J_DQ_DQS_BYTE5\"
				( memberType ( signal ) )
				( spacingCSetRef "@sapphirecity_baseboard_lib.sapphirecity_baseboard(sch_1):\10H_SL_12H_MS\" )
				( sameNetSpacingCSetRef "@crescent_city_bb_fab1_lib.crescent_city_bb_fab1(sch_1):\7H_US_AND_5H_SL\" )
				( objectFlag fObjectSpacing )
				( objectFlag fObjectSameNetSpacing )
				( member ( diffPairRef "@sapphirecity_baseboard_lib.sapphirecity_baseboard(sch_1):\M_J_DQS_D\(5)") )
				( member ( diffPairRef "@sapphirecity_baseboard_lib.sapphirecity_baseboard(sch_1):\M_J_DQS_D\(14)") )
				( member ( signalRef "@baseboard_fab2_lib.baseboard_fab2(sch_1):m_j_dq(40)") )
				( member ( signalRef "@baseboard_fab2_lib.baseboard_fab2(sch_1):m_j_dq(41)") )
				( member ( signalRef "@baseboard_fab2_lib.baseboard_fab2(sch_1):m_j_dq(42)") )
				( member ( signalRef "@baseboard_fab2_lib.baseboard_fab2(sch_1):m_j_dq(43)") )
				( member ( signalRef "@baseboard_fab2_lib.baseboard_fab2(sch_1):m_j_dq(44)") )
				( member ( signalRef "@baseboard_fab2_lib.baseboard_fab2(sch_1):m_j_dq(45)") )
				( member ( signalRef "@baseboard_fab2_lib.baseboard_fab2(sch_1):m_j_dq(46)") )
				( member ( signalRef "@baseboard_fab2_lib.baseboard_fab2(sch_1):m_j_dq(47)") )
				( objectStatus "SNCLS_DDR4_CHN_J_DQ_DQS_BYTE5" )
			)
			( netClass "@sapphirecity_baseboard_lib.sapphirecity_baseboard(sch_1):\DDR4_CHN_J_DQ_DQS_BYTE6\"
				( memberType ( signal ) )
				( spacingCSetRef "@sapphirecity_baseboard_lib.sapphirecity_baseboard(sch_1):\10H_SL_12H_MS\" )
				( sameNetSpacingCSetRef "@crescent_city_bb_fab1_lib.crescent_city_bb_fab1(sch_1):\7H_US_AND_5H_SL\" )
				( objectFlag fObjectSpacing )
				( objectFlag fObjectSameNetSpacing )
				( member ( diffPairRef "@sapphirecity_baseboard_lib.sapphirecity_baseboard(sch_1):\M_J_DQS_D\(6)") )
				( member ( diffPairRef "@sapphirecity_baseboard_lib.sapphirecity_baseboard(sch_1):\M_J_DQS_D\(15)") )
				( member ( signalRef "@baseboard_fab2_lib.baseboard_fab2(sch_1):m_j_dq(48)") )
				( member ( signalRef "@baseboard_fab2_lib.baseboard_fab2(sch_1):m_j_dq(49)") )
				( member ( signalRef "@baseboard_fab2_lib.baseboard_fab2(sch_1):m_j_dq(50)") )
				( member ( signalRef "@baseboard_fab2_lib.baseboard_fab2(sch_1):m_j_dq(51)") )
				( member ( signalRef "@baseboard_fab2_lib.baseboard_fab2(sch_1):m_j_dq(52)") )
				( member ( signalRef "@baseboard_fab2_lib.baseboard_fab2(sch_1):m_j_dq(53)") )
				( member ( signalRef "@baseboard_fab2_lib.baseboard_fab2(sch_1):m_j_dq(54)") )
				( member ( signalRef "@baseboard_fab2_lib.baseboard_fab2(sch_1):m_j_dq(55)") )
				( objectStatus "SNCLS_DDR4_CHN_J_DQ_DQS_BYTE6" )
			)
			( netClass "@sapphirecity_baseboard_lib.sapphirecity_baseboard(sch_1):\DDR4_CHN_J_DQ_DQS_BYTE7\"
				( memberType ( signal ) )
				( spacingCSetRef "@sapphirecity_baseboard_lib.sapphirecity_baseboard(sch_1):\10H_SL_12H_MS\" )
				( sameNetSpacingCSetRef "@crescent_city_bb_fab1_lib.crescent_city_bb_fab1(sch_1):\7H_US_AND_5H_SL\" )
				( objectFlag fObjectSpacing )
				( objectFlag fObjectSameNetSpacing )
				( member ( diffPairRef "@sapphirecity_baseboard_lib.sapphirecity_baseboard(sch_1):\M_J_DQS_D\(7)") )
				( member ( diffPairRef "@sapphirecity_baseboard_lib.sapphirecity_baseboard(sch_1):\M_J_DQS_D\(16)") )
				( member ( signalRef "@baseboard_fab2_lib.baseboard_fab2(sch_1):m_j_dq(56)") )
				( member ( signalRef "@baseboard_fab2_lib.baseboard_fab2(sch_1):m_j_dq(57)") )
				( member ( signalRef "@baseboard_fab2_lib.baseboard_fab2(sch_1):m_j_dq(58)") )
				( member ( signalRef "@baseboard_fab2_lib.baseboard_fab2(sch_1):m_j_dq(59)") )
				( member ( signalRef "@baseboard_fab2_lib.baseboard_fab2(sch_1):m_j_dq(60)") )
				( member ( signalRef "@baseboard_fab2_lib.baseboard_fab2(sch_1):m_j_dq(61)") )
				( member ( signalRef "@baseboard_fab2_lib.baseboard_fab2(sch_1):m_j_dq(62)") )
				( member ( signalRef "@baseboard_fab2_lib.baseboard_fab2(sch_1):m_j_dq(63)") )
				( objectStatus "SNCLS_DDR4_CHN_J_DQ_DQS_BYTE7" )
			)
			( netClass "@sapphirecity_baseboard_lib.sapphirecity_baseboard(sch_1):\DDR4_CHN_K_DQ_DQS_BYTE1\"
				( memberType ( signal ) )
				( spacingCSetRef "@sapphirecity_baseboard_lib.sapphirecity_baseboard(sch_1):\10H_SL_12H_MS\" )
				( sameNetSpacingCSetRef "@crescent_city_bb_fab1_lib.crescent_city_bb_fab1(sch_1):\7H_US_AND_5H_SL\" )
				( objectFlag fObjectSpacing )
				( objectFlag fObjectSameNetSpacing )
				( member ( diffPairRef "@sapphirecity_baseboard_lib.sapphirecity_baseboard(sch_1):\M_K_DQS_D\(1)") )
				( member ( diffPairRef "@sapphirecity_baseboard_lib.sapphirecity_baseboard(sch_1):\M_K_DQS_D\(10)") )
				( member ( signalRef "@baseboard_fab2_lib.baseboard_fab2(sch_1):m_k_dq(8)") )
				( member ( signalRef "@baseboard_fab2_lib.baseboard_fab2(sch_1):m_k_dq(9)") )
				( member ( signalRef "@baseboard_fab2_lib.baseboard_fab2(sch_1):m_k_dq(10)") )
				( member ( signalRef "@baseboard_fab2_lib.baseboard_fab2(sch_1):m_k_dq(11)") )
				( member ( signalRef "@baseboard_fab2_lib.baseboard_fab2(sch_1):m_k_dq(12)") )
				( member ( signalRef "@baseboard_fab2_lib.baseboard_fab2(sch_1):m_k_dq(13)") )
				( member ( signalRef "@baseboard_fab2_lib.baseboard_fab2(sch_1):m_k_dq(14)") )
				( member ( signalRef "@baseboard_fab2_lib.baseboard_fab2(sch_1):m_k_dq(15)") )
				( objectStatus "SNCLS_DDR4_CHN_K_DQ_DQS_BYTE1" )
			)
			( netClass "@sapphirecity_baseboard_lib.sapphirecity_baseboard(sch_1):\DDR4_CHN_K_DQ_DQS_BYTE2\"
				( memberType ( signal ) )
				( spacingCSetRef "@sapphirecity_baseboard_lib.sapphirecity_baseboard(sch_1):\10H_SL_12H_MS\" )
				( sameNetSpacingCSetRef "@crescent_city_bb_fab1_lib.crescent_city_bb_fab1(sch_1):\7H_US_AND_5H_SL\" )
				( objectFlag fObjectSpacing )
				( objectFlag fObjectSameNetSpacing )
				( member ( diffPairRef "@sapphirecity_baseboard_lib.sapphirecity_baseboard(sch_1):\M_K_DQS_D\(2)") )
				( member ( diffPairRef "@sapphirecity_baseboard_lib.sapphirecity_baseboard(sch_1):\M_K_DQS_D\(11)") )
				( member ( signalRef "@baseboard_fab2_lib.baseboard_fab2(sch_1):m_k_dq(16)") )
				( member ( signalRef "@baseboard_fab2_lib.baseboard_fab2(sch_1):m_k_dq(17)") )
				( member ( signalRef "@baseboard_fab2_lib.baseboard_fab2(sch_1):m_k_dq(18)") )
				( member ( signalRef "@baseboard_fab2_lib.baseboard_fab2(sch_1):m_k_dq(19)") )
				( member ( signalRef "@baseboard_fab2_lib.baseboard_fab2(sch_1):m_k_dq(20)") )
				( member ( signalRef "@baseboard_fab2_lib.baseboard_fab2(sch_1):m_k_dq(21)") )
				( member ( signalRef "@baseboard_fab2_lib.baseboard_fab2(sch_1):m_k_dq(22)") )
				( member ( signalRef "@baseboard_fab2_lib.baseboard_fab2(sch_1):m_k_dq(23)") )
				( objectStatus "SNCLS_DDR4_CHN_K_DQ_DQS_BYTE2" )
			)
			( netClass "@sapphirecity_baseboard_lib.sapphirecity_baseboard(sch_1):\DDR4_CHN_K_DQ_DQS_BYTE3\"
				( memberType ( signal ) )
				( spacingCSetRef "@sapphirecity_baseboard_lib.sapphirecity_baseboard(sch_1):\10H_SL_12H_MS\" )
				( sameNetSpacingCSetRef "@crescent_city_bb_fab1_lib.crescent_city_bb_fab1(sch_1):\7H_US_AND_5H_SL\" )
				( objectFlag fObjectSpacing )
				( objectFlag fObjectSameNetSpacing )
				( member ( diffPairRef "@sapphirecity_baseboard_lib.sapphirecity_baseboard(sch_1):\M_K_DQS_D\(3)") )
				( member ( diffPairRef "@sapphirecity_baseboard_lib.sapphirecity_baseboard(sch_1):\M_K_DQS_D\(12)") )
				( member ( signalRef "@baseboard_fab2_lib.baseboard_fab2(sch_1):m_k_dq(24)") )
				( member ( signalRef "@baseboard_fab2_lib.baseboard_fab2(sch_1):m_k_dq(25)") )
				( member ( signalRef "@baseboard_fab2_lib.baseboard_fab2(sch_1):m_k_dq(26)") )
				( member ( signalRef "@baseboard_fab2_lib.baseboard_fab2(sch_1):m_k_dq(27)") )
				( member ( signalRef "@baseboard_fab2_lib.baseboard_fab2(sch_1):m_k_dq(28)") )
				( member ( signalRef "@baseboard_fab2_lib.baseboard_fab2(sch_1):m_k_dq(29)") )
				( member ( signalRef "@baseboard_fab2_lib.baseboard_fab2(sch_1):m_k_dq(30)") )
				( member ( signalRef "@baseboard_fab2_lib.baseboard_fab2(sch_1):m_k_dq(31)") )
				( objectStatus "SNCLS_DDR4_CHN_K_DQ_DQS_BYTE3" )
			)
			( netClass "@sapphirecity_baseboard_lib.sapphirecity_baseboard(sch_1):\DDR4_CHN_K_DQ_DQS_BYTE4\"
				( memberType ( signal ) )
				( spacingCSetRef "@sapphirecity_baseboard_lib.sapphirecity_baseboard(sch_1):\10H_SL_12H_MS\" )
				( sameNetSpacingCSetRef "@crescent_city_bb_fab1_lib.crescent_city_bb_fab1(sch_1):\7H_US_AND_5H_SL\" )
				( objectFlag fObjectSpacing )
				( objectFlag fObjectSameNetSpacing )
				( member ( diffPairRef "@sapphirecity_baseboard_lib.sapphirecity_baseboard(sch_1):\M_K_DQS_D\(4)") )
				( member ( diffPairRef "@sapphirecity_baseboard_lib.sapphirecity_baseboard(sch_1):\M_K_DQS_D\(13)") )
				( member ( signalRef "@baseboard_fab2_lib.baseboard_fab2(sch_1):m_k_dq(32)") )
				( member ( signalRef "@baseboard_fab2_lib.baseboard_fab2(sch_1):m_k_dq(33)") )
				( member ( signalRef "@baseboard_fab2_lib.baseboard_fab2(sch_1):m_k_dq(34)") )
				( member ( signalRef "@baseboard_fab2_lib.baseboard_fab2(sch_1):m_k_dq(35)") )
				( member ( signalRef "@baseboard_fab2_lib.baseboard_fab2(sch_1):m_k_dq(36)") )
				( member ( signalRef "@baseboard_fab2_lib.baseboard_fab2(sch_1):m_k_dq(37)") )
				( member ( signalRef "@baseboard_fab2_lib.baseboard_fab2(sch_1):m_k_dq(38)") )
				( member ( signalRef "@baseboard_fab2_lib.baseboard_fab2(sch_1):m_k_dq(39)") )
				( objectStatus "SNCLS_DDR4_CHN_K_DQ_DQS_BYTE4" )
			)
			( netClass "@sapphirecity_baseboard_lib.sapphirecity_baseboard(sch_1):\DDR4_CHN_K_DQ_DQS_BYTE5\"
				( memberType ( signal ) )
				( spacingCSetRef "@sapphirecity_baseboard_lib.sapphirecity_baseboard(sch_1):\10H_SL_12H_MS\" )
				( sameNetSpacingCSetRef "@crescent_city_bb_fab1_lib.crescent_city_bb_fab1(sch_1):\7H_US_AND_5H_SL\" )
				( objectFlag fObjectSpacing )
				( objectFlag fObjectSameNetSpacing )
				( member ( diffPairRef "@sapphirecity_baseboard_lib.sapphirecity_baseboard(sch_1):\M_K_DQS_D\(5)") )
				( member ( diffPairRef "@sapphirecity_baseboard_lib.sapphirecity_baseboard(sch_1):\M_K_DQS_D\(14)") )
				( member ( signalRef "@baseboard_fab2_lib.baseboard_fab2(sch_1):m_k_dq(40)") )
				( member ( signalRef "@baseboard_fab2_lib.baseboard_fab2(sch_1):m_k_dq(41)") )
				( member ( signalRef "@baseboard_fab2_lib.baseboard_fab2(sch_1):m_k_dq(42)") )
				( member ( signalRef "@baseboard_fab2_lib.baseboard_fab2(sch_1):m_k_dq(43)") )
				( member ( signalRef "@baseboard_fab2_lib.baseboard_fab2(sch_1):m_k_dq(44)") )
				( member ( signalRef "@baseboard_fab2_lib.baseboard_fab2(sch_1):m_k_dq(45)") )
				( member ( signalRef "@baseboard_fab2_lib.baseboard_fab2(sch_1):m_k_dq(46)") )
				( member ( signalRef "@baseboard_fab2_lib.baseboard_fab2(sch_1):m_k_dq(47)") )
				( objectStatus "SNCLS_DDR4_CHN_K_DQ_DQS_BYTE5" )
			)
			( netClass "@sapphirecity_baseboard_lib.sapphirecity_baseboard(sch_1):\DDR4_CHN_K_DQ_DQS_BYTE6\"
				( memberType ( signal ) )
				( spacingCSetRef "@sapphirecity_baseboard_lib.sapphirecity_baseboard(sch_1):\10H_SL_12H_MS\" )
				( sameNetSpacingCSetRef "@crescent_city_bb_fab1_lib.crescent_city_bb_fab1(sch_1):\7H_US_AND_5H_SL\" )
				( objectFlag fObjectSpacing )
				( objectFlag fObjectSameNetSpacing )
				( member ( diffPairRef "@sapphirecity_baseboard_lib.sapphirecity_baseboard(sch_1):\M_K_DQS_D\(6)") )
				( member ( diffPairRef "@sapphirecity_baseboard_lib.sapphirecity_baseboard(sch_1):\M_K_DQS_D\(15)") )
				( member ( signalRef "@baseboard_fab2_lib.baseboard_fab2(sch_1):m_k_dq(48)") )
				( member ( signalRef "@baseboard_fab2_lib.baseboard_fab2(sch_1):m_k_dq(49)") )
				( member ( signalRef "@baseboard_fab2_lib.baseboard_fab2(sch_1):m_k_dq(50)") )
				( member ( signalRef "@baseboard_fab2_lib.baseboard_fab2(sch_1):m_k_dq(51)") )
				( member ( signalRef "@baseboard_fab2_lib.baseboard_fab2(sch_1):m_k_dq(52)") )
				( member ( signalRef "@baseboard_fab2_lib.baseboard_fab2(sch_1):m_k_dq(53)") )
				( member ( signalRef "@baseboard_fab2_lib.baseboard_fab2(sch_1):m_k_dq(54)") )
				( member ( signalRef "@baseboard_fab2_lib.baseboard_fab2(sch_1):m_k_dq(55)") )
				( objectStatus "SNCLS_DDR4_CHN_K_DQ_DQS_BYTE6" )
			)
			( netClass "@sapphirecity_baseboard_lib.sapphirecity_baseboard(sch_1):\DDR4_CHN_K_DQ_DQS_BYTE7\"
				( memberType ( signal ) )
				( spacingCSetRef "@sapphirecity_baseboard_lib.sapphirecity_baseboard(sch_1):\10H_SL_12H_MS\" )
				( sameNetSpacingCSetRef "@crescent_city_bb_fab1_lib.crescent_city_bb_fab1(sch_1):\7H_US_AND_5H_SL\" )
				( objectFlag fObjectSpacing )
				( objectFlag fObjectSameNetSpacing )
				( member ( diffPairRef "@sapphirecity_baseboard_lib.sapphirecity_baseboard(sch_1):\M_K_DQS_D\(7)") )
				( member ( diffPairRef "@sapphirecity_baseboard_lib.sapphirecity_baseboard(sch_1):\M_K_DQS_D\(16)") )
				( member ( signalRef "@baseboard_fab2_lib.baseboard_fab2(sch_1):m_k_dq(56)") )
				( member ( signalRef "@baseboard_fab2_lib.baseboard_fab2(sch_1):m_k_dq(57)") )
				( member ( signalRef "@baseboard_fab2_lib.baseboard_fab2(sch_1):m_k_dq(58)") )
				( member ( signalRef "@baseboard_fab2_lib.baseboard_fab2(sch_1):m_k_dq(59)") )
				( member ( signalRef "@baseboard_fab2_lib.baseboard_fab2(sch_1):m_k_dq(60)") )
				( member ( signalRef "@baseboard_fab2_lib.baseboard_fab2(sch_1):m_k_dq(61)") )
				( member ( signalRef "@baseboard_fab2_lib.baseboard_fab2(sch_1):m_k_dq(62)") )
				( member ( signalRef "@baseboard_fab2_lib.baseboard_fab2(sch_1):m_k_dq(63)") )
				( objectStatus "SNCLS_DDR4_CHN_K_DQ_DQS_BYTE7" )
			)
			( netClass "@sapphirecity_baseboard_lib.sapphirecity_baseboard(sch_1):\DDR4_CHN_L_DQ_DQS_BYTE0\"
				( memberType ( signal ) )
				( spacingCSetRef "@sapphirecity_baseboard_lib.sapphirecity_baseboard(sch_1):\10H_SL_12H_MS\" )
				( sameNetSpacingCSetRef "@crescent_city_bb_fab1_lib.crescent_city_bb_fab1(sch_1):\7H_US_AND_5H_SL\" )
				( objectFlag fObjectSpacing )
				( objectFlag fObjectSameNetSpacing )
				( member ( diffPairRef "@sapphirecity_baseboard_lib.sapphirecity_baseboard(sch_1):\M_L_DQS_D\(0)") )
				( member ( diffPairRef "@sapphirecity_baseboard_lib.sapphirecity_baseboard(sch_1):\M_L_DQS_D\(9)") )
				( member ( signalRef "@baseboard_fab2_lib.baseboard_fab2(sch_1):m_l_dq(0)") )
				( member ( signalRef "@baseboard_fab2_lib.baseboard_fab2(sch_1):m_l_dq(1)") )
				( member ( signalRef "@baseboard_fab2_lib.baseboard_fab2(sch_1):m_l_dq(2)") )
				( member ( signalRef "@baseboard_fab2_lib.baseboard_fab2(sch_1):m_l_dq(3)") )
				( member ( signalRef "@baseboard_fab2_lib.baseboard_fab2(sch_1):m_l_dq(4)") )
				( member ( signalRef "@baseboard_fab2_lib.baseboard_fab2(sch_1):m_l_dq(5)") )
				( member ( signalRef "@baseboard_fab2_lib.baseboard_fab2(sch_1):m_l_dq(6)") )
				( member ( signalRef "@baseboard_fab2_lib.baseboard_fab2(sch_1):m_l_dq(7)") )
				( objectStatus "SNCLS_DDR4_CHN_L_DQ_DQS_BYTE0" )
			)
			( netClass "@sapphirecity_baseboard_lib.sapphirecity_baseboard(sch_1):\DDR4_CHN_L_DQ_DQS_BYTE1\"
				( memberType ( signal ) )
				( spacingCSetRef "@sapphirecity_baseboard_lib.sapphirecity_baseboard(sch_1):\10H_SL_12H_MS\" )
				( sameNetSpacingCSetRef "@crescent_city_bb_fab1_lib.crescent_city_bb_fab1(sch_1):\7H_US_AND_5H_SL\" )
				( objectFlag fObjectSpacing )
				( objectFlag fObjectSameNetSpacing )
				( member ( diffPairRef "@sapphirecity_baseboard_lib.sapphirecity_baseboard(sch_1):\M_L_DQS_D\(1)") )
				( member ( diffPairRef "@sapphirecity_baseboard_lib.sapphirecity_baseboard(sch_1):\M_L_DQS_D\(10)") )
				( member ( signalRef "@baseboard_fab2_lib.baseboard_fab2(sch_1):m_l_dq(8)") )
				( member ( signalRef "@baseboard_fab2_lib.baseboard_fab2(sch_1):m_l_dq(9)") )
				( member ( signalRef "@baseboard_fab2_lib.baseboard_fab2(sch_1):m_l_dq(10)") )
				( member ( signalRef "@baseboard_fab2_lib.baseboard_fab2(sch_1):m_l_dq(11)") )
				( member ( signalRef "@baseboard_fab2_lib.baseboard_fab2(sch_1):m_l_dq(12)") )
				( member ( signalRef "@baseboard_fab2_lib.baseboard_fab2(sch_1):m_l_dq(13)") )
				( member ( signalRef "@baseboard_fab2_lib.baseboard_fab2(sch_1):m_l_dq(14)") )
				( member ( signalRef "@baseboard_fab2_lib.baseboard_fab2(sch_1):m_l_dq(15)") )
				( objectStatus "SNCLS_DDR4_CHN_L_DQ_DQS_BYTE1" )
			)
			( netClass "@sapphirecity_baseboard_lib.sapphirecity_baseboard(sch_1):\DDR4_CHN_L_DQ_DQS_BYTE2\"
				( memberType ( signal ) )
				( spacingCSetRef "@sapphirecity_baseboard_lib.sapphirecity_baseboard(sch_1):\10H_SL_12H_MS\" )
				( sameNetSpacingCSetRef "@crescent_city_bb_fab1_lib.crescent_city_bb_fab1(sch_1):\7H_US_AND_5H_SL\" )
				( objectFlag fObjectSpacing )
				( objectFlag fObjectSameNetSpacing )
				( member ( diffPairRef "@sapphirecity_baseboard_lib.sapphirecity_baseboard(sch_1):\M_L_DQS_D\(2)") )
				( member ( diffPairRef "@sapphirecity_baseboard_lib.sapphirecity_baseboard(sch_1):\M_L_DQS_D\(11)") )
				( member ( signalRef "@baseboard_fab2_lib.baseboard_fab2(sch_1):m_l_dq(16)") )
				( member ( signalRef "@baseboard_fab2_lib.baseboard_fab2(sch_1):m_l_dq(17)") )
				( member ( signalRef "@baseboard_fab2_lib.baseboard_fab2(sch_1):m_l_dq(18)") )
				( member ( signalRef "@baseboard_fab2_lib.baseboard_fab2(sch_1):m_l_dq(19)") )
				( member ( signalRef "@baseboard_fab2_lib.baseboard_fab2(sch_1):m_l_dq(20)") )
				( member ( signalRef "@baseboard_fab2_lib.baseboard_fab2(sch_1):m_l_dq(21)") )
				( member ( signalRef "@baseboard_fab2_lib.baseboard_fab2(sch_1):m_l_dq(22)") )
				( member ( signalRef "@baseboard_fab2_lib.baseboard_fab2(sch_1):m_l_dq(23)") )
				( objectStatus "SNCLS_DDR4_CHN_L_DQ_DQS_BYTE2" )
			)
			( netClass "@sapphirecity_baseboard_lib.sapphirecity_baseboard(sch_1):\DDR4_CHN_L_DQ_DQS_BYTE3\"
				( memberType ( signal ) )
				( spacingCSetRef "@sapphirecity_baseboard_lib.sapphirecity_baseboard(sch_1):\DQ_TO_DQ\" )
				( sameNetSpacingCSetRef "@crescent_city_bb_fab1_lib.crescent_city_bb_fab1(sch_1):\7H_US_AND_5H_SL\" )
				( objectFlag fObjectSpacing )
				( objectFlag fObjectSameNetSpacing )
				( member ( diffPairRef "@sapphirecity_baseboard_lib.sapphirecity_baseboard(sch_1):\M_L_DQS_D\(3)") )
				( member ( diffPairRef "@sapphirecity_baseboard_lib.sapphirecity_baseboard(sch_1):\M_L_DQS_D\(12)") )
				( member ( signalRef "@baseboard_fab2_lib.baseboard_fab2(sch_1):m_l_dq(24)") )
				( member ( signalRef "@baseboard_fab2_lib.baseboard_fab2(sch_1):m_l_dq(25)") )
				( member ( signalRef "@baseboard_fab2_lib.baseboard_fab2(sch_1):m_l_dq(26)") )
				( member ( signalRef "@baseboard_fab2_lib.baseboard_fab2(sch_1):m_l_dq(27)") )
				( member ( signalRef "@baseboard_fab2_lib.baseboard_fab2(sch_1):m_l_dq(28)") )
				( member ( signalRef "@baseboard_fab2_lib.baseboard_fab2(sch_1):m_l_dq(29)") )
				( member ( signalRef "@baseboard_fab2_lib.baseboard_fab2(sch_1):m_l_dq(30)") )
				( member ( signalRef "@baseboard_fab2_lib.baseboard_fab2(sch_1):m_l_dq(31)") )
				( objectStatus "SNCLS_DDR4_CHN_L_DQ_DQS_BYTE3" )
			)
			( netClass "@sapphirecity_baseboard_lib.sapphirecity_baseboard(sch_1):\DDR4_CHN_L_DQ_DQS_BYTE4\"
				( memberType ( signal ) )
				( spacingCSetRef "@sapphirecity_baseboard_lib.sapphirecity_baseboard(sch_1):\10H_SL_12H_MS\" )
				( sameNetSpacingCSetRef "@crescent_city_bb_fab1_lib.crescent_city_bb_fab1(sch_1):\7H_US_AND_5H_SL\" )
				( objectFlag fObjectSpacing )
				( objectFlag fObjectSameNetSpacing )
				( member ( diffPairRef "@sapphirecity_baseboard_lib.sapphirecity_baseboard(sch_1):\M_L_DQS_D\(4)") )
				( member ( diffPairRef "@sapphirecity_baseboard_lib.sapphirecity_baseboard(sch_1):\M_L_DQS_D\(13)") )
				( member ( signalRef "@baseboard_fab2_lib.baseboard_fab2(sch_1):m_l_dq(32)") )
				( member ( signalRef "@baseboard_fab2_lib.baseboard_fab2(sch_1):m_l_dq(33)") )
				( member ( signalRef "@baseboard_fab2_lib.baseboard_fab2(sch_1):m_l_dq(34)") )
				( member ( signalRef "@baseboard_fab2_lib.baseboard_fab2(sch_1):m_l_dq(35)") )
				( member ( signalRef "@baseboard_fab2_lib.baseboard_fab2(sch_1):m_l_dq(36)") )
				( member ( signalRef "@baseboard_fab2_lib.baseboard_fab2(sch_1):m_l_dq(37)") )
				( member ( signalRef "@baseboard_fab2_lib.baseboard_fab2(sch_1):m_l_dq(38)") )
				( member ( signalRef "@baseboard_fab2_lib.baseboard_fab2(sch_1):m_l_dq(39)") )
				( objectStatus "SNCLS_DDR4_CHN_L_DQ_DQS_BYTE4" )
			)
			( netClass "@sapphirecity_baseboard_lib.sapphirecity_baseboard(sch_1):\DDR4_CHN_L_DQ_DQS_BYTE5\"
				( memberType ( signal ) )
				( spacingCSetRef "@sapphirecity_baseboard_lib.sapphirecity_baseboard(sch_1):\10H_SL_12H_MS\" )
				( sameNetSpacingCSetRef "@crescent_city_bb_fab1_lib.crescent_city_bb_fab1(sch_1):\7H_US_AND_5H_SL\" )
				( objectFlag fObjectSpacing )
				( objectFlag fObjectSameNetSpacing )
				( member ( diffPairRef "@sapphirecity_baseboard_lib.sapphirecity_baseboard(sch_1):\M_L_DQS_D\(5)") )
				( member ( diffPairRef "@sapphirecity_baseboard_lib.sapphirecity_baseboard(sch_1):\M_L_DQS_D\(14)") )
				( member ( signalRef "@baseboard_fab2_lib.baseboard_fab2(sch_1):m_l_dq(40)") )
				( member ( signalRef "@baseboard_fab2_lib.baseboard_fab2(sch_1):m_l_dq(41)") )
				( member ( signalRef "@baseboard_fab2_lib.baseboard_fab2(sch_1):m_l_dq(42)") )
				( member ( signalRef "@baseboard_fab2_lib.baseboard_fab2(sch_1):m_l_dq(43)") )
				( member ( signalRef "@baseboard_fab2_lib.baseboard_fab2(sch_1):m_l_dq(44)") )
				( member ( signalRef "@baseboard_fab2_lib.baseboard_fab2(sch_1):m_l_dq(45)") )
				( member ( signalRef "@baseboard_fab2_lib.baseboard_fab2(sch_1):m_l_dq(46)") )
				( member ( signalRef "@baseboard_fab2_lib.baseboard_fab2(sch_1):m_l_dq(47)") )
				( objectStatus "SNCLS_DDR4_CHN_L_DQ_DQS_BYTE5" )
			)
			( netClass "@sapphirecity_baseboard_lib.sapphirecity_baseboard(sch_1):\DDR4_CHN_L_DQ_DQS_BYTE6\"
				( memberType ( signal ) )
				( spacingCSetRef "@sapphirecity_baseboard_lib.sapphirecity_baseboard(sch_1):\10H_SL_12H_MS\" )
				( sameNetSpacingCSetRef "@crescent_city_bb_fab1_lib.crescent_city_bb_fab1(sch_1):\7H_US_AND_5H_SL\" )
				( objectFlag fObjectSpacing )
				( objectFlag fObjectSameNetSpacing )
				( member ( diffPairRef "@sapphirecity_baseboard_lib.sapphirecity_baseboard(sch_1):\M_L_DQS_D\(6)") )
				( member ( diffPairRef "@sapphirecity_baseboard_lib.sapphirecity_baseboard(sch_1):\M_L_DQS_D\(15)") )
				( member ( signalRef "@baseboard_fab2_lib.baseboard_fab2(sch_1):m_l_dq(48)") )
				( member ( signalRef "@baseboard_fab2_lib.baseboard_fab2(sch_1):m_l_dq(49)") )
				( member ( signalRef "@baseboard_fab2_lib.baseboard_fab2(sch_1):m_l_dq(50)") )
				( member ( signalRef "@baseboard_fab2_lib.baseboard_fab2(sch_1):m_l_dq(51)") )
				( member ( signalRef "@baseboard_fab2_lib.baseboard_fab2(sch_1):m_l_dq(52)") )
				( member ( signalRef "@baseboard_fab2_lib.baseboard_fab2(sch_1):m_l_dq(53)") )
				( member ( signalRef "@baseboard_fab2_lib.baseboard_fab2(sch_1):m_l_dq(54)") )
				( member ( signalRef "@baseboard_fab2_lib.baseboard_fab2(sch_1):m_l_dq(55)") )
				( objectStatus "SNCLS_DDR4_CHN_L_DQ_DQS_BYTE6" )
			)
			( netClass "@sapphirecity_baseboard_lib.sapphirecity_baseboard(sch_1):\DDR4_CHN_L_DQ_DQS_BYTE7\"
				( memberType ( signal ) )
				( spacingCSetRef "@sapphirecity_baseboard_lib.sapphirecity_baseboard(sch_1):\10H_SL_12H_MS\" )
				( sameNetSpacingCSetRef "@crescent_city_bb_fab1_lib.crescent_city_bb_fab1(sch_1):\7H_US_AND_5H_SL\" )
				( objectFlag fObjectSpacing )
				( objectFlag fObjectSameNetSpacing )
				( member ( diffPairRef "@sapphirecity_baseboard_lib.sapphirecity_baseboard(sch_1):\M_L_DQS_D\(7)") )
				( member ( diffPairRef "@sapphirecity_baseboard_lib.sapphirecity_baseboard(sch_1):\M_L_DQS_D\(16)") )
				( member ( signalRef "@baseboard_fab2_lib.baseboard_fab2(sch_1):m_l_dq(56)") )
				( member ( signalRef "@baseboard_fab2_lib.baseboard_fab2(sch_1):m_l_dq(57)") )
				( member ( signalRef "@baseboard_fab2_lib.baseboard_fab2(sch_1):m_l_dq(58)") )
				( member ( signalRef "@baseboard_fab2_lib.baseboard_fab2(sch_1):m_l_dq(59)") )
				( member ( signalRef "@baseboard_fab2_lib.baseboard_fab2(sch_1):m_l_dq(60)") )
				( member ( signalRef "@baseboard_fab2_lib.baseboard_fab2(sch_1):m_l_dq(61)") )
				( member ( signalRef "@baseboard_fab2_lib.baseboard_fab2(sch_1):m_l_dq(62)") )
				( member ( signalRef "@baseboard_fab2_lib.baseboard_fab2(sch_1):m_l_dq(63)") )
				( objectStatus "SNCLS_DDR4_CHN_L_DQ_DQS_BYTE7" )
			)
			( netClass "@sapphirecity_baseboard_lib.sapphirecity_baseboard(sch_1):\DDR4_CHN_M_DQ_DQS_BYTE0\"
				( memberType ( signal ) )
				( spacingCSetRef "@sapphirecity_baseboard_lib.sapphirecity_baseboard(sch_1):\10H_SL_12H_MS\" )
				( sameNetSpacingCSetRef "@crescent_city_bb_fab1_lib.crescent_city_bb_fab1(sch_1):\7H_US_AND_5H_SL\" )
				( objectFlag fObjectSpacing )
				( objectFlag fObjectSameNetSpacing )
				( member ( diffPairRef "@sapphirecity_baseboard_lib.sapphirecity_baseboard(sch_1):\M_M_DQS_D\(0)") )
				( member ( diffPairRef "@sapphirecity_baseboard_lib.sapphirecity_baseboard(sch_1):\M_M_DQS_D\(9)") )
				( member ( signalRef "@baseboard_fab2_lib.baseboard_fab2(sch_1):m_m_dq(0)") )
				( member ( signalRef "@baseboard_fab2_lib.baseboard_fab2(sch_1):m_m_dq(1)") )
				( member ( signalRef "@baseboard_fab2_lib.baseboard_fab2(sch_1):m_m_dq(2)") )
				( member ( signalRef "@baseboard_fab2_lib.baseboard_fab2(sch_1):m_m_dq(3)") )
				( member ( signalRef "@baseboard_fab2_lib.baseboard_fab2(sch_1):m_m_dq(4)") )
				( member ( signalRef "@baseboard_fab2_lib.baseboard_fab2(sch_1):m_m_dq(5)") )
				( member ( signalRef "@baseboard_fab2_lib.baseboard_fab2(sch_1):m_m_dq(6)") )
				( member ( signalRef "@baseboard_fab2_lib.baseboard_fab2(sch_1):m_m_dq(7)") )
				( objectStatus "SNCLS_DDR4_CHN_M_DQ_DQS_BYTE0" )
			)
			( netClass "@sapphirecity_baseboard_lib.sapphirecity_baseboard(sch_1):\DDR4_CHN_M_DQ_DQS_BYTE1\"
				( memberType ( signal ) )
				( spacingCSetRef "@sapphirecity_baseboard_lib.sapphirecity_baseboard(sch_1):\10H_SL_12H_MS\" )
				( sameNetSpacingCSetRef "@crescent_city_bb_fab1_lib.crescent_city_bb_fab1(sch_1):\7H_US_AND_5H_SL\" )
				( objectFlag fObjectSpacing )
				( objectFlag fObjectSameNetSpacing )
				( member ( diffPairRef "@sapphirecity_baseboard_lib.sapphirecity_baseboard(sch_1):\M_M_DQS_D\(1)") )
				( member ( diffPairRef "@sapphirecity_baseboard_lib.sapphirecity_baseboard(sch_1):\M_M_DQS_D\(10)") )
				( member ( signalRef "@baseboard_fab2_lib.baseboard_fab2(sch_1):m_m_dq(8)") )
				( member ( signalRef "@baseboard_fab2_lib.baseboard_fab2(sch_1):m_m_dq(9)") )
				( member ( signalRef "@baseboard_fab2_lib.baseboard_fab2(sch_1):m_m_dq(10)") )
				( member ( signalRef "@baseboard_fab2_lib.baseboard_fab2(sch_1):m_m_dq(11)") )
				( member ( signalRef "@baseboard_fab2_lib.baseboard_fab2(sch_1):m_m_dq(12)") )
				( member ( signalRef "@baseboard_fab2_lib.baseboard_fab2(sch_1):m_m_dq(13)") )
				( member ( signalRef "@baseboard_fab2_lib.baseboard_fab2(sch_1):m_m_dq(14)") )
				( member ( signalRef "@baseboard_fab2_lib.baseboard_fab2(sch_1):m_m_dq(15)") )
				( objectStatus "SNCLS_DDR4_CHN_M_DQ_DQS_BYTE1" )
			)
			( netClass "@sapphirecity_baseboard_lib.sapphirecity_baseboard(sch_1):\DDR4_CHN_M_DQ_DQS_BYTE2\"
				( memberType ( signal ) )
				( spacingCSetRef "@sapphirecity_baseboard_lib.sapphirecity_baseboard(sch_1):\10H_SL_12H_MS\" )
				( sameNetSpacingCSetRef "@crescent_city_bb_fab1_lib.crescent_city_bb_fab1(sch_1):\7H_US_AND_5H_SL\" )
				( objectFlag fObjectSpacing )
				( objectFlag fObjectSameNetSpacing )
				( member ( diffPairRef "@sapphirecity_baseboard_lib.sapphirecity_baseboard(sch_1):\M_M_DQS_D\(2)") )
				( member ( diffPairRef "@sapphirecity_baseboard_lib.sapphirecity_baseboard(sch_1):\M_M_DQS_D\(11)") )
				( member ( signalRef "@baseboard_fab2_lib.baseboard_fab2(sch_1):m_m_dq(16)") )
				( member ( signalRef "@baseboard_fab2_lib.baseboard_fab2(sch_1):m_m_dq(17)") )
				( member ( signalRef "@baseboard_fab2_lib.baseboard_fab2(sch_1):m_m_dq(18)") )
				( member ( signalRef "@baseboard_fab2_lib.baseboard_fab2(sch_1):m_m_dq(19)") )
				( member ( signalRef "@baseboard_fab2_lib.baseboard_fab2(sch_1):m_m_dq(20)") )
				( member ( signalRef "@baseboard_fab2_lib.baseboard_fab2(sch_1):m_m_dq(21)") )
				( member ( signalRef "@baseboard_fab2_lib.baseboard_fab2(sch_1):m_m_dq(22)") )
				( member ( signalRef "@baseboard_fab2_lib.baseboard_fab2(sch_1):m_m_dq(23)") )
				( objectStatus "SNCLS_DDR4_CHN_M_DQ_DQS_BYTE2" )
			)
			( netClass "@sapphirecity_baseboard_lib.sapphirecity_baseboard(sch_1):\DDR4_CHN_M_DQ_DQS_BYTE3\"
				( memberType ( signal ) )
				( spacingCSetRef "@sapphirecity_baseboard_lib.sapphirecity_baseboard(sch_1):\10H_SL_12H_MS\" )
				( sameNetSpacingCSetRef "@crescent_city_bb_fab1_lib.crescent_city_bb_fab1(sch_1):\7H_US_AND_5H_SL\" )
				( objectFlag fObjectSpacing )
				( objectFlag fObjectSameNetSpacing )
				( member ( diffPairRef "@sapphirecity_baseboard_lib.sapphirecity_baseboard(sch_1):\M_M_DQS_D\(3)") )
				( member ( diffPairRef "@sapphirecity_baseboard_lib.sapphirecity_baseboard(sch_1):\M_M_DQS_D\(12)") )
				( member ( signalRef "@baseboard_fab2_lib.baseboard_fab2(sch_1):m_m_dq(24)") )
				( member ( signalRef "@baseboard_fab2_lib.baseboard_fab2(sch_1):m_m_dq(25)") )
				( member ( signalRef "@baseboard_fab2_lib.baseboard_fab2(sch_1):m_m_dq(26)") )
				( member ( signalRef "@baseboard_fab2_lib.baseboard_fab2(sch_1):m_m_dq(27)") )
				( member ( signalRef "@baseboard_fab2_lib.baseboard_fab2(sch_1):m_m_dq(28)") )
				( member ( signalRef "@baseboard_fab2_lib.baseboard_fab2(sch_1):m_m_dq(29)") )
				( member ( signalRef "@baseboard_fab2_lib.baseboard_fab2(sch_1):m_m_dq(30)") )
				( member ( signalRef "@baseboard_fab2_lib.baseboard_fab2(sch_1):m_m_dq(31)") )
				( objectStatus "SNCLS_DDR4_CHN_M_DQ_DQS_BYTE3" )
			)
			( netClass "@sapphirecity_baseboard_lib.sapphirecity_baseboard(sch_1):\DDR4_CHN_M_DQ_DQS_BYTE4\"
				( memberType ( signal ) )
				( spacingCSetRef "@sapphirecity_baseboard_lib.sapphirecity_baseboard(sch_1):\10H_SL_12H_MS\" )
				( sameNetSpacingCSetRef "@crescent_city_bb_fab1_lib.crescent_city_bb_fab1(sch_1):\7H_US_AND_5H_SL\" )
				( objectFlag fObjectSpacing )
				( objectFlag fObjectSameNetSpacing )
				( member ( diffPairRef "@sapphirecity_baseboard_lib.sapphirecity_baseboard(sch_1):\M_M_DQS_D\(4)") )
				( member ( diffPairRef "@sapphirecity_baseboard_lib.sapphirecity_baseboard(sch_1):\M_M_DQS_D\(13)") )
				( member ( signalRef "@baseboard_fab2_lib.baseboard_fab2(sch_1):m_m_dq(32)") )
				( member ( signalRef "@baseboard_fab2_lib.baseboard_fab2(sch_1):m_m_dq(33)") )
				( member ( signalRef "@baseboard_fab2_lib.baseboard_fab2(sch_1):m_m_dq(34)") )
				( member ( signalRef "@baseboard_fab2_lib.baseboard_fab2(sch_1):m_m_dq(35)") )
				( member ( signalRef "@baseboard_fab2_lib.baseboard_fab2(sch_1):m_m_dq(36)") )
				( member ( signalRef "@baseboard_fab2_lib.baseboard_fab2(sch_1):m_m_dq(37)") )
				( member ( signalRef "@baseboard_fab2_lib.baseboard_fab2(sch_1):m_m_dq(38)") )
				( member ( signalRef "@baseboard_fab2_lib.baseboard_fab2(sch_1):m_m_dq(39)") )
				( objectStatus "SNCLS_DDR4_CHN_M_DQ_DQS_BYTE4" )
			)
			( netClass "@sapphirecity_baseboard_lib.sapphirecity_baseboard(sch_1):\DDR4_CHN_M_DQ_DQS_BYTE5\"
				( memberType ( signal ) )
				( spacingCSetRef "@sapphirecity_baseboard_lib.sapphirecity_baseboard(sch_1):\10H_SL_12H_MS\" )
				( sameNetSpacingCSetRef "@crescent_city_bb_fab1_lib.crescent_city_bb_fab1(sch_1):\7H_US_AND_5H_SL\" )
				( objectFlag fObjectSpacing )
				( objectFlag fObjectSameNetSpacing )
				( member ( diffPairRef "@sapphirecity_baseboard_lib.sapphirecity_baseboard(sch_1):\M_M_DQS_D\(5)") )
				( member ( diffPairRef "@sapphirecity_baseboard_lib.sapphirecity_baseboard(sch_1):\M_M_DQS_D\(14)") )
				( member ( signalRef "@baseboard_fab2_lib.baseboard_fab2(sch_1):m_m_dq(40)") )
				( member ( signalRef "@baseboard_fab2_lib.baseboard_fab2(sch_1):m_m_dq(41)") )
				( member ( signalRef "@baseboard_fab2_lib.baseboard_fab2(sch_1):m_m_dq(42)") )
				( member ( signalRef "@baseboard_fab2_lib.baseboard_fab2(sch_1):m_m_dq(43)") )
				( member ( signalRef "@baseboard_fab2_lib.baseboard_fab2(sch_1):m_m_dq(44)") )
				( member ( signalRef "@baseboard_fab2_lib.baseboard_fab2(sch_1):m_m_dq(45)") )
				( member ( signalRef "@baseboard_fab2_lib.baseboard_fab2(sch_1):m_m_dq(46)") )
				( member ( signalRef "@baseboard_fab2_lib.baseboard_fab2(sch_1):m_m_dq(47)") )
				( objectStatus "SNCLS_DDR4_CHN_M_DQ_DQS_BYTE5" )
			)
			( netClass "@sapphirecity_baseboard_lib.sapphirecity_baseboard(sch_1):\DDR4_CHN_M_DQ_DQS_BYTE6\"
				( memberType ( signal ) )
				( spacingCSetRef "@sapphirecity_baseboard_lib.sapphirecity_baseboard(sch_1):\10H_SL_12H_MS\" )
				( sameNetSpacingCSetRef "@crescent_city_bb_fab1_lib.crescent_city_bb_fab1(sch_1):\7H_US_AND_5H_SL\" )
				( objectFlag fObjectSpacing )
				( objectFlag fObjectSameNetSpacing )
				( member ( diffPairRef "@sapphirecity_baseboard_lib.sapphirecity_baseboard(sch_1):\M_M_DQS_D\(6)") )
				( member ( diffPairRef "@sapphirecity_baseboard_lib.sapphirecity_baseboard(sch_1):\M_M_DQS_D\(15)") )
				( member ( signalRef "@baseboard_fab2_lib.baseboard_fab2(sch_1):m_m_dq(48)") )
				( member ( signalRef "@baseboard_fab2_lib.baseboard_fab2(sch_1):m_m_dq(49)") )
				( member ( signalRef "@baseboard_fab2_lib.baseboard_fab2(sch_1):m_m_dq(50)") )
				( member ( signalRef "@baseboard_fab2_lib.baseboard_fab2(sch_1):m_m_dq(51)") )
				( member ( signalRef "@baseboard_fab2_lib.baseboard_fab2(sch_1):m_m_dq(52)") )
				( member ( signalRef "@baseboard_fab2_lib.baseboard_fab2(sch_1):m_m_dq(53)") )
				( member ( signalRef "@baseboard_fab2_lib.baseboard_fab2(sch_1):m_m_dq(54)") )
				( member ( signalRef "@baseboard_fab2_lib.baseboard_fab2(sch_1):m_m_dq(55)") )
				( objectStatus "SNCLS_DDR4_CHN_M_DQ_DQS_BYTE6" )
			)
			( netClass "@sapphirecity_baseboard_lib.sapphirecity_baseboard(sch_1):\DDR4_CHN_M_DQ_DQS_BYTE7\"
				( memberType ( signal ) )
				( spacingCSetRef "@sapphirecity_baseboard_lib.sapphirecity_baseboard(sch_1):\10H_SL_12H_MS\" )
				( sameNetSpacingCSetRef "@crescent_city_bb_fab1_lib.crescent_city_bb_fab1(sch_1):\7H_US_AND_5H_SL\" )
				( objectFlag fObjectSpacing )
				( objectFlag fObjectSameNetSpacing )
				( member ( diffPairRef "@sapphirecity_baseboard_lib.sapphirecity_baseboard(sch_1):\M_M_DQS_D\(7)") )
				( member ( diffPairRef "@sapphirecity_baseboard_lib.sapphirecity_baseboard(sch_1):\M_M_DQS_D\(16)") )
				( member ( signalRef "@baseboard_fab2_lib.baseboard_fab2(sch_1):m_m_dq(56)") )
				( member ( signalRef "@baseboard_fab2_lib.baseboard_fab2(sch_1):m_m_dq(57)") )
				( member ( signalRef "@baseboard_fab2_lib.baseboard_fab2(sch_1):m_m_dq(58)") )
				( member ( signalRef "@baseboard_fab2_lib.baseboard_fab2(sch_1):m_m_dq(59)") )
				( member ( signalRef "@baseboard_fab2_lib.baseboard_fab2(sch_1):m_m_dq(60)") )
				( member ( signalRef "@baseboard_fab2_lib.baseboard_fab2(sch_1):m_m_dq(61)") )
				( member ( signalRef "@baseboard_fab2_lib.baseboard_fab2(sch_1):m_m_dq(62)") )
				( member ( signalRef "@baseboard_fab2_lib.baseboard_fab2(sch_1):m_m_dq(63)") )
				( objectStatus "SNCLS_DDR4_CHN_M_DQ_DQS_BYTE7" )
			)
			( netClass "@sapphirecity_baseboard_lib.sapphirecity_baseboard(sch_1):\DDR4_CHN_M_ECC\"
				( memberType ( signal ) )
				( spacingCSetRef "@sapphirecity_baseboard_lib.sapphirecity_baseboard(sch_1):\10H_SL_12H_MS\" )
				( sameNetSpacingCSetRef "@crescent_city_bb_fab1_lib.crescent_city_bb_fab1(sch_1):\7H_US_AND_5H_SL\" )
				( objectFlag fObjectSpacing )
				( objectFlag fObjectSameNetSpacing )
				( member ( diffPairRef "@sapphirecity_baseboard_lib.sapphirecity_baseboard(sch_1):\M_M_DQS_D\(8)") )
				( member ( diffPairRef "@sapphirecity_baseboard_lib.sapphirecity_baseboard(sch_1):\M_M_DQS_D\(17)") )
				( member ( signalRef "@baseboard_fab2_lib.baseboard_fab2(sch_1):m_m_ecc(0)") )
				( member ( signalRef "@baseboard_fab2_lib.baseboard_fab2(sch_1):m_m_ecc(1)") )
				( member ( signalRef "@baseboard_fab2_lib.baseboard_fab2(sch_1):m_m_ecc(2)") )
				( member ( signalRef "@baseboard_fab2_lib.baseboard_fab2(sch_1):m_m_ecc(3)") )
				( member ( signalRef "@baseboard_fab2_lib.baseboard_fab2(sch_1):m_m_ecc(4)") )
				( member ( signalRef "@baseboard_fab2_lib.baseboard_fab2(sch_1):m_m_ecc(5)") )
				( member ( signalRef "@baseboard_fab2_lib.baseboard_fab2(sch_1):m_m_ecc(6)") )
				( member ( signalRef "@baseboard_fab2_lib.baseboard_fab2(sch_1):m_m_ecc(7)") )
				( objectStatus "SNCLS_DDR4_CHN_M_ECC" )
			)
			( netClass "@sapphirecity_baseboard_lib.sapphirecity_baseboard(sch_1):\DDR4_CHN_L_ECC\"
				( memberType ( signal ) )
				( spacingCSetRef "@sapphirecity_baseboard_lib.sapphirecity_baseboard(sch_1):\10H_SL_12H_MS\" )
				( sameNetSpacingCSetRef "@crescent_city_bb_fab1_lib.crescent_city_bb_fab1(sch_1):\7H_US_AND_5H_SL\" )
				( objectFlag fObjectSpacing )
				( objectFlag fObjectSameNetSpacing )
				( member ( diffPairRef "@sapphirecity_baseboard_lib.sapphirecity_baseboard(sch_1):\M_L_DQS_D\(8)") )
				( member ( diffPairRef "@sapphirecity_baseboard_lib.sapphirecity_baseboard(sch_1):\M_L_DQS_D\(17)") )
				( member ( signalRef "@baseboard_fab2_lib.baseboard_fab2(sch_1):m_l_ecc(0)") )
				( member ( signalRef "@baseboard_fab2_lib.baseboard_fab2(sch_1):m_l_ecc(1)") )
				( member ( signalRef "@baseboard_fab2_lib.baseboard_fab2(sch_1):m_l_ecc(2)") )
				( member ( signalRef "@baseboard_fab2_lib.baseboard_fab2(sch_1):m_l_ecc(3)") )
				( member ( signalRef "@baseboard_fab2_lib.baseboard_fab2(sch_1):m_l_ecc(4)") )
				( member ( signalRef "@baseboard_fab2_lib.baseboard_fab2(sch_1):m_l_ecc(5)") )
				( member ( signalRef "@baseboard_fab2_lib.baseboard_fab2(sch_1):m_l_ecc(6)") )
				( member ( signalRef "@baseboard_fab2_lib.baseboard_fab2(sch_1):m_l_ecc(7)") )
				( objectStatus "SNCLS_DDR4_CHN_L_ECC" )
			)
			( netClass "@sapphirecity_baseboard_lib.sapphirecity_baseboard(sch_1):\DDR4_CHN_K_ECC\"
				( memberType ( signal ) )
				( spacingCSetRef "@sapphirecity_baseboard_lib.sapphirecity_baseboard(sch_1):\10H_SL_12H_MS\" )
				( sameNetSpacingCSetRef "@crescent_city_bb_fab1_lib.crescent_city_bb_fab1(sch_1):\7H_US_AND_5H_SL\" )
				( objectFlag fObjectSpacing )
				( objectFlag fObjectSameNetSpacing )
				( member ( diffPairRef "@sapphirecity_baseboard_lib.sapphirecity_baseboard(sch_1):\M_K_DQS_D\(8)") )
				( member ( diffPairRef "@sapphirecity_baseboard_lib.sapphirecity_baseboard(sch_1):\M_K_DQS_D\(17)") )
				( member ( signalRef "@baseboard_fab2_lib.baseboard_fab2(sch_1):m_k_ecc(0)") )
				( member ( signalRef "@baseboard_fab2_lib.baseboard_fab2(sch_1):m_k_ecc(1)") )
				( member ( signalRef "@baseboard_fab2_lib.baseboard_fab2(sch_1):m_k_ecc(2)") )
				( member ( signalRef "@baseboard_fab2_lib.baseboard_fab2(sch_1):m_k_ecc(3)") )
				( member ( signalRef "@baseboard_fab2_lib.baseboard_fab2(sch_1):m_k_ecc(4)") )
				( member ( signalRef "@baseboard_fab2_lib.baseboard_fab2(sch_1):m_k_ecc(5)") )
				( member ( signalRef "@baseboard_fab2_lib.baseboard_fab2(sch_1):m_k_ecc(6)") )
				( member ( signalRef "@baseboard_fab2_lib.baseboard_fab2(sch_1):m_k_ecc(7)") )
				( objectStatus "SNCLS_DDR4_CHN_K_ECC" )
			)
			( netClass "@sapphirecity_baseboard_lib.sapphirecity_baseboard(sch_1):\DDR4_CHN_J_ECC\"
				( memberType ( signal ) )
				( spacingCSetRef "@sapphirecity_baseboard_lib.sapphirecity_baseboard(sch_1):\10H_SL_12H_MS\" )
				( sameNetSpacingCSetRef "@crescent_city_bb_fab1_lib.crescent_city_bb_fab1(sch_1):\7H_US_AND_5H_SL\" )
				( objectFlag fObjectSpacing )
				( objectFlag fObjectSameNetSpacing )
				( member ( diffPairRef "@sapphirecity_baseboard_lib.sapphirecity_baseboard(sch_1):\M_J_DQS_D\(8)") )
				( member ( diffPairRef "@sapphirecity_baseboard_lib.sapphirecity_baseboard(sch_1):\M_J_DQS_D\(17)") )
				( member ( signalRef "@baseboard_fab2_lib.baseboard_fab2(sch_1):m_j_ecc(0)") )
				( member ( signalRef "@baseboard_fab2_lib.baseboard_fab2(sch_1):m_j_ecc(1)") )
				( member ( signalRef "@baseboard_fab2_lib.baseboard_fab2(sch_1):m_j_ecc(2)") )
				( member ( signalRef "@baseboard_fab2_lib.baseboard_fab2(sch_1):m_j_ecc(3)") )
				( member ( signalRef "@baseboard_fab2_lib.baseboard_fab2(sch_1):m_j_ecc(4)") )
				( member ( signalRef "@baseboard_fab2_lib.baseboard_fab2(sch_1):m_j_ecc(5)") )
				( member ( signalRef "@baseboard_fab2_lib.baseboard_fab2(sch_1):m_j_ecc(6)") )
				( member ( signalRef "@baseboard_fab2_lib.baseboard_fab2(sch_1):m_j_ecc(7)") )
				( objectStatus "SNCLS_DDR4_CHN_J_ECC" )
			)
			( netClass "@sapphirecity_baseboard_lib.sapphirecity_baseboard(sch_1):\DDR4_CHN_A_DQ_DQS_BYTE6\"
				( memberType ( signal ) )
				( spacingCSetRef "@sapphirecity_baseboard_lib.sapphirecity_baseboard(sch_1):\10H_SL_12H_MS\" )
				( sameNetSpacingCSetRef "@crescent_city_bb_fab1_lib.crescent_city_bb_fab1(sch_1):\7H_US_AND_5H_SL\" )
				( objectFlag fObjectSpacing )
				( objectFlag fObjectSameNetSpacing )
				( member ( diffPairRef "@sapphirecity_baseboard_lib.sapphirecity_baseboard(sch_1):\M_A_DQS_D\(6)") )
				( member ( diffPairRef "@sapphirecity_baseboard_lib.sapphirecity_baseboard(sch_1):\M_A_DQS_D\(15)") )
				( member ( signalRef "@baseboard_fab2_lib.baseboard_fab2(sch_1):m_a_dq(48)") )
				( member ( signalRef "@baseboard_fab2_lib.baseboard_fab2(sch_1):m_a_dq(49)") )
				( member ( signalRef "@baseboard_fab2_lib.baseboard_fab2(sch_1):m_a_dq(50)") )
				( member ( signalRef "@baseboard_fab2_lib.baseboard_fab2(sch_1):m_a_dq(51)") )
				( member ( signalRef "@baseboard_fab2_lib.baseboard_fab2(sch_1):m_a_dq(52)") )
				( member ( signalRef "@baseboard_fab2_lib.baseboard_fab2(sch_1):m_a_dq(53)") )
				( member ( signalRef "@baseboard_fab2_lib.baseboard_fab2(sch_1):m_a_dq(54)") )
				( member ( signalRef "@baseboard_fab2_lib.baseboard_fab2(sch_1):m_a_dq(55)") )
				( objectStatus "SNCLS_DDR4_CHN_A_DQ_DQS_BYTE6" )
			)
			( netClass "@sapphirecity_baseboard_lib.sapphirecity_baseboard(sch_1):\DDR4_CHN_A_DQ_DQS_BYTE5\"
				( memberType ( signal ) )
				( spacingCSetRef "@sapphirecity_baseboard_lib.sapphirecity_baseboard(sch_1):\10H_SL_12H_MS\" )
				( sameNetSpacingCSetRef "@crescent_city_bb_fab1_lib.crescent_city_bb_fab1(sch_1):\7H_US_AND_5H_SL\" )
				( objectFlag fObjectSpacing )
				( objectFlag fObjectSameNetSpacing )
				( member ( diffPairRef "@sapphirecity_baseboard_lib.sapphirecity_baseboard(sch_1):\M_A_DQS_D\(5)") )
				( member ( diffPairRef "@sapphirecity_baseboard_lib.sapphirecity_baseboard(sch_1):\M_A_DQS_D\(14)") )
				( member ( signalRef "@baseboard_fab2_lib.baseboard_fab2(sch_1):m_a_dq(40)") )
				( member ( signalRef "@baseboard_fab2_lib.baseboard_fab2(sch_1):m_a_dq(41)") )
				( member ( signalRef "@baseboard_fab2_lib.baseboard_fab2(sch_1):m_a_dq(42)") )
				( member ( signalRef "@baseboard_fab2_lib.baseboard_fab2(sch_1):m_a_dq(43)") )
				( member ( signalRef "@baseboard_fab2_lib.baseboard_fab2(sch_1):m_a_dq(44)") )
				( member ( signalRef "@baseboard_fab2_lib.baseboard_fab2(sch_1):m_a_dq(45)") )
				( member ( signalRef "@baseboard_fab2_lib.baseboard_fab2(sch_1):m_a_dq(46)") )
				( member ( signalRef "@baseboard_fab2_lib.baseboard_fab2(sch_1):m_a_dq(47)") )
				( objectStatus "SNCLS_DDR4_CHN_A_DQ_DQS_BYTE5" )
			)
			( netClass "@sapphirecity_baseboard_lib.sapphirecity_baseboard(sch_1):\DDR4_CHN_A_DQ_DQS_BYTE4\"
				( memberType ( signal ) )
				( spacingCSetRef "@sapphirecity_baseboard_lib.sapphirecity_baseboard(sch_1):\10H_SL_12H_MS\" )
				( sameNetSpacingCSetRef "@crescent_city_bb_fab1_lib.crescent_city_bb_fab1(sch_1):\7H_US_AND_5H_SL\" )
				( objectFlag fObjectSpacing )
				( objectFlag fObjectSameNetSpacing )
				( member ( diffPairRef "@sapphirecity_baseboard_lib.sapphirecity_baseboard(sch_1):\M_A_DQS_D\(4)") )
				( member ( diffPairRef "@sapphirecity_baseboard_lib.sapphirecity_baseboard(sch_1):\M_A_DQS_D\(13)") )
				( member ( signalRef "@baseboard_fab2_lib.baseboard_fab2(sch_1):m_a_dq(32)") )
				( member ( signalRef "@baseboard_fab2_lib.baseboard_fab2(sch_1):m_a_dq(33)") )
				( member ( signalRef "@baseboard_fab2_lib.baseboard_fab2(sch_1):m_a_dq(34)") )
				( member ( signalRef "@baseboard_fab2_lib.baseboard_fab2(sch_1):m_a_dq(35)") )
				( member ( signalRef "@baseboard_fab2_lib.baseboard_fab2(sch_1):m_a_dq(36)") )
				( member ( signalRef "@baseboard_fab2_lib.baseboard_fab2(sch_1):m_a_dq(37)") )
				( member ( signalRef "@baseboard_fab2_lib.baseboard_fab2(sch_1):m_a_dq(38)") )
				( member ( signalRef "@baseboard_fab2_lib.baseboard_fab2(sch_1):m_a_dq(39)") )
				( objectStatus "SNCLS_DDR4_CHN_A_DQ_DQS_BYTE4" )
			)
			( netClass "@sapphirecity_baseboard_lib.sapphirecity_baseboard(sch_1):\DDR4_CHN_A_DQ_DQS_BYTE3\"
				( memberType ( signal ) )
				( spacingCSetRef "@sapphirecity_baseboard_lib.sapphirecity_baseboard(sch_1):\10H_SL_12H_MS\" )
				( sameNetSpacingCSetRef "@crescent_city_bb_fab1_lib.crescent_city_bb_fab1(sch_1):\7H_US_AND_5H_SL\" )
				( objectFlag fObjectSpacing )
				( objectFlag fObjectSameNetSpacing )
				( member ( diffPairRef "@sapphirecity_baseboard_lib.sapphirecity_baseboard(sch_1):\M_A_DQS_D\(3)") )
				( member ( diffPairRef "@sapphirecity_baseboard_lib.sapphirecity_baseboard(sch_1):\M_A_DQS_D\(12)") )
				( member ( signalRef "@baseboard_fab2_lib.baseboard_fab2(sch_1):m_a_dq(24)") )
				( member ( signalRef "@baseboard_fab2_lib.baseboard_fab2(sch_1):m_a_dq(25)") )
				( member ( signalRef "@baseboard_fab2_lib.baseboard_fab2(sch_1):m_a_dq(26)") )
				( member ( signalRef "@baseboard_fab2_lib.baseboard_fab2(sch_1):m_a_dq(27)") )
				( member ( signalRef "@baseboard_fab2_lib.baseboard_fab2(sch_1):m_a_dq(28)") )
				( member ( signalRef "@baseboard_fab2_lib.baseboard_fab2(sch_1):m_a_dq(29)") )
				( member ( signalRef "@baseboard_fab2_lib.baseboard_fab2(sch_1):m_a_dq(30)") )
				( member ( signalRef "@baseboard_fab2_lib.baseboard_fab2(sch_1):m_a_dq(31)") )
				( objectStatus "SNCLS_DDR4_CHN_A_DQ_DQS_BYTE3" )
			)
			( netClass "@sapphirecity_baseboard_lib.sapphirecity_baseboard(sch_1):\DDR4_CHN_A_DQ_DQS_BYTE2\"
				( memberType ( signal ) )
				( spacingCSetRef "@sapphirecity_baseboard_lib.sapphirecity_baseboard(sch_1):\10H_SL_12H_MS\" )
				( sameNetSpacingCSetRef "@crescent_city_bb_fab1_lib.crescent_city_bb_fab1(sch_1):\7H_US_AND_5H_SL\" )
				( objectFlag fObjectSpacing )
				( objectFlag fObjectSameNetSpacing )
				( member ( diffPairRef "@sapphirecity_baseboard_lib.sapphirecity_baseboard(sch_1):\M_A_DQS_D\(2)") )
				( member ( diffPairRef "@sapphirecity_baseboard_lib.sapphirecity_baseboard(sch_1):\M_A_DQS_D\(11)") )
				( member ( signalRef "@baseboard_fab2_lib.baseboard_fab2(sch_1):m_a_dq(16)") )
				( member ( signalRef "@baseboard_fab2_lib.baseboard_fab2(sch_1):m_a_dq(17)") )
				( member ( signalRef "@baseboard_fab2_lib.baseboard_fab2(sch_1):m_a_dq(18)") )
				( member ( signalRef "@baseboard_fab2_lib.baseboard_fab2(sch_1):m_a_dq(19)") )
				( member ( signalRef "@baseboard_fab2_lib.baseboard_fab2(sch_1):m_a_dq(20)") )
				( member ( signalRef "@baseboard_fab2_lib.baseboard_fab2(sch_1):m_a_dq(21)") )
				( member ( signalRef "@baseboard_fab2_lib.baseboard_fab2(sch_1):m_a_dq(22)") )
				( member ( signalRef "@baseboard_fab2_lib.baseboard_fab2(sch_1):m_a_dq(23)") )
				( objectStatus "SNCLS_DDR4_CHN_A_DQ_DQS_BYTE2" )
			)
			( netClass "@sapphirecity_baseboard_lib.sapphirecity_baseboard(sch_1):\DDR4_CHN_A_DQ_DQS_BYTE1\"
				( memberType ( signal ) )
				( spacingCSetRef "@sapphirecity_baseboard_lib.sapphirecity_baseboard(sch_1):\10H_SL_12H_MS\" )
				( sameNetSpacingCSetRef "@crescent_city_bb_fab1_lib.crescent_city_bb_fab1(sch_1):\7H_US_AND_5H_SL\" )
				( objectFlag fObjectSpacing )
				( objectFlag fObjectSameNetSpacing )
				( member ( diffPairRef "@sapphirecity_baseboard_lib.sapphirecity_baseboard(sch_1):\M_A_DQS_D\(1)") )
				( member ( diffPairRef "@sapphirecity_baseboard_lib.sapphirecity_baseboard(sch_1):\M_A_DQS_D\(10)") )
				( member ( signalRef "@baseboard_fab2_lib.baseboard_fab2(sch_1):m_a_dq(8)") )
				( member ( signalRef "@baseboard_fab2_lib.baseboard_fab2(sch_1):m_a_dq(9)") )
				( member ( signalRef "@baseboard_fab2_lib.baseboard_fab2(sch_1):m_a_dq(10)") )
				( member ( signalRef "@baseboard_fab2_lib.baseboard_fab2(sch_1):m_a_dq(11)") )
				( member ( signalRef "@baseboard_fab2_lib.baseboard_fab2(sch_1):m_a_dq(12)") )
				( member ( signalRef "@baseboard_fab2_lib.baseboard_fab2(sch_1):m_a_dq(13)") )
				( member ( signalRef "@baseboard_fab2_lib.baseboard_fab2(sch_1):m_a_dq(14)") )
				( member ( signalRef "@baseboard_fab2_lib.baseboard_fab2(sch_1):m_a_dq(15)") )
				( objectStatus "SNCLS_DDR4_CHN_A_DQ_DQS_BYTE1" )
			)
			( netClass "@sapphirecity_baseboard_lib.sapphirecity_baseboard(sch_1):\DDR4_CHN_A_DQ_DQS_BYTE0\"
				( memberType ( signal ) )
				( spacingCSetRef "@sapphirecity_baseboard_lib.sapphirecity_baseboard(sch_1):\10H_SL_12H_MS\" )
				( sameNetSpacingCSetRef "@crescent_city_bb_fab1_lib.crescent_city_bb_fab1(sch_1):\7H_US_AND_5H_SL\" )
				( objectFlag fObjectSpacing )
				( objectFlag fObjectSameNetSpacing )
				( member ( diffPairRef "@sapphirecity_baseboard_lib.sapphirecity_baseboard(sch_1):\M_A_DQS_D\(9)") )
				( member ( diffPairRef "@sapphirecity_baseboard_lib.sapphirecity_baseboard(sch_1):\M_A_DQS_D\(0)") )
				( member ( signalRef "@baseboard_fab2_lib.baseboard_fab2(sch_1):m_a_dq(0)") )
				( member ( signalRef "@baseboard_fab2_lib.baseboard_fab2(sch_1):m_a_dq(1)") )
				( member ( signalRef "@baseboard_fab2_lib.baseboard_fab2(sch_1):m_a_dq(2)") )
				( member ( signalRef "@baseboard_fab2_lib.baseboard_fab2(sch_1):m_a_dq(3)") )
				( member ( signalRef "@baseboard_fab2_lib.baseboard_fab2(sch_1):m_a_dq(4)") )
				( member ( signalRef "@baseboard_fab2_lib.baseboard_fab2(sch_1):m_a_dq(5)") )
				( member ( signalRef "@baseboard_fab2_lib.baseboard_fab2(sch_1):m_a_dq(6)") )
				( member ( signalRef "@baseboard_fab2_lib.baseboard_fab2(sch_1):m_a_dq(7)") )
				( objectStatus "SNCLS_DDR4_CHN_A_DQ_DQS_BYTE0" )
			)
			( netClass "@sapphirecity_baseboard_lib.sapphirecity_baseboard(sch_1):\DDR4_CHN_B_DQ_DQS_BYTE7\"
				( memberType ( signal ) )
				( spacingCSetRef "@sapphirecity_baseboard_lib.sapphirecity_baseboard(sch_1):\10H_SL_12H_MS\" )
				( sameNetSpacingCSetRef "@crescent_city_bb_fab1_lib.crescent_city_bb_fab1(sch_1):\7H_US_AND_5H_SL\" )
				( objectFlag fObjectSpacing )
				( objectFlag fObjectSameNetSpacing )
				( member ( diffPairRef "@sapphirecity_baseboard_lib.sapphirecity_baseboard(sch_1):\M_B_DQS_D\(7)") )
				( member ( diffPairRef "@sapphirecity_baseboard_lib.sapphirecity_baseboard(sch_1):\M_B_DQS_D\(16)") )
				( member ( signalRef "@baseboard_fab2_lib.baseboard_fab2(sch_1):m_b_dq(56)") )
				( member ( signalRef "@baseboard_fab2_lib.baseboard_fab2(sch_1):m_b_dq(57)") )
				( member ( signalRef "@baseboard_fab2_lib.baseboard_fab2(sch_1):m_b_dq(58)") )
				( member ( signalRef "@baseboard_fab2_lib.baseboard_fab2(sch_1):m_b_dq(59)") )
				( member ( signalRef "@baseboard_fab2_lib.baseboard_fab2(sch_1):m_b_dq(60)") )
				( member ( signalRef "@baseboard_fab2_lib.baseboard_fab2(sch_1):m_b_dq(61)") )
				( member ( signalRef "@baseboard_fab2_lib.baseboard_fab2(sch_1):m_b_dq(62)") )
				( member ( signalRef "@baseboard_fab2_lib.baseboard_fab2(sch_1):m_b_dq(63)") )
				( objectStatus "SNCLS_DDR4_CHN_B_DQ_DQS_BYTE7" )
			)
			( netClass "@sapphirecity_baseboard_lib.sapphirecity_baseboard(sch_1):\DDR4_CHN_B_DQ_DQS_BYTE6\"
				( memberType ( signal ) )
				( spacingCSetRef "@sapphirecity_baseboard_lib.sapphirecity_baseboard(sch_1):\10H_SL_12H_MS\" )
				( sameNetSpacingCSetRef "@crescent_city_bb_fab1_lib.crescent_city_bb_fab1(sch_1):\7H_US_AND_5H_SL\" )
				( objectFlag fObjectSpacing )
				( objectFlag fObjectSameNetSpacing )
				( member ( diffPairRef "@sapphirecity_baseboard_lib.sapphirecity_baseboard(sch_1):\M_B_DQS_D\(6)") )
				( member ( diffPairRef "@sapphirecity_baseboard_lib.sapphirecity_baseboard(sch_1):\M_B_DQS_D\(15)") )
				( member ( signalRef "@baseboard_fab2_lib.baseboard_fab2(sch_1):m_b_dq(48)") )
				( member ( signalRef "@baseboard_fab2_lib.baseboard_fab2(sch_1):m_b_dq(49)") )
				( member ( signalRef "@baseboard_fab2_lib.baseboard_fab2(sch_1):m_b_dq(50)") )
				( member ( signalRef "@baseboard_fab2_lib.baseboard_fab2(sch_1):m_b_dq(51)") )
				( member ( signalRef "@baseboard_fab2_lib.baseboard_fab2(sch_1):m_b_dq(52)") )
				( member ( signalRef "@baseboard_fab2_lib.baseboard_fab2(sch_1):m_b_dq(53)") )
				( member ( signalRef "@baseboard_fab2_lib.baseboard_fab2(sch_1):m_b_dq(54)") )
				( member ( signalRef "@baseboard_fab2_lib.baseboard_fab2(sch_1):m_b_dq(55)") )
				( objectStatus "SNCLS_DDR4_CHN_B_DQ_DQS_BYTE6" )
			)
			( netClass "@sapphirecity_baseboard_lib.sapphirecity_baseboard(sch_1):\DDR4_CHN_B_DQ_DQS_BYTE5\"
				( memberType ( signal ) )
				( spacingCSetRef "@sapphirecity_baseboard_lib.sapphirecity_baseboard(sch_1):\10H_SL_12H_MS\" )
				( sameNetSpacingCSetRef "@crescent_city_bb_fab1_lib.crescent_city_bb_fab1(sch_1):\7H_US_AND_5H_SL\" )
				( objectFlag fObjectSpacing )
				( objectFlag fObjectSameNetSpacing )
				( member ( diffPairRef "@sapphirecity_baseboard_lib.sapphirecity_baseboard(sch_1):\M_B_DQS_D\(5)") )
				( member ( diffPairRef "@sapphirecity_baseboard_lib.sapphirecity_baseboard(sch_1):\M_B_DQS_D\(14)") )
				( member ( signalRef "@baseboard_fab2_lib.baseboard_fab2(sch_1):m_b_dq(40)") )
				( member ( signalRef "@baseboard_fab2_lib.baseboard_fab2(sch_1):m_b_dq(41)") )
				( member ( signalRef "@baseboard_fab2_lib.baseboard_fab2(sch_1):m_b_dq(42)") )
				( member ( signalRef "@baseboard_fab2_lib.baseboard_fab2(sch_1):m_b_dq(43)") )
				( member ( signalRef "@baseboard_fab2_lib.baseboard_fab2(sch_1):m_b_dq(44)") )
				( member ( signalRef "@baseboard_fab2_lib.baseboard_fab2(sch_1):m_b_dq(45)") )
				( member ( signalRef "@baseboard_fab2_lib.baseboard_fab2(sch_1):m_b_dq(46)") )
				( member ( signalRef "@baseboard_fab2_lib.baseboard_fab2(sch_1):m_b_dq(47)") )
				( objectStatus "SNCLS_DDR4_CHN_B_DQ_DQS_BYTE5" )
			)
			( netClass "@sapphirecity_baseboard_lib.sapphirecity_baseboard(sch_1):\DDR4_CHN_B_DQ_DQS_BYTE4\"
				( memberType ( signal ) )
				( spacingCSetRef "@sapphirecity_baseboard_lib.sapphirecity_baseboard(sch_1):\10H_SL_12H_MS\" )
				( sameNetSpacingCSetRef "@crescent_city_bb_fab1_lib.crescent_city_bb_fab1(sch_1):\7H_US_AND_5H_SL\" )
				( objectFlag fObjectSpacing )
				( objectFlag fObjectSameNetSpacing )
				( member ( diffPairRef "@sapphirecity_baseboard_lib.sapphirecity_baseboard(sch_1):\M_B_DQS_D\(4)") )
				( member ( diffPairRef "@sapphirecity_baseboard_lib.sapphirecity_baseboard(sch_1):\M_B_DQS_D\(13)") )
				( member ( signalRef "@baseboard_fab2_lib.baseboard_fab2(sch_1):m_b_dq(32)") )
				( member ( signalRef "@baseboard_fab2_lib.baseboard_fab2(sch_1):m_b_dq(33)") )
				( member ( signalRef "@baseboard_fab2_lib.baseboard_fab2(sch_1):m_b_dq(34)") )
				( member ( signalRef "@baseboard_fab2_lib.baseboard_fab2(sch_1):m_b_dq(35)") )
				( member ( signalRef "@baseboard_fab2_lib.baseboard_fab2(sch_1):m_b_dq(36)") )
				( member ( signalRef "@baseboard_fab2_lib.baseboard_fab2(sch_1):m_b_dq(37)") )
				( member ( signalRef "@baseboard_fab2_lib.baseboard_fab2(sch_1):m_b_dq(38)") )
				( member ( signalRef "@baseboard_fab2_lib.baseboard_fab2(sch_1):m_b_dq(39)") )
				( objectStatus "SNCLS_DDR4_CHN_B_DQ_DQS_BYTE4" )
			)
			( netClass "@sapphirecity_baseboard_lib.sapphirecity_baseboard(sch_1):\DDR4_CHN_B_DQ_DQS_BYTE3\"
				( memberType ( signal ) )
				( spacingCSetRef "@sapphirecity_baseboard_lib.sapphirecity_baseboard(sch_1):\10H_SL_12H_MS\" )
				( sameNetSpacingCSetRef "@crescent_city_bb_fab1_lib.crescent_city_bb_fab1(sch_1):\7H_US_AND_5H_SL\" )
				( objectFlag fObjectSpacing )
				( objectFlag fObjectSameNetSpacing )
				( member ( diffPairRef "@sapphirecity_baseboard_lib.sapphirecity_baseboard(sch_1):\M_B_DQS_D\(3)") )
				( member ( diffPairRef "@sapphirecity_baseboard_lib.sapphirecity_baseboard(sch_1):\M_B_DQS_D\(12)") )
				( member ( signalRef "@baseboard_fab2_lib.baseboard_fab2(sch_1):m_b_dq(24)") )
				( member ( signalRef "@baseboard_fab2_lib.baseboard_fab2(sch_1):m_b_dq(25)") )
				( member ( signalRef "@baseboard_fab2_lib.baseboard_fab2(sch_1):m_b_dq(26)") )
				( member ( signalRef "@baseboard_fab2_lib.baseboard_fab2(sch_1):m_b_dq(27)") )
				( member ( signalRef "@baseboard_fab2_lib.baseboard_fab2(sch_1):m_b_dq(28)") )
				( member ( signalRef "@baseboard_fab2_lib.baseboard_fab2(sch_1):m_b_dq(29)") )
				( member ( signalRef "@baseboard_fab2_lib.baseboard_fab2(sch_1):m_b_dq(30)") )
				( member ( signalRef "@baseboard_fab2_lib.baseboard_fab2(sch_1):m_b_dq(31)") )
				( objectStatus "SNCLS_DDR4_CHN_B_DQ_DQS_BYTE3" )
			)
			( netClass "@sapphirecity_baseboard_lib.sapphirecity_baseboard(sch_1):\DDR4_CHN_B_DQ_DQS_BYTE2\"
				( memberType ( signal ) )
				( spacingCSetRef "@sapphirecity_baseboard_lib.sapphirecity_baseboard(sch_1):\10H_SL_12H_MS\" )
				( sameNetSpacingCSetRef "@crescent_city_bb_fab1_lib.crescent_city_bb_fab1(sch_1):\7H_US_AND_5H_SL\" )
				( objectFlag fObjectSpacing )
				( objectFlag fObjectSameNetSpacing )
				( member ( diffPairRef "@sapphirecity_baseboard_lib.sapphirecity_baseboard(sch_1):\M_B_DQS_D\(2)") )
				( member ( diffPairRef "@sapphirecity_baseboard_lib.sapphirecity_baseboard(sch_1):\M_B_DQS_D\(11)") )
				( member ( signalRef "@baseboard_fab2_lib.baseboard_fab2(sch_1):m_b_dq(16)") )
				( member ( signalRef "@baseboard_fab2_lib.baseboard_fab2(sch_1):m_b_dq(17)") )
				( member ( signalRef "@baseboard_fab2_lib.baseboard_fab2(sch_1):m_b_dq(18)") )
				( member ( signalRef "@baseboard_fab2_lib.baseboard_fab2(sch_1):m_b_dq(19)") )
				( member ( signalRef "@baseboard_fab2_lib.baseboard_fab2(sch_1):m_b_dq(20)") )
				( member ( signalRef "@baseboard_fab2_lib.baseboard_fab2(sch_1):m_b_dq(21)") )
				( member ( signalRef "@baseboard_fab2_lib.baseboard_fab2(sch_1):m_b_dq(22)") )
				( member ( signalRef "@baseboard_fab2_lib.baseboard_fab2(sch_1):m_b_dq(23)") )
				( objectStatus "SNCLS_DDR4_CHN_B_DQ_DQS_BYTE2" )
			)
			( netClass "@sapphirecity_baseboard_lib.sapphirecity_baseboard(sch_1):\DDR4_CHN_B_DQ_DQS_BYTE1\"
				( memberType ( signal ) )
				( spacingCSetRef "@sapphirecity_baseboard_lib.sapphirecity_baseboard(sch_1):\10H_SL_12H_MS\" )
				( sameNetSpacingCSetRef "@crescent_city_bb_fab1_lib.crescent_city_bb_fab1(sch_1):\7H_US_AND_5H_SL\" )
				( objectFlag fObjectSpacing )
				( objectFlag fObjectSameNetSpacing )
				( member ( diffPairRef "@sapphirecity_baseboard_lib.sapphirecity_baseboard(sch_1):\M_B_DQS_D\(1)") )
				( member ( diffPairRef "@sapphirecity_baseboard_lib.sapphirecity_baseboard(sch_1):\M_B_DQS_D\(10)") )
				( member ( signalRef "@baseboard_fab2_lib.baseboard_fab2(sch_1):m_b_dq(8)") )
				( member ( signalRef "@baseboard_fab2_lib.baseboard_fab2(sch_1):m_b_dq(9)") )
				( member ( signalRef "@baseboard_fab2_lib.baseboard_fab2(sch_1):m_b_dq(10)") )
				( member ( signalRef "@baseboard_fab2_lib.baseboard_fab2(sch_1):m_b_dq(11)") )
				( member ( signalRef "@baseboard_fab2_lib.baseboard_fab2(sch_1):m_b_dq(12)") )
				( member ( signalRef "@baseboard_fab2_lib.baseboard_fab2(sch_1):m_b_dq(13)") )
				( member ( signalRef "@baseboard_fab2_lib.baseboard_fab2(sch_1):m_b_dq(14)") )
				( member ( signalRef "@baseboard_fab2_lib.baseboard_fab2(sch_1):m_b_dq(15)") )
				( objectStatus "SNCLS_DDR4_CHN_B_DQ_DQS_BYTE1" )
			)
			( netClass "@sapphirecity_baseboard_lib.sapphirecity_baseboard(sch_1):\DDR4_CHN_B_DQ_DQS_BYTE0\"
				( memberType ( signal ) )
				( spacingCSetRef "@sapphirecity_baseboard_lib.sapphirecity_baseboard(sch_1):\10H_SL_12H_MS\" )
				( sameNetSpacingCSetRef "@crescent_city_bb_fab1_lib.crescent_city_bb_fab1(sch_1):\7H_US_AND_5H_SL\" )
				( objectFlag fObjectSpacing )
				( objectFlag fObjectSameNetSpacing )
				( member ( diffPairRef "@sapphirecity_baseboard_lib.sapphirecity_baseboard(sch_1):\M_B_DQS_D\(0)") )
				( member ( diffPairRef "@sapphirecity_baseboard_lib.sapphirecity_baseboard(sch_1):\M_B_DQS_D\(9)") )
				( member ( signalRef "@baseboard_fab2_lib.baseboard_fab2(sch_1):m_b_dq(0)") )
				( member ( signalRef "@baseboard_fab2_lib.baseboard_fab2(sch_1):m_b_dq(1)") )
				( member ( signalRef "@baseboard_fab2_lib.baseboard_fab2(sch_1):m_b_dq(2)") )
				( member ( signalRef "@baseboard_fab2_lib.baseboard_fab2(sch_1):m_b_dq(3)") )
				( member ( signalRef "@baseboard_fab2_lib.baseboard_fab2(sch_1):m_b_dq(4)") )
				( member ( signalRef "@baseboard_fab2_lib.baseboard_fab2(sch_1):m_b_dq(5)") )
				( member ( signalRef "@baseboard_fab2_lib.baseboard_fab2(sch_1):m_b_dq(6)") )
				( member ( signalRef "@baseboard_fab2_lib.baseboard_fab2(sch_1):m_b_dq(7)") )
				( objectStatus "SNCLS_DDR4_CHN_B_DQ_DQS_BYTE0" )
			)
			( netClass "@sapphirecity_baseboard_lib.sapphirecity_baseboard(sch_1):\DDR4_CHN_C_DQ_DQS_BYTE7\"
				( memberType ( signal ) )
				( spacingCSetRef "@sapphirecity_baseboard_lib.sapphirecity_baseboard(sch_1):\10H_SL_12H_MS\" )
				( sameNetSpacingCSetRef "@crescent_city_bb_fab1_lib.crescent_city_bb_fab1(sch_1):\7H_US_AND_5H_SL\" )
				( objectFlag fObjectSpacing )
				( objectFlag fObjectSameNetSpacing )
				( member ( diffPairRef "@sapphirecity_baseboard_lib.sapphirecity_baseboard(sch_1):\M_C_DQS_D\(7)") )
				( member ( diffPairRef "@sapphirecity_baseboard_lib.sapphirecity_baseboard(sch_1):\M_C_DQS_D\(16)") )
				( member ( signalRef "@baseboard_fab2_lib.baseboard_fab2(sch_1):m_c_dq(56)") )
				( member ( signalRef "@baseboard_fab2_lib.baseboard_fab2(sch_1):m_c_dq(57)") )
				( member ( signalRef "@baseboard_fab2_lib.baseboard_fab2(sch_1):m_c_dq(58)") )
				( member ( signalRef "@baseboard_fab2_lib.baseboard_fab2(sch_1):m_c_dq(59)") )
				( member ( signalRef "@baseboard_fab2_lib.baseboard_fab2(sch_1):m_c_dq(60)") )
				( member ( signalRef "@baseboard_fab2_lib.baseboard_fab2(sch_1):m_c_dq(61)") )
				( member ( signalRef "@baseboard_fab2_lib.baseboard_fab2(sch_1):m_c_dq(62)") )
				( member ( signalRef "@baseboard_fab2_lib.baseboard_fab2(sch_1):m_c_dq(63)") )
				( objectStatus "SNCLS_DDR4_CHN_C_DQ_DQS_BYTE7" )
			)
			( netClass "@sapphirecity_baseboard_lib.sapphirecity_baseboard(sch_1):\DDR4_CHN_C_DQ_DQS_BYTE6\"
				( memberType ( signal ) )
				( spacingCSetRef "@sapphirecity_baseboard_lib.sapphirecity_baseboard(sch_1):\10H_SL_12H_MS\" )
				( sameNetSpacingCSetRef "@crescent_city_bb_fab1_lib.crescent_city_bb_fab1(sch_1):\7H_US_AND_5H_SL\" )
				( objectFlag fObjectSpacing )
				( objectFlag fObjectSameNetSpacing )
				( member ( diffPairRef "@sapphirecity_baseboard_lib.sapphirecity_baseboard(sch_1):\M_C_DQS_D\(6)") )
				( member ( diffPairRef "@sapphirecity_baseboard_lib.sapphirecity_baseboard(sch_1):\M_C_DQS_D\(15)") )
				( member ( signalRef "@baseboard_fab2_lib.baseboard_fab2(sch_1):m_c_dq(48)") )
				( member ( signalRef "@baseboard_fab2_lib.baseboard_fab2(sch_1):m_c_dq(49)") )
				( member ( signalRef "@baseboard_fab2_lib.baseboard_fab2(sch_1):m_c_dq(50)") )
				( member ( signalRef "@baseboard_fab2_lib.baseboard_fab2(sch_1):m_c_dq(51)") )
				( member ( signalRef "@baseboard_fab2_lib.baseboard_fab2(sch_1):m_c_dq(52)") )
				( member ( signalRef "@baseboard_fab2_lib.baseboard_fab2(sch_1):m_c_dq(53)") )
				( member ( signalRef "@baseboard_fab2_lib.baseboard_fab2(sch_1):m_c_dq(54)") )
				( member ( signalRef "@baseboard_fab2_lib.baseboard_fab2(sch_1):m_c_dq(55)") )
				( objectStatus "SNCLS_DDR4_CHN_C_DQ_DQS_BYTE6" )
			)
			( netClass "@sapphirecity_baseboard_lib.sapphirecity_baseboard(sch_1):\DDR4_CHN_C_DQ_DQS_BYTE5\"
				( memberType ( signal ) )
				( spacingCSetRef "@sapphirecity_baseboard_lib.sapphirecity_baseboard(sch_1):\10H_SL_12H_MS\" )
				( sameNetSpacingCSetRef "@crescent_city_bb_fab1_lib.crescent_city_bb_fab1(sch_1):\7H_US_AND_5H_SL\" )
				( objectFlag fObjectSpacing )
				( objectFlag fObjectSameNetSpacing )
				( member ( diffPairRef "@sapphirecity_baseboard_lib.sapphirecity_baseboard(sch_1):\M_C_DQS_D\(5)") )
				( member ( diffPairRef "@sapphirecity_baseboard_lib.sapphirecity_baseboard(sch_1):\M_C_DQS_D\(14)") )
				( member ( signalRef "@baseboard_fab2_lib.baseboard_fab2(sch_1):m_c_dq(40)") )
				( member ( signalRef "@baseboard_fab2_lib.baseboard_fab2(sch_1):m_c_dq(41)") )
				( member ( signalRef "@baseboard_fab2_lib.baseboard_fab2(sch_1):m_c_dq(42)") )
				( member ( signalRef "@baseboard_fab2_lib.baseboard_fab2(sch_1):m_c_dq(43)") )
				( member ( signalRef "@baseboard_fab2_lib.baseboard_fab2(sch_1):m_c_dq(44)") )
				( member ( signalRef "@baseboard_fab2_lib.baseboard_fab2(sch_1):m_c_dq(45)") )
				( member ( signalRef "@baseboard_fab2_lib.baseboard_fab2(sch_1):m_c_dq(46)") )
				( member ( signalRef "@baseboard_fab2_lib.baseboard_fab2(sch_1):m_c_dq(47)") )
				( objectStatus "SNCLS_DDR4_CHN_C_DQ_DQS_BYTE5" )
			)
			( netClass "@sapphirecity_baseboard_lib.sapphirecity_baseboard(sch_1):\DDR4_CHN_C_DQ_DQS_BYTE4\"
				( memberType ( signal ) )
				( spacingCSetRef "@sapphirecity_baseboard_lib.sapphirecity_baseboard(sch_1):\10H_SL_12H_MS\" )
				( sameNetSpacingCSetRef "@crescent_city_bb_fab1_lib.crescent_city_bb_fab1(sch_1):\7H_US_AND_5H_SL\" )
				( objectFlag fObjectSpacing )
				( objectFlag fObjectSameNetSpacing )
				( member ( diffPairRef "@sapphirecity_baseboard_lib.sapphirecity_baseboard(sch_1):\M_C_DQS_D\(4)") )
				( member ( diffPairRef "@sapphirecity_baseboard_lib.sapphirecity_baseboard(sch_1):\M_C_DQS_D\(13)") )
				( member ( signalRef "@baseboard_fab2_lib.baseboard_fab2(sch_1):m_c_dq(32)") )
				( member ( signalRef "@baseboard_fab2_lib.baseboard_fab2(sch_1):m_c_dq(33)") )
				( member ( signalRef "@baseboard_fab2_lib.baseboard_fab2(sch_1):m_c_dq(34)") )
				( member ( signalRef "@baseboard_fab2_lib.baseboard_fab2(sch_1):m_c_dq(35)") )
				( member ( signalRef "@baseboard_fab2_lib.baseboard_fab2(sch_1):m_c_dq(36)") )
				( member ( signalRef "@baseboard_fab2_lib.baseboard_fab2(sch_1):m_c_dq(37)") )
				( member ( signalRef "@baseboard_fab2_lib.baseboard_fab2(sch_1):m_c_dq(38)") )
				( member ( signalRef "@baseboard_fab2_lib.baseboard_fab2(sch_1):m_c_dq(39)") )
				( objectStatus "SNCLS_DDR4_CHN_C_DQ_DQS_BYTE4" )
			)
			( netClass "@sapphirecity_baseboard_lib.sapphirecity_baseboard(sch_1):\DDR4_CHN_C_DQ_DQS_BYTE3\"
				( memberType ( signal ) )
				( spacingCSetRef "@sapphirecity_baseboard_lib.sapphirecity_baseboard(sch_1):\10H_SL_12H_MS\" )
				( sameNetSpacingCSetRef "@crescent_city_bb_fab1_lib.crescent_city_bb_fab1(sch_1):\7H_US_AND_5H_SL\" )
				( objectFlag fObjectSpacing )
				( objectFlag fObjectSameNetSpacing )
				( member ( diffPairRef "@sapphirecity_baseboard_lib.sapphirecity_baseboard(sch_1):\M_C_DQS_D\(3)") )
				( member ( diffPairRef "@sapphirecity_baseboard_lib.sapphirecity_baseboard(sch_1):\M_C_DQS_D\(12)") )
				( member ( signalRef "@baseboard_fab2_lib.baseboard_fab2(sch_1):m_c_dq(24)") )
				( member ( signalRef "@baseboard_fab2_lib.baseboard_fab2(sch_1):m_c_dq(25)") )
				( member ( signalRef "@baseboard_fab2_lib.baseboard_fab2(sch_1):m_c_dq(26)") )
				( member ( signalRef "@baseboard_fab2_lib.baseboard_fab2(sch_1):m_c_dq(27)") )
				( member ( signalRef "@baseboard_fab2_lib.baseboard_fab2(sch_1):m_c_dq(28)") )
				( member ( signalRef "@baseboard_fab2_lib.baseboard_fab2(sch_1):m_c_dq(29)") )
				( member ( signalRef "@baseboard_fab2_lib.baseboard_fab2(sch_1):m_c_dq(30)") )
				( member ( signalRef "@baseboard_fab2_lib.baseboard_fab2(sch_1):m_c_dq(31)") )
				( objectStatus "SNCLS_DDR4_CHN_C_DQ_DQS_BYTE3" )
			)
			( netClass "@sapphirecity_baseboard_lib.sapphirecity_baseboard(sch_1):\DDR4_CHN_C_DQ_DQS_BYTE2\"
				( memberType ( signal ) )
				( spacingCSetRef "@sapphirecity_baseboard_lib.sapphirecity_baseboard(sch_1):\10H_SL_12H_MS\" )
				( sameNetSpacingCSetRef "@crescent_city_bb_fab1_lib.crescent_city_bb_fab1(sch_1):\7H_US_AND_5H_SL\" )
				( objectFlag fObjectSpacing )
				( objectFlag fObjectSameNetSpacing )
				( member ( diffPairRef "@sapphirecity_baseboard_lib.sapphirecity_baseboard(sch_1):\M_C_DQS_D\(2)") )
				( member ( diffPairRef "@sapphirecity_baseboard_lib.sapphirecity_baseboard(sch_1):\M_C_DQS_D\(11)") )
				( member ( signalRef "@baseboard_fab2_lib.baseboard_fab2(sch_1):m_c_dq(16)") )
				( member ( signalRef "@baseboard_fab2_lib.baseboard_fab2(sch_1):m_c_dq(17)") )
				( member ( signalRef "@baseboard_fab2_lib.baseboard_fab2(sch_1):m_c_dq(18)") )
				( member ( signalRef "@baseboard_fab2_lib.baseboard_fab2(sch_1):m_c_dq(19)") )
				( member ( signalRef "@baseboard_fab2_lib.baseboard_fab2(sch_1):m_c_dq(20)") )
				( member ( signalRef "@baseboard_fab2_lib.baseboard_fab2(sch_1):m_c_dq(21)") )
				( member ( signalRef "@baseboard_fab2_lib.baseboard_fab2(sch_1):m_c_dq(22)") )
				( member ( signalRef "@baseboard_fab2_lib.baseboard_fab2(sch_1):m_c_dq(23)") )
				( objectStatus "SNCLS_DDR4_CHN_C_DQ_DQS_BYTE2" )
			)
			( netClass "@sapphirecity_baseboard_lib.sapphirecity_baseboard(sch_1):\DDR4_CHN_C_DQ_DQS_BYTE1\"
				( memberType ( signal ) )
				( spacingCSetRef "@sapphirecity_baseboard_lib.sapphirecity_baseboard(sch_1):\10H_SL_12H_MS\" )
				( sameNetSpacingCSetRef "@crescent_city_bb_fab1_lib.crescent_city_bb_fab1(sch_1):\7H_US_AND_5H_SL\" )
				( objectFlag fObjectSpacing )
				( objectFlag fObjectSameNetSpacing )
				( member ( diffPairRef "@sapphirecity_baseboard_lib.sapphirecity_baseboard(sch_1):\M_C_DQS_D\(1)") )
				( member ( diffPairRef "@sapphirecity_baseboard_lib.sapphirecity_baseboard(sch_1):\M_C_DQS_D\(10)") )
				( member ( signalRef "@baseboard_fab2_lib.baseboard_fab2(sch_1):m_c_dq(8)") )
				( member ( signalRef "@baseboard_fab2_lib.baseboard_fab2(sch_1):m_c_dq(9)") )
				( member ( signalRef "@baseboard_fab2_lib.baseboard_fab2(sch_1):m_c_dq(10)") )
				( member ( signalRef "@baseboard_fab2_lib.baseboard_fab2(sch_1):m_c_dq(11)") )
				( member ( signalRef "@baseboard_fab2_lib.baseboard_fab2(sch_1):m_c_dq(12)") )
				( member ( signalRef "@baseboard_fab2_lib.baseboard_fab2(sch_1):m_c_dq(13)") )
				( member ( signalRef "@baseboard_fab2_lib.baseboard_fab2(sch_1):m_c_dq(14)") )
				( member ( signalRef "@baseboard_fab2_lib.baseboard_fab2(sch_1):m_c_dq(15)") )
				( objectStatus "SNCLS_DDR4_CHN_C_DQ_DQS_BYTE1" )
			)
			( netClass "@sapphirecity_baseboard_lib.sapphirecity_baseboard(sch_1):\DDR4_CHN_C_DQ_DQS_BYTE0\"
				( memberType ( signal ) )
				( spacingCSetRef "@sapphirecity_baseboard_lib.sapphirecity_baseboard(sch_1):\10H_SL_12H_MS\" )
				( sameNetSpacingCSetRef "@crescent_city_bb_fab1_lib.crescent_city_bb_fab1(sch_1):\7H_US_AND_5H_SL\" )
				( objectFlag fObjectSpacing )
				( objectFlag fObjectSameNetSpacing )
				( member ( diffPairRef "@sapphirecity_baseboard_lib.sapphirecity_baseboard(sch_1):\M_C_DQS_D\(0)") )
				( member ( diffPairRef "@sapphirecity_baseboard_lib.sapphirecity_baseboard(sch_1):\M_C_DQS_D\(9)") )
				( member ( signalRef "@baseboard_fab2_lib.baseboard_fab2(sch_1):m_c_dq(0)") )
				( member ( signalRef "@baseboard_fab2_lib.baseboard_fab2(sch_1):m_c_dq(1)") )
				( member ( signalRef "@baseboard_fab2_lib.baseboard_fab2(sch_1):m_c_dq(2)") )
				( member ( signalRef "@baseboard_fab2_lib.baseboard_fab2(sch_1):m_c_dq(3)") )
				( member ( signalRef "@baseboard_fab2_lib.baseboard_fab2(sch_1):m_c_dq(4)") )
				( member ( signalRef "@baseboard_fab2_lib.baseboard_fab2(sch_1):m_c_dq(5)") )
				( member ( signalRef "@baseboard_fab2_lib.baseboard_fab2(sch_1):m_c_dq(6)") )
				( member ( signalRef "@baseboard_fab2_lib.baseboard_fab2(sch_1):m_c_dq(7)") )
				( objectStatus "SNCLS_DDR4_CHN_C_DQ_DQS_BYTE0" )
			)
			( netClass "@sapphirecity_baseboard_lib.sapphirecity_baseboard(sch_1):\DDR4_CHN_D_CLK\"
				( memberType ( signal ) )
				( spacingCSetRef "@crescent_city_bb_fab1_lib.crescent_city_bb_fab1(sch_1):\8P9_US_&_6H_SL\" )
				( sameNetSpacingCSetRef "@crescent_city_bb_fab1_lib.crescent_city_bb_fab1(sch_1):\7H_US_AND_5H_SL\" )
				( objectFlag fObjectSpacing )
				( objectFlag fObjectSameNetSpacing )
				( member ( diffPairRef "@sapphirecity_baseboard_lib.sapphirecity_baseboard(sch_1):\M_D_CLK_D\(0)") )
				( member ( diffPairRef "@sapphirecity_baseboard_lib.sapphirecity_baseboard(sch_1):\M_D_CLK_D\(2)") )
				( member ( diffPairRef "@sapphirecity_baseboard_lib.sapphirecity_baseboard(sch_1):\DP_M_D_CLK_D1\") )
				( member ( diffPairRef "@sapphirecity_baseboard_lib.sapphirecity_baseboard(sch_1):\DP_M_D_CLK_D3\") )
				( objectStatus "SNCLS_DDR4_CHN_D_CLK" )
			)
			( netClass "@sapphirecity_baseboard_lib.sapphirecity_baseboard(sch_1):\DDR4_CHN_D_CMD_ADD\"
				( memberType ( signal ) )
				( spacingCSetRef "@crescent_city_bb_fab1_lib.crescent_city_bb_fab1(sch_1):\8P9_US_&_6H_SL\" )
				( sameNetSpacingCSetRef "@crescent_city_bb_fab1_lib.crescent_city_bb_fab1(sch_1):\7H_US_AND_5H_SL\" )
				( objectFlag fObjectSpacing )
				( objectFlag fObjectSameNetSpacing )
				( member ( signalRef "@baseboard_fab2_lib.baseboard_fab2(sch_1):m_d_act_n") )
				( member ( signalRef "@baseboard_fab2_lib.baseboard_fab2(sch_1):m_d_c(2)") )
				( member ( signalRef "@baseboard_fab2_lib.baseboard_fab2(sch_1):m_d_par") )
				( member ( signalRef "@baseboard_fab2_lib.baseboard_fab2(sch_1):m_d_ma(0)") )
				( member ( signalRef "@baseboard_fab2_lib.baseboard_fab2(sch_1):m_d_ma(1)") )
				( member ( signalRef "@baseboard_fab2_lib.baseboard_fab2(sch_1):m_d_ma(2)") )
				( member ( signalRef "@baseboard_fab2_lib.baseboard_fab2(sch_1):m_d_ma(3)") )
				( member ( signalRef "@baseboard_fab2_lib.baseboard_fab2(sch_1):m_d_ma(4)") )
				( member ( signalRef "@baseboard_fab2_lib.baseboard_fab2(sch_1):m_d_ma(5)") )
				( member ( signalRef "@baseboard_fab2_lib.baseboard_fab2(sch_1):m_d_ma(6)") )
				( member ( signalRef "@baseboard_fab2_lib.baseboard_fab2(sch_1):m_d_ma(7)") )
				( member ( signalRef "@baseboard_fab2_lib.baseboard_fab2(sch_1):m_d_ma(8)") )
				( member ( signalRef "@baseboard_fab2_lib.baseboard_fab2(sch_1):m_d_ma(9)") )
				( member ( signalRef "@baseboard_fab2_lib.baseboard_fab2(sch_1):m_d_ma(10)") )
				( member ( signalRef "@baseboard_fab2_lib.baseboard_fab2(sch_1):m_d_ma(11)") )
				( member ( signalRef "@baseboard_fab2_lib.baseboard_fab2(sch_1):m_d_ma(12)") )
				( member ( signalRef "@baseboard_fab2_lib.baseboard_fab2(sch_1):m_d_ma(13)") )
				( member ( signalRef "@baseboard_fab2_lib.baseboard_fab2(sch_1):m_d_ma(14)") )
				( member ( signalRef "@baseboard_fab2_lib.baseboard_fab2(sch_1):m_d_ma(15)") )
				( member ( signalRef "@baseboard_fab2_lib.baseboard_fab2(sch_1):m_d_ma(16)") )
				( member ( signalRef "@baseboard_fab2_lib.baseboard_fab2(sch_1):m_d_ma(17)") )
				( member ( signalRef "@baseboard_fab2_lib.baseboard_fab2(sch_1):m_d_ba(0)") )
				( member ( signalRef "@baseboard_fab2_lib.baseboard_fab2(sch_1):m_d_ba(1)") )
				( member ( signalRef "@baseboard_fab2_lib.baseboard_fab2(sch_1):m_d_bg(0)") )
				( member ( signalRef "@baseboard_fab2_lib.baseboard_fab2(sch_1):m_d_bg(1)") )
				( objectStatus "SNCLS_DDR4_CHN_D_CMD_ADD" )
			)
			( netClass "@sapphirecity_baseboard_lib.sapphirecity_baseboard(sch_1):\DDR4_CHN_D_CTRL\"
				( memberType ( signal ) )
				( spacingCSetRef "@crescent_city_bb_fab1_lib.crescent_city_bb_fab1(sch_1):\8P9_US_&_6H_SL\" )
				( sameNetSpacingCSetRef "@crescent_city_bb_fab1_lib.crescent_city_bb_fab1(sch_1):\7H_US_AND_5H_SL\" )
				( objectFlag fObjectSpacing )
				( objectFlag fObjectSameNetSpacing )
				( member ( signalRef "@baseboard_fab2_lib.baseboard_fab2(sch_1):m_d_cke(0)") )
				( member ( signalRef "@baseboard_fab2_lib.baseboard_fab2(sch_1):m_d_cke(1)") )
				( member ( signalRef "@baseboard_fab2_lib.baseboard_fab2(sch_1):m_d_cke(2)") )
				( member ( signalRef "@baseboard_fab2_lib.baseboard_fab2(sch_1):m_d_cke(3)") )
				( member ( signalRef "@baseboard_fab2_lib.baseboard_fab2(sch_1):m_d_cs_n(0)") )
				( member ( signalRef "@baseboard_fab2_lib.baseboard_fab2(sch_1):m_d_cs_n(1)") )
				( member ( signalRef "@baseboard_fab2_lib.baseboard_fab2(sch_1):m_d_cs_n(2)") )
				( member ( signalRef "@baseboard_fab2_lib.baseboard_fab2(sch_1):m_d_cs_n(3)") )
				( member ( signalRef "@baseboard_fab2_lib.baseboard_fab2(sch_1):m_d_cs_n(4)") )
				( member ( signalRef "@baseboard_fab2_lib.baseboard_fab2(sch_1):m_d_cs_n(5)") )
				( member ( signalRef "@baseboard_fab2_lib.baseboard_fab2(sch_1):m_d_cs_n(6)") )
				( member ( signalRef "@baseboard_fab2_lib.baseboard_fab2(sch_1):m_d_cs_n(7)") )
				( member ( signalRef "@baseboard_fab2_lib.baseboard_fab2(sch_1):m_d_odt(0)") )
				( member ( signalRef "@baseboard_fab2_lib.baseboard_fab2(sch_1):m_d_odt(1)") )
				( member ( signalRef "@baseboard_fab2_lib.baseboard_fab2(sch_1):m_d_odt(2)") )
				( member ( signalRef "@baseboard_fab2_lib.baseboard_fab2(sch_1):m_d_odt(3)") )
				( member ( signalRef "@baseboard_fab2_lib.baseboard_fab2(sch_1):m_d_alert_n") )
				( objectStatus "SNCLS_DDR4_CHN_D_CTRL" )
			)
			( netClass "@sapphirecity_baseboard_lib.sapphirecity_baseboard(sch_1):\DDR4_CHN_D_DQ_DQS_BYTE0\"
				( memberType ( signal ) )
				( spacingCSetRef "@sapphirecity_baseboard_lib.sapphirecity_baseboard(sch_1):\10H_SL_12H_MS\" )
				( sameNetSpacingCSetRef "@crescent_city_bb_fab1_lib.crescent_city_bb_fab1(sch_1):\7H_US_AND_5H_SL\" )
				( objectFlag fObjectSpacing )
				( objectFlag fObjectSameNetSpacing )
				( member ( diffPairRef "@sapphirecity_baseboard_lib.sapphirecity_baseboard(sch_1):\M_D_DQS_D\(0)") )
				( member ( diffPairRef "@sapphirecity_baseboard_lib.sapphirecity_baseboard(sch_1):\M_D_DQS_D\(9)") )
				( member ( signalRef "@baseboard_fab2_lib.baseboard_fab2(sch_1):m_d_dq(0)") )
				( member ( signalRef "@baseboard_fab2_lib.baseboard_fab2(sch_1):m_d_dq(1)") )
				( member ( signalRef "@baseboard_fab2_lib.baseboard_fab2(sch_1):m_d_dq(2)") )
				( member ( signalRef "@baseboard_fab2_lib.baseboard_fab2(sch_1):m_d_dq(3)") )
				( member ( signalRef "@baseboard_fab2_lib.baseboard_fab2(sch_1):m_d_dq(4)") )
				( member ( signalRef "@baseboard_fab2_lib.baseboard_fab2(sch_1):m_d_dq(5)") )
				( member ( signalRef "@baseboard_fab2_lib.baseboard_fab2(sch_1):m_d_dq(6)") )
				( member ( signalRef "@baseboard_fab2_lib.baseboard_fab2(sch_1):m_d_dq(7)") )
				( objectStatus "SNCLS_DDR4_CHN_D_DQ_DQS_BYTE0" )
			)
			( netClass "@sapphirecity_baseboard_lib.sapphirecity_baseboard(sch_1):\DDR4_CHN_A_CLK\"
				( memberType ( signal ) )
				( spacingCSetRef "@crescent_city_bb_fab1_lib.crescent_city_bb_fab1(sch_1):\8P9_US_&_6H_SL\" )
				( sameNetSpacingCSetRef "@crescent_city_bb_fab1_lib.crescent_city_bb_fab1(sch_1):\7H_US_AND_5H_SL\" )
				( objectFlag fObjectSpacing )
				( objectFlag fObjectSameNetSpacing )
				( member ( diffPairRef "@sapphirecity_baseboard_lib.sapphirecity_baseboard(sch_1):\M_A_CLK_D\(0)") )
				( member ( diffPairRef "@sapphirecity_baseboard_lib.sapphirecity_baseboard(sch_1):\M_A_CLK_D\(2)") )
				( member ( diffPairRef "@sapphirecity_baseboard_lib.sapphirecity_baseboard(sch_1):\M_A_CLK_D\(1)") )
				( member ( diffPairRef "@sapphirecity_baseboard_lib.sapphirecity_baseboard(sch_1):\M_A_CLK_D\(3)") )
				( objectStatus "SNCLS_DDR4_CHN_A_CLK" )
			)
			( netClass "@sapphirecity_baseboard_lib.sapphirecity_baseboard(sch_1):\DDR4_CHN_A_CMD_ADD\"
				( memberType ( signal ) )
				( spacingCSetRef "@crescent_city_bb_fab1_lib.crescent_city_bb_fab1(sch_1):\8P9_US_&_6H_SL\" )
				( sameNetSpacingCSetRef "@crescent_city_bb_fab1_lib.crescent_city_bb_fab1(sch_1):\7H_US_AND_5H_SL\" )
				( objectFlag fObjectSpacing )
				( objectFlag fObjectSameNetSpacing )
				( member ( signalRef "@baseboard_fab2_lib.baseboard_fab2(sch_1):m_a_c(2)") )
				( member ( signalRef "@baseboard_fab2_lib.baseboard_fab2(sch_1):m_a_par") )
				( member ( signalRef "@baseboard_fab2_lib.baseboard_fab2(sch_1):m_a_act_n") )
				( member ( signalRef "@baseboard_fab2_lib.baseboard_fab2(sch_1):m_a_ba(0)") )
				( member ( signalRef "@baseboard_fab2_lib.baseboard_fab2(sch_1):m_a_ba(1)") )
				( member ( signalRef "@baseboard_fab2_lib.baseboard_fab2(sch_1):m_a_bg(0)") )
				( member ( signalRef "@baseboard_fab2_lib.baseboard_fab2(sch_1):m_a_bg(1)") )
				( member ( signalRef "@baseboard_fab2_lib.baseboard_fab2(sch_1):m_a_ma(0)") )
				( member ( signalRef "@baseboard_fab2_lib.baseboard_fab2(sch_1):m_a_ma(1)") )
				( member ( signalRef "@baseboard_fab2_lib.baseboard_fab2(sch_1):m_a_ma(2)") )
				( member ( signalRef "@baseboard_fab2_lib.baseboard_fab2(sch_1):m_a_ma(3)") )
				( member ( signalRef "@baseboard_fab2_lib.baseboard_fab2(sch_1):m_a_ma(4)") )
				( member ( signalRef "@baseboard_fab2_lib.baseboard_fab2(sch_1):m_a_ma(5)") )
				( member ( signalRef "@baseboard_fab2_lib.baseboard_fab2(sch_1):m_a_ma(6)") )
				( member ( signalRef "@baseboard_fab2_lib.baseboard_fab2(sch_1):m_a_ma(7)") )
				( member ( signalRef "@baseboard_fab2_lib.baseboard_fab2(sch_1):m_a_ma(8)") )
				( member ( signalRef "@baseboard_fab2_lib.baseboard_fab2(sch_1):m_a_ma(9)") )
				( member ( signalRef "@baseboard_fab2_lib.baseboard_fab2(sch_1):m_a_ma(10)") )
				( member ( signalRef "@baseboard_fab2_lib.baseboard_fab2(sch_1):m_a_ma(11)") )
				( member ( signalRef "@baseboard_fab2_lib.baseboard_fab2(sch_1):m_a_ma(12)") )
				( member ( signalRef "@baseboard_fab2_lib.baseboard_fab2(sch_1):m_a_ma(13)") )
				( member ( signalRef "@baseboard_fab2_lib.baseboard_fab2(sch_1):m_a_ma(14)") )
				( member ( signalRef "@baseboard_fab2_lib.baseboard_fab2(sch_1):m_a_ma(15)") )
				( member ( signalRef "@baseboard_fab2_lib.baseboard_fab2(sch_1):m_a_ma(16)") )
				( member ( signalRef "@baseboard_fab2_lib.baseboard_fab2(sch_1):m_a_ma(17)") )
				( objectStatus "SNCLS_DDR4_CHN_A_CMD_ADD" )
			)
			( netClass "@sapphirecity_baseboard_lib.sapphirecity_baseboard(sch_1):\DDR4_CHN_A_CTRL\"
				( memberType ( signal ) )
				( spacingCSetRef "@crescent_city_bb_fab1_lib.crescent_city_bb_fab1(sch_1):\8P9_US_&_6H_SL\" )
				( sameNetSpacingCSetRef "@crescent_city_bb_fab1_lib.crescent_city_bb_fab1(sch_1):\7H_US_AND_5H_SL\" )
				( objectFlag fObjectSpacing )
				( objectFlag fObjectSameNetSpacing )
				( member ( signalRef "@baseboard_fab2_lib.baseboard_fab2(sch_1):m_a_alert_n") )
				( member ( signalRef "@baseboard_fab2_lib.baseboard_fab2(sch_1):m_a_cke(0)") )
				( member ( signalRef "@baseboard_fab2_lib.baseboard_fab2(sch_1):m_a_cke(1)") )
				( member ( signalRef "@baseboard_fab2_lib.baseboard_fab2(sch_1):m_a_cke(2)") )
				( member ( signalRef "@baseboard_fab2_lib.baseboard_fab2(sch_1):m_a_cke(3)") )
				( member ( signalRef "@baseboard_fab2_lib.baseboard_fab2(sch_1):m_a_cs_n(0)") )
				( member ( signalRef "@baseboard_fab2_lib.baseboard_fab2(sch_1):m_a_cs_n(1)") )
				( member ( signalRef "@baseboard_fab2_lib.baseboard_fab2(sch_1):m_a_cs_n(2)") )
				( member ( signalRef "@baseboard_fab2_lib.baseboard_fab2(sch_1):m_a_cs_n(3)") )
				( member ( signalRef "@baseboard_fab2_lib.baseboard_fab2(sch_1):m_a_cs_n(4)") )
				( member ( signalRef "@baseboard_fab2_lib.baseboard_fab2(sch_1):m_a_cs_n(5)") )
				( member ( signalRef "@baseboard_fab2_lib.baseboard_fab2(sch_1):m_a_cs_n(6)") )
				( member ( signalRef "@baseboard_fab2_lib.baseboard_fab2(sch_1):m_a_cs_n(7)") )
				( member ( signalRef "@baseboard_fab2_lib.baseboard_fab2(sch_1):m_a_odt(0)") )
				( member ( signalRef "@baseboard_fab2_lib.baseboard_fab2(sch_1):m_a_odt(1)") )
				( member ( signalRef "@baseboard_fab2_lib.baseboard_fab2(sch_1):m_a_odt(2)") )
				( member ( signalRef "@baseboard_fab2_lib.baseboard_fab2(sch_1):m_a_odt(3)") )
				( objectStatus "SNCLS_DDR4_CHN_A_CTRL" )
			)
			( netClass "@sapphirecity_baseboard_lib.sapphirecity_baseboard(sch_1):\DDR4_CHN_A_ECC\"
				( memberType ( signal ) )
				( spacingCSetRef "@sapphirecity_baseboard_lib.sapphirecity_baseboard(sch_1):\10H_SL_12H_MS\" )
				( sameNetSpacingCSetRef "@crescent_city_bb_fab1_lib.crescent_city_bb_fab1(sch_1):\7H_US_AND_5H_SL\" )
				( objectFlag fObjectSpacing )
				( objectFlag fObjectSameNetSpacing )
				( member ( diffPairRef "@sapphirecity_baseboard_lib.sapphirecity_baseboard(sch_1):\M_A_DQS_D\(8)") )
				( member ( diffPairRef "@sapphirecity_baseboard_lib.sapphirecity_baseboard(sch_1):\M_A_DQS_D\(17)") )
				( member ( signalRef "@baseboard_fab2_lib.baseboard_fab2(sch_1):m_a_ecc(0)") )
				( member ( signalRef "@baseboard_fab2_lib.baseboard_fab2(sch_1):m_a_ecc(1)") )
				( member ( signalRef "@baseboard_fab2_lib.baseboard_fab2(sch_1):m_a_ecc(2)") )
				( member ( signalRef "@baseboard_fab2_lib.baseboard_fab2(sch_1):m_a_ecc(3)") )
				( member ( signalRef "@baseboard_fab2_lib.baseboard_fab2(sch_1):m_a_ecc(4)") )
				( member ( signalRef "@baseboard_fab2_lib.baseboard_fab2(sch_1):m_a_ecc(5)") )
				( member ( signalRef "@baseboard_fab2_lib.baseboard_fab2(sch_1):m_a_ecc(6)") )
				( member ( signalRef "@baseboard_fab2_lib.baseboard_fab2(sch_1):m_a_ecc(7)") )
				( objectStatus "SNCLS_DDR4_CHN_A_ECC" )
			)
			( netClass "@sapphirecity_baseboard_lib.sapphirecity_baseboard(sch_1):\DDR4_CHN_B_CLK\"
				( memberType ( signal ) )
				( spacingCSetRef "@crescent_city_bb_fab1_lib.crescent_city_bb_fab1(sch_1):\8P9_US_&_6H_SL\" )
				( sameNetSpacingCSetRef "@crescent_city_bb_fab1_lib.crescent_city_bb_fab1(sch_1):\7H_US_AND_5H_SL\" )
				( objectFlag fObjectSpacing )
				( objectFlag fObjectSameNetSpacing )
				( member ( diffPairRef "@sapphirecity_baseboard_lib.sapphirecity_baseboard(sch_1):\M_B_CLK_D\(0)") )
				( member ( diffPairRef "@sapphirecity_baseboard_lib.sapphirecity_baseboard(sch_1):\M_B_CLK_D\(2)") )
				( member ( diffPairRef "@sapphirecity_baseboard_lib.sapphirecity_baseboard(sch_1):\M_H_CLK_D\(1)") )
				( member ( diffPairRef "@sapphirecity_baseboard_lib.sapphirecity_baseboard(sch_1):\M_H_CLK_D\(3)") )
				( objectStatus "SNCLS_DDR4_CHN_B_CLK" )
			)
			( netClass "@sapphirecity_baseboard_lib.sapphirecity_baseboard(sch_1):\DDR4_CHN_B_CMD_ADD\"
				( memberType ( signal ) )
				( spacingCSetRef "@crescent_city_bb_fab1_lib.crescent_city_bb_fab1(sch_1):\8P9_US_&_6H_SL\" )
				( sameNetSpacingCSetRef "@crescent_city_bb_fab1_lib.crescent_city_bb_fab1(sch_1):\7H_US_AND_5H_SL\" )
				( objectFlag fObjectSpacing )
				( objectFlag fObjectSameNetSpacing )
				( member ( signalRef "@baseboard_fab2_lib.baseboard_fab2(sch_1):m_b_act_n") )
				( member ( signalRef "@baseboard_fab2_lib.baseboard_fab2(sch_1):m_b_c(2)") )
				( member ( signalRef "@baseboard_fab2_lib.baseboard_fab2(sch_1):m_b_par") )
				( member ( signalRef "@baseboard_fab2_lib.baseboard_fab2(sch_1):m_b_ba(0)") )
				( member ( signalRef "@baseboard_fab2_lib.baseboard_fab2(sch_1):m_b_ba(1)") )
				( member ( signalRef "@baseboard_fab2_lib.baseboard_fab2(sch_1):m_b_bg(0)") )
				( member ( signalRef "@baseboard_fab2_lib.baseboard_fab2(sch_1):m_b_bg(1)") )
				( member ( signalRef "@baseboard_fab2_lib.baseboard_fab2(sch_1):m_b_ma(0)") )
				( member ( signalRef "@baseboard_fab2_lib.baseboard_fab2(sch_1):m_b_ma(1)") )
				( member ( signalRef "@baseboard_fab2_lib.baseboard_fab2(sch_1):m_b_ma(2)") )
				( member ( signalRef "@baseboard_fab2_lib.baseboard_fab2(sch_1):m_b_ma(3)") )
				( member ( signalRef "@baseboard_fab2_lib.baseboard_fab2(sch_1):m_b_ma(4)") )
				( member ( signalRef "@baseboard_fab2_lib.baseboard_fab2(sch_1):m_b_ma(5)") )
				( member ( signalRef "@baseboard_fab2_lib.baseboard_fab2(sch_1):m_b_ma(6)") )
				( member ( signalRef "@baseboard_fab2_lib.baseboard_fab2(sch_1):m_b_ma(7)") )
				( member ( signalRef "@baseboard_fab2_lib.baseboard_fab2(sch_1):m_b_ma(8)") )
				( member ( signalRef "@baseboard_fab2_lib.baseboard_fab2(sch_1):m_b_ma(9)") )
				( member ( signalRef "@baseboard_fab2_lib.baseboard_fab2(sch_1):m_b_ma(10)") )
				( member ( signalRef "@baseboard_fab2_lib.baseboard_fab2(sch_1):m_b_ma(11)") )
				( member ( signalRef "@baseboard_fab2_lib.baseboard_fab2(sch_1):m_b_ma(12)") )
				( member ( signalRef "@baseboard_fab2_lib.baseboard_fab2(sch_1):m_b_ma(13)") )
				( member ( signalRef "@baseboard_fab2_lib.baseboard_fab2(sch_1):m_b_ma(14)") )
				( member ( signalRef "@baseboard_fab2_lib.baseboard_fab2(sch_1):m_b_ma(15)") )
				( member ( signalRef "@baseboard_fab2_lib.baseboard_fab2(sch_1):m_b_ma(16)") )
				( member ( signalRef "@baseboard_fab2_lib.baseboard_fab2(sch_1):m_b_ma(17)") )
				( objectStatus "SNCLS_DDR4_CHN_B_CMD_ADD" )
			)
			( netClass "@sapphirecity_baseboard_lib.sapphirecity_baseboard(sch_1):\DDR4_CHN_B_CTRL\"
				( memberType ( signal ) )
				( spacingCSetRef "@crescent_city_bb_fab1_lib.crescent_city_bb_fab1(sch_1):\8P9_US_&_6H_SL\" )
				( sameNetSpacingCSetRef "@crescent_city_bb_fab1_lib.crescent_city_bb_fab1(sch_1):\7H_US_AND_5H_SL\" )
				( objectFlag fObjectSpacing )
				( objectFlag fObjectSameNetSpacing )
				( member ( signalRef "@baseboard_fab2_lib.baseboard_fab2(sch_1):m_b_cke(2)") )
				( member ( signalRef "@baseboard_fab2_lib.baseboard_fab2(sch_1):m_b_cke(0)") )
				( member ( signalRef "@baseboard_fab2_lib.baseboard_fab2(sch_1):m_b_cke(1)") )
				( member ( signalRef "@baseboard_fab2_lib.baseboard_fab2(sch_1):m_b_cke(3)") )
				( member ( signalRef "@baseboard_fab2_lib.baseboard_fab2(sch_1):m_b_alert_n") )
				( member ( signalRef "@baseboard_fab2_lib.baseboard_fab2(sch_1):m_b_cs_n(0)") )
				( member ( signalRef "@baseboard_fab2_lib.baseboard_fab2(sch_1):m_b_cs_n(1)") )
				( member ( signalRef "@baseboard_fab2_lib.baseboard_fab2(sch_1):m_b_cs_n(2)") )
				( member ( signalRef "@baseboard_fab2_lib.baseboard_fab2(sch_1):m_b_cs_n(3)") )
				( member ( signalRef "@baseboard_fab2_lib.baseboard_fab2(sch_1):m_b_cs_n(4)") )
				( member ( signalRef "@baseboard_fab2_lib.baseboard_fab2(sch_1):m_b_cs_n(5)") )
				( member ( signalRef "@baseboard_fab2_lib.baseboard_fab2(sch_1):m_b_cs_n(6)") )
				( member ( signalRef "@baseboard_fab2_lib.baseboard_fab2(sch_1):m_b_cs_n(7)") )
				( member ( signalRef "@baseboard_fab2_lib.baseboard_fab2(sch_1):m_b_odt(0)") )
				( member ( signalRef "@baseboard_fab2_lib.baseboard_fab2(sch_1):m_b_odt(1)") )
				( member ( signalRef "@baseboard_fab2_lib.baseboard_fab2(sch_1):m_b_odt(2)") )
				( member ( signalRef "@baseboard_fab2_lib.baseboard_fab2(sch_1):m_b_odt(3)") )
				( objectStatus "SNCLS_DDR4_CHN_B_CTRL" )
			)
			( netClass "@sapphirecity_baseboard_lib.sapphirecity_baseboard(sch_1):\DDR4_CHN_B_ECC\"
				( memberType ( signal ) )
				( spacingCSetRef "@sapphirecity_baseboard_lib.sapphirecity_baseboard(sch_1):\10H_SL_12H_MS\" )
				( sameNetSpacingCSetRef "@crescent_city_bb_fab1_lib.crescent_city_bb_fab1(sch_1):\7H_US_AND_5H_SL\" )
				( objectFlag fObjectSpacing )
				( objectFlag fObjectSameNetSpacing )
				( member ( diffPairRef "@sapphirecity_baseboard_lib.sapphirecity_baseboard(sch_1):\M_B_DQS_D\(8)") )
				( member ( diffPairRef "@sapphirecity_baseboard_lib.sapphirecity_baseboard(sch_1):\M_B_DQS_D\(17)") )
				( member ( signalRef "@baseboard_fab2_lib.baseboard_fab2(sch_1):m_b_ecc(0)") )
				( member ( signalRef "@baseboard_fab2_lib.baseboard_fab2(sch_1):m_b_ecc(1)") )
				( member ( signalRef "@baseboard_fab2_lib.baseboard_fab2(sch_1):m_b_ecc(2)") )
				( member ( signalRef "@baseboard_fab2_lib.baseboard_fab2(sch_1):m_b_ecc(3)") )
				( member ( signalRef "@baseboard_fab2_lib.baseboard_fab2(sch_1):m_b_ecc(4)") )
				( member ( signalRef "@baseboard_fab2_lib.baseboard_fab2(sch_1):m_b_ecc(5)") )
				( member ( signalRef "@baseboard_fab2_lib.baseboard_fab2(sch_1):m_b_ecc(6)") )
				( member ( signalRef "@baseboard_fab2_lib.baseboard_fab2(sch_1):m_b_ecc(7)") )
				( objectStatus "SNCLS_DDR4_CHN_B_ECC" )
			)
			( netClass "@sapphirecity_baseboard_lib.sapphirecity_baseboard(sch_1):\DDR4_CHN_C_CLK\"
				( memberType ( signal ) )
				( spacingCSetRef "@crescent_city_bb_fab1_lib.crescent_city_bb_fab1(sch_1):\8P9_US_&_6H_SL\" )
				( sameNetSpacingCSetRef "@crescent_city_bb_fab1_lib.crescent_city_bb_fab1(sch_1):\7H_US_AND_5H_SL\" )
				( objectFlag fObjectSpacing )
				( objectFlag fObjectSameNetSpacing )
				( member ( diffPairRef "@sapphirecity_baseboard_lib.sapphirecity_baseboard(sch_1):\M_C_CLK_D\(0)") )
				( member ( diffPairRef "@sapphirecity_baseboard_lib.sapphirecity_baseboard(sch_1):\M_C_CLK_D\(2)") )
				( member ( diffPairRef "@sapphirecity_baseboard_lib.sapphirecity_baseboard(sch_1):\M_G_CLK_D\(1)") )
				( member ( diffPairRef "@sapphirecity_baseboard_lib.sapphirecity_baseboard(sch_1):\M_G_CLK_D\(3)") )
				( objectStatus "SNCLS_DDR4_CHN_C_CLK" )
			)
			( netClass "@sapphirecity_baseboard_lib.sapphirecity_baseboard(sch_1):\DDR4_CHN_C_CMD_ADD\"
				( memberType ( signal ) )
				( spacingCSetRef "@crescent_city_bb_fab1_lib.crescent_city_bb_fab1(sch_1):\8P9_US_&_6H_SL\" )
				( sameNetSpacingCSetRef "@crescent_city_bb_fab1_lib.crescent_city_bb_fab1(sch_1):\7H_US_AND_5H_SL\" )
				( objectFlag fObjectSpacing )
				( objectFlag fObjectSameNetSpacing )
				( member ( signalRef "@baseboard_fab2_lib.baseboard_fab2(sch_1):m_c_act_n") )
				( member ( signalRef "@baseboard_fab2_lib.baseboard_fab2(sch_1):m_c_c(2)") )
				( member ( signalRef "@baseboard_fab2_lib.baseboard_fab2(sch_1):m_c_par") )
				( member ( signalRef "@baseboard_fab2_lib.baseboard_fab2(sch_1):m_c_ba(0)") )
				( member ( signalRef "@baseboard_fab2_lib.baseboard_fab2(sch_1):m_c_ba(1)") )
				( member ( signalRef "@baseboard_fab2_lib.baseboard_fab2(sch_1):m_c_bg(0)") )
				( member ( signalRef "@baseboard_fab2_lib.baseboard_fab2(sch_1):m_c_bg(1)") )
				( member ( signalRef "@baseboard_fab2_lib.baseboard_fab2(sch_1):m_c_ma(0)") )
				( member ( signalRef "@baseboard_fab2_lib.baseboard_fab2(sch_1):m_c_ma(1)") )
				( member ( signalRef "@baseboard_fab2_lib.baseboard_fab2(sch_1):m_c_ma(2)") )
				( member ( signalRef "@baseboard_fab2_lib.baseboard_fab2(sch_1):m_c_ma(3)") )
				( member ( signalRef "@baseboard_fab2_lib.baseboard_fab2(sch_1):m_c_ma(4)") )
				( member ( signalRef "@baseboard_fab2_lib.baseboard_fab2(sch_1):m_c_ma(5)") )
				( member ( signalRef "@baseboard_fab2_lib.baseboard_fab2(sch_1):m_c_ma(6)") )
				( member ( signalRef "@baseboard_fab2_lib.baseboard_fab2(sch_1):m_c_ma(7)") )
				( member ( signalRef "@baseboard_fab2_lib.baseboard_fab2(sch_1):m_c_ma(8)") )
				( member ( signalRef "@baseboard_fab2_lib.baseboard_fab2(sch_1):m_c_ma(9)") )
				( member ( signalRef "@baseboard_fab2_lib.baseboard_fab2(sch_1):m_c_ma(10)") )
				( member ( signalRef "@baseboard_fab2_lib.baseboard_fab2(sch_1):m_c_ma(11)") )
				( member ( signalRef "@baseboard_fab2_lib.baseboard_fab2(sch_1):m_c_ma(12)") )
				( member ( signalRef "@baseboard_fab2_lib.baseboard_fab2(sch_1):m_c_ma(13)") )
				( member ( signalRef "@baseboard_fab2_lib.baseboard_fab2(sch_1):m_c_ma(14)") )
				( member ( signalRef "@baseboard_fab2_lib.baseboard_fab2(sch_1):m_c_ma(15)") )
				( member ( signalRef "@baseboard_fab2_lib.baseboard_fab2(sch_1):m_c_ma(16)") )
				( member ( signalRef "@baseboard_fab2_lib.baseboard_fab2(sch_1):m_c_ma(17)") )
				( objectStatus "SNCLS_DDR4_CHN_C_CMD_ADD" )
			)
			( netClass "@sapphirecity_baseboard_lib.sapphirecity_baseboard(sch_1):\DDR4_CHN_C_CTRL\"
				( memberType ( signal ) )
				( spacingCSetRef "@crescent_city_bb_fab1_lib.crescent_city_bb_fab1(sch_1):\8P9_US_&_6H_SL\" )
				( sameNetSpacingCSetRef "@crescent_city_bb_fab1_lib.crescent_city_bb_fab1(sch_1):\7H_US_AND_5H_SL\" )
				( objectFlag fObjectSpacing )
				( objectFlag fObjectSameNetSpacing )
				( member ( signalRef "@baseboard_fab2_lib.baseboard_fab2(sch_1):m_c_cke(0)") )
				( member ( signalRef "@baseboard_fab2_lib.baseboard_fab2(sch_1):m_c_cke(1)") )
				( member ( signalRef "@baseboard_fab2_lib.baseboard_fab2(sch_1):m_c_cke(2)") )
				( member ( signalRef "@baseboard_fab2_lib.baseboard_fab2(sch_1):m_c_cke(3)") )
				( member ( signalRef "@baseboard_fab2_lib.baseboard_fab2(sch_1):m_c_alert_n") )
				( member ( signalRef "@baseboard_fab2_lib.baseboard_fab2(sch_1):m_c_odt(0)") )
				( member ( signalRef "@baseboard_fab2_lib.baseboard_fab2(sch_1):m_c_odt(1)") )
				( member ( signalRef "@baseboard_fab2_lib.baseboard_fab2(sch_1):m_c_odt(2)") )
				( member ( signalRef "@baseboard_fab2_lib.baseboard_fab2(sch_1):m_c_odt(3)") )
				( member ( signalRef "@baseboard_fab2_lib.baseboard_fab2(sch_1):m_c_cs_n(0)") )
				( member ( signalRef "@baseboard_fab2_lib.baseboard_fab2(sch_1):m_c_cs_n(1)") )
				( member ( signalRef "@baseboard_fab2_lib.baseboard_fab2(sch_1):m_c_cs_n(2)") )
				( member ( signalRef "@baseboard_fab2_lib.baseboard_fab2(sch_1):m_c_cs_n(3)") )
				( member ( signalRef "@baseboard_fab2_lib.baseboard_fab2(sch_1):m_c_cs_n(4)") )
				( member ( signalRef "@baseboard_fab2_lib.baseboard_fab2(sch_1):m_c_cs_n(5)") )
				( member ( signalRef "@baseboard_fab2_lib.baseboard_fab2(sch_1):m_c_cs_n(6)") )
				( member ( signalRef "@baseboard_fab2_lib.baseboard_fab2(sch_1):m_c_cs_n(7)") )
				( objectStatus "SNCLS_DDR4_CHN_C_CTRL" )
			)
			( netClass "@sapphirecity_baseboard_lib.sapphirecity_baseboard(sch_1):\DDR4_CHN_C_ECC\"
				( memberType ( signal ) )
				( spacingCSetRef "@sapphirecity_baseboard_lib.sapphirecity_baseboard(sch_1):\10H_SL_12H_MS\" )
				( sameNetSpacingCSetRef "@crescent_city_bb_fab1_lib.crescent_city_bb_fab1(sch_1):\7H_US_AND_5H_SL\" )
				( objectFlag fObjectSpacing )
				( objectFlag fObjectSameNetSpacing )
				( member ( diffPairRef "@sapphirecity_baseboard_lib.sapphirecity_baseboard(sch_1):\M_C_DQS_D\(8)") )
				( member ( diffPairRef "@sapphirecity_baseboard_lib.sapphirecity_baseboard(sch_1):\M_C_DQS_D\(17)") )
				( member ( signalRef "@baseboard_fab2_lib.baseboard_fab2(sch_1):m_c_ecc(0)") )
				( member ( signalRef "@baseboard_fab2_lib.baseboard_fab2(sch_1):m_c_ecc(1)") )
				( member ( signalRef "@baseboard_fab2_lib.baseboard_fab2(sch_1):m_c_ecc(2)") )
				( member ( signalRef "@baseboard_fab2_lib.baseboard_fab2(sch_1):m_c_ecc(3)") )
				( member ( signalRef "@baseboard_fab2_lib.baseboard_fab2(sch_1):m_c_ecc(4)") )
				( member ( signalRef "@baseboard_fab2_lib.baseboard_fab2(sch_1):m_c_ecc(5)") )
				( member ( signalRef "@baseboard_fab2_lib.baseboard_fab2(sch_1):m_c_ecc(6)") )
				( member ( signalRef "@baseboard_fab2_lib.baseboard_fab2(sch_1):m_c_ecc(7)") )
				( objectStatus "SNCLS_DDR4_CHN_C_ECC" )
			)
			( netClass "@sapphirecity_baseboard_lib.sapphirecity_baseboard(sch_1):\DDR4_CHN_E_CLK\"
				( memberType ( signal ) )
				( spacingCSetRef "@crescent_city_bb_fab1_lib.crescent_city_bb_fab1(sch_1):\8P9_US_&_6H_SL\" )
				( sameNetSpacingCSetRef "@crescent_city_bb_fab1_lib.crescent_city_bb_fab1(sch_1):\7H_US_AND_5H_SL\" )
				( objectFlag fObjectSpacing )
				( objectFlag fObjectSameNetSpacing )
				( member ( diffPairRef "@sapphirecity_baseboard_lib.sapphirecity_baseboard(sch_1):\M_E_CLK_D\(0)") )
				( member ( diffPairRef "@sapphirecity_baseboard_lib.sapphirecity_baseboard(sch_1):\M_E_CLK_D\(2)") )
				( member ( diffPairRef "@sapphirecity_baseboard_lib.sapphirecity_baseboard(sch_1):\M_L_CLK_D\(3)") )
				( member ( diffPairRef "@sapphirecity_baseboard_lib.sapphirecity_baseboard(sch_1):\M_L_CLK_D\(1)") )
				( objectStatus "SNCLS_DDR4_CHN_E_CLK" )
			)
			( netClass "@sapphirecity_baseboard_lib.sapphirecity_baseboard(sch_1):\DDR4_CHN_E_CMD_ADD\"
				( memberType ( signal ) )
				( spacingCSetRef "@crescent_city_bb_fab1_lib.crescent_city_bb_fab1(sch_1):\8P9_US_&_6H_SL\" )
				( sameNetSpacingCSetRef "@crescent_city_bb_fab1_lib.crescent_city_bb_fab1(sch_1):\7H_US_AND_5H_SL\" )
				( objectFlag fObjectSpacing )
				( objectFlag fObjectSameNetSpacing )
				( member ( signalRef "@baseboard_fab2_lib.baseboard_fab2(sch_1):m_e_act_n") )
				( member ( signalRef "@baseboard_fab2_lib.baseboard_fab2(sch_1):m_e_c(2)") )
				( member ( signalRef "@baseboard_fab2_lib.baseboard_fab2(sch_1):m_e_par") )
				( member ( signalRef "@baseboard_fab2_lib.baseboard_fab2(sch_1):m_e_ba(0)") )
				( member ( signalRef "@baseboard_fab2_lib.baseboard_fab2(sch_1):m_e_ba(1)") )
				( member ( signalRef "@baseboard_fab2_lib.baseboard_fab2(sch_1):m_e_bg(0)") )
				( member ( signalRef "@baseboard_fab2_lib.baseboard_fab2(sch_1):m_e_bg(1)") )
				( member ( signalRef "@baseboard_fab2_lib.baseboard_fab2(sch_1):m_e_ma(0)") )
				( member ( signalRef "@baseboard_fab2_lib.baseboard_fab2(sch_1):m_e_ma(1)") )
				( member ( signalRef "@baseboard_fab2_lib.baseboard_fab2(sch_1):m_e_ma(2)") )
				( member ( signalRef "@baseboard_fab2_lib.baseboard_fab2(sch_1):m_e_ma(3)") )
				( member ( signalRef "@baseboard_fab2_lib.baseboard_fab2(sch_1):m_e_ma(4)") )
				( member ( signalRef "@baseboard_fab2_lib.baseboard_fab2(sch_1):m_e_ma(5)") )
				( member ( signalRef "@baseboard_fab2_lib.baseboard_fab2(sch_1):m_e_ma(6)") )
				( member ( signalRef "@baseboard_fab2_lib.baseboard_fab2(sch_1):m_e_ma(7)") )
				( member ( signalRef "@baseboard_fab2_lib.baseboard_fab2(sch_1):m_e_ma(8)") )
				( member ( signalRef "@baseboard_fab2_lib.baseboard_fab2(sch_1):m_e_ma(9)") )
				( member ( signalRef "@baseboard_fab2_lib.baseboard_fab2(sch_1):m_e_ma(10)") )
				( member ( signalRef "@baseboard_fab2_lib.baseboard_fab2(sch_1):m_e_ma(11)") )
				( member ( signalRef "@baseboard_fab2_lib.baseboard_fab2(sch_1):m_e_ma(12)") )
				( member ( signalRef "@baseboard_fab2_lib.baseboard_fab2(sch_1):m_e_ma(13)") )
				( member ( signalRef "@baseboard_fab2_lib.baseboard_fab2(sch_1):m_e_ma(14)") )
				( member ( signalRef "@baseboard_fab2_lib.baseboard_fab2(sch_1):m_e_ma(15)") )
				( member ( signalRef "@baseboard_fab2_lib.baseboard_fab2(sch_1):m_e_ma(16)") )
				( member ( signalRef "@baseboard_fab2_lib.baseboard_fab2(sch_1):m_e_ma(17)") )
				( objectStatus "SNCLS_DDR4_CHN_E_CMD_ADD" )
			)
			( netClass "@sapphirecity_baseboard_lib.sapphirecity_baseboard(sch_1):\DDR4_CHN_E_CTRL\"
				( memberType ( signal ) )
				( spacingCSetRef "@crescent_city_bb_fab1_lib.crescent_city_bb_fab1(sch_1):\8P9_US_&_6H_SL\" )
				( sameNetSpacingCSetRef "@crescent_city_bb_fab1_lib.crescent_city_bb_fab1(sch_1):\7H_US_AND_5H_SL\" )
				( objectFlag fObjectSpacing )
				( objectFlag fObjectSameNetSpacing )
				( member ( signalRef "@baseboard_fab2_lib.baseboard_fab2(sch_1):m_e_cke(0)") )
				( member ( signalRef "@baseboard_fab2_lib.baseboard_fab2(sch_1):m_e_cke(1)") )
				( member ( signalRef "@baseboard_fab2_lib.baseboard_fab2(sch_1):m_e_cke(2)") )
				( member ( signalRef "@baseboard_fab2_lib.baseboard_fab2(sch_1):m_e_cke(3)") )
				( member ( signalRef "@baseboard_fab2_lib.baseboard_fab2(sch_1):m_e_cs_n(0)") )
				( member ( signalRef "@baseboard_fab2_lib.baseboard_fab2(sch_1):m_e_cs_n(1)") )
				( member ( signalRef "@baseboard_fab2_lib.baseboard_fab2(sch_1):m_e_cs_n(2)") )
				( member ( signalRef "@baseboard_fab2_lib.baseboard_fab2(sch_1):m_e_cs_n(3)") )
				( member ( signalRef "@baseboard_fab2_lib.baseboard_fab2(sch_1):m_e_cs_n(6)") )
				( member ( signalRef "@baseboard_fab2_lib.baseboard_fab2(sch_1):m_e_cs_n(7)") )
				( member ( signalRef "@baseboard_fab2_lib.baseboard_fab2(sch_1):m_e_odt(0)") )
				( member ( signalRef "@baseboard_fab2_lib.baseboard_fab2(sch_1):m_e_odt(1)") )
				( member ( signalRef "@baseboard_fab2_lib.baseboard_fab2(sch_1):m_e_odt(2)") )
				( member ( signalRef "@baseboard_fab2_lib.baseboard_fab2(sch_1):m_e_odt(3)") )
				( member ( signalRef "@baseboard_fab2_lib.baseboard_fab2(sch_1):m_e_alert_n") )
				( member ( signalRef "@baseboard_fab2_lib.baseboard_fab2(sch_1):m_e_cs_n(4)") )
				( member ( signalRef "@baseboard_fab2_lib.baseboard_fab2(sch_1):m_e_cs_n(5)") )
				( objectStatus "SNCLS_DDR4_CHN_E_CTRL" )
			)
			( netClass "@sapphirecity_baseboard_lib.sapphirecity_baseboard(sch_1):\DDR4_CHN_F_CLK\"
				( memberType ( signal ) )
				( spacingCSetRef "@crescent_city_bb_fab1_lib.crescent_city_bb_fab1(sch_1):\8P9_US_&_6H_SL\" )
				( sameNetSpacingCSetRef "@crescent_city_bb_fab1_lib.crescent_city_bb_fab1(sch_1):\7H_US_AND_5H_SL\" )
				( objectFlag fObjectSpacing )
				( objectFlag fObjectSameNetSpacing )
				( member ( diffPairRef "@sapphirecity_baseboard_lib.sapphirecity_baseboard(sch_1):\M_F_CLK_D\(0)") )
				( member ( diffPairRef "@sapphirecity_baseboard_lib.sapphirecity_baseboard(sch_1):\M_F_CLK_D\(2)") )
				( member ( diffPairRef "@sapphirecity_baseboard_lib.sapphirecity_baseboard(sch_1):\M_K_CLK_D\(3)") )
				( member ( diffPairRef "@sapphirecity_baseboard_lib.sapphirecity_baseboard(sch_1):\M_K_CLK_D\(1)") )
				( objectStatus "SNCLS_DDR4_CHN_F_CLK" )
			)
			( netClass "@sapphirecity_baseboard_lib.sapphirecity_baseboard(sch_1):\DDR4_CHN_F_CMD_ADD\"
				( memberType ( signal ) )
				( spacingCSetRef "@crescent_city_bb_fab1_lib.crescent_city_bb_fab1(sch_1):\8P9_US_&_6H_SL\" )
				( sameNetSpacingCSetRef "@crescent_city_bb_fab1_lib.crescent_city_bb_fab1(sch_1):\7H_US_AND_5H_SL\" )
				( objectFlag fObjectSpacing )
				( objectFlag fObjectSameNetSpacing )
				( member ( signalRef "@baseboard_fab2_lib.baseboard_fab2(sch_1):m_f_act_n") )
				( member ( signalRef "@baseboard_fab2_lib.baseboard_fab2(sch_1):m_f_c(2)") )
				( member ( signalRef "@baseboard_fab2_lib.baseboard_fab2(sch_1):m_f_par") )
				( member ( signalRef "@baseboard_fab2_lib.baseboard_fab2(sch_1):m_f_ma(0)") )
				( member ( signalRef "@baseboard_fab2_lib.baseboard_fab2(sch_1):m_f_ma(1)") )
				( member ( signalRef "@baseboard_fab2_lib.baseboard_fab2(sch_1):m_f_ma(2)") )
				( member ( signalRef "@baseboard_fab2_lib.baseboard_fab2(sch_1):m_f_ma(3)") )
				( member ( signalRef "@baseboard_fab2_lib.baseboard_fab2(sch_1):m_f_ma(4)") )
				( member ( signalRef "@baseboard_fab2_lib.baseboard_fab2(sch_1):m_f_ma(5)") )
				( member ( signalRef "@baseboard_fab2_lib.baseboard_fab2(sch_1):m_f_ma(6)") )
				( member ( signalRef "@baseboard_fab2_lib.baseboard_fab2(sch_1):m_f_ma(7)") )
				( member ( signalRef "@baseboard_fab2_lib.baseboard_fab2(sch_1):m_f_ma(8)") )
				( member ( signalRef "@baseboard_fab2_lib.baseboard_fab2(sch_1):m_f_ma(9)") )
				( member ( signalRef "@baseboard_fab2_lib.baseboard_fab2(sch_1):m_f_ma(10)") )
				( member ( signalRef "@baseboard_fab2_lib.baseboard_fab2(sch_1):m_f_ma(11)") )
				( member ( signalRef "@baseboard_fab2_lib.baseboard_fab2(sch_1):m_f_ma(12)") )
				( member ( signalRef "@baseboard_fab2_lib.baseboard_fab2(sch_1):m_f_ma(13)") )
				( member ( signalRef "@baseboard_fab2_lib.baseboard_fab2(sch_1):m_f_ma(14)") )
				( member ( signalRef "@baseboard_fab2_lib.baseboard_fab2(sch_1):m_f_ma(15)") )
				( member ( signalRef "@baseboard_fab2_lib.baseboard_fab2(sch_1):m_f_ma(16)") )
				( member ( signalRef "@baseboard_fab2_lib.baseboard_fab2(sch_1):m_f_ma(17)") )
				( member ( signalRef "@baseboard_fab2_lib.baseboard_fab2(sch_1):m_f_ba(0)") )
				( member ( signalRef "@baseboard_fab2_lib.baseboard_fab2(sch_1):m_f_ba(1)") )
				( member ( signalRef "@baseboard_fab2_lib.baseboard_fab2(sch_1):m_f_bg(0)") )
				( member ( signalRef "@baseboard_fab2_lib.baseboard_fab2(sch_1):m_f_bg(1)") )
				( objectStatus "SNCLS_DDR4_CHN_F_CMD_ADD" )
			)
			( netClass "@sapphirecity_baseboard_lib.sapphirecity_baseboard(sch_1):\DDR4_CHN_F_CTRL\"
				( memberType ( signal ) )
				( spacingCSetRef "@crescent_city_bb_fab1_lib.crescent_city_bb_fab1(sch_1):\8P9_US_&_6H_SL\" )
				( sameNetSpacingCSetRef "@crescent_city_bb_fab1_lib.crescent_city_bb_fab1(sch_1):\7H_US_AND_5H_SL\" )
				( objectFlag fObjectSpacing )
				( objectFlag fObjectSameNetSpacing )
				( member ( signalRef "@baseboard_fab2_lib.baseboard_fab2(sch_1):m_f_cke(0)") )
				( member ( signalRef "@baseboard_fab2_lib.baseboard_fab2(sch_1):m_f_cke(1)") )
				( member ( signalRef "@baseboard_fab2_lib.baseboard_fab2(sch_1):m_f_cs_n(0)") )
				( member ( signalRef "@baseboard_fab2_lib.baseboard_fab2(sch_1):m_f_cs_n(1)") )
				( member ( signalRef "@baseboard_fab2_lib.baseboard_fab2(sch_1):m_f_cs_n(2)") )
				( member ( signalRef "@baseboard_fab2_lib.baseboard_fab2(sch_1):m_f_cs_n(3)") )
				( member ( signalRef "@baseboard_fab2_lib.baseboard_fab2(sch_1):m_f_odt(0)") )
				( member ( signalRef "@baseboard_fab2_lib.baseboard_fab2(sch_1):m_f_odt(1)") )
				( member ( signalRef "@baseboard_fab2_lib.baseboard_fab2(sch_1):m_f_alert_n") )
				( member ( signalRef "@baseboard_fab2_lib.baseboard_fab2(sch_1):m_f_cke(2)") )
				( member ( signalRef "@baseboard_fab2_lib.baseboard_fab2(sch_1):m_f_cke(3)") )
				( member ( signalRef "@baseboard_fab2_lib.baseboard_fab2(sch_1):m_f_cs_n(4)") )
				( member ( signalRef "@baseboard_fab2_lib.baseboard_fab2(sch_1):m_f_cs_n(5)") )
				( member ( signalRef "@baseboard_fab2_lib.baseboard_fab2(sch_1):m_f_cs_n(6)") )
				( member ( signalRef "@baseboard_fab2_lib.baseboard_fab2(sch_1):m_f_cs_n(7)") )
				( member ( signalRef "@baseboard_fab2_lib.baseboard_fab2(sch_1):m_f_odt(2)") )
				( member ( signalRef "@baseboard_fab2_lib.baseboard_fab2(sch_1):m_f_odt(3)") )
				( objectStatus "SNCLS_DDR4_CHN_F_CTRL" )
			)
			( netClass "@sapphirecity_baseboard_lib.sapphirecity_baseboard(sch_1):\DDR4_CHN_H_CLK\"
				( memberType ( signal ) )
				( spacingCSetRef "@crescent_city_bb_fab1_lib.crescent_city_bb_fab1(sch_1):\8P9_US_&_6H_SL\" )
				( sameNetSpacingCSetRef "@crescent_city_bb_fab1_lib.crescent_city_bb_fab1(sch_1):\7H_US_AND_5H_SL\" )
				( objectFlag fObjectSpacing )
				( objectFlag fObjectSameNetSpacing )
				( member ( diffPairRef "@sapphirecity_baseboard_lib.sapphirecity_baseboard(sch_1):\M_H_CLK_D\(0)") )
				( member ( diffPairRef "@sapphirecity_baseboard_lib.sapphirecity_baseboard(sch_1):\M_H_CLK_D\(2)") )
				( member ( diffPairRef "@sapphirecity_baseboard_lib.sapphirecity_baseboard(sch_1):\M_B_CLK_D\(1)") )
				( member ( diffPairRef "@sapphirecity_baseboard_lib.sapphirecity_baseboard(sch_1):\M_B_CLK_D\(3)") )
				( objectStatus "SNCLS_DDR4_CHN_H_CLK" )
			)
			( netClass "@sapphirecity_baseboard_lib.sapphirecity_baseboard(sch_1):\DDR4_CHN_H_CMD_ADD\"
				( memberType ( signal ) )
				( spacingCSetRef "@crescent_city_bb_fab1_lib.crescent_city_bb_fab1(sch_1):\8P9_US_&_6H_SL\" )
				( sameNetSpacingCSetRef "@crescent_city_bb_fab1_lib.crescent_city_bb_fab1(sch_1):\7H_US_AND_5H_SL\" )
				( objectFlag fObjectSpacing )
				( objectFlag fObjectSameNetSpacing )
				( member ( signalRef "@baseboard_fab2_lib.baseboard_fab2(sch_1):m_h_act_n") )
				( member ( signalRef "@baseboard_fab2_lib.baseboard_fab2(sch_1):m_h_c(2)") )
				( member ( signalRef "@baseboard_fab2_lib.baseboard_fab2(sch_1):m_h_par") )
				( member ( signalRef "@baseboard_fab2_lib.baseboard_fab2(sch_1):m_h_ba(0)") )
				( member ( signalRef "@baseboard_fab2_lib.baseboard_fab2(sch_1):m_h_ba(1)") )
				( member ( signalRef "@baseboard_fab2_lib.baseboard_fab2(sch_1):m_h_bg(0)") )
				( member ( signalRef "@baseboard_fab2_lib.baseboard_fab2(sch_1):m_h_bg(1)") )
				( member ( signalRef "@baseboard_fab2_lib.baseboard_fab2(sch_1):m_h_ma(0)") )
				( member ( signalRef "@baseboard_fab2_lib.baseboard_fab2(sch_1):m_h_ma(1)") )
				( member ( signalRef "@baseboard_fab2_lib.baseboard_fab2(sch_1):m_h_ma(2)") )
				( member ( signalRef "@baseboard_fab2_lib.baseboard_fab2(sch_1):m_h_ma(3)") )
				( member ( signalRef "@baseboard_fab2_lib.baseboard_fab2(sch_1):m_h_ma(4)") )
				( member ( signalRef "@baseboard_fab2_lib.baseboard_fab2(sch_1):m_h_ma(5)") )
				( member ( signalRef "@baseboard_fab2_lib.baseboard_fab2(sch_1):m_h_ma(6)") )
				( member ( signalRef "@baseboard_fab2_lib.baseboard_fab2(sch_1):m_h_ma(7)") )
				( member ( signalRef "@baseboard_fab2_lib.baseboard_fab2(sch_1):m_h_ma(8)") )
				( member ( signalRef "@baseboard_fab2_lib.baseboard_fab2(sch_1):m_h_ma(9)") )
				( member ( signalRef "@baseboard_fab2_lib.baseboard_fab2(sch_1):m_h_ma(10)") )
				( member ( signalRef "@baseboard_fab2_lib.baseboard_fab2(sch_1):m_h_ma(11)") )
				( member ( signalRef "@baseboard_fab2_lib.baseboard_fab2(sch_1):m_h_ma(12)") )
				( member ( signalRef "@baseboard_fab2_lib.baseboard_fab2(sch_1):m_h_ma(13)") )
				( member ( signalRef "@baseboard_fab2_lib.baseboard_fab2(sch_1):m_h_ma(14)") )
				( member ( signalRef "@baseboard_fab2_lib.baseboard_fab2(sch_1):m_h_ma(15)") )
				( member ( signalRef "@baseboard_fab2_lib.baseboard_fab2(sch_1):m_h_ma(16)") )
				( member ( signalRef "@baseboard_fab2_lib.baseboard_fab2(sch_1):m_h_ma(17)") )
				( objectStatus "SNCLS_DDR4_CHN_H_CMD_ADD" )
			)
			( netClass "@sapphirecity_baseboard_lib.sapphirecity_baseboard(sch_1):\DDR4_CHN_H_CTRL\"
				( memberType ( signal ) )
				( spacingCSetRef "@crescent_city_bb_fab1_lib.crescent_city_bb_fab1(sch_1):\8P9_US_&_6H_SL\" )
				( sameNetSpacingCSetRef "@crescent_city_bb_fab1_lib.crescent_city_bb_fab1(sch_1):\7H_US_AND_5H_SL\" )
				( objectFlag fObjectSpacing )
				( objectFlag fObjectSameNetSpacing )
				( member ( signalRef "@baseboard_fab2_lib.baseboard_fab2(sch_1):m_h_cke(0)") )
				( member ( signalRef "@baseboard_fab2_lib.baseboard_fab2(sch_1):m_h_cke(1)") )
				( member ( signalRef "@baseboard_fab2_lib.baseboard_fab2(sch_1):m_h_cke(2)") )
				( member ( signalRef "@baseboard_fab2_lib.baseboard_fab2(sch_1):m_h_cke(3)") )
				( member ( signalRef "@baseboard_fab2_lib.baseboard_fab2(sch_1):m_h_cs_n(0)") )
				( member ( signalRef "@baseboard_fab2_lib.baseboard_fab2(sch_1):m_h_cs_n(1)") )
				( member ( signalRef "@baseboard_fab2_lib.baseboard_fab2(sch_1):m_h_cs_n(2)") )
				( member ( signalRef "@baseboard_fab2_lib.baseboard_fab2(sch_1):m_h_cs_n(3)") )
				( member ( signalRef "@baseboard_fab2_lib.baseboard_fab2(sch_1):m_h_cs_n(4)") )
				( member ( signalRef "@baseboard_fab2_lib.baseboard_fab2(sch_1):m_h_cs_n(5)") )
				( member ( signalRef "@baseboard_fab2_lib.baseboard_fab2(sch_1):m_h_cs_n(6)") )
				( member ( signalRef "@baseboard_fab2_lib.baseboard_fab2(sch_1):m_h_cs_n(7)") )
				( member ( signalRef "@baseboard_fab2_lib.baseboard_fab2(sch_1):m_h_odt(0)") )
				( member ( signalRef "@baseboard_fab2_lib.baseboard_fab2(sch_1):m_h_odt(1)") )
				( member ( signalRef "@baseboard_fab2_lib.baseboard_fab2(sch_1):m_h_odt(2)") )
				( member ( signalRef "@baseboard_fab2_lib.baseboard_fab2(sch_1):m_h_odt(3)") )
				( member ( signalRef "@baseboard_fab2_lib.baseboard_fab2(sch_1):m_h_alert_n") )
				( objectStatus "SNCLS_DDR4_CHN_H_CTRL" )
			)
			( netClass "@sapphirecity_baseboard_lib.sapphirecity_baseboard(sch_1):\DDR4_CHN_D_ECC\"
				( memberType ( signal ) )
				( spacingCSetRef "@sapphirecity_baseboard_lib.sapphirecity_baseboard(sch_1):\10H_SL_12H_MS\" )
				( sameNetSpacingCSetRef "@crescent_city_bb_fab1_lib.crescent_city_bb_fab1(sch_1):\7H_US_AND_5H_SL\" )
				( objectFlag fObjectSpacing )
				( objectFlag fObjectSameNetSpacing )
				( member ( diffPairRef "@sapphirecity_baseboard_lib.sapphirecity_baseboard(sch_1):\M_D_DQS_D\(8)") )
				( member ( diffPairRef "@sapphirecity_baseboard_lib.sapphirecity_baseboard(sch_1):\M_D_DQS_D\(17)") )
				( member ( signalRef "@baseboard_fab2_lib.baseboard_fab2(sch_1):m_d_ecc(0)") )
				( member ( signalRef "@baseboard_fab2_lib.baseboard_fab2(sch_1):m_d_ecc(1)") )
				( member ( signalRef "@baseboard_fab2_lib.baseboard_fab2(sch_1):m_d_ecc(2)") )
				( member ( signalRef "@baseboard_fab2_lib.baseboard_fab2(sch_1):m_d_ecc(3)") )
				( member ( signalRef "@baseboard_fab2_lib.baseboard_fab2(sch_1):m_d_ecc(4)") )
				( member ( signalRef "@baseboard_fab2_lib.baseboard_fab2(sch_1):m_d_ecc(5)") )
				( member ( signalRef "@baseboard_fab2_lib.baseboard_fab2(sch_1):m_d_ecc(6)") )
				( member ( signalRef "@baseboard_fab2_lib.baseboard_fab2(sch_1):m_d_ecc(7)") )
				( objectStatus "SNCLS_DDR4_CHN_D_ECC" )
			)
			( netClass "@sapphirecity_baseboard_lib.sapphirecity_baseboard(sch_1):\DDR4_CHN_E_DQ_DQS_BYTE0\"
				( memberType ( signal ) )
				( spacingCSetRef "@sapphirecity_baseboard_lib.sapphirecity_baseboard(sch_1):\10H_SL_12H_MS\" )
				( sameNetSpacingCSetRef "@crescent_city_bb_fab1_lib.crescent_city_bb_fab1(sch_1):\7H_US_AND_5H_SL\" )
				( objectFlag fObjectSpacing )
				( objectFlag fObjectSameNetSpacing )
				( member ( diffPairRef "@sapphirecity_baseboard_lib.sapphirecity_baseboard(sch_1):\M_E_DQS_D\(0)") )
				( member ( diffPairRef "@sapphirecity_baseboard_lib.sapphirecity_baseboard(sch_1):\M_E_DQS_D\(9)") )
				( member ( signalRef "@baseboard_fab2_lib.baseboard_fab2(sch_1):m_e_dq(0)") )
				( member ( signalRef "@baseboard_fab2_lib.baseboard_fab2(sch_1):m_e_dq(1)") )
				( member ( signalRef "@baseboard_fab2_lib.baseboard_fab2(sch_1):m_e_dq(2)") )
				( member ( signalRef "@baseboard_fab2_lib.baseboard_fab2(sch_1):m_e_dq(3)") )
				( member ( signalRef "@baseboard_fab2_lib.baseboard_fab2(sch_1):m_e_dq(4)") )
				( member ( signalRef "@baseboard_fab2_lib.baseboard_fab2(sch_1):m_e_dq(5)") )
				( member ( signalRef "@baseboard_fab2_lib.baseboard_fab2(sch_1):m_e_dq(6)") )
				( member ( signalRef "@baseboard_fab2_lib.baseboard_fab2(sch_1):m_e_dq(7)") )
				( objectStatus "SNCLS_DDR4_CHN_E_DQ_DQS_BYTE0" )
			)
			( netClass "@sapphirecity_baseboard_lib.sapphirecity_baseboard(sch_1):\DDR4_CHN_E_DQ_DQS_BYTE1\"
				( memberType ( signal ) )
				( spacingCSetRef "@sapphirecity_baseboard_lib.sapphirecity_baseboard(sch_1):\10H_SL_12H_MS\" )
				( sameNetSpacingCSetRef "@crescent_city_bb_fab1_lib.crescent_city_bb_fab1(sch_1):\7H_US_AND_5H_SL\" )
				( objectFlag fObjectSpacing )
				( objectFlag fObjectSameNetSpacing )
				( member ( diffPairRef "@sapphirecity_baseboard_lib.sapphirecity_baseboard(sch_1):\M_E_DQS_D\(1)") )
				( member ( diffPairRef "@sapphirecity_baseboard_lib.sapphirecity_baseboard(sch_1):\M_E_DQS_D\(10)") )
				( member ( signalRef "@baseboard_fab2_lib.baseboard_fab2(sch_1):m_e_dq(8)") )
				( member ( signalRef "@baseboard_fab2_lib.baseboard_fab2(sch_1):m_e_dq(9)") )
				( member ( signalRef "@baseboard_fab2_lib.baseboard_fab2(sch_1):m_e_dq(10)") )
				( member ( signalRef "@baseboard_fab2_lib.baseboard_fab2(sch_1):m_e_dq(11)") )
				( member ( signalRef "@baseboard_fab2_lib.baseboard_fab2(sch_1):m_e_dq(12)") )
				( member ( signalRef "@baseboard_fab2_lib.baseboard_fab2(sch_1):m_e_dq(13)") )
				( member ( signalRef "@baseboard_fab2_lib.baseboard_fab2(sch_1):m_e_dq(14)") )
				( member ( signalRef "@baseboard_fab2_lib.baseboard_fab2(sch_1):m_e_dq(15)") )
				( objectStatus "SNCLS_DDR4_CHN_E_DQ_DQS_BYTE1" )
			)
			( netClass "@sapphirecity_baseboard_lib.sapphirecity_baseboard(sch_1):\DDR4_CHN_E_DQ_DQS_BYTE2\"
				( memberType ( signal ) )
				( spacingCSetRef "@sapphirecity_baseboard_lib.sapphirecity_baseboard(sch_1):\10H_SL_12H_MS\" )
				( sameNetSpacingCSetRef "@crescent_city_bb_fab1_lib.crescent_city_bb_fab1(sch_1):\7H_US_AND_5H_SL\" )
				( objectFlag fObjectSpacing )
				( objectFlag fObjectSameNetSpacing )
				( member ( diffPairRef "@sapphirecity_baseboard_lib.sapphirecity_baseboard(sch_1):\M_E_DQS_D\(2)") )
				( member ( diffPairRef "@sapphirecity_baseboard_lib.sapphirecity_baseboard(sch_1):\M_E_DQS_D\(11)") )
				( member ( signalRef "@baseboard_fab2_lib.baseboard_fab2(sch_1):m_e_dq(16)") )
				( member ( signalRef "@baseboard_fab2_lib.baseboard_fab2(sch_1):m_e_dq(17)") )
				( member ( signalRef "@baseboard_fab2_lib.baseboard_fab2(sch_1):m_e_dq(18)") )
				( member ( signalRef "@baseboard_fab2_lib.baseboard_fab2(sch_1):m_e_dq(19)") )
				( member ( signalRef "@baseboard_fab2_lib.baseboard_fab2(sch_1):m_e_dq(20)") )
				( member ( signalRef "@baseboard_fab2_lib.baseboard_fab2(sch_1):m_e_dq(21)") )
				( member ( signalRef "@baseboard_fab2_lib.baseboard_fab2(sch_1):m_e_dq(22)") )
				( member ( signalRef "@baseboard_fab2_lib.baseboard_fab2(sch_1):m_e_dq(23)") )
				( objectStatus "SNCLS_DDR4_CHN_E_DQ_DQS_BYTE2" )
			)
			( netClass "@sapphirecity_baseboard_lib.sapphirecity_baseboard(sch_1):\DDR4_CHN_E_DQ_DQS_BYTE3\"
				( memberType ( signal ) )
				( spacingCSetRef "@sapphirecity_baseboard_lib.sapphirecity_baseboard(sch_1):\10H_SL_12H_MS\" )
				( sameNetSpacingCSetRef "@crescent_city_bb_fab1_lib.crescent_city_bb_fab1(sch_1):\7H_US_AND_5H_SL\" )
				( objectFlag fObjectSpacing )
				( objectFlag fObjectSameNetSpacing )
				( member ( diffPairRef "@sapphirecity_baseboard_lib.sapphirecity_baseboard(sch_1):\M_E_DQS_D\(3)") )
				( member ( diffPairRef "@sapphirecity_baseboard_lib.sapphirecity_baseboard(sch_1):\M_E_DQS_D\(12)") )
				( member ( signalRef "@baseboard_fab2_lib.baseboard_fab2(sch_1):m_e_dq(24)") )
				( member ( signalRef "@baseboard_fab2_lib.baseboard_fab2(sch_1):m_e_dq(25)") )
				( member ( signalRef "@baseboard_fab2_lib.baseboard_fab2(sch_1):m_e_dq(26)") )
				( member ( signalRef "@baseboard_fab2_lib.baseboard_fab2(sch_1):m_e_dq(27)") )
				( member ( signalRef "@baseboard_fab2_lib.baseboard_fab2(sch_1):m_e_dq(28)") )
				( member ( signalRef "@baseboard_fab2_lib.baseboard_fab2(sch_1):m_e_dq(29)") )
				( member ( signalRef "@baseboard_fab2_lib.baseboard_fab2(sch_1):m_e_dq(30)") )
				( member ( signalRef "@baseboard_fab2_lib.baseboard_fab2(sch_1):m_e_dq(31)") )
				( objectStatus "SNCLS_DDR4_CHN_E_DQ_DQS_BYTE3" )
			)
			( netClass "@sapphirecity_baseboard_lib.sapphirecity_baseboard(sch_1):\DDR4_CHN_E_DQ_DQS_BYTE4\"
				( memberType ( signal ) )
				( spacingCSetRef "@sapphirecity_baseboard_lib.sapphirecity_baseboard(sch_1):\10H_SL_12H_MS\" )
				( sameNetSpacingCSetRef "@crescent_city_bb_fab1_lib.crescent_city_bb_fab1(sch_1):\7H_US_AND_5H_SL\" )
				( objectFlag fObjectSpacing )
				( objectFlag fObjectSameNetSpacing )
				( member ( diffPairRef "@sapphirecity_baseboard_lib.sapphirecity_baseboard(sch_1):\M_E_DQS_D\(4)") )
				( member ( diffPairRef "@sapphirecity_baseboard_lib.sapphirecity_baseboard(sch_1):\M_E_DQS_D\(13)") )
				( member ( signalRef "@baseboard_fab2_lib.baseboard_fab2(sch_1):m_e_dq(32)") )
				( member ( signalRef "@baseboard_fab2_lib.baseboard_fab2(sch_1):m_e_dq(33)") )
				( member ( signalRef "@baseboard_fab2_lib.baseboard_fab2(sch_1):m_e_dq(34)") )
				( member ( signalRef "@baseboard_fab2_lib.baseboard_fab2(sch_1):m_e_dq(35)") )
				( member ( signalRef "@baseboard_fab2_lib.baseboard_fab2(sch_1):m_e_dq(36)") )
				( member ( signalRef "@baseboard_fab2_lib.baseboard_fab2(sch_1):m_e_dq(37)") )
				( member ( signalRef "@baseboard_fab2_lib.baseboard_fab2(sch_1):m_e_dq(38)") )
				( member ( signalRef "@baseboard_fab2_lib.baseboard_fab2(sch_1):m_e_dq(39)") )
				( objectStatus "SNCLS_DDR4_CHN_E_DQ_DQS_BYTE4" )
			)
			( netClass "@sapphirecity_baseboard_lib.sapphirecity_baseboard(sch_1):\DDR4_CHN_E_DQ_DQS_BYTE5\"
				( memberType ( signal ) )
				( spacingCSetRef "@sapphirecity_baseboard_lib.sapphirecity_baseboard(sch_1):\10H_SL_12H_MS\" )
				( sameNetSpacingCSetRef "@crescent_city_bb_fab1_lib.crescent_city_bb_fab1(sch_1):\7H_US_AND_5H_SL\" )
				( objectFlag fObjectSpacing )
				( objectFlag fObjectSameNetSpacing )
				( member ( diffPairRef "@sapphirecity_baseboard_lib.sapphirecity_baseboard(sch_1):\M_E_DQS_D\(5)") )
				( member ( diffPairRef "@sapphirecity_baseboard_lib.sapphirecity_baseboard(sch_1):\M_E_DQS_D\(14)") )
				( member ( signalRef "@baseboard_fab2_lib.baseboard_fab2(sch_1):m_e_dq(40)") )
				( member ( signalRef "@baseboard_fab2_lib.baseboard_fab2(sch_1):m_e_dq(41)") )
				( member ( signalRef "@baseboard_fab2_lib.baseboard_fab2(sch_1):m_e_dq(42)") )
				( member ( signalRef "@baseboard_fab2_lib.baseboard_fab2(sch_1):m_e_dq(43)") )
				( member ( signalRef "@baseboard_fab2_lib.baseboard_fab2(sch_1):m_e_dq(44)") )
				( member ( signalRef "@baseboard_fab2_lib.baseboard_fab2(sch_1):m_e_dq(45)") )
				( member ( signalRef "@baseboard_fab2_lib.baseboard_fab2(sch_1):m_e_dq(46)") )
				( member ( signalRef "@baseboard_fab2_lib.baseboard_fab2(sch_1):m_e_dq(47)") )
				( objectStatus "SNCLS_DDR4_CHN_E_DQ_DQS_BYTE5" )
			)
			( netClass "@sapphirecity_baseboard_lib.sapphirecity_baseboard(sch_1):\DDR4_CHN_E_DQ_DQS_BYTE6\"
				( memberType ( signal ) )
				( spacingCSetRef "@sapphirecity_baseboard_lib.sapphirecity_baseboard(sch_1):\10H_SL_12H_MS\" )
				( sameNetSpacingCSetRef "@crescent_city_bb_fab1_lib.crescent_city_bb_fab1(sch_1):\7H_US_AND_5H_SL\" )
				( objectFlag fObjectSpacing )
				( objectFlag fObjectSameNetSpacing )
				( member ( diffPairRef "@sapphirecity_baseboard_lib.sapphirecity_baseboard(sch_1):\M_E_DQS_D\(6)") )
				( member ( diffPairRef "@sapphirecity_baseboard_lib.sapphirecity_baseboard(sch_1):\M_E_DQS_D\(15)") )
				( member ( signalRef "@baseboard_fab2_lib.baseboard_fab2(sch_1):m_e_dq(48)") )
				( member ( signalRef "@baseboard_fab2_lib.baseboard_fab2(sch_1):m_e_dq(49)") )
				( member ( signalRef "@baseboard_fab2_lib.baseboard_fab2(sch_1):m_e_dq(50)") )
				( member ( signalRef "@baseboard_fab2_lib.baseboard_fab2(sch_1):m_e_dq(51)") )
				( member ( signalRef "@baseboard_fab2_lib.baseboard_fab2(sch_1):m_e_dq(52)") )
				( member ( signalRef "@baseboard_fab2_lib.baseboard_fab2(sch_1):m_e_dq(53)") )
				( member ( signalRef "@baseboard_fab2_lib.baseboard_fab2(sch_1):m_e_dq(54)") )
				( member ( signalRef "@baseboard_fab2_lib.baseboard_fab2(sch_1):m_e_dq(55)") )
				( objectStatus "SNCLS_DDR4_CHN_E_DQ_DQS_BYTE6" )
			)
			( netClass "@sapphirecity_baseboard_lib.sapphirecity_baseboard(sch_1):\DDR4_CHN_E_DQ_DQS_BYTE7\"
				( memberType ( signal ) )
				( spacingCSetRef "@sapphirecity_baseboard_lib.sapphirecity_baseboard(sch_1):\10H_SL_12H_MS\" )
				( sameNetSpacingCSetRef "@crescent_city_bb_fab1_lib.crescent_city_bb_fab1(sch_1):\7H_US_AND_5H_SL\" )
				( objectFlag fObjectSpacing )
				( objectFlag fObjectSameNetSpacing )
				( member ( diffPairRef "@sapphirecity_baseboard_lib.sapphirecity_baseboard(sch_1):\M_E_DQS_D\(7)") )
				( member ( diffPairRef "@sapphirecity_baseboard_lib.sapphirecity_baseboard(sch_1):\M_E_DQS_D\(16)") )
				( member ( signalRef "@baseboard_fab2_lib.baseboard_fab2(sch_1):m_e_dq(56)") )
				( member ( signalRef "@baseboard_fab2_lib.baseboard_fab2(sch_1):m_e_dq(57)") )
				( member ( signalRef "@baseboard_fab2_lib.baseboard_fab2(sch_1):m_e_dq(58)") )
				( member ( signalRef "@baseboard_fab2_lib.baseboard_fab2(sch_1):m_e_dq(59)") )
				( member ( signalRef "@baseboard_fab2_lib.baseboard_fab2(sch_1):m_e_dq(60)") )
				( member ( signalRef "@baseboard_fab2_lib.baseboard_fab2(sch_1):m_e_dq(61)") )
				( member ( signalRef "@baseboard_fab2_lib.baseboard_fab2(sch_1):m_e_dq(62)") )
				( member ( signalRef "@baseboard_fab2_lib.baseboard_fab2(sch_1):m_e_dq(63)") )
				( objectStatus "SNCLS_DDR4_CHN_E_DQ_DQS_BYTE7" )
			)
			( netClass "@sapphirecity_baseboard_lib.sapphirecity_baseboard(sch_1):\DDR4_CHN_E_ECC\"
				( memberType ( signal ) )
				( spacingCSetRef "@sapphirecity_baseboard_lib.sapphirecity_baseboard(sch_1):\10H_SL_12H_MS\" )
				( sameNetSpacingCSetRef "@crescent_city_bb_fab1_lib.crescent_city_bb_fab1(sch_1):\7H_US_AND_5H_SL\" )
				( objectFlag fObjectSpacing )
				( objectFlag fObjectSameNetSpacing )
				( member ( diffPairRef "@sapphirecity_baseboard_lib.sapphirecity_baseboard(sch_1):\M_E_DQS_D\(8)") )
				( member ( diffPairRef "@sapphirecity_baseboard_lib.sapphirecity_baseboard(sch_1):\M_E_DQS_D\(17)") )
				( member ( signalRef "@baseboard_fab2_lib.baseboard_fab2(sch_1):m_e_ecc(0)") )
				( member ( signalRef "@baseboard_fab2_lib.baseboard_fab2(sch_1):m_e_ecc(1)") )
				( member ( signalRef "@baseboard_fab2_lib.baseboard_fab2(sch_1):m_e_ecc(2)") )
				( member ( signalRef "@baseboard_fab2_lib.baseboard_fab2(sch_1):m_e_ecc(3)") )
				( member ( signalRef "@baseboard_fab2_lib.baseboard_fab2(sch_1):m_e_ecc(4)") )
				( member ( signalRef "@baseboard_fab2_lib.baseboard_fab2(sch_1):m_e_ecc(5)") )
				( member ( signalRef "@baseboard_fab2_lib.baseboard_fab2(sch_1):m_e_ecc(6)") )
				( member ( signalRef "@baseboard_fab2_lib.baseboard_fab2(sch_1):m_e_ecc(7)") )
				( objectStatus "SNCLS_DDR4_CHN_E_ECC" )
			)
			( netClass "@sapphirecity_baseboard_lib.sapphirecity_baseboard(sch_1):\DDR4_CHN_F_DQ_DQS_BYTE0\"
				( memberType ( signal ) )
				( spacingCSetRef "@sapphirecity_baseboard_lib.sapphirecity_baseboard(sch_1):\10H_SL_12H_MS\" )
				( sameNetSpacingCSetRef "@crescent_city_bb_fab1_lib.crescent_city_bb_fab1(sch_1):\7H_US_AND_5H_SL\" )
				( objectFlag fObjectSpacing )
				( objectFlag fObjectSameNetSpacing )
				( member ( diffPairRef "@sapphirecity_baseboard_lib.sapphirecity_baseboard(sch_1):\M_F_DQS_D\(0)") )
				( member ( diffPairRef "@sapphirecity_baseboard_lib.sapphirecity_baseboard(sch_1):\M_F_DQS_D\(9)") )
				( member ( signalRef "@baseboard_fab2_lib.baseboard_fab2(sch_1):m_f_dq(0)") )
				( member ( signalRef "@baseboard_fab2_lib.baseboard_fab2(sch_1):m_f_dq(1)") )
				( member ( signalRef "@baseboard_fab2_lib.baseboard_fab2(sch_1):m_f_dq(2)") )
				( member ( signalRef "@baseboard_fab2_lib.baseboard_fab2(sch_1):m_f_dq(3)") )
				( member ( signalRef "@baseboard_fab2_lib.baseboard_fab2(sch_1):m_f_dq(4)") )
				( member ( signalRef "@baseboard_fab2_lib.baseboard_fab2(sch_1):m_f_dq(5)") )
				( member ( signalRef "@baseboard_fab2_lib.baseboard_fab2(sch_1):m_f_dq(6)") )
				( member ( signalRef "@baseboard_fab2_lib.baseboard_fab2(sch_1):m_f_dq(7)") )
				( objectStatus "SNCLS_DDR4_CHN_F_DQ_DQS_BYTE0" )
			)
			( netClass "@sapphirecity_baseboard_lib.sapphirecity_baseboard(sch_1):\DDR4_CHN_F_DQ_DQS_BYTE1\"
				( memberType ( signal ) )
				( spacingCSetRef "@sapphirecity_baseboard_lib.sapphirecity_baseboard(sch_1):\10H_SL_12H_MS\" )
				( sameNetSpacingCSetRef "@crescent_city_bb_fab1_lib.crescent_city_bb_fab1(sch_1):\7H_US_AND_5H_SL\" )
				( objectFlag fObjectSpacing )
				( objectFlag fObjectSameNetSpacing )
				( member ( diffPairRef "@sapphirecity_baseboard_lib.sapphirecity_baseboard(sch_1):\M_F_DQS_D\(1)") )
				( member ( diffPairRef "@sapphirecity_baseboard_lib.sapphirecity_baseboard(sch_1):\M_F_DQS_D\(10)") )
				( member ( signalRef "@baseboard_fab2_lib.baseboard_fab2(sch_1):m_f_dq(8)") )
				( member ( signalRef "@baseboard_fab2_lib.baseboard_fab2(sch_1):m_f_dq(9)") )
				( member ( signalRef "@baseboard_fab2_lib.baseboard_fab2(sch_1):m_f_dq(10)") )
				( member ( signalRef "@baseboard_fab2_lib.baseboard_fab2(sch_1):m_f_dq(11)") )
				( member ( signalRef "@baseboard_fab2_lib.baseboard_fab2(sch_1):m_f_dq(12)") )
				( member ( signalRef "@baseboard_fab2_lib.baseboard_fab2(sch_1):m_f_dq(13)") )
				( member ( signalRef "@baseboard_fab2_lib.baseboard_fab2(sch_1):m_f_dq(14)") )
				( member ( signalRef "@baseboard_fab2_lib.baseboard_fab2(sch_1):m_f_dq(15)") )
				( objectStatus "SNCLS_DDR4_CHN_F_DQ_DQS_BYTE1" )
			)
			( netClass "@sapphirecity_baseboard_lib.sapphirecity_baseboard(sch_1):\DDR4_CHN_F_DQ_DQS_BYTE2\"
				( memberType ( signal ) )
				( spacingCSetRef "@sapphirecity_baseboard_lib.sapphirecity_baseboard(sch_1):\10H_SL_12H_MS\" )
				( sameNetSpacingCSetRef "@crescent_city_bb_fab1_lib.crescent_city_bb_fab1(sch_1):\7H_US_AND_5H_SL\" )
				( objectFlag fObjectSpacing )
				( objectFlag fObjectSameNetSpacing )
				( member ( diffPairRef "@sapphirecity_baseboard_lib.sapphirecity_baseboard(sch_1):\M_F_DQS_D\(2)") )
				( member ( diffPairRef "@sapphirecity_baseboard_lib.sapphirecity_baseboard(sch_1):\M_F_DQS_D\(11)") )
				( member ( signalRef "@baseboard_fab2_lib.baseboard_fab2(sch_1):m_f_dq(16)") )
				( member ( signalRef "@baseboard_fab2_lib.baseboard_fab2(sch_1):m_f_dq(17)") )
				( member ( signalRef "@baseboard_fab2_lib.baseboard_fab2(sch_1):m_f_dq(18)") )
				( member ( signalRef "@baseboard_fab2_lib.baseboard_fab2(sch_1):m_f_dq(19)") )
				( member ( signalRef "@baseboard_fab2_lib.baseboard_fab2(sch_1):m_f_dq(20)") )
				( member ( signalRef "@baseboard_fab2_lib.baseboard_fab2(sch_1):m_f_dq(21)") )
				( member ( signalRef "@baseboard_fab2_lib.baseboard_fab2(sch_1):m_f_dq(22)") )
				( member ( signalRef "@baseboard_fab2_lib.baseboard_fab2(sch_1):m_f_dq(23)") )
				( objectStatus "SNCLS_DDR4_CHN_F_DQ_DQS_BYTE2" )
			)
			( netClass "@sapphirecity_baseboard_lib.sapphirecity_baseboard(sch_1):\DDR4_CHN_F_DQ_DQS_BYTE3\"
				( memberType ( signal ) )
				( spacingCSetRef "@sapphirecity_baseboard_lib.sapphirecity_baseboard(sch_1):\10H_SL_12H_MS\" )
				( sameNetSpacingCSetRef "@crescent_city_bb_fab1_lib.crescent_city_bb_fab1(sch_1):\7H_US_AND_5H_SL\" )
				( objectFlag fObjectSpacing )
				( objectFlag fObjectSameNetSpacing )
				( member ( diffPairRef "@sapphirecity_baseboard_lib.sapphirecity_baseboard(sch_1):\M_F_DQS_D\(3)") )
				( member ( diffPairRef "@sapphirecity_baseboard_lib.sapphirecity_baseboard(sch_1):\M_F_DQS_D\(12)") )
				( member ( signalRef "@baseboard_fab2_lib.baseboard_fab2(sch_1):m_f_dq(24)") )
				( member ( signalRef "@baseboard_fab2_lib.baseboard_fab2(sch_1):m_f_dq(25)") )
				( member ( signalRef "@baseboard_fab2_lib.baseboard_fab2(sch_1):m_f_dq(26)") )
				( member ( signalRef "@baseboard_fab2_lib.baseboard_fab2(sch_1):m_f_dq(27)") )
				( member ( signalRef "@baseboard_fab2_lib.baseboard_fab2(sch_1):m_f_dq(28)") )
				( member ( signalRef "@baseboard_fab2_lib.baseboard_fab2(sch_1):m_f_dq(29)") )
				( member ( signalRef "@baseboard_fab2_lib.baseboard_fab2(sch_1):m_f_dq(30)") )
				( member ( signalRef "@baseboard_fab2_lib.baseboard_fab2(sch_1):m_f_dq(31)") )
				( objectStatus "SNCLS_DDR4_CHN_F_DQ_DQS_BYTE3" )
			)
			( netClass "@sapphirecity_baseboard_lib.sapphirecity_baseboard(sch_1):\DDR4_CHN_F_DQ_DQS_BYTE4\"
				( memberType ( signal ) )
				( spacingCSetRef "@sapphirecity_baseboard_lib.sapphirecity_baseboard(sch_1):\10H_SL_12H_MS\" )
				( sameNetSpacingCSetRef "@crescent_city_bb_fab1_lib.crescent_city_bb_fab1(sch_1):\7H_US_AND_5H_SL\" )
				( objectFlag fObjectSpacing )
				( objectFlag fObjectSameNetSpacing )
				( member ( diffPairRef "@sapphirecity_baseboard_lib.sapphirecity_baseboard(sch_1):\M_F_DQS_D\(4)") )
				( member ( diffPairRef "@sapphirecity_baseboard_lib.sapphirecity_baseboard(sch_1):\M_F_DQS_D\(13)") )
				( member ( signalRef "@baseboard_fab2_lib.baseboard_fab2(sch_1):m_f_dq(32)") )
				( member ( signalRef "@baseboard_fab2_lib.baseboard_fab2(sch_1):m_f_dq(33)") )
				( member ( signalRef "@baseboard_fab2_lib.baseboard_fab2(sch_1):m_f_dq(34)") )
				( member ( signalRef "@baseboard_fab2_lib.baseboard_fab2(sch_1):m_f_dq(35)") )
				( member ( signalRef "@baseboard_fab2_lib.baseboard_fab2(sch_1):m_f_dq(36)") )
				( member ( signalRef "@baseboard_fab2_lib.baseboard_fab2(sch_1):m_f_dq(37)") )
				( member ( signalRef "@baseboard_fab2_lib.baseboard_fab2(sch_1):m_f_dq(38)") )
				( member ( signalRef "@baseboard_fab2_lib.baseboard_fab2(sch_1):m_f_dq(39)") )
				( objectStatus "SNCLS_DDR4_CHN_F_DQ_DQS_BYTE4" )
			)
			( netClass "@sapphirecity_baseboard_lib.sapphirecity_baseboard(sch_1):\DDR4_CHN_F_DQ_DQS_BYTE5\"
				( memberType ( signal ) )
				( spacingCSetRef "@sapphirecity_baseboard_lib.sapphirecity_baseboard(sch_1):\10H_SL_12H_MS\" )
				( sameNetSpacingCSetRef "@crescent_city_bb_fab1_lib.crescent_city_bb_fab1(sch_1):\7H_US_AND_5H_SL\" )
				( objectFlag fObjectSpacing )
				( objectFlag fObjectSameNetSpacing )
				( member ( diffPairRef "@sapphirecity_baseboard_lib.sapphirecity_baseboard(sch_1):\M_F_DQS_D\(5)") )
				( member ( diffPairRef "@sapphirecity_baseboard_lib.sapphirecity_baseboard(sch_1):\M_F_DQS_D\(14)") )
				( member ( signalRef "@baseboard_fab2_lib.baseboard_fab2(sch_1):m_f_dq(40)") )
				( member ( signalRef "@baseboard_fab2_lib.baseboard_fab2(sch_1):m_f_dq(41)") )
				( member ( signalRef "@baseboard_fab2_lib.baseboard_fab2(sch_1):m_f_dq(42)") )
				( member ( signalRef "@baseboard_fab2_lib.baseboard_fab2(sch_1):m_f_dq(43)") )
				( member ( signalRef "@baseboard_fab2_lib.baseboard_fab2(sch_1):m_f_dq(44)") )
				( member ( signalRef "@baseboard_fab2_lib.baseboard_fab2(sch_1):m_f_dq(45)") )
				( member ( signalRef "@baseboard_fab2_lib.baseboard_fab2(sch_1):m_f_dq(46)") )
				( member ( signalRef "@baseboard_fab2_lib.baseboard_fab2(sch_1):m_f_dq(47)") )
				( objectStatus "SNCLS_DDR4_CHN_F_DQ_DQS_BYTE5" )
			)
			( netClass "@sapphirecity_baseboard_lib.sapphirecity_baseboard(sch_1):\DDR4_CHN_F_DQ_DQS_BYTE6\"
				( memberType ( signal ) )
				( spacingCSetRef "@sapphirecity_baseboard_lib.sapphirecity_baseboard(sch_1):\10H_SL_12H_MS\" )
				( sameNetSpacingCSetRef "@crescent_city_bb_fab1_lib.crescent_city_bb_fab1(sch_1):\7H_US_AND_5H_SL\" )
				( objectFlag fObjectSpacing )
				( objectFlag fObjectSameNetSpacing )
				( member ( diffPairRef "@sapphirecity_baseboard_lib.sapphirecity_baseboard(sch_1):\M_F_DQS_D\(6)") )
				( member ( diffPairRef "@sapphirecity_baseboard_lib.sapphirecity_baseboard(sch_1):\M_F_DQS_D\(15)") )
				( member ( signalRef "@baseboard_fab2_lib.baseboard_fab2(sch_1):m_f_dq(48)") )
				( member ( signalRef "@baseboard_fab2_lib.baseboard_fab2(sch_1):m_f_dq(49)") )
				( member ( signalRef "@baseboard_fab2_lib.baseboard_fab2(sch_1):m_f_dq(50)") )
				( member ( signalRef "@baseboard_fab2_lib.baseboard_fab2(sch_1):m_f_dq(51)") )
				( member ( signalRef "@baseboard_fab2_lib.baseboard_fab2(sch_1):m_f_dq(52)") )
				( member ( signalRef "@baseboard_fab2_lib.baseboard_fab2(sch_1):m_f_dq(53)") )
				( member ( signalRef "@baseboard_fab2_lib.baseboard_fab2(sch_1):m_f_dq(54)") )
				( member ( signalRef "@baseboard_fab2_lib.baseboard_fab2(sch_1):m_f_dq(55)") )
				( objectStatus "SNCLS_DDR4_CHN_F_DQ_DQS_BYTE6" )
			)
			( netClass "@sapphirecity_baseboard_lib.sapphirecity_baseboard(sch_1):\DDR4_CHN_F_DQ_DQS_BYTE7\"
				( memberType ( signal ) )
				( spacingCSetRef "@sapphirecity_baseboard_lib.sapphirecity_baseboard(sch_1):\10H_SL_12H_MS\" )
				( sameNetSpacingCSetRef "@crescent_city_bb_fab1_lib.crescent_city_bb_fab1(sch_1):\7H_US_AND_5H_SL\" )
				( objectFlag fObjectSpacing )
				( objectFlag fObjectSameNetSpacing )
				( member ( diffPairRef "@sapphirecity_baseboard_lib.sapphirecity_baseboard(sch_1):\M_F_DQS_D\(7)") )
				( member ( diffPairRef "@sapphirecity_baseboard_lib.sapphirecity_baseboard(sch_1):\M_F_DQS_D\(16)") )
				( member ( signalRef "@baseboard_fab2_lib.baseboard_fab2(sch_1):m_f_dq(56)") )
				( member ( signalRef "@baseboard_fab2_lib.baseboard_fab2(sch_1):m_f_dq(57)") )
				( member ( signalRef "@baseboard_fab2_lib.baseboard_fab2(sch_1):m_f_dq(58)") )
				( member ( signalRef "@baseboard_fab2_lib.baseboard_fab2(sch_1):m_f_dq(59)") )
				( member ( signalRef "@baseboard_fab2_lib.baseboard_fab2(sch_1):m_f_dq(60)") )
				( member ( signalRef "@baseboard_fab2_lib.baseboard_fab2(sch_1):m_f_dq(61)") )
				( member ( signalRef "@baseboard_fab2_lib.baseboard_fab2(sch_1):m_f_dq(62)") )
				( member ( signalRef "@baseboard_fab2_lib.baseboard_fab2(sch_1):m_f_dq(63)") )
				( objectStatus "SNCLS_DDR4_CHN_F_DQ_DQS_BYTE7" )
			)
			( netClass "@sapphirecity_baseboard_lib.sapphirecity_baseboard(sch_1):\DDR4_CHN_F_ECC\"
				( memberType ( signal ) )
				( spacingCSetRef "@sapphirecity_baseboard_lib.sapphirecity_baseboard(sch_1):\10H_SL_12H_MS\" )
				( sameNetSpacingCSetRef "@crescent_city_bb_fab1_lib.crescent_city_bb_fab1(sch_1):\7H_US_AND_5H_SL\" )
				( objectFlag fObjectSpacing )
				( objectFlag fObjectSameNetSpacing )
				( member ( diffPairRef "@sapphirecity_baseboard_lib.sapphirecity_baseboard(sch_1):\M_F_DQS_D\(8)") )
				( member ( diffPairRef "@sapphirecity_baseboard_lib.sapphirecity_baseboard(sch_1):\M_F_DQS_D\(17)") )
				( member ( signalRef "@baseboard_fab2_lib.baseboard_fab2(sch_1):m_f_ecc(0)") )
				( member ( signalRef "@baseboard_fab2_lib.baseboard_fab2(sch_1):m_f_ecc(1)") )
				( member ( signalRef "@baseboard_fab2_lib.baseboard_fab2(sch_1):m_f_ecc(2)") )
				( member ( signalRef "@baseboard_fab2_lib.baseboard_fab2(sch_1):m_f_ecc(3)") )
				( member ( signalRef "@baseboard_fab2_lib.baseboard_fab2(sch_1):m_f_ecc(4)") )
				( member ( signalRef "@baseboard_fab2_lib.baseboard_fab2(sch_1):m_f_ecc(5)") )
				( member ( signalRef "@baseboard_fab2_lib.baseboard_fab2(sch_1):m_f_ecc(6)") )
				( member ( signalRef "@baseboard_fab2_lib.baseboard_fab2(sch_1):m_f_ecc(7)") )
				( objectStatus "SNCLS_DDR4_CHN_F_ECC" )
			)
			( netClass "@sapphirecity_baseboard_lib.sapphirecity_baseboard(sch_1):\DDR4_CHN_G_DQ_DQS_BYTE0\"
				( memberType ( signal ) )
				( spacingCSetRef "@sapphirecity_baseboard_lib.sapphirecity_baseboard(sch_1):\10H_SL_12H_MS\" )
				( sameNetSpacingCSetRef "@crescent_city_bb_fab1_lib.crescent_city_bb_fab1(sch_1):\7H_US_AND_5H_SL\" )
				( objectFlag fObjectSpacing )
				( objectFlag fObjectSameNetSpacing )
				( member ( diffPairRef "@sapphirecity_baseboard_lib.sapphirecity_baseboard(sch_1):\M_G_DQS_D\(0)") )
				( member ( diffPairRef "@sapphirecity_baseboard_lib.sapphirecity_baseboard(sch_1):\M_G_DQS_D\(9)") )
				( member ( signalRef "@baseboard_fab2_lib.baseboard_fab2(sch_1):m_g_dq(0)") )
				( member ( signalRef "@baseboard_fab2_lib.baseboard_fab2(sch_1):m_g_dq(1)") )
				( member ( signalRef "@baseboard_fab2_lib.baseboard_fab2(sch_1):m_g_dq(2)") )
				( member ( signalRef "@baseboard_fab2_lib.baseboard_fab2(sch_1):m_g_dq(3)") )
				( member ( signalRef "@baseboard_fab2_lib.baseboard_fab2(sch_1):m_g_dq(4)") )
				( member ( signalRef "@baseboard_fab2_lib.baseboard_fab2(sch_1):m_g_dq(5)") )
				( member ( signalRef "@baseboard_fab2_lib.baseboard_fab2(sch_1):m_g_dq(6)") )
				( member ( signalRef "@baseboard_fab2_lib.baseboard_fab2(sch_1):m_g_dq(7)") )
				( objectStatus "SNCLS_DDR4_CHN_G_DQ_DQS_BYTE0" )
			)
			( netClass "@sapphirecity_baseboard_lib.sapphirecity_baseboard(sch_1):\DDR4_CHN_G_DQ_DQS_BYTE1\"
				( memberType ( signal ) )
				( spacingCSetRef "@sapphirecity_baseboard_lib.sapphirecity_baseboard(sch_1):\10H_SL_12H_MS\" )
				( sameNetSpacingCSetRef "@crescent_city_bb_fab1_lib.crescent_city_bb_fab1(sch_1):\7H_US_AND_5H_SL\" )
				( objectFlag fObjectSpacing )
				( objectFlag fObjectSameNetSpacing )
				( member ( diffPairRef "@sapphirecity_baseboard_lib.sapphirecity_baseboard(sch_1):\M_G_DQS_D\(1)") )
				( member ( diffPairRef "@sapphirecity_baseboard_lib.sapphirecity_baseboard(sch_1):\M_G_DQS_D\(10)") )
				( member ( signalRef "@baseboard_fab2_lib.baseboard_fab2(sch_1):m_g_dq(8)") )
				( member ( signalRef "@baseboard_fab2_lib.baseboard_fab2(sch_1):m_g_dq(9)") )
				( member ( signalRef "@baseboard_fab2_lib.baseboard_fab2(sch_1):m_g_dq(10)") )
				( member ( signalRef "@baseboard_fab2_lib.baseboard_fab2(sch_1):m_g_dq(11)") )
				( member ( signalRef "@baseboard_fab2_lib.baseboard_fab2(sch_1):m_g_dq(12)") )
				( member ( signalRef "@baseboard_fab2_lib.baseboard_fab2(sch_1):m_g_dq(13)") )
				( member ( signalRef "@baseboard_fab2_lib.baseboard_fab2(sch_1):m_g_dq(14)") )
				( member ( signalRef "@baseboard_fab2_lib.baseboard_fab2(sch_1):m_g_dq(15)") )
				( objectStatus "SNCLS_DDR4_CHN_G_DQ_DQS_BYTE1" )
			)
			( netClass "@sapphirecity_baseboard_lib.sapphirecity_baseboard(sch_1):\DDR4_CHN_G_DQ_DQS_BYTE2\"
				( memberType ( signal ) )
				( spacingCSetRef "@sapphirecity_baseboard_lib.sapphirecity_baseboard(sch_1):\10H_SL_12H_MS\" )
				( sameNetSpacingCSetRef "@crescent_city_bb_fab1_lib.crescent_city_bb_fab1(sch_1):\7H_US_AND_5H_SL\" )
				( objectFlag fObjectSpacing )
				( objectFlag fObjectSameNetSpacing )
				( member ( diffPairRef "@sapphirecity_baseboard_lib.sapphirecity_baseboard(sch_1):\M_G_DQS_D\(2)") )
				( member ( diffPairRef "@sapphirecity_baseboard_lib.sapphirecity_baseboard(sch_1):\M_G_DQS_D\(11)") )
				( member ( signalRef "@baseboard_fab2_lib.baseboard_fab2(sch_1):m_g_dq(16)") )
				( member ( signalRef "@baseboard_fab2_lib.baseboard_fab2(sch_1):m_g_dq(17)") )
				( member ( signalRef "@baseboard_fab2_lib.baseboard_fab2(sch_1):m_g_dq(18)") )
				( member ( signalRef "@baseboard_fab2_lib.baseboard_fab2(sch_1):m_g_dq(19)") )
				( member ( signalRef "@baseboard_fab2_lib.baseboard_fab2(sch_1):m_g_dq(20)") )
				( member ( signalRef "@baseboard_fab2_lib.baseboard_fab2(sch_1):m_g_dq(21)") )
				( member ( signalRef "@baseboard_fab2_lib.baseboard_fab2(sch_1):m_g_dq(22)") )
				( member ( signalRef "@baseboard_fab2_lib.baseboard_fab2(sch_1):m_g_dq(23)") )
				( objectStatus "SNCLS_DDR4_CHN_G_DQ_DQS_BYTE2" )
			)
			( netClass "@sapphirecity_baseboard_lib.sapphirecity_baseboard(sch_1):\DDR4_CHN_G_DQ_DQS_BYTE3\"
				( memberType ( signal ) )
				( spacingCSetRef "@sapphirecity_baseboard_lib.sapphirecity_baseboard(sch_1):\10H_SL_12H_MS\" )
				( sameNetSpacingCSetRef "@crescent_city_bb_fab1_lib.crescent_city_bb_fab1(sch_1):\7H_US_AND_5H_SL\" )
				( objectFlag fObjectSpacing )
				( objectFlag fObjectSameNetSpacing )
				( member ( diffPairRef "@sapphirecity_baseboard_lib.sapphirecity_baseboard(sch_1):\M_G_DQS_D\(3)") )
				( member ( diffPairRef "@sapphirecity_baseboard_lib.sapphirecity_baseboard(sch_1):\M_G_DQS_D\(12)") )
				( member ( signalRef "@baseboard_fab2_lib.baseboard_fab2(sch_1):m_g_dq(24)") )
				( member ( signalRef "@baseboard_fab2_lib.baseboard_fab2(sch_1):m_g_dq(25)") )
				( member ( signalRef "@baseboard_fab2_lib.baseboard_fab2(sch_1):m_g_dq(26)") )
				( member ( signalRef "@baseboard_fab2_lib.baseboard_fab2(sch_1):m_g_dq(27)") )
				( member ( signalRef "@baseboard_fab2_lib.baseboard_fab2(sch_1):m_g_dq(28)") )
				( member ( signalRef "@baseboard_fab2_lib.baseboard_fab2(sch_1):m_g_dq(29)") )
				( member ( signalRef "@baseboard_fab2_lib.baseboard_fab2(sch_1):m_g_dq(30)") )
				( member ( signalRef "@baseboard_fab2_lib.baseboard_fab2(sch_1):m_g_dq(31)") )
				( objectStatus "SNCLS_DDR4_CHN_G_DQ_DQS_BYTE3" )
			)
			( netClass "@sapphirecity_baseboard_lib.sapphirecity_baseboard(sch_1):\DDR4_CHN_G_DQ_DQS_BYTE4\"
				( memberType ( signal ) )
				( spacingCSetRef "@sapphirecity_baseboard_lib.sapphirecity_baseboard(sch_1):\10H_SL_12H_MS\" )
				( sameNetSpacingCSetRef "@crescent_city_bb_fab1_lib.crescent_city_bb_fab1(sch_1):\7H_US_AND_5H_SL\" )
				( objectFlag fObjectSpacing )
				( objectFlag fObjectSameNetSpacing )
				( member ( diffPairRef "@sapphirecity_baseboard_lib.sapphirecity_baseboard(sch_1):\M_G_DQS_D\(4)") )
				( member ( diffPairRef "@sapphirecity_baseboard_lib.sapphirecity_baseboard(sch_1):\M_G_DQS_D\(13)") )
				( member ( signalRef "@baseboard_fab2_lib.baseboard_fab2(sch_1):m_g_dq(32)") )
				( member ( signalRef "@baseboard_fab2_lib.baseboard_fab2(sch_1):m_g_dq(33)") )
				( member ( signalRef "@baseboard_fab2_lib.baseboard_fab2(sch_1):m_g_dq(34)") )
				( member ( signalRef "@baseboard_fab2_lib.baseboard_fab2(sch_1):m_g_dq(35)") )
				( member ( signalRef "@baseboard_fab2_lib.baseboard_fab2(sch_1):m_g_dq(36)") )
				( member ( signalRef "@baseboard_fab2_lib.baseboard_fab2(sch_1):m_g_dq(37)") )
				( member ( signalRef "@baseboard_fab2_lib.baseboard_fab2(sch_1):m_g_dq(38)") )
				( member ( signalRef "@baseboard_fab2_lib.baseboard_fab2(sch_1):m_g_dq(39)") )
				( objectStatus "SNCLS_DDR4_CHN_G_DQ_DQS_BYTE4" )
			)
			( netClass "@sapphirecity_baseboard_lib.sapphirecity_baseboard(sch_1):\DDR4_CHN_G_DQ_DQS_BYTE5\"
				( memberType ( signal ) )
				( spacingCSetRef "@sapphirecity_baseboard_lib.sapphirecity_baseboard(sch_1):\10H_SL_12H_MS\" )
				( sameNetSpacingCSetRef "@crescent_city_bb_fab1_lib.crescent_city_bb_fab1(sch_1):\7H_US_AND_5H_SL\" )
				( objectFlag fObjectSpacing )
				( objectFlag fObjectSameNetSpacing )
				( member ( diffPairRef "@sapphirecity_baseboard_lib.sapphirecity_baseboard(sch_1):\M_G_DQS_D\(5)") )
				( member ( diffPairRef "@sapphirecity_baseboard_lib.sapphirecity_baseboard(sch_1):\M_G_DQS_D\(14)") )
				( member ( signalRef "@baseboard_fab2_lib.baseboard_fab2(sch_1):m_g_dq(40)") )
				( member ( signalRef "@baseboard_fab2_lib.baseboard_fab2(sch_1):m_g_dq(41)") )
				( member ( signalRef "@baseboard_fab2_lib.baseboard_fab2(sch_1):m_g_dq(42)") )
				( member ( signalRef "@baseboard_fab2_lib.baseboard_fab2(sch_1):m_g_dq(43)") )
				( member ( signalRef "@baseboard_fab2_lib.baseboard_fab2(sch_1):m_g_dq(44)") )
				( member ( signalRef "@baseboard_fab2_lib.baseboard_fab2(sch_1):m_g_dq(45)") )
				( member ( signalRef "@baseboard_fab2_lib.baseboard_fab2(sch_1):m_g_dq(46)") )
				( member ( signalRef "@baseboard_fab2_lib.baseboard_fab2(sch_1):m_g_dq(47)") )
				( objectStatus "SNCLS_DDR4_CHN_G_DQ_DQS_BYTE5" )
			)
			( netClass "@sapphirecity_baseboard_lib.sapphirecity_baseboard(sch_1):\DDR4_CHN_G_DQ_DQS_BYTE6\"
				( memberType ( signal ) )
				( spacingCSetRef "@sapphirecity_baseboard_lib.sapphirecity_baseboard(sch_1):\10H_SL_12H_MS\" )
				( sameNetSpacingCSetRef "@crescent_city_bb_fab1_lib.crescent_city_bb_fab1(sch_1):\7H_US_AND_5H_SL\" )
				( objectFlag fObjectSpacing )
				( objectFlag fObjectSameNetSpacing )
				( member ( diffPairRef "@sapphirecity_baseboard_lib.sapphirecity_baseboard(sch_1):\M_G_DQS_D\(6)") )
				( member ( diffPairRef "@sapphirecity_baseboard_lib.sapphirecity_baseboard(sch_1):\M_G_DQS_D\(15)") )
				( member ( signalRef "@baseboard_fab2_lib.baseboard_fab2(sch_1):m_g_dq(48)") )
				( member ( signalRef "@baseboard_fab2_lib.baseboard_fab2(sch_1):m_g_dq(49)") )
				( member ( signalRef "@baseboard_fab2_lib.baseboard_fab2(sch_1):m_g_dq(50)") )
				( member ( signalRef "@baseboard_fab2_lib.baseboard_fab2(sch_1):m_g_dq(51)") )
				( member ( signalRef "@baseboard_fab2_lib.baseboard_fab2(sch_1):m_g_dq(52)") )
				( member ( signalRef "@baseboard_fab2_lib.baseboard_fab2(sch_1):m_g_dq(53)") )
				( member ( signalRef "@baseboard_fab2_lib.baseboard_fab2(sch_1):m_g_dq(54)") )
				( member ( signalRef "@baseboard_fab2_lib.baseboard_fab2(sch_1):m_g_dq(55)") )
				( objectStatus "SNCLS_DDR4_CHN_G_DQ_DQS_BYTE6" )
			)
			( netClass "@sapphirecity_baseboard_lib.sapphirecity_baseboard(sch_1):\DDR4_CHN_G_DQ_DQS_BYTE7\"
				( memberType ( signal ) )
				( spacingCSetRef "@sapphirecity_baseboard_lib.sapphirecity_baseboard(sch_1):\10H_SL_12H_MS\" )
				( sameNetSpacingCSetRef "@crescent_city_bb_fab1_lib.crescent_city_bb_fab1(sch_1):\7H_US_AND_5H_SL\" )
				( objectFlag fObjectSpacing )
				( objectFlag fObjectSameNetSpacing )
				( member ( diffPairRef "@sapphirecity_baseboard_lib.sapphirecity_baseboard(sch_1):\M_G_DQS_D\(7)") )
				( member ( diffPairRef "@sapphirecity_baseboard_lib.sapphirecity_baseboard(sch_1):\M_G_DQS_D\(16)") )
				( member ( signalRef "@baseboard_fab2_lib.baseboard_fab2(sch_1):m_g_dq(56)") )
				( member ( signalRef "@baseboard_fab2_lib.baseboard_fab2(sch_1):m_g_dq(57)") )
				( member ( signalRef "@baseboard_fab2_lib.baseboard_fab2(sch_1):m_g_dq(58)") )
				( member ( signalRef "@baseboard_fab2_lib.baseboard_fab2(sch_1):m_g_dq(59)") )
				( member ( signalRef "@baseboard_fab2_lib.baseboard_fab2(sch_1):m_g_dq(60)") )
				( member ( signalRef "@baseboard_fab2_lib.baseboard_fab2(sch_1):m_g_dq(61)") )
				( member ( signalRef "@baseboard_fab2_lib.baseboard_fab2(sch_1):m_g_dq(62)") )
				( member ( signalRef "@baseboard_fab2_lib.baseboard_fab2(sch_1):m_g_dq(63)") )
				( objectStatus "SNCLS_DDR4_CHN_G_DQ_DQS_BYTE7" )
			)
			( netClass "@sapphirecity_baseboard_lib.sapphirecity_baseboard(sch_1):\DDR4_CHN_G_ECC\"
				( memberType ( signal ) )
				( spacingCSetRef "@sapphirecity_baseboard_lib.sapphirecity_baseboard(sch_1):\10H_SL_12H_MS\" )
				( sameNetSpacingCSetRef "@crescent_city_bb_fab1_lib.crescent_city_bb_fab1(sch_1):\7H_US_AND_5H_SL\" )
				( objectFlag fObjectSpacing )
				( objectFlag fObjectSameNetSpacing )
				( member ( diffPairRef "@sapphirecity_baseboard_lib.sapphirecity_baseboard(sch_1):\M_G_DQS_D\(8)") )
				( member ( diffPairRef "@sapphirecity_baseboard_lib.sapphirecity_baseboard(sch_1):\M_G_DQS_D\(17)") )
				( member ( signalRef "@baseboard_fab2_lib.baseboard_fab2(sch_1):m_g_ecc(0)") )
				( member ( signalRef "@baseboard_fab2_lib.baseboard_fab2(sch_1):m_g_ecc(1)") )
				( member ( signalRef "@baseboard_fab2_lib.baseboard_fab2(sch_1):m_g_ecc(2)") )
				( member ( signalRef "@baseboard_fab2_lib.baseboard_fab2(sch_1):m_g_ecc(3)") )
				( member ( signalRef "@baseboard_fab2_lib.baseboard_fab2(sch_1):m_g_ecc(4)") )
				( member ( signalRef "@baseboard_fab2_lib.baseboard_fab2(sch_1):m_g_ecc(5)") )
				( member ( signalRef "@baseboard_fab2_lib.baseboard_fab2(sch_1):m_g_ecc(6)") )
				( member ( signalRef "@baseboard_fab2_lib.baseboard_fab2(sch_1):m_g_ecc(7)") )
				( objectStatus "SNCLS_DDR4_CHN_G_ECC" )
			)
			( netClass "@sapphirecity_baseboard_lib.sapphirecity_baseboard(sch_1):\DDR4_CHN_H_DQ_DQS_BYTE0\"
				( memberType ( signal ) )
				( spacingCSetRef "@sapphirecity_baseboard_lib.sapphirecity_baseboard(sch_1):\10H_SL_12H_MS\" )
				( sameNetSpacingCSetRef "@crescent_city_bb_fab1_lib.crescent_city_bb_fab1(sch_1):\7H_US_AND_5H_SL\" )
				( objectFlag fObjectSpacing )
				( objectFlag fObjectSameNetSpacing )
				( member ( diffPairRef "@sapphirecity_baseboard_lib.sapphirecity_baseboard(sch_1):\M_H_DQS_D\(0)") )
				( member ( diffPairRef "@sapphirecity_baseboard_lib.sapphirecity_baseboard(sch_1):\M_H_DQS_D\(9)") )
				( member ( signalRef "@baseboard_fab2_lib.baseboard_fab2(sch_1):m_h_dq(0)") )
				( member ( signalRef "@baseboard_fab2_lib.baseboard_fab2(sch_1):m_h_dq(1)") )
				( member ( signalRef "@baseboard_fab2_lib.baseboard_fab2(sch_1):m_h_dq(2)") )
				( member ( signalRef "@baseboard_fab2_lib.baseboard_fab2(sch_1):m_h_dq(3)") )
				( member ( signalRef "@baseboard_fab2_lib.baseboard_fab2(sch_1):m_h_dq(4)") )
				( member ( signalRef "@baseboard_fab2_lib.baseboard_fab2(sch_1):m_h_dq(5)") )
				( member ( signalRef "@baseboard_fab2_lib.baseboard_fab2(sch_1):m_h_dq(6)") )
				( member ( signalRef "@baseboard_fab2_lib.baseboard_fab2(sch_1):m_h_dq(7)") )
				( objectStatus "SNCLS_DDR4_CHN_H_DQ_DQS_BYTE0" )
			)
			( netClass "@sapphirecity_baseboard_lib.sapphirecity_baseboard(sch_1):\DDR4_CHN_H_DQ_DQS_BYTE1\"
				( memberType ( signal ) )
				( spacingCSetRef "@sapphirecity_baseboard_lib.sapphirecity_baseboard(sch_1):\10H_SL_12H_MS\" )
				( sameNetSpacingCSetRef "@crescent_city_bb_fab1_lib.crescent_city_bb_fab1(sch_1):\7H_US_AND_5H_SL\" )
				( objectFlag fObjectSpacing )
				( objectFlag fObjectSameNetSpacing )
				( member ( diffPairRef "@sapphirecity_baseboard_lib.sapphirecity_baseboard(sch_1):\M_H_DQS_D\(1)") )
				( member ( diffPairRef "@sapphirecity_baseboard_lib.sapphirecity_baseboard(sch_1):\M_H_DQS_D\(10)") )
				( member ( signalRef "@baseboard_fab2_lib.baseboard_fab2(sch_1):m_h_dq(8)") )
				( member ( signalRef "@baseboard_fab2_lib.baseboard_fab2(sch_1):m_h_dq(9)") )
				( member ( signalRef "@baseboard_fab2_lib.baseboard_fab2(sch_1):m_h_dq(10)") )
				( member ( signalRef "@baseboard_fab2_lib.baseboard_fab2(sch_1):m_h_dq(11)") )
				( member ( signalRef "@baseboard_fab2_lib.baseboard_fab2(sch_1):m_h_dq(12)") )
				( member ( signalRef "@baseboard_fab2_lib.baseboard_fab2(sch_1):m_h_dq(13)") )
				( member ( signalRef "@baseboard_fab2_lib.baseboard_fab2(sch_1):m_h_dq(14)") )
				( member ( signalRef "@baseboard_fab2_lib.baseboard_fab2(sch_1):m_h_dq(15)") )
				( objectStatus "SNCLS_DDR4_CHN_H_DQ_DQS_BYTE1" )
			)
			( netClass "@sapphirecity_baseboard_lib.sapphirecity_baseboard(sch_1):\DDR4_CHN_H_DQ_DQS_BYTE2\"
				( memberType ( signal ) )
				( spacingCSetRef "@sapphirecity_baseboard_lib.sapphirecity_baseboard(sch_1):\10H_SL_12H_MS\" )
				( sameNetSpacingCSetRef "@crescent_city_bb_fab1_lib.crescent_city_bb_fab1(sch_1):\7H_US_AND_5H_SL\" )
				( objectFlag fObjectSpacing )
				( objectFlag fObjectSameNetSpacing )
				( member ( diffPairRef "@sapphirecity_baseboard_lib.sapphirecity_baseboard(sch_1):\M_H_DQS_D\(2)") )
				( member ( diffPairRef "@sapphirecity_baseboard_lib.sapphirecity_baseboard(sch_1):\M_H_DQS_D\(11)") )
				( member ( signalRef "@baseboard_fab2_lib.baseboard_fab2(sch_1):m_h_dq(16)") )
				( member ( signalRef "@baseboard_fab2_lib.baseboard_fab2(sch_1):m_h_dq(17)") )
				( member ( signalRef "@baseboard_fab2_lib.baseboard_fab2(sch_1):m_h_dq(18)") )
				( member ( signalRef "@baseboard_fab2_lib.baseboard_fab2(sch_1):m_h_dq(19)") )
				( member ( signalRef "@baseboard_fab2_lib.baseboard_fab2(sch_1):m_h_dq(20)") )
				( member ( signalRef "@baseboard_fab2_lib.baseboard_fab2(sch_1):m_h_dq(21)") )
				( member ( signalRef "@baseboard_fab2_lib.baseboard_fab2(sch_1):m_h_dq(22)") )
				( member ( signalRef "@baseboard_fab2_lib.baseboard_fab2(sch_1):m_h_dq(23)") )
				( objectStatus "SNCLS_DDR4_CHN_H_DQ_DQS_BYTE2" )
			)
			( netClass "@sapphirecity_baseboard_lib.sapphirecity_baseboard(sch_1):\DDR4_CHN_H_DQ_DQS_BYTE3\"
				( memberType ( signal ) )
				( spacingCSetRef "@sapphirecity_baseboard_lib.sapphirecity_baseboard(sch_1):\10H_SL_12H_MS\" )
				( sameNetSpacingCSetRef "@crescent_city_bb_fab1_lib.crescent_city_bb_fab1(sch_1):\7H_US_AND_5H_SL\" )
				( objectFlag fObjectSpacing )
				( objectFlag fObjectSameNetSpacing )
				( member ( diffPairRef "@sapphirecity_baseboard_lib.sapphirecity_baseboard(sch_1):\M_H_DQS_D\(3)") )
				( member ( diffPairRef "@sapphirecity_baseboard_lib.sapphirecity_baseboard(sch_1):\M_H_DQS_D\(12)") )
				( member ( signalRef "@baseboard_fab2_lib.baseboard_fab2(sch_1):m_h_dq(24)") )
				( member ( signalRef "@baseboard_fab2_lib.baseboard_fab2(sch_1):m_h_dq(25)") )
				( member ( signalRef "@baseboard_fab2_lib.baseboard_fab2(sch_1):m_h_dq(26)") )
				( member ( signalRef "@baseboard_fab2_lib.baseboard_fab2(sch_1):m_h_dq(27)") )
				( member ( signalRef "@baseboard_fab2_lib.baseboard_fab2(sch_1):m_h_dq(28)") )
				( member ( signalRef "@baseboard_fab2_lib.baseboard_fab2(sch_1):m_h_dq(29)") )
				( member ( signalRef "@baseboard_fab2_lib.baseboard_fab2(sch_1):m_h_dq(30)") )
				( member ( signalRef "@baseboard_fab2_lib.baseboard_fab2(sch_1):m_h_dq(31)") )
				( objectStatus "SNCLS_DDR4_CHN_H_DQ_DQS_BYTE3" )
			)
			( netClass "@sapphirecity_baseboard_lib.sapphirecity_baseboard(sch_1):\DDR4_CHN_H_DQ_DQS_BYTE4\"
				( memberType ( signal ) )
				( spacingCSetRef "@sapphirecity_baseboard_lib.sapphirecity_baseboard(sch_1):\10H_SL_12H_MS\" )
				( sameNetSpacingCSetRef "@crescent_city_bb_fab1_lib.crescent_city_bb_fab1(sch_1):\7H_US_AND_5H_SL\" )
				( objectFlag fObjectSpacing )
				( objectFlag fObjectSameNetSpacing )
				( member ( diffPairRef "@sapphirecity_baseboard_lib.sapphirecity_baseboard(sch_1):\M_H_DQS_D\(4)") )
				( member ( diffPairRef "@sapphirecity_baseboard_lib.sapphirecity_baseboard(sch_1):\M_H_DQS_D\(13)") )
				( member ( signalRef "@baseboard_fab2_lib.baseboard_fab2(sch_1):m_h_dq(32)") )
				( member ( signalRef "@baseboard_fab2_lib.baseboard_fab2(sch_1):m_h_dq(33)") )
				( member ( signalRef "@baseboard_fab2_lib.baseboard_fab2(sch_1):m_h_dq(34)") )
				( member ( signalRef "@baseboard_fab2_lib.baseboard_fab2(sch_1):m_h_dq(35)") )
				( member ( signalRef "@baseboard_fab2_lib.baseboard_fab2(sch_1):m_h_dq(36)") )
				( member ( signalRef "@baseboard_fab2_lib.baseboard_fab2(sch_1):m_h_dq(37)") )
				( member ( signalRef "@baseboard_fab2_lib.baseboard_fab2(sch_1):m_h_dq(38)") )
				( member ( signalRef "@baseboard_fab2_lib.baseboard_fab2(sch_1):m_h_dq(39)") )
				( objectStatus "SNCLS_DDR4_CHN_H_DQ_DQS_BYTE4" )
			)
			( netClass "@sapphirecity_baseboard_lib.sapphirecity_baseboard(sch_1):\DDR4_CHN_H_DQ_DQS_BYTE5\"
				( memberType ( signal ) )
				( spacingCSetRef "@sapphirecity_baseboard_lib.sapphirecity_baseboard(sch_1):\10H_SL_12H_MS\" )
				( sameNetSpacingCSetRef "@crescent_city_bb_fab1_lib.crescent_city_bb_fab1(sch_1):\7H_US_AND_5H_SL\" )
				( objectFlag fObjectSpacing )
				( objectFlag fObjectSameNetSpacing )
				( member ( diffPairRef "@sapphirecity_baseboard_lib.sapphirecity_baseboard(sch_1):\M_H_DQS_D\(5)") )
				( member ( diffPairRef "@sapphirecity_baseboard_lib.sapphirecity_baseboard(sch_1):\M_H_DQS_D\(14)") )
				( member ( signalRef "@baseboard_fab2_lib.baseboard_fab2(sch_1):m_h_dq(40)") )
				( member ( signalRef "@baseboard_fab2_lib.baseboard_fab2(sch_1):m_h_dq(41)") )
				( member ( signalRef "@baseboard_fab2_lib.baseboard_fab2(sch_1):m_h_dq(42)") )
				( member ( signalRef "@baseboard_fab2_lib.baseboard_fab2(sch_1):m_h_dq(43)") )
				( member ( signalRef "@baseboard_fab2_lib.baseboard_fab2(sch_1):m_h_dq(44)") )
				( member ( signalRef "@baseboard_fab2_lib.baseboard_fab2(sch_1):m_h_dq(45)") )
				( member ( signalRef "@baseboard_fab2_lib.baseboard_fab2(sch_1):m_h_dq(46)") )
				( member ( signalRef "@baseboard_fab2_lib.baseboard_fab2(sch_1):m_h_dq(47)") )
				( objectStatus "SNCLS_DDR4_CHN_H_DQ_DQS_BYTE5" )
			)
			( netClass "@sapphirecity_baseboard_lib.sapphirecity_baseboard(sch_1):\DDR4_CHN_H_DQ_DQS_BYTE6\"
				( memberType ( signal ) )
				( spacingCSetRef "@sapphirecity_baseboard_lib.sapphirecity_baseboard(sch_1):\10H_SL_12H_MS\" )
				( sameNetSpacingCSetRef "@crescent_city_bb_fab1_lib.crescent_city_bb_fab1(sch_1):\7H_US_AND_5H_SL\" )
				( objectFlag fObjectSpacing )
				( objectFlag fObjectSameNetSpacing )
				( member ( diffPairRef "@sapphirecity_baseboard_lib.sapphirecity_baseboard(sch_1):\M_H_DQS_D\(6)") )
				( member ( diffPairRef "@sapphirecity_baseboard_lib.sapphirecity_baseboard(sch_1):\M_H_DQS_D\(15)") )
				( member ( signalRef "@baseboard_fab2_lib.baseboard_fab2(sch_1):m_h_dq(48)") )
				( member ( signalRef "@baseboard_fab2_lib.baseboard_fab2(sch_1):m_h_dq(49)") )
				( member ( signalRef "@baseboard_fab2_lib.baseboard_fab2(sch_1):m_h_dq(50)") )
				( member ( signalRef "@baseboard_fab2_lib.baseboard_fab2(sch_1):m_h_dq(51)") )
				( member ( signalRef "@baseboard_fab2_lib.baseboard_fab2(sch_1):m_h_dq(52)") )
				( member ( signalRef "@baseboard_fab2_lib.baseboard_fab2(sch_1):m_h_dq(53)") )
				( member ( signalRef "@baseboard_fab2_lib.baseboard_fab2(sch_1):m_h_dq(54)") )
				( member ( signalRef "@baseboard_fab2_lib.baseboard_fab2(sch_1):m_h_dq(55)") )
				( objectStatus "SNCLS_DDR4_CHN_H_DQ_DQS_BYTE6" )
			)
			( netClass "@sapphirecity_baseboard_lib.sapphirecity_baseboard(sch_1):\DDR4_CHN_H_DQ_DQS_BYTE7\"
				( memberType ( signal ) )
				( spacingCSetRef "@sapphirecity_baseboard_lib.sapphirecity_baseboard(sch_1):\10H_SL_12H_MS\" )
				( sameNetSpacingCSetRef "@crescent_city_bb_fab1_lib.crescent_city_bb_fab1(sch_1):\7H_US_AND_5H_SL\" )
				( objectFlag fObjectSpacing )
				( objectFlag fObjectSameNetSpacing )
				( member ( diffPairRef "@sapphirecity_baseboard_lib.sapphirecity_baseboard(sch_1):\M_H_DQS_D\(7)") )
				( member ( diffPairRef "@sapphirecity_baseboard_lib.sapphirecity_baseboard(sch_1):\M_H_DQS_D\(16)") )
				( member ( signalRef "@baseboard_fab2_lib.baseboard_fab2(sch_1):m_h_dq(56)") )
				( member ( signalRef "@baseboard_fab2_lib.baseboard_fab2(sch_1):m_h_dq(57)") )
				( member ( signalRef "@baseboard_fab2_lib.baseboard_fab2(sch_1):m_h_dq(58)") )
				( member ( signalRef "@baseboard_fab2_lib.baseboard_fab2(sch_1):m_h_dq(59)") )
				( member ( signalRef "@baseboard_fab2_lib.baseboard_fab2(sch_1):m_h_dq(60)") )
				( member ( signalRef "@baseboard_fab2_lib.baseboard_fab2(sch_1):m_h_dq(61)") )
				( member ( signalRef "@baseboard_fab2_lib.baseboard_fab2(sch_1):m_h_dq(62)") )
				( member ( signalRef "@baseboard_fab2_lib.baseboard_fab2(sch_1):m_h_dq(63)") )
				( objectStatus "SNCLS_DDR4_CHN_H_DQ_DQS_BYTE7" )
			)
			( netClass "@sapphirecity_baseboard_lib.sapphirecity_baseboard(sch_1):\DDR4_CHN_H_ECC\"
				( memberType ( signal ) )
				( spacingCSetRef "@sapphirecity_baseboard_lib.sapphirecity_baseboard(sch_1):\10H_SL_12H_MS\" )
				( sameNetSpacingCSetRef "@crescent_city_bb_fab1_lib.crescent_city_bb_fab1(sch_1):\7H_US_AND_5H_SL\" )
				( objectFlag fObjectSpacing )
				( objectFlag fObjectSameNetSpacing )
				( member ( diffPairRef "@sapphirecity_baseboard_lib.sapphirecity_baseboard(sch_1):\M_H_DQS_D\(8)") )
				( member ( diffPairRef "@sapphirecity_baseboard_lib.sapphirecity_baseboard(sch_1):\M_H_DQS_D\(17)") )
				( member ( signalRef "@baseboard_fab2_lib.baseboard_fab2(sch_1):m_h_ecc(0)") )
				( member ( signalRef "@baseboard_fab2_lib.baseboard_fab2(sch_1):m_h_ecc(1)") )
				( member ( signalRef "@baseboard_fab2_lib.baseboard_fab2(sch_1):m_h_ecc(2)") )
				( member ( signalRef "@baseboard_fab2_lib.baseboard_fab2(sch_1):m_h_ecc(3)") )
				( member ( signalRef "@baseboard_fab2_lib.baseboard_fab2(sch_1):m_h_ecc(4)") )
				( member ( signalRef "@baseboard_fab2_lib.baseboard_fab2(sch_1):m_h_ecc(5)") )
				( member ( signalRef "@baseboard_fab2_lib.baseboard_fab2(sch_1):m_h_ecc(6)") )
				( member ( signalRef "@baseboard_fab2_lib.baseboard_fab2(sch_1):m_h_ecc(7)") )
				( objectStatus "SNCLS_DDR4_CHN_H_ECC" )
			)
			( netClass "@sapphirecity_baseboard_lib.sapphirecity_baseboard(sch_1):\DDR4_CHN_D_DQ_DQS_BYTE7\"
				( memberType ( signal ) )
				( spacingCSetRef "@sapphirecity_baseboard_lib.sapphirecity_baseboard(sch_1):\10H_SL_12H_MS\" )
				( sameNetSpacingCSetRef "@crescent_city_bb_fab1_lib.crescent_city_bb_fab1(sch_1):\7H_US_AND_5H_SL\" )
				( objectFlag fObjectSpacing )
				( objectFlag fObjectSameNetSpacing )
				( member ( diffPairRef "@sapphirecity_baseboard_lib.sapphirecity_baseboard(sch_1):\M_D_DQS_D\(7)") )
				( member ( diffPairRef "@sapphirecity_baseboard_lib.sapphirecity_baseboard(sch_1):\M_D_DQS_D\(16)") )
				( member ( signalRef "@baseboard_fab2_lib.baseboard_fab2(sch_1):m_d_dq(56)") )
				( member ( signalRef "@baseboard_fab2_lib.baseboard_fab2(sch_1):m_d_dq(57)") )
				( member ( signalRef "@baseboard_fab2_lib.baseboard_fab2(sch_1):m_d_dq(58)") )
				( member ( signalRef "@baseboard_fab2_lib.baseboard_fab2(sch_1):m_d_dq(59)") )
				( member ( signalRef "@baseboard_fab2_lib.baseboard_fab2(sch_1):m_d_dq(60)") )
				( member ( signalRef "@baseboard_fab2_lib.baseboard_fab2(sch_1):m_d_dq(61)") )
				( member ( signalRef "@baseboard_fab2_lib.baseboard_fab2(sch_1):m_d_dq(62)") )
				( member ( signalRef "@baseboard_fab2_lib.baseboard_fab2(sch_1):m_d_dq(63)") )
				( objectStatus "SNCLS_DDR4_CHN_D_DQ_DQS_BYTE7" )
			)
			( netClass "@sapphirecity_baseboard_lib.sapphirecity_baseboard(sch_1):\DDR4_CHN_D_DQ_DQS_BYTE6\"
				( memberType ( signal ) )
				( spacingCSetRef "@sapphirecity_baseboard_lib.sapphirecity_baseboard(sch_1):\10H_SL_12H_MS\" )
				( sameNetSpacingCSetRef "@crescent_city_bb_fab1_lib.crescent_city_bb_fab1(sch_1):\7H_US_AND_5H_SL\" )
				( objectFlag fObjectSpacing )
				( objectFlag fObjectSameNetSpacing )
				( member ( diffPairRef "@sapphirecity_baseboard_lib.sapphirecity_baseboard(sch_1):\M_D_DQS_D\(6)") )
				( member ( diffPairRef "@sapphirecity_baseboard_lib.sapphirecity_baseboard(sch_1):\M_D_DQS_D\(15)") )
				( member ( signalRef "@baseboard_fab2_lib.baseboard_fab2(sch_1):m_d_dq(48)") )
				( member ( signalRef "@baseboard_fab2_lib.baseboard_fab2(sch_1):m_d_dq(49)") )
				( member ( signalRef "@baseboard_fab2_lib.baseboard_fab2(sch_1):m_d_dq(50)") )
				( member ( signalRef "@baseboard_fab2_lib.baseboard_fab2(sch_1):m_d_dq(51)") )
				( member ( signalRef "@baseboard_fab2_lib.baseboard_fab2(sch_1):m_d_dq(52)") )
				( member ( signalRef "@baseboard_fab2_lib.baseboard_fab2(sch_1):m_d_dq(53)") )
				( member ( signalRef "@baseboard_fab2_lib.baseboard_fab2(sch_1):m_d_dq(54)") )
				( member ( signalRef "@baseboard_fab2_lib.baseboard_fab2(sch_1):m_d_dq(55)") )
				( objectStatus "SNCLS_DDR4_CHN_D_DQ_DQS_BYTE6" )
			)
			( netClass "@sapphirecity_baseboard_lib.sapphirecity_baseboard(sch_1):\DDR4_CHN_D_DQ_DQS_BYTE4\"
				( memberType ( signal ) )
				( spacingCSetRef "@sapphirecity_baseboard_lib.sapphirecity_baseboard(sch_1):\10H_SL_12H_MS\" )
				( sameNetSpacingCSetRef "@crescent_city_bb_fab1_lib.crescent_city_bb_fab1(sch_1):\7H_US_AND_5H_SL\" )
				( objectFlag fObjectSpacing )
				( objectFlag fObjectSameNetSpacing )
				( member ( diffPairRef "@sapphirecity_baseboard_lib.sapphirecity_baseboard(sch_1):\M_D_DQS_D\(4)") )
				( member ( diffPairRef "@sapphirecity_baseboard_lib.sapphirecity_baseboard(sch_1):\M_D_DQS_D\(13)") )
				( member ( signalRef "@baseboard_fab2_lib.baseboard_fab2(sch_1):m_d_dq(32)") )
				( member ( signalRef "@baseboard_fab2_lib.baseboard_fab2(sch_1):m_d_dq(33)") )
				( member ( signalRef "@baseboard_fab2_lib.baseboard_fab2(sch_1):m_d_dq(34)") )
				( member ( signalRef "@baseboard_fab2_lib.baseboard_fab2(sch_1):m_d_dq(35)") )
				( member ( signalRef "@baseboard_fab2_lib.baseboard_fab2(sch_1):m_d_dq(36)") )
				( member ( signalRef "@baseboard_fab2_lib.baseboard_fab2(sch_1):m_d_dq(37)") )
				( member ( signalRef "@baseboard_fab2_lib.baseboard_fab2(sch_1):m_d_dq(38)") )
				( member ( signalRef "@baseboard_fab2_lib.baseboard_fab2(sch_1):m_d_dq(39)") )
				( objectStatus "SNCLS_DDR4_CHN_D_DQ_DQS_BYTE4" )
			)
			( netClass "@sapphirecity_baseboard_lib.sapphirecity_baseboard(sch_1):\DDR4_CHN_D_DQ_DQS_BYTE3\"
				( memberType ( signal ) )
				( spacingCSetRef "@sapphirecity_baseboard_lib.sapphirecity_baseboard(sch_1):\10H_SL_12H_MS\" )
				( sameNetSpacingCSetRef "@crescent_city_bb_fab1_lib.crescent_city_bb_fab1(sch_1):\7H_US_AND_5H_SL\" )
				( objectFlag fObjectSpacing )
				( objectFlag fObjectSameNetSpacing )
				( member ( diffPairRef "@sapphirecity_baseboard_lib.sapphirecity_baseboard(sch_1):\M_D_DQS_D\(3)") )
				( member ( diffPairRef "@sapphirecity_baseboard_lib.sapphirecity_baseboard(sch_1):\M_D_DQS_D\(12)") )
				( member ( signalRef "@baseboard_fab2_lib.baseboard_fab2(sch_1):m_d_dq(24)") )
				( member ( signalRef "@baseboard_fab2_lib.baseboard_fab2(sch_1):m_d_dq(25)") )
				( member ( signalRef "@baseboard_fab2_lib.baseboard_fab2(sch_1):m_d_dq(26)") )
				( member ( signalRef "@baseboard_fab2_lib.baseboard_fab2(sch_1):m_d_dq(27)") )
				( member ( signalRef "@baseboard_fab2_lib.baseboard_fab2(sch_1):m_d_dq(28)") )
				( member ( signalRef "@baseboard_fab2_lib.baseboard_fab2(sch_1):m_d_dq(29)") )
				( member ( signalRef "@baseboard_fab2_lib.baseboard_fab2(sch_1):m_d_dq(30)") )
				( member ( signalRef "@baseboard_fab2_lib.baseboard_fab2(sch_1):m_d_dq(31)") )
				( objectStatus "SNCLS_DDR4_CHN_D_DQ_DQS_BYTE3" )
			)
			( netClass "@sapphirecity_baseboard_lib.sapphirecity_baseboard(sch_1):\DDR4_CHN_D_DQ_DQS_BYTE2\"
				( memberType ( signal ) )
				( spacingCSetRef "@sapphirecity_baseboard_lib.sapphirecity_baseboard(sch_1):\10H_SL_12H_MS\" )
				( sameNetSpacingCSetRef "@crescent_city_bb_fab1_lib.crescent_city_bb_fab1(sch_1):\7H_US_AND_5H_SL\" )
				( objectFlag fObjectSpacing )
				( objectFlag fObjectSameNetSpacing )
				( member ( diffPairRef "@sapphirecity_baseboard_lib.sapphirecity_baseboard(sch_1):\M_D_DQS_D\(2)") )
				( member ( diffPairRef "@sapphirecity_baseboard_lib.sapphirecity_baseboard(sch_1):\M_D_DQS_D\(11)") )
				( member ( signalRef "@baseboard_fab2_lib.baseboard_fab2(sch_1):m_d_dq(16)") )
				( member ( signalRef "@baseboard_fab2_lib.baseboard_fab2(sch_1):m_d_dq(17)") )
				( member ( signalRef "@baseboard_fab2_lib.baseboard_fab2(sch_1):m_d_dq(18)") )
				( member ( signalRef "@baseboard_fab2_lib.baseboard_fab2(sch_1):m_d_dq(19)") )
				( member ( signalRef "@baseboard_fab2_lib.baseboard_fab2(sch_1):m_d_dq(20)") )
				( member ( signalRef "@baseboard_fab2_lib.baseboard_fab2(sch_1):m_d_dq(21)") )
				( member ( signalRef "@baseboard_fab2_lib.baseboard_fab2(sch_1):m_d_dq(22)") )
				( member ( signalRef "@baseboard_fab2_lib.baseboard_fab2(sch_1):m_d_dq(23)") )
				( objectStatus "SNCLS_DDR4_CHN_D_DQ_DQS_BYTE2" )
			)
			( netClass "@sapphirecity_baseboard_lib.sapphirecity_baseboard(sch_1):\DDR4_CHN_D_DQ_DQS_BYTE1\"
				( memberType ( signal ) )
				( spacingCSetRef "@sapphirecity_baseboard_lib.sapphirecity_baseboard(sch_1):\10H_SL_12H_MS\" )
				( sameNetSpacingCSetRef "@crescent_city_bb_fab1_lib.crescent_city_bb_fab1(sch_1):\7H_US_AND_5H_SL\" )
				( objectFlag fObjectSpacing )
				( objectFlag fObjectSameNetSpacing )
				( member ( diffPairRef "@sapphirecity_baseboard_lib.sapphirecity_baseboard(sch_1):\M_D_DQS_D\(1)") )
				( member ( diffPairRef "@sapphirecity_baseboard_lib.sapphirecity_baseboard(sch_1):\M_D_DQS_D\(10)") )
				( member ( signalRef "@baseboard_fab2_lib.baseboard_fab2(sch_1):m_d_dq(8)") )
				( member ( signalRef "@baseboard_fab2_lib.baseboard_fab2(sch_1):m_d_dq(9)") )
				( member ( signalRef "@baseboard_fab2_lib.baseboard_fab2(sch_1):m_d_dq(10)") )
				( member ( signalRef "@baseboard_fab2_lib.baseboard_fab2(sch_1):m_d_dq(11)") )
				( member ( signalRef "@baseboard_fab2_lib.baseboard_fab2(sch_1):m_d_dq(12)") )
				( member ( signalRef "@baseboard_fab2_lib.baseboard_fab2(sch_1):m_d_dq(13)") )
				( member ( signalRef "@baseboard_fab2_lib.baseboard_fab2(sch_1):m_d_dq(14)") )
				( member ( signalRef "@baseboard_fab2_lib.baseboard_fab2(sch_1):m_d_dq(15)") )
				( objectStatus "SNCLS_DDR4_CHN_D_DQ_DQS_BYTE1" )
			)
			( netClass "@sapphirecity_baseboard_lib.sapphirecity_baseboard(sch_1):\DDR4_CHN_J_CLK\"
				( memberType ( signal ) )
				( spacingCSetRef "@crescent_city_bb_fab1_lib.crescent_city_bb_fab1(sch_1):\8P9_US_&_6H_SL\" )
				( sameNetSpacingCSetRef "@crescent_city_bb_fab1_lib.crescent_city_bb_fab1(sch_1):\7H_US_AND_5H_SL\" )
				( objectFlag fObjectSpacing )
				( objectFlag fObjectSameNetSpacing )
				( member ( diffPairRef "@sapphirecity_baseboard_lib.sapphirecity_baseboard(sch_1):\M_J_CLK_D\(0)") )
				( member ( diffPairRef "@sapphirecity_baseboard_lib.sapphirecity_baseboard(sch_1):\M_J_CLK_D\(2)") )
				( member ( diffPairRef "@crescent_city_bb_fab1_lib.crescent_city_bb_fab1(sch_1):\DP_M_J_CLK\(1)") )
				( member ( diffPairRef "@crescent_city_bb_fab1_lib.crescent_city_bb_fab1(sch_1):\DP_M_J_CLK\(3)") )
				( objectStatus "SNCLS_DDR4_CHN_J_CLK" )
			)
			( netClass "@sapphirecity_baseboard_lib.sapphirecity_baseboard(sch_1):\DDR4_CHN_J_CMD_ADD\"
				( memberType ( signal ) )
				( spacingCSetRef "@crescent_city_bb_fab1_lib.crescent_city_bb_fab1(sch_1):\8P9_US_&_6H_SL\" )
				( sameNetSpacingCSetRef "@crescent_city_bb_fab1_lib.crescent_city_bb_fab1(sch_1):\7H_US_AND_5H_SL\" )
				( objectFlag fObjectSpacing )
				( objectFlag fObjectSameNetSpacing )
				( member ( signalRef "@baseboard_fab2_lib.baseboard_fab2(sch_1):m_j_act_n") )
				( member ( signalRef "@baseboard_fab2_lib.baseboard_fab2(sch_1):m_j_c(2)") )
				( member ( signalRef "@baseboard_fab2_lib.baseboard_fab2(sch_1):m_j_par") )
				( member ( signalRef "@baseboard_fab2_lib.baseboard_fab2(sch_1):m_j_ba(0)") )
				( member ( signalRef "@baseboard_fab2_lib.baseboard_fab2(sch_1):m_j_ba(1)") )
				( member ( signalRef "@baseboard_fab2_lib.baseboard_fab2(sch_1):m_j_bg(0)") )
				( member ( signalRef "@baseboard_fab2_lib.baseboard_fab2(sch_1):m_j_bg(1)") )
				( member ( signalRef "@baseboard_fab2_lib.baseboard_fab2(sch_1):m_j_ma(0)") )
				( member ( signalRef "@baseboard_fab2_lib.baseboard_fab2(sch_1):m_j_ma(1)") )
				( member ( signalRef "@baseboard_fab2_lib.baseboard_fab2(sch_1):m_j_ma(2)") )
				( member ( signalRef "@baseboard_fab2_lib.baseboard_fab2(sch_1):m_j_ma(3)") )
				( member ( signalRef "@baseboard_fab2_lib.baseboard_fab2(sch_1):m_j_ma(4)") )
				( member ( signalRef "@baseboard_fab2_lib.baseboard_fab2(sch_1):m_j_ma(5)") )
				( member ( signalRef "@baseboard_fab2_lib.baseboard_fab2(sch_1):m_j_ma(6)") )
				( member ( signalRef "@baseboard_fab2_lib.baseboard_fab2(sch_1):m_j_ma(7)") )
				( member ( signalRef "@baseboard_fab2_lib.baseboard_fab2(sch_1):m_j_ma(8)") )
				( member ( signalRef "@baseboard_fab2_lib.baseboard_fab2(sch_1):m_j_ma(9)") )
				( member ( signalRef "@baseboard_fab2_lib.baseboard_fab2(sch_1):m_j_ma(10)") )
				( member ( signalRef "@baseboard_fab2_lib.baseboard_fab2(sch_1):m_j_ma(11)") )
				( member ( signalRef "@baseboard_fab2_lib.baseboard_fab2(sch_1):m_j_ma(12)") )
				( member ( signalRef "@baseboard_fab2_lib.baseboard_fab2(sch_1):m_j_ma(13)") )
				( member ( signalRef "@baseboard_fab2_lib.baseboard_fab2(sch_1):m_j_ma(14)") )
				( member ( signalRef "@baseboard_fab2_lib.baseboard_fab2(sch_1):m_j_ma(15)") )
				( member ( signalRef "@baseboard_fab2_lib.baseboard_fab2(sch_1):m_j_ma(16)") )
				( member ( signalRef "@baseboard_fab2_lib.baseboard_fab2(sch_1):m_j_ma(17)") )
				( objectStatus "SNCLS_DDR4_CHN_J_CMD_ADD" )
			)
			( netClass "@sapphirecity_baseboard_lib.sapphirecity_baseboard(sch_1):\DDR4_CHN_J_CTRL\"
				( memberType ( signal ) )
				( spacingCSetRef "@crescent_city_bb_fab1_lib.crescent_city_bb_fab1(sch_1):\8P9_US_&_6H_SL\" )
				( sameNetSpacingCSetRef "@crescent_city_bb_fab1_lib.crescent_city_bb_fab1(sch_1):\7H_US_AND_5H_SL\" )
				( objectFlag fObjectSpacing )
				( objectFlag fObjectSameNetSpacing )
				( member ( signalRef "@baseboard_fab2_lib.baseboard_fab2(sch_1):m_j_cke(0)") )
				( member ( signalRef "@baseboard_fab2_lib.baseboard_fab2(sch_1):m_j_cke(1)") )
				( member ( signalRef "@baseboard_fab2_lib.baseboard_fab2(sch_1):m_j_cs_n(0)") )
				( member ( signalRef "@baseboard_fab2_lib.baseboard_fab2(sch_1):m_j_cs_n(1)") )
				( member ( signalRef "@baseboard_fab2_lib.baseboard_fab2(sch_1):m_j_cs_n(2)") )
				( member ( signalRef "@baseboard_fab2_lib.baseboard_fab2(sch_1):m_j_cs_n(3)") )
				( member ( signalRef "@baseboard_fab2_lib.baseboard_fab2(sch_1):m_j_odt(0)") )
				( member ( signalRef "@baseboard_fab2_lib.baseboard_fab2(sch_1):m_j_odt(1)") )
				( member ( signalRef "@baseboard_fab2_lib.baseboard_fab2(sch_1):m_j_alert_n") )
				( member ( signalRef "@baseboard_fab2_lib.baseboard_fab2(sch_1):m_j_cke(2)") )
				( member ( signalRef "@baseboard_fab2_lib.baseboard_fab2(sch_1):m_j_cke(3)") )
				( member ( signalRef "@baseboard_fab2_lib.baseboard_fab2(sch_1):m_j_cs_n(4)") )
				( member ( signalRef "@baseboard_fab2_lib.baseboard_fab2(sch_1):m_j_cs_n(5)") )
				( member ( signalRef "@baseboard_fab2_lib.baseboard_fab2(sch_1):m_j_cs_n(6)") )
				( member ( signalRef "@baseboard_fab2_lib.baseboard_fab2(sch_1):m_j_cs_n(7)") )
				( member ( signalRef "@baseboard_fab2_lib.baseboard_fab2(sch_1):m_j_odt(2)") )
				( member ( signalRef "@baseboard_fab2_lib.baseboard_fab2(sch_1):m_j_odt(3)") )
				( objectStatus "SNCLS_DDR4_CHN_J_CTRL" )
			)
			( netClass "@sapphirecity_baseboard_lib.sapphirecity_baseboard(sch_1):\DDR4_CHN_K_CLK\"
				( memberType ( signal ) )
				( spacingCSetRef "@crescent_city_bb_fab1_lib.crescent_city_bb_fab1(sch_1):\8P9_US_&_6H_SL\" )
				( sameNetSpacingCSetRef "@crescent_city_bb_fab1_lib.crescent_city_bb_fab1(sch_1):\7H_US_AND_5H_SL\" )
				( objectFlag fObjectSpacing )
				( objectFlag fObjectSameNetSpacing )
				( member ( diffPairRef "@sapphirecity_baseboard_lib.sapphirecity_baseboard(sch_1):\M_K_CLK_D\(0)") )
				( member ( diffPairRef "@sapphirecity_baseboard_lib.sapphirecity_baseboard(sch_1):\M_K_CLK_D\(2)") )
				( member ( diffPairRef "@crescent_city_bb_fab1_lib.crescent_city_bb_fab1(sch_1):\DP_M_K_CLK\(1)") )
				( member ( diffPairRef "@crescent_city_bb_fab1_lib.crescent_city_bb_fab1(sch_1):\DP_M_K_CLK\(3)") )
				( objectStatus "SNCLS_DDR4_CHN_K_CLK" )
			)
			( netClass "@sapphirecity_baseboard_lib.sapphirecity_baseboard(sch_1):\DDR4_CHN_K_CMD_ADD\"
				( memberType ( signal ) )
				( spacingCSetRef "@crescent_city_bb_fab1_lib.crescent_city_bb_fab1(sch_1):\8P9_US_&_6H_SL\" )
				( sameNetSpacingCSetRef "@crescent_city_bb_fab1_lib.crescent_city_bb_fab1(sch_1):\7H_US_AND_5H_SL\" )
				( objectFlag fObjectSpacing )
				( objectFlag fObjectSameNetSpacing )
				( member ( signalRef "@baseboard_fab2_lib.baseboard_fab2(sch_1):m_k_act_n") )
				( member ( signalRef "@baseboard_fab2_lib.baseboard_fab2(sch_1):m_k_c(2)") )
				( member ( signalRef "@baseboard_fab2_lib.baseboard_fab2(sch_1):m_k_par") )
				( member ( signalRef "@baseboard_fab2_lib.baseboard_fab2(sch_1):m_k_ba(0)") )
				( member ( signalRef "@baseboard_fab2_lib.baseboard_fab2(sch_1):m_k_ba(1)") )
				( member ( signalRef "@baseboard_fab2_lib.baseboard_fab2(sch_1):m_k_bg(0)") )
				( member ( signalRef "@baseboard_fab2_lib.baseboard_fab2(sch_1):m_k_bg(1)") )
				( member ( signalRef "@baseboard_fab2_lib.baseboard_fab2(sch_1):m_k_ma(0)") )
				( member ( signalRef "@baseboard_fab2_lib.baseboard_fab2(sch_1):m_k_ma(1)") )
				( member ( signalRef "@baseboard_fab2_lib.baseboard_fab2(sch_1):m_k_ma(2)") )
				( member ( signalRef "@baseboard_fab2_lib.baseboard_fab2(sch_1):m_k_ma(3)") )
				( member ( signalRef "@baseboard_fab2_lib.baseboard_fab2(sch_1):m_k_ma(4)") )
				( member ( signalRef "@baseboard_fab2_lib.baseboard_fab2(sch_1):m_k_ma(5)") )
				( member ( signalRef "@baseboard_fab2_lib.baseboard_fab2(sch_1):m_k_ma(6)") )
				( member ( signalRef "@baseboard_fab2_lib.baseboard_fab2(sch_1):m_k_ma(7)") )
				( member ( signalRef "@baseboard_fab2_lib.baseboard_fab2(sch_1):m_k_ma(8)") )
				( member ( signalRef "@baseboard_fab2_lib.baseboard_fab2(sch_1):m_k_ma(9)") )
				( member ( signalRef "@baseboard_fab2_lib.baseboard_fab2(sch_1):m_k_ma(10)") )
				( member ( signalRef "@baseboard_fab2_lib.baseboard_fab2(sch_1):m_k_ma(11)") )
				( member ( signalRef "@baseboard_fab2_lib.baseboard_fab2(sch_1):m_k_ma(12)") )
				( member ( signalRef "@baseboard_fab2_lib.baseboard_fab2(sch_1):m_k_ma(13)") )
				( member ( signalRef "@baseboard_fab2_lib.baseboard_fab2(sch_1):m_k_ma(14)") )
				( member ( signalRef "@baseboard_fab2_lib.baseboard_fab2(sch_1):m_k_ma(15)") )
				( member ( signalRef "@baseboard_fab2_lib.baseboard_fab2(sch_1):m_k_ma(16)") )
				( member ( signalRef "@baseboard_fab2_lib.baseboard_fab2(sch_1):m_k_ma(17)") )
				( objectStatus "SNCLS_DDR4_CHN_K_CMD_ADD" )
			)
			( netClass "@sapphirecity_baseboard_lib.sapphirecity_baseboard(sch_1):\DDR4_CHN_K_CTRL\"
				( memberType ( signal ) )
				( spacingCSetRef "@crescent_city_bb_fab1_lib.crescent_city_bb_fab1(sch_1):\8P9_US_&_6H_SL\" )
				( sameNetSpacingCSetRef "@crescent_city_bb_fab1_lib.crescent_city_bb_fab1(sch_1):\7H_US_AND_5H_SL\" )
				( objectFlag fObjectSpacing )
				( objectFlag fObjectSameNetSpacing )
				( member ( signalRef "@baseboard_fab2_lib.baseboard_fab2(sch_1):m_k_cke(0)") )
				( member ( signalRef "@baseboard_fab2_lib.baseboard_fab2(sch_1):m_k_cke(1)") )
				( member ( signalRef "@baseboard_fab2_lib.baseboard_fab2(sch_1):m_k_cke(2)") )
				( member ( signalRef "@baseboard_fab2_lib.baseboard_fab2(sch_1):m_k_cke(3)") )
				( member ( signalRef "@baseboard_fab2_lib.baseboard_fab2(sch_1):m_k_cs_n(0)") )
				( member ( signalRef "@baseboard_fab2_lib.baseboard_fab2(sch_1):m_k_cs_n(1)") )
				( member ( signalRef "@baseboard_fab2_lib.baseboard_fab2(sch_1):m_k_cs_n(2)") )
				( member ( signalRef "@baseboard_fab2_lib.baseboard_fab2(sch_1):m_k_cs_n(3)") )
				( member ( signalRef "@baseboard_fab2_lib.baseboard_fab2(sch_1):m_k_cs_n(4)") )
				( member ( signalRef "@baseboard_fab2_lib.baseboard_fab2(sch_1):m_k_cs_n(5)") )
				( member ( signalRef "@baseboard_fab2_lib.baseboard_fab2(sch_1):m_k_cs_n(6)") )
				( member ( signalRef "@baseboard_fab2_lib.baseboard_fab2(sch_1):m_k_cs_n(7)") )
				( member ( signalRef "@baseboard_fab2_lib.baseboard_fab2(sch_1):m_k_odt(0)") )
				( member ( signalRef "@baseboard_fab2_lib.baseboard_fab2(sch_1):m_k_odt(1)") )
				( member ( signalRef "@baseboard_fab2_lib.baseboard_fab2(sch_1):m_k_odt(2)") )
				( member ( signalRef "@baseboard_fab2_lib.baseboard_fab2(sch_1):m_k_odt(3)") )
				( member ( signalRef "@baseboard_fab2_lib.baseboard_fab2(sch_1):m_k_alert_n") )
				( objectStatus "SNCLS_DDR4_CHN_K_CTRL" )
			)
			( netClass "@sapphirecity_baseboard_lib.sapphirecity_baseboard(sch_1):\DDR4_CHN_L_CLK\"
				( memberType ( signal ) )
				( spacingCSetRef "@crescent_city_bb_fab1_lib.crescent_city_bb_fab1(sch_1):\8P9_US_&_6H_SL\" )
				( sameNetSpacingCSetRef "@crescent_city_bb_fab1_lib.crescent_city_bb_fab1(sch_1):\7H_US_AND_5H_SL\" )
				( objectFlag fObjectSpacing )
				( objectFlag fObjectSameNetSpacing )
				( member ( diffPairRef "@sapphirecity_baseboard_lib.sapphirecity_baseboard(sch_1):\M_L_CLK_D\(0)") )
				( member ( diffPairRef "@sapphirecity_baseboard_lib.sapphirecity_baseboard(sch_1):\M_L_CLK_D\(2)") )
				( member ( diffPairRef "@sapphirecity_baseboard_lib.sapphirecity_baseboard(sch_1):\M_E_CLK_D\(3)") )
				( member ( diffPairRef "@sapphirecity_baseboard_lib.sapphirecity_baseboard(sch_1):\M_E_CLK_D\(1)") )
				( objectStatus "SNCLS_DDR4_CHN_L_CLK" )
			)
			( netClass "@sapphirecity_baseboard_lib.sapphirecity_baseboard(sch_1):\DDR4_CHN_L_CMD_ADD\"
				( memberType ( signal ) )
				( spacingCSetRef "@crescent_city_bb_fab1_lib.crescent_city_bb_fab1(sch_1):\8P9_US_&_6H_SL\" )
				( sameNetSpacingCSetRef "@crescent_city_bb_fab1_lib.crescent_city_bb_fab1(sch_1):\7H_US_AND_5H_SL\" )
				( objectFlag fObjectSpacing )
				( objectFlag fObjectSameNetSpacing )
				( member ( signalRef "@baseboard_fab2_lib.baseboard_fab2(sch_1):m_l_act_n") )
				( member ( signalRef "@baseboard_fab2_lib.baseboard_fab2(sch_1):m_l_c(2)") )
				( member ( signalRef "@baseboard_fab2_lib.baseboard_fab2(sch_1):m_l_par") )
				( member ( signalRef "@baseboard_fab2_lib.baseboard_fab2(sch_1):m_l_ba(0)") )
				( member ( signalRef "@baseboard_fab2_lib.baseboard_fab2(sch_1):m_l_ba(1)") )
				( member ( signalRef "@baseboard_fab2_lib.baseboard_fab2(sch_1):m_l_bg(0)") )
				( member ( signalRef "@baseboard_fab2_lib.baseboard_fab2(sch_1):m_l_bg(1)") )
				( member ( signalRef "@baseboard_fab2_lib.baseboard_fab2(sch_1):m_l_ma(0)") )
				( member ( signalRef "@baseboard_fab2_lib.baseboard_fab2(sch_1):m_l_ma(1)") )
				( member ( signalRef "@baseboard_fab2_lib.baseboard_fab2(sch_1):m_l_ma(2)") )
				( member ( signalRef "@baseboard_fab2_lib.baseboard_fab2(sch_1):m_l_ma(3)") )
				( member ( signalRef "@baseboard_fab2_lib.baseboard_fab2(sch_1):m_l_ma(4)") )
				( member ( signalRef "@baseboard_fab2_lib.baseboard_fab2(sch_1):m_l_ma(5)") )
				( member ( signalRef "@baseboard_fab2_lib.baseboard_fab2(sch_1):m_l_ma(6)") )
				( member ( signalRef "@baseboard_fab2_lib.baseboard_fab2(sch_1):m_l_ma(7)") )
				( member ( signalRef "@baseboard_fab2_lib.baseboard_fab2(sch_1):m_l_ma(8)") )
				( member ( signalRef "@baseboard_fab2_lib.baseboard_fab2(sch_1):m_l_ma(9)") )
				( member ( signalRef "@baseboard_fab2_lib.baseboard_fab2(sch_1):m_l_ma(10)") )
				( member ( signalRef "@baseboard_fab2_lib.baseboard_fab2(sch_1):m_l_ma(11)") )
				( member ( signalRef "@baseboard_fab2_lib.baseboard_fab2(sch_1):m_l_ma(12)") )
				( member ( signalRef "@baseboard_fab2_lib.baseboard_fab2(sch_1):m_l_ma(13)") )
				( member ( signalRef "@baseboard_fab2_lib.baseboard_fab2(sch_1):m_l_ma(14)") )
				( member ( signalRef "@baseboard_fab2_lib.baseboard_fab2(sch_1):m_l_ma(15)") )
				( member ( signalRef "@baseboard_fab2_lib.baseboard_fab2(sch_1):m_l_ma(16)") )
				( member ( signalRef "@baseboard_fab2_lib.baseboard_fab2(sch_1):m_l_ma(17)") )
				( objectStatus "SNCLS_DDR4_CHN_L_CMD_ADD" )
			)
			( netClass "@sapphirecity_baseboard_lib.sapphirecity_baseboard(sch_1):\DDR4_CHN_L_CTRL\"
				( memberType ( signal ) )
				( spacingCSetRef "@crescent_city_bb_fab1_lib.crescent_city_bb_fab1(sch_1):\8P9_US_&_6H_SL\" )
				( sameNetSpacingCSetRef "@crescent_city_bb_fab1_lib.crescent_city_bb_fab1(sch_1):\7H_US_AND_5H_SL\" )
				( objectFlag fObjectSpacing )
				( objectFlag fObjectSameNetSpacing )
				( member ( signalRef "@baseboard_fab2_lib.baseboard_fab2(sch_1):m_l_cs_n(0)") )
				( member ( signalRef "@baseboard_fab2_lib.baseboard_fab2(sch_1):m_l_cs_n(1)") )
				( member ( signalRef "@baseboard_fab2_lib.baseboard_fab2(sch_1):m_l_cs_n(2)") )
				( member ( signalRef "@baseboard_fab2_lib.baseboard_fab2(sch_1):m_l_cs_n(3)") )
				( member ( signalRef "@baseboard_fab2_lib.baseboard_fab2(sch_1):m_l_cs_n(6)") )
				( member ( signalRef "@baseboard_fab2_lib.baseboard_fab2(sch_1):m_l_cs_n(7)") )
				( member ( signalRef "@baseboard_fab2_lib.baseboard_fab2(sch_1):m_l_alert_n") )
				( member ( signalRef "@baseboard_fab2_lib.baseboard_fab2(sch_1):m_l_cke(0)") )
				( member ( signalRef "@baseboard_fab2_lib.baseboard_fab2(sch_1):m_l_cke(1)") )
				( member ( signalRef "@baseboard_fab2_lib.baseboard_fab2(sch_1):m_l_cke(2)") )
				( member ( signalRef "@baseboard_fab2_lib.baseboard_fab2(sch_1):m_l_cke(3)") )
				( member ( signalRef "@baseboard_fab2_lib.baseboard_fab2(sch_1):m_l_cs_n(4)") )
				( member ( signalRef "@baseboard_fab2_lib.baseboard_fab2(sch_1):m_l_cs_n(5)") )
				( member ( signalRef "@baseboard_fab2_lib.baseboard_fab2(sch_1):m_l_odt(0)") )
				( member ( signalRef "@baseboard_fab2_lib.baseboard_fab2(sch_1):m_l_odt(1)") )
				( member ( signalRef "@baseboard_fab2_lib.baseboard_fab2(sch_1):m_l_odt(2)") )
				( member ( signalRef "@baseboard_fab2_lib.baseboard_fab2(sch_1):m_l_odt(3)") )
				( objectStatus "SNCLS_DDR4_CHN_L_CTRL" )
			)
			( netClass "@sapphirecity_baseboard_lib.sapphirecity_baseboard(sch_1):\DDR4_CHN_M_CLK\"
				( memberType ( signal ) )
				( spacingCSetRef "@crescent_city_bb_fab1_lib.crescent_city_bb_fab1(sch_1):\8P9_US_&_6H_SL\" )
				( sameNetSpacingCSetRef "@crescent_city_bb_fab1_lib.crescent_city_bb_fab1(sch_1):\7H_US_AND_5H_SL\" )
				( objectFlag fObjectSpacing )
				( objectFlag fObjectSameNetSpacing )
				( member ( diffPairRef "@sapphirecity_baseboard_lib.sapphirecity_baseboard(sch_1):\M_M_CLK_D\(0)") )
				( member ( diffPairRef "@sapphirecity_baseboard_lib.sapphirecity_baseboard(sch_1):\M_M_CLK_D\(2)") )
				( member ( diffPairRef "@sapphirecity_baseboard_lib.sapphirecity_baseboard(sch_1):\M_D_CLK_D\(1)") )
				( member ( diffPairRef "@sapphirecity_baseboard_lib.sapphirecity_baseboard(sch_1):\M_D_CLK_D\(3)") )
				( objectStatus "SNCLS_DDR4_CHN_M_CLK" )
			)
			( netClass "@sapphirecity_baseboard_lib.sapphirecity_baseboard(sch_1):\DDR4_CHN_M_CMD_ADD\"
				( memberType ( signal ) )
				( spacingCSetRef "@crescent_city_bb_fab1_lib.crescent_city_bb_fab1(sch_1):\8P9_US_&_6H_SL\" )
				( sameNetSpacingCSetRef "@crescent_city_bb_fab1_lib.crescent_city_bb_fab1(sch_1):\7H_US_AND_5H_SL\" )
				( objectFlag fObjectSpacing )
				( objectFlag fObjectSameNetSpacing )
				( member ( signalRef "@baseboard_fab2_lib.baseboard_fab2(sch_1):m_m_act_n") )
				( member ( signalRef "@baseboard_fab2_lib.baseboard_fab2(sch_1):m_m_c(2)") )
				( member ( signalRef "@baseboard_fab2_lib.baseboard_fab2(sch_1):m_m_par") )
				( member ( signalRef "@baseboard_fab2_lib.baseboard_fab2(sch_1):m_m_ba(0)") )
				( member ( signalRef "@baseboard_fab2_lib.baseboard_fab2(sch_1):m_m_ba(1)") )
				( member ( signalRef "@baseboard_fab2_lib.baseboard_fab2(sch_1):m_m_bg(0)") )
				( member ( signalRef "@baseboard_fab2_lib.baseboard_fab2(sch_1):m_m_bg(1)") )
				( member ( signalRef "@baseboard_fab2_lib.baseboard_fab2(sch_1):m_m_ma(0)") )
				( member ( signalRef "@baseboard_fab2_lib.baseboard_fab2(sch_1):m_m_ma(1)") )
				( member ( signalRef "@baseboard_fab2_lib.baseboard_fab2(sch_1):m_m_ma(2)") )
				( member ( signalRef "@baseboard_fab2_lib.baseboard_fab2(sch_1):m_m_ma(3)") )
				( member ( signalRef "@baseboard_fab2_lib.baseboard_fab2(sch_1):m_m_ma(4)") )
				( member ( signalRef "@baseboard_fab2_lib.baseboard_fab2(sch_1):m_m_ma(5)") )
				( member ( signalRef "@baseboard_fab2_lib.baseboard_fab2(sch_1):m_m_ma(6)") )
				( member ( signalRef "@baseboard_fab2_lib.baseboard_fab2(sch_1):m_m_ma(7)") )
				( member ( signalRef "@baseboard_fab2_lib.baseboard_fab2(sch_1):m_m_ma(8)") )
				( member ( signalRef "@baseboard_fab2_lib.baseboard_fab2(sch_1):m_m_ma(9)") )
				( member ( signalRef "@baseboard_fab2_lib.baseboard_fab2(sch_1):m_m_ma(10)") )
				( member ( signalRef "@baseboard_fab2_lib.baseboard_fab2(sch_1):m_m_ma(11)") )
				( member ( signalRef "@baseboard_fab2_lib.baseboard_fab2(sch_1):m_m_ma(12)") )
				( member ( signalRef "@baseboard_fab2_lib.baseboard_fab2(sch_1):m_m_ma(13)") )
				( member ( signalRef "@baseboard_fab2_lib.baseboard_fab2(sch_1):m_m_ma(14)") )
				( member ( signalRef "@baseboard_fab2_lib.baseboard_fab2(sch_1):m_m_ma(15)") )
				( member ( signalRef "@baseboard_fab2_lib.baseboard_fab2(sch_1):m_m_ma(16)") )
				( member ( signalRef "@baseboard_fab2_lib.baseboard_fab2(sch_1):m_m_ma(17)") )
				( objectStatus "SNCLS_DDR4_CHN_M_CMD_ADD" )
			)
			( netClass "@sapphirecity_baseboard_lib.sapphirecity_baseboard(sch_1):\DDR4_CHN_M_CTRL\"
				( memberType ( signal ) )
				( spacingCSetRef "@crescent_city_bb_fab1_lib.crescent_city_bb_fab1(sch_1):\8P9_US_&_6H_SL\" )
				( sameNetSpacingCSetRef "@crescent_city_bb_fab1_lib.crescent_city_bb_fab1(sch_1):\7H_US_AND_5H_SL\" )
				( objectFlag fObjectSpacing )
				( objectFlag fObjectSameNetSpacing )
				( member ( signalRef "@baseboard_fab2_lib.baseboard_fab2(sch_1):m_m_cke(0)") )
				( member ( signalRef "@baseboard_fab2_lib.baseboard_fab2(sch_1):m_m_cke(1)") )
				( member ( signalRef "@baseboard_fab2_lib.baseboard_fab2(sch_1):m_m_alert_n") )
				( member ( signalRef "@baseboard_fab2_lib.baseboard_fab2(sch_1):m_m_cke(2)") )
				( member ( signalRef "@baseboard_fab2_lib.baseboard_fab2(sch_1):m_m_cke(3)") )
				( member ( signalRef "@baseboard_fab2_lib.baseboard_fab2(sch_1):m_m_cs_n(0)") )
				( member ( signalRef "@baseboard_fab2_lib.baseboard_fab2(sch_1):m_m_cs_n(1)") )
				( member ( signalRef "@baseboard_fab2_lib.baseboard_fab2(sch_1):m_m_cs_n(2)") )
				( member ( signalRef "@baseboard_fab2_lib.baseboard_fab2(sch_1):m_m_cs_n(3)") )
				( member ( signalRef "@baseboard_fab2_lib.baseboard_fab2(sch_1):m_m_cs_n(4)") )
				( member ( signalRef "@baseboard_fab2_lib.baseboard_fab2(sch_1):m_m_cs_n(5)") )
				( member ( signalRef "@baseboard_fab2_lib.baseboard_fab2(sch_1):m_m_cs_n(6)") )
				( member ( signalRef "@baseboard_fab2_lib.baseboard_fab2(sch_1):m_m_cs_n(7)") )
				( member ( signalRef "@baseboard_fab2_lib.baseboard_fab2(sch_1):m_m_odt(0)") )
				( member ( signalRef "@baseboard_fab2_lib.baseboard_fab2(sch_1):m_m_odt(1)") )
				( member ( signalRef "@baseboard_fab2_lib.baseboard_fab2(sch_1):m_m_odt(2)") )
				( member ( signalRef "@baseboard_fab2_lib.baseboard_fab2(sch_1):m_m_odt(3)") )
				( objectStatus "SNCLS_DDR4_CHN_M_CTRL" )
			)
			( netClass "@sapphirecity_baseboard_lib.sapphirecity_baseboard(sch_1):\P3E_CPU0_PE1AB_SLOTB_RX\"
				( memberType ( signal ) )
				( spacingCSetRef "@sapphirecity_baseboard_lib.sapphirecity_baseboard(sch_1):\11H_US_AND_5H_SL_VIA+3H_A\" )
				( sameNetSpacingCSetRef "@crescent_city_bb_fab1_lib.crescent_city_bb_fab1(sch_1):\7H_US_AND_5H_SL\" )
				( objectFlag fObjectSpacing )
				( objectFlag fObjectSameNetSpacing )
				( objectStatus "SNCLS_P3E_CPU0_PE1_SS_RX" )
			)
			( netClass "@sapphirecity_baseboard_lib.sapphirecity_baseboard(sch_1):\P3E_CPU0_PE1AB_SLOTB_TX\"
				( memberType ( signal ) )
				( spacingCSetRef "@sapphirecity_baseboard_lib.sapphirecity_baseboard(sch_1):\11H_US_AND_5H_SL_VIA+3H_A\" )
				( sameNetSpacingCSetRef "@crescent_city_bb_fab1_lib.crescent_city_bb_fab1(sch_1):\7H_US_AND_5H_SL\" )
				( objectFlag fObjectSpacing )
				( objectFlag fObjectSameNetSpacing )
				( objectStatus "SNCLS_P3E_CPU0_PE1_SS_TX" )
			)
			( netClass "@sapphirecity_baseboard_lib.sapphirecity_baseboard(sch_1):\P3E_CPU1_PE1A_RISER1_RX\"
				( memberType ( signal ) )
				( spacingCSetRef "@sapphirecity_baseboard_lib.sapphirecity_baseboard(sch_1):\11H_US_AND_5H_SL_VIA+3H_A\" )
				( sameNetSpacingCSetRef "@crescent_city_bb_fab1_lib.crescent_city_bb_fab1(sch_1):\7H_US_AND_5H_SL\" )
				( objectFlag fObjectSpacing )
				( objectFlag fObjectSameNetSpacing )
				( objectStatus "SNCLS_P3E_CPU0_PE1_SS_PCIEUP_RX" )
			)
			( netClass "@sapphirecity_baseboard_lib.sapphirecity_baseboard(sch_1):\P3E_CPU1_PE1A_RISER1_TX\"
				( memberType ( signal ) )
				( spacingCSetRef "@sapphirecity_baseboard_lib.sapphirecity_baseboard(sch_1):\11H_US_AND_5H_SL_VIA+3H_A\" )
				( sameNetSpacingCSetRef "@crescent_city_bb_fab1_lib.crescent_city_bb_fab1(sch_1):\7H_US_AND_5H_SL\" )
				( objectFlag fObjectSpacing )
				( objectFlag fObjectSameNetSpacing )
				( objectStatus "SNCLS_P3E_CPU0_PE1_SS_PCIEUP_TX" )
			)
			( netClass "@sapphirecity_baseboard_lib.sapphirecity_baseboard(sch_1):\P3E_CPU1_PE1B_RISER1_RX\"
				( memberType ( signal ) )
				( spacingCSetRef "@sapphirecity_baseboard_lib.sapphirecity_baseboard(sch_1):\11H_US_AND_5H_SL_VIA+3H_A\" )
				( sameNetSpacingCSetRef "@crescent_city_bb_fab1_lib.crescent_city_bb_fab1(sch_1):\7H_US_AND_5H_SL\" )
				( objectFlag fObjectSpacing )
				( objectFlag fObjectSameNetSpacing )
				( objectStatus "SNCLS_P3E_PCH_PCIE_UP_RX" )
			)
			( netClass "@sapphirecity_baseboard_lib.sapphirecity_baseboard(sch_1):\P3E_CPU1_PE1B_RISER1_TX\"
				( memberType ( signal ) )
				( spacingCSetRef "@sapphirecity_baseboard_lib.sapphirecity_baseboard(sch_1):\11H_US_AND_5H_SL_VIA+3H_A\" )
				( sameNetSpacingCSetRef "@crescent_city_bb_fab1_lib.crescent_city_bb_fab1(sch_1):\7H_US_AND_5H_SL\" )
				( objectFlag fObjectSpacing )
				( objectFlag fObjectSameNetSpacing )
				( objectStatus "SNCLS_P3E_PCH_PCIE_UP_TX" )
			)
			( netClass "@sapphirecity_baseboard_lib.sapphirecity_baseboard(sch_1):\P3E_CPU1_PE2_RISER2_RX\"
				( memberType ( signal ) )
				( spacingCSetRef "@sapphirecity_baseboard_lib.sapphirecity_baseboard(sch_1):\11H_US_AND_5H_SL_VIA+3H_A\" )
				( sameNetSpacingCSetRef "@crescent_city_bb_fab1_lib.crescent_city_bb_fab1(sch_1):\7H_US_AND_5H_SL\" )
				( objectFlag fObjectSpacing )
				( objectFlag fObjectSameNetSpacing )
				( member ( diffPairRef "@crescent_city_bb_fab1_lib.crescent_city_bb_fab1(sch_1):\P3E_CPU0_PE2_SS_RX\(0)") )
				( member ( diffPairRef "@crescent_city_bb_fab1_lib.crescent_city_bb_fab1(sch_1):\P3E_CPU0_PE2_SS_RX\(1)") )
				( member ( diffPairRef "@crescent_city_bb_fab1_lib.crescent_city_bb_fab1(sch_1):\P3E_CPU0_PE2_SS_RX\(2)") )
				( member ( diffPairRef "@crescent_city_bb_fab1_lib.crescent_city_bb_fab1(sch_1):\P3E_CPU0_PE2_SS_RX\(3)") )
				( member ( diffPairRef "@crescent_city_bb_fab1_lib.crescent_city_bb_fab1(sch_1):\P3E_CPU0_PE2_SS_RX\(4)") )
				( member ( diffPairRef "@crescent_city_bb_fab1_lib.crescent_city_bb_fab1(sch_1):\P3E_CPU0_PE2_SS_RX\(5)") )
				( member ( diffPairRef "@crescent_city_bb_fab1_lib.crescent_city_bb_fab1(sch_1):\P3E_CPU0_PE2_SS_RX\(6)") )
				( member ( diffPairRef "@crescent_city_bb_fab1_lib.crescent_city_bb_fab1(sch_1):\P3E_CPU0_PE2_SS_RX\(7)") )
				( member ( diffPairRef "@crescent_city_bb_fab1_lib.crescent_city_bb_fab1(sch_1):\P3E_CPU0_PE2_SS_RX\(8)") )
				( member ( diffPairRef "@crescent_city_bb_fab1_lib.crescent_city_bb_fab1(sch_1):\P3E_CPU0_PE2_SS_RX\(9)") )
				( member ( diffPairRef "@crescent_city_bb_fab1_lib.crescent_city_bb_fab1(sch_1):\P3E_CPU0_PE2_SS_RX\(10)") )
				( member ( diffPairRef "@crescent_city_bb_fab1_lib.crescent_city_bb_fab1(sch_1):\P3E_CPU0_PE2_SS_RX\(11)") )
				( member ( diffPairRef "@crescent_city_bb_fab1_lib.crescent_city_bb_fab1(sch_1):\P3E_CPU0_PE2_SS_RX\(12)") )
				( member ( diffPairRef "@crescent_city_bb_fab1_lib.crescent_city_bb_fab1(sch_1):\P3E_CPU0_PE2_SS_RX\(13)") )
				( member ( diffPairRef "@crescent_city_bb_fab1_lib.crescent_city_bb_fab1(sch_1):\P3E_CPU0_PE2_SS_RX\(14)") )
				( member ( diffPairRef "@crescent_city_bb_fab1_lib.crescent_city_bb_fab1(sch_1):\P3E_CPU0_PE2_SS_RX\(15)") )
				( member ( signalRef "@baseboard_fab2_lib.baseboard_fab2(sch_1):p3e_cpu0_pe2_ss_rxn(0)") )
				( member ( signalRef "@baseboard_fab2_lib.baseboard_fab2(sch_1):p3e_cpu0_pe2_ss_rxp(0)") )
				( member ( signalRef "@baseboard_fab2_lib.baseboard_fab2(sch_1):p3e_cpu0_pe2_ss_rxn(1)") )
				( member ( signalRef "@baseboard_fab2_lib.baseboard_fab2(sch_1):p3e_cpu0_pe2_ss_rxn(2)") )
				( member ( signalRef "@baseboard_fab2_lib.baseboard_fab2(sch_1):p3e_cpu0_pe2_ss_rxn(3)") )
				( member ( signalRef "@baseboard_fab2_lib.baseboard_fab2(sch_1):p3e_cpu0_pe2_ss_rxp(1)") )
				( member ( signalRef "@baseboard_fab2_lib.baseboard_fab2(sch_1):p3e_cpu0_pe2_ss_rxp(2)") )
				( member ( signalRef "@baseboard_fab2_lib.baseboard_fab2(sch_1):p3e_cpu0_pe2_ss_rxp(3)") )
				( member ( signalRef "@baseboard_fab2_lib.baseboard_fab2(sch_1):p3e_cpu0_pe2_ss_rxn(4)") )
				( member ( signalRef "@baseboard_fab2_lib.baseboard_fab2(sch_1):p3e_cpu0_pe2_ss_rxn(5)") )
				( member ( signalRef "@baseboard_fab2_lib.baseboard_fab2(sch_1):p3e_cpu0_pe2_ss_rxn(6)") )
				( member ( signalRef "@baseboard_fab2_lib.baseboard_fab2(sch_1):p3e_cpu0_pe2_ss_rxn(7)") )
				( member ( signalRef "@baseboard_fab2_lib.baseboard_fab2(sch_1):p3e_cpu0_pe2_ss_rxn(8)") )
				( member ( signalRef "@baseboard_fab2_lib.baseboard_fab2(sch_1):p3e_cpu0_pe2_ss_rxn(9)") )
				( member ( signalRef "@baseboard_fab2_lib.baseboard_fab2(sch_1):p3e_cpu0_pe2_ss_rxn(10)") )
				( member ( signalRef "@baseboard_fab2_lib.baseboard_fab2(sch_1):p3e_cpu0_pe2_ss_rxn(11)") )
				( member ( signalRef "@baseboard_fab2_lib.baseboard_fab2(sch_1):p3e_cpu0_pe2_ss_rxn(12)") )
				( member ( signalRef "@baseboard_fab2_lib.baseboard_fab2(sch_1):p3e_cpu0_pe2_ss_rxn(13)") )
				( member ( signalRef "@baseboard_fab2_lib.baseboard_fab2(sch_1):p3e_cpu0_pe2_ss_rxn(14)") )
				( member ( signalRef "@baseboard_fab2_lib.baseboard_fab2(sch_1):p3e_cpu0_pe2_ss_rxn(15)") )
				( member ( signalRef "@baseboard_fab2_lib.baseboard_fab2(sch_1):p3e_cpu0_pe2_ss_rxp(4)") )
				( member ( signalRef "@baseboard_fab2_lib.baseboard_fab2(sch_1):p3e_cpu0_pe2_ss_rxp(5)") )
				( member ( signalRef "@baseboard_fab2_lib.baseboard_fab2(sch_1):p3e_cpu0_pe2_ss_rxp(6)") )
				( member ( signalRef "@baseboard_fab2_lib.baseboard_fab2(sch_1):p3e_cpu0_pe2_ss_rxp(7)") )
				( member ( signalRef "@baseboard_fab2_lib.baseboard_fab2(sch_1):p3e_cpu0_pe2_ss_rxp(8)") )
				( member ( signalRef "@baseboard_fab2_lib.baseboard_fab2(sch_1):p3e_cpu0_pe2_ss_rxp(9)") )
				( member ( signalRef "@baseboard_fab2_lib.baseboard_fab2(sch_1):p3e_cpu0_pe2_ss_rxp(10)") )
				( member ( signalRef "@baseboard_fab2_lib.baseboard_fab2(sch_1):p3e_cpu0_pe2_ss_rxp(11)") )
				( member ( signalRef "@baseboard_fab2_lib.baseboard_fab2(sch_1):p3e_cpu0_pe2_ss_rxp(12)") )
				( member ( signalRef "@baseboard_fab2_lib.baseboard_fab2(sch_1):p3e_cpu0_pe2_ss_rxp(13)") )
				( member ( signalRef "@baseboard_fab2_lib.baseboard_fab2(sch_1):p3e_cpu0_pe2_ss_rxp(14)") )
				( member ( signalRef "@baseboard_fab2_lib.baseboard_fab2(sch_1):p3e_cpu0_pe2_ss_rxp(15)") )
				( objectStatus "SNCLS_P3E_CPU0_PE2_SS_RX" )
			)
			( netClass "@sapphirecity_baseboard_lib.sapphirecity_baseboard(sch_1):\P3E_CPU1_PE2_RISER2_TX\"
				( memberType ( signal ) )
				( spacingCSetRef "@sapphirecity_baseboard_lib.sapphirecity_baseboard(sch_1):\11H_US_AND_5H_SL_VIA+3H_A\" )
				( sameNetSpacingCSetRef "@crescent_city_bb_fab1_lib.crescent_city_bb_fab1(sch_1):\7H_US_AND_5H_SL\" )
				( objectFlag fObjectSpacing )
				( objectFlag fObjectSameNetSpacing )
				( member ( diffPairRef "@crescent_city_bb_fab1_lib.crescent_city_bb_fab1(sch_1):\DP_23\") )
				( member ( diffPairRef "@crescent_city_bb_fab1_lib.crescent_city_bb_fab1(sch_1):\DP_24\") )
				( member ( diffPairRef "@crescent_city_bb_fab1_lib.crescent_city_bb_fab1(sch_1):\DP_25\") )
				( member ( diffPairRef "@crescent_city_bb_fab1_lib.crescent_city_bb_fab1(sch_1):\DP_26\") )
				( member ( diffPairRef "@crescent_city_bb_fab1_lib.crescent_city_bb_fab1(sch_1):\DP_27\") )
				( member ( diffPairRef "@crescent_city_bb_fab1_lib.crescent_city_bb_fab1(sch_1):\DP_28\") )
				( member ( diffPairRef "@crescent_city_bb_fab1_lib.crescent_city_bb_fab1(sch_1):\DP_29\") )
				( member ( diffPairRef "@crescent_city_bb_fab1_lib.crescent_city_bb_fab1(sch_1):\DP_30\") )
				( member ( diffPairRef "@crescent_city_bb_fab1_lib.crescent_city_bb_fab1(sch_1):\DP_31\") )
				( member ( diffPairRef "@crescent_city_bb_fab1_lib.crescent_city_bb_fab1(sch_1):\DP_32\") )
				( member ( diffPairRef "@crescent_city_bb_fab1_lib.crescent_city_bb_fab1(sch_1):\DP_33\") )
				( member ( diffPairRef "@crescent_city_bb_fab1_lib.crescent_city_bb_fab1(sch_1):\DP_34\") )
				( member ( diffPairRef "@crescent_city_bb_fab1_lib.crescent_city_bb_fab1(sch_1):\DP_35\") )
				( member ( diffPairRef "@crescent_city_bb_fab1_lib.crescent_city_bb_fab1(sch_1):\DP_36\") )
				( member ( diffPairRef "@crescent_city_bb_fab1_lib.crescent_city_bb_fab1(sch_1):\DP_37\") )
				( member ( diffPairRef "@crescent_city_bb_fab1_lib.crescent_city_bb_fab1(sch_1):\DP_38\") )
				( member ( electricalNetRef "@crescent_city_bb_fab1_lib.crescent_city_bb_fab1(sch_1):p3e_cpu0_pe2_ss_c_txn(0)") )
				( member ( electricalNetRef "@crescent_city_bb_fab1_lib.crescent_city_bb_fab1(sch_1):p3e_cpu0_pe2_ss_c_txn(1)") )
				( member ( electricalNetRef "@crescent_city_bb_fab1_lib.crescent_city_bb_fab1(sch_1):p3e_cpu0_pe2_ss_c_txn(2)") )
				( member ( electricalNetRef "@crescent_city_bb_fab1_lib.crescent_city_bb_fab1(sch_1):p3e_cpu0_pe2_ss_c_txn(3)") )
				( member ( electricalNetRef "@crescent_city_bb_fab1_lib.crescent_city_bb_fab1(sch_1):p3e_cpu0_pe2_ss_c_txn(4)") )
				( member ( electricalNetRef "@crescent_city_bb_fab1_lib.crescent_city_bb_fab1(sch_1):p3e_cpu0_pe2_ss_c_txn(5)") )
				( member ( electricalNetRef "@crescent_city_bb_fab1_lib.crescent_city_bb_fab1(sch_1):p3e_cpu0_pe2_ss_c_txn(6)") )
				( member ( electricalNetRef "@crescent_city_bb_fab1_lib.crescent_city_bb_fab1(sch_1):p3e_cpu0_pe2_ss_c_txn(7)") )
				( member ( electricalNetRef "@crescent_city_bb_fab1_lib.crescent_city_bb_fab1(sch_1):p3e_cpu0_pe2_ss_c_txn(8)") )
				( member ( electricalNetRef "@crescent_city_bb_fab1_lib.crescent_city_bb_fab1(sch_1):p3e_cpu0_pe2_ss_c_txn(9)") )
				( member ( electricalNetRef "@crescent_city_bb_fab1_lib.crescent_city_bb_fab1(sch_1):p3e_cpu0_pe2_ss_c_txn(10)") )
				( member ( electricalNetRef "@crescent_city_bb_fab1_lib.crescent_city_bb_fab1(sch_1):p3e_cpu0_pe2_ss_c_txn(11)") )
				( member ( electricalNetRef "@crescent_city_bb_fab1_lib.crescent_city_bb_fab1(sch_1):p3e_cpu0_pe2_ss_c_txn(12)") )
				( member ( electricalNetRef "@crescent_city_bb_fab1_lib.crescent_city_bb_fab1(sch_1):p3e_cpu0_pe2_ss_c_txn(13)") )
				( member ( electricalNetRef "@crescent_city_bb_fab1_lib.crescent_city_bb_fab1(sch_1):p3e_cpu0_pe2_ss_c_txn(14)") )
				( member ( electricalNetRef "@crescent_city_bb_fab1_lib.crescent_city_bb_fab1(sch_1):p3e_cpu0_pe2_ss_c_txn(15)") )
				( member ( electricalNetRef "@crescent_city_bb_fab1_lib.crescent_city_bb_fab1(sch_1):p3e_cpu0_pe2_ss_c_txp(0)") )
				( member ( electricalNetRef "@crescent_city_bb_fab1_lib.crescent_city_bb_fab1(sch_1):p3e_cpu0_pe2_ss_c_txp(1)") )
				( member ( electricalNetRef "@crescent_city_bb_fab1_lib.crescent_city_bb_fab1(sch_1):p3e_cpu0_pe2_ss_c_txp(2)") )
				( member ( electricalNetRef "@crescent_city_bb_fab1_lib.crescent_city_bb_fab1(sch_1):p3e_cpu0_pe2_ss_c_txp(3)") )
				( member ( electricalNetRef "@crescent_city_bb_fab1_lib.crescent_city_bb_fab1(sch_1):p3e_cpu0_pe2_ss_c_txp(4)") )
				( member ( electricalNetRef "@crescent_city_bb_fab1_lib.crescent_city_bb_fab1(sch_1):p3e_cpu0_pe2_ss_c_txp(5)") )
				( member ( electricalNetRef "@crescent_city_bb_fab1_lib.crescent_city_bb_fab1(sch_1):p3e_cpu0_pe2_ss_c_txp(6)") )
				( member ( electricalNetRef "@crescent_city_bb_fab1_lib.crescent_city_bb_fab1(sch_1):p3e_cpu0_pe2_ss_c_txp(7)") )
				( member ( electricalNetRef "@crescent_city_bb_fab1_lib.crescent_city_bb_fab1(sch_1):p3e_cpu0_pe2_ss_c_txp(8)") )
				( member ( electricalNetRef "@crescent_city_bb_fab1_lib.crescent_city_bb_fab1(sch_1):p3e_cpu0_pe2_ss_c_txp(9)") )
				( member ( electricalNetRef "@crescent_city_bb_fab1_lib.crescent_city_bb_fab1(sch_1):p3e_cpu0_pe2_ss_c_txp(10)") )
				( member ( electricalNetRef "@crescent_city_bb_fab1_lib.crescent_city_bb_fab1(sch_1):p3e_cpu0_pe2_ss_c_txp(11)") )
				( member ( electricalNetRef "@crescent_city_bb_fab1_lib.crescent_city_bb_fab1(sch_1):p3e_cpu0_pe2_ss_c_txp(12)") )
				( member ( electricalNetRef "@crescent_city_bb_fab1_lib.crescent_city_bb_fab1(sch_1):p3e_cpu0_pe2_ss_c_txp(13)") )
				( member ( electricalNetRef "@crescent_city_bb_fab1_lib.crescent_city_bb_fab1(sch_1):p3e_cpu0_pe2_ss_c_txp(14)") )
				( member ( electricalNetRef "@crescent_city_bb_fab1_lib.crescent_city_bb_fab1(sch_1):p3e_cpu0_pe2_ss_c_txp(15)") )
				( objectStatus "SNCLS_P3E_CPU0_PE2_SS_TX" )
			)
			( netClass "@sapphirecity_baseboard_lib.sapphirecity_baseboard(sch_1):\P3E_CPU1_PE3AB_SLOTE_RX\"
				( memberType ( signal ) )
				( spacingCSetRef "@sapphirecity_baseboard_lib.sapphirecity_baseboard(sch_1):\11H_US_AND_5H_SL_VIA+3H_A\" )
				( sameNetSpacingCSetRef "@crescent_city_bb_fab1_lib.crescent_city_bb_fab1(sch_1):\7H_US_AND_5H_SL\" )
				( objectFlag fObjectSpacing )
				( objectFlag fObjectSameNetSpacing )
				( member ( diffPairRef "@crescent_city_bb_fab1_lib.crescent_city_bb_fab1(sch_1):\DP_P3E_CPU1_PE3_MP_R\(0)") )
				( member ( diffPairRef "@crescent_city_bb_fab1_lib.crescent_city_bb_fab1(sch_1):\DP_P3E_CPU1_PE3_MP_R\(1)") )
				( member ( diffPairRef "@crescent_city_bb_fab1_lib.crescent_city_bb_fab1(sch_1):\DP_P3E_CPU1_PE3_MP_R\(2)") )
				( member ( diffPairRef "@crescent_city_bb_fab1_lib.crescent_city_bb_fab1(sch_1):\DP_P3E_CPU1_PE3_MP_R\(3)") )
				( member ( diffPairRef "@crescent_city_bb_fab1_lib.crescent_city_bb_fab1(sch_1):\DP_P3E_CPU1_PE3_MP_R\(4)") )
				( member ( diffPairRef "@crescent_city_bb_fab1_lib.crescent_city_bb_fab1(sch_1):\DP_P3E_CPU1_PE3_MP_R\(5)") )
				( member ( diffPairRef "@crescent_city_bb_fab1_lib.crescent_city_bb_fab1(sch_1):\DP_P3E_CPU1_PE3_MP_R\(6)") )
				( member ( diffPairRef "@crescent_city_bb_fab1_lib.crescent_city_bb_fab1(sch_1):\DP_P3E_CPU1_PE3_MP_R\(7)") )
				( member ( diffPairRef "@crescent_city_bb_fab1_lib.crescent_city_bb_fab1(sch_1):\DP_P3E_CPU1_PE3_MP_R\(8)") )
				( member ( diffPairRef "@crescent_city_bb_fab1_lib.crescent_city_bb_fab1(sch_1):\DP_P3E_CPU1_PE3_MP_R\(9)") )
				( member ( diffPairRef "@crescent_city_bb_fab1_lib.crescent_city_bb_fab1(sch_1):\DP_P3E_CPU1_PE3_MP_R\(10)") )
				( member ( diffPairRef "@crescent_city_bb_fab1_lib.crescent_city_bb_fab1(sch_1):\DP_P3E_CPU1_PE3_MP_R\(11)") )
				( member ( diffPairRef "@crescent_city_bb_fab1_lib.crescent_city_bb_fab1(sch_1):\DP_P3E_CPU1_PE3_MP_R\(12)") )
				( member ( diffPairRef "@crescent_city_bb_fab1_lib.crescent_city_bb_fab1(sch_1):\DP_P3E_CPU1_PE3_MP_R\(13)") )
				( member ( diffPairRef "@crescent_city_bb_fab1_lib.crescent_city_bb_fab1(sch_1):\DP_P3E_CPU1_PE3_MP_R\(14)") )
				( member ( diffPairRef "@crescent_city_bb_fab1_lib.crescent_city_bb_fab1(sch_1):\DP_P3E_CPU1_PE3_MP_R\(15)") )
				( member ( signalRef "@baseboard_fab2_lib.baseboard_fab2(sch_1):p3e_cpu1_pe3_mp_rxn(0)") )
				( member ( signalRef "@baseboard_fab2_lib.baseboard_fab2(sch_1):p3e_cpu1_pe3_mp_rxn(1)") )
				( member ( signalRef "@baseboard_fab2_lib.baseboard_fab2(sch_1):p3e_cpu1_pe3_mp_rxn(2)") )
				( member ( signalRef "@baseboard_fab2_lib.baseboard_fab2(sch_1):p3e_cpu1_pe3_mp_rxn(3)") )
				( member ( signalRef "@baseboard_fab2_lib.baseboard_fab2(sch_1):p3e_cpu1_pe3_mp_rxn(4)") )
				( member ( signalRef "@baseboard_fab2_lib.baseboard_fab2(sch_1):p3e_cpu1_pe3_mp_rxn(5)") )
				( member ( signalRef "@baseboard_fab2_lib.baseboard_fab2(sch_1):p3e_cpu1_pe3_mp_rxn(6)") )
				( member ( signalRef "@baseboard_fab2_lib.baseboard_fab2(sch_1):p3e_cpu1_pe3_mp_rxn(7)") )
				( member ( signalRef "@baseboard_fab2_lib.baseboard_fab2(sch_1):p3e_cpu1_pe3_mp_rxn(8)") )
				( member ( signalRef "@baseboard_fab2_lib.baseboard_fab2(sch_1):p3e_cpu1_pe3_mp_rxn(9)") )
				( member ( signalRef "@baseboard_fab2_lib.baseboard_fab2(sch_1):p3e_cpu1_pe3_mp_rxn(10)") )
				( member ( signalRef "@baseboard_fab2_lib.baseboard_fab2(sch_1):p3e_cpu1_pe3_mp_rxn(11)") )
				( member ( signalRef "@baseboard_fab2_lib.baseboard_fab2(sch_1):p3e_cpu1_pe3_mp_rxn(12)") )
				( member ( signalRef "@baseboard_fab2_lib.baseboard_fab2(sch_1):p3e_cpu1_pe3_mp_rxn(13)") )
				( member ( signalRef "@baseboard_fab2_lib.baseboard_fab2(sch_1):p3e_cpu1_pe3_mp_rxn(14)") )
				( member ( signalRef "@baseboard_fab2_lib.baseboard_fab2(sch_1):p3e_cpu1_pe3_mp_rxn(15)") )
				( member ( signalRef "@baseboard_fab2_lib.baseboard_fab2(sch_1):p3e_cpu1_pe3_mp_rxp(0)") )
				( member ( signalRef "@baseboard_fab2_lib.baseboard_fab2(sch_1):p3e_cpu1_pe3_mp_rxp(1)") )
				( member ( signalRef "@baseboard_fab2_lib.baseboard_fab2(sch_1):p3e_cpu1_pe3_mp_rxp(2)") )
				( member ( signalRef "@baseboard_fab2_lib.baseboard_fab2(sch_1):p3e_cpu1_pe3_mp_rxp(3)") )
				( member ( signalRef "@baseboard_fab2_lib.baseboard_fab2(sch_1):p3e_cpu1_pe3_mp_rxp(4)") )
				( member ( signalRef "@baseboard_fab2_lib.baseboard_fab2(sch_1):p3e_cpu1_pe3_mp_rxp(5)") )
				( member ( signalRef "@baseboard_fab2_lib.baseboard_fab2(sch_1):p3e_cpu1_pe3_mp_rxp(6)") )
				( member ( signalRef "@baseboard_fab2_lib.baseboard_fab2(sch_1):p3e_cpu1_pe3_mp_rxp(7)") )
				( member ( signalRef "@baseboard_fab2_lib.baseboard_fab2(sch_1):p3e_cpu1_pe3_mp_rxp(8)") )
				( member ( signalRef "@baseboard_fab2_lib.baseboard_fab2(sch_1):p3e_cpu1_pe3_mp_rxp(9)") )
				( member ( signalRef "@baseboard_fab2_lib.baseboard_fab2(sch_1):p3e_cpu1_pe3_mp_rxp(10)") )
				( member ( signalRef "@baseboard_fab2_lib.baseboard_fab2(sch_1):p3e_cpu1_pe3_mp_rxp(11)") )
				( member ( signalRef "@baseboard_fab2_lib.baseboard_fab2(sch_1):p3e_cpu1_pe3_mp_rxp(12)") )
				( member ( signalRef "@baseboard_fab2_lib.baseboard_fab2(sch_1):p3e_cpu1_pe3_mp_rxp(13)") )
				( member ( signalRef "@baseboard_fab2_lib.baseboard_fab2(sch_1):p3e_cpu1_pe3_mp_rxp(14)") )
				( member ( signalRef "@baseboard_fab2_lib.baseboard_fab2(sch_1):p3e_cpu1_pe3_mp_rxp(15)") )
				( objectStatus "SNCLS_P3E_CPU1_PE3_MP_RX" )
			)
			( netClass "@sapphirecity_baseboard_lib.sapphirecity_baseboard(sch_1):\P3E_CPU1_PE3AB_SLOTE_TX\"
				( memberType ( signal ) )
				( spacingCSetRef "@sapphirecity_baseboard_lib.sapphirecity_baseboard(sch_1):\11H_US_AND_5H_SL_VIA+3H_A\" )
				( sameNetSpacingCSetRef "@crescent_city_bb_fab1_lib.crescent_city_bb_fab1(sch_1):\7H_US_AND_5H_SL\" )
				( objectFlag fObjectSpacing )
				( objectFlag fObjectSameNetSpacing )
				( member ( diffPairRef "@crescent_city_bb_fab1_lib.crescent_city_bb_fab1(sch_1):\DP_70\") )
				( member ( diffPairRef "@crescent_city_bb_fab1_lib.crescent_city_bb_fab1(sch_1):\DP_P3E_CPU1_PE3_MP_C\(10)") )
				( member ( diffPairRef "@crescent_city_bb_fab1_lib.crescent_city_bb_fab1(sch_1):\DP_62\") )
				( member ( diffPairRef "@crescent_city_bb_fab1_lib.crescent_city_bb_fab1(sch_1):\DP_64\") )
				( member ( diffPairRef "@crescent_city_bb_fab1_lib.crescent_city_bb_fab1(sch_1):\DP_P3E_CPU1_PE3_MP_C\(8)") )
				( member ( diffPairRef "@crescent_city_bb_fab1_lib.crescent_city_bb_fab1(sch_1):\DP_55\") )
				( member ( diffPairRef "@crescent_city_bb_fab1_lib.crescent_city_bb_fab1(sch_1):\DP_56\") )
				( member ( diffPairRef "@crescent_city_bb_fab1_lib.crescent_city_bb_fab1(sch_1):\DP_57\") )
				( member ( diffPairRef "@crescent_city_bb_fab1_lib.crescent_city_bb_fab1(sch_1):\DP_58\") )
				( member ( diffPairRef "@crescent_city_bb_fab1_lib.crescent_city_bb_fab1(sch_1):\DP_59\") )
				( member ( diffPairRef "@crescent_city_bb_fab1_lib.crescent_city_bb_fab1(sch_1):\DP_60\") )
				( member ( diffPairRef "@crescent_city_bb_fab1_lib.crescent_city_bb_fab1(sch_1):\DP_61\") )
				( member ( diffPairRef "@crescent_city_bb_fab1_lib.crescent_city_bb_fab1(sch_1):\DP_66\") )
				( member ( diffPairRef "@crescent_city_bb_fab1_lib.crescent_city_bb_fab1(sch_1):\DP_67\") )
				( member ( diffPairRef "@crescent_city_bb_fab1_lib.crescent_city_bb_fab1(sch_1):\DP_68\") )
				( member ( diffPairRef "@crescent_city_bb_fab1_lib.crescent_city_bb_fab1(sch_1):\DP_69\") )
				( member ( signalRef "@baseboard_fab2_lib.baseboard_fab2(sch_1):p3e_cpu1_pe3_mp_c_txn(0)") )
				( member ( signalRef "@baseboard_fab2_lib.baseboard_fab2(sch_1):p3e_cpu1_pe3_mp_c_txn(1)") )
				( member ( signalRef "@baseboard_fab2_lib.baseboard_fab2(sch_1):p3e_cpu1_pe3_mp_c_txn(2)") )
				( member ( signalRef "@baseboard_fab2_lib.baseboard_fab2(sch_1):p3e_cpu1_pe3_mp_c_txn(3)") )
				( member ( signalRef "@baseboard_fab2_lib.baseboard_fab2(sch_1):p3e_cpu1_pe3_mp_c_txn(4)") )
				( member ( signalRef "@baseboard_fab2_lib.baseboard_fab2(sch_1):p3e_cpu1_pe3_mp_c_txn(5)") )
				( member ( signalRef "@baseboard_fab2_lib.baseboard_fab2(sch_1):p3e_cpu1_pe3_mp_c_txn(6)") )
				( member ( signalRef "@baseboard_fab2_lib.baseboard_fab2(sch_1):p3e_cpu1_pe3_mp_c_txn(7)") )
				( member ( signalRef "@baseboard_fab2_lib.baseboard_fab2(sch_1):p3e_cpu1_pe3_mp_c_txp(0)") )
				( member ( signalRef "@baseboard_fab2_lib.baseboard_fab2(sch_1):p3e_cpu1_pe3_mp_c_txp(1)") )
				( member ( signalRef "@baseboard_fab2_lib.baseboard_fab2(sch_1):p3e_cpu1_pe3_mp_c_txp(2)") )
				( member ( signalRef "@baseboard_fab2_lib.baseboard_fab2(sch_1):p3e_cpu1_pe3_mp_c_txp(3)") )
				( member ( signalRef "@baseboard_fab2_lib.baseboard_fab2(sch_1):p3e_cpu1_pe3_mp_c_txp(4)") )
				( member ( signalRef "@baseboard_fab2_lib.baseboard_fab2(sch_1):p3e_cpu1_pe3_mp_c_txp(5)") )
				( member ( signalRef "@baseboard_fab2_lib.baseboard_fab2(sch_1):p3e_cpu1_pe3_mp_c_txp(6)") )
				( member ( signalRef "@baseboard_fab2_lib.baseboard_fab2(sch_1):p3e_cpu1_pe3_mp_c_txp(7)") )
				( member ( signalRef "@baseboard_fab2_lib.baseboard_fab2(sch_1):p3e_cpu1_pe3_mp_txn(0)") )
				( member ( signalRef "@baseboard_fab2_lib.baseboard_fab2(sch_1):p3e_cpu1_pe3_mp_txn(1)") )
				( member ( signalRef "@baseboard_fab2_lib.baseboard_fab2(sch_1):p3e_cpu1_pe3_mp_txn(2)") )
				( member ( signalRef "@baseboard_fab2_lib.baseboard_fab2(sch_1):p3e_cpu1_pe3_mp_txn(3)") )
				( member ( signalRef "@baseboard_fab2_lib.baseboard_fab2(sch_1):p3e_cpu1_pe3_mp_txn(4)") )
				( member ( signalRef "@baseboard_fab2_lib.baseboard_fab2(sch_1):p3e_cpu1_pe3_mp_txn(5)") )
				( member ( signalRef "@baseboard_fab2_lib.baseboard_fab2(sch_1):p3e_cpu1_pe3_mp_txn(6)") )
				( member ( signalRef "@baseboard_fab2_lib.baseboard_fab2(sch_1):p3e_cpu1_pe3_mp_txn(7)") )
				( member ( signalRef "@baseboard_fab2_lib.baseboard_fab2(sch_1):p3e_cpu1_pe3_mp_txp(0)") )
				( member ( signalRef "@baseboard_fab2_lib.baseboard_fab2(sch_1):p3e_cpu1_pe3_mp_txp(1)") )
				( member ( signalRef "@baseboard_fab2_lib.baseboard_fab2(sch_1):p3e_cpu1_pe3_mp_txp(2)") )
				( member ( signalRef "@baseboard_fab2_lib.baseboard_fab2(sch_1):p3e_cpu1_pe3_mp_txp(3)") )
				( member ( signalRef "@baseboard_fab2_lib.baseboard_fab2(sch_1):p3e_cpu1_pe3_mp_txp(4)") )
				( member ( signalRef "@baseboard_fab2_lib.baseboard_fab2(sch_1):p3e_cpu1_pe3_mp_txp(5)") )
				( member ( signalRef "@baseboard_fab2_lib.baseboard_fab2(sch_1):p3e_cpu1_pe3_mp_txp(6)") )
				( member ( signalRef "@baseboard_fab2_lib.baseboard_fab2(sch_1):p3e_cpu1_pe3_mp_txp(7)") )
				( member ( signalRef "@baseboard_fab2_lib.baseboard_fab2(sch_1):p3e_cpu1_pe3_mp_c_txn(12)") )
				( member ( signalRef "@baseboard_fab2_lib.baseboard_fab2(sch_1):p3e_cpu1_pe3_mp_c_txn(13)") )
				( member ( signalRef "@baseboard_fab2_lib.baseboard_fab2(sch_1):p3e_cpu1_pe3_mp_c_txn(14)") )
				( member ( signalRef "@baseboard_fab2_lib.baseboard_fab2(sch_1):p3e_cpu1_pe3_mp_c_txn(15)") )
				( member ( signalRef "@baseboard_fab2_lib.baseboard_fab2(sch_1):p3e_cpu1_pe3_mp_c_txp(11)") )
				( member ( signalRef "@baseboard_fab2_lib.baseboard_fab2(sch_1):p3e_cpu1_pe3_mp_c_txp(12)") )
				( member ( signalRef "@baseboard_fab2_lib.baseboard_fab2(sch_1):p3e_cpu1_pe3_mp_c_txp(13)") )
				( member ( signalRef "@baseboard_fab2_lib.baseboard_fab2(sch_1):p3e_cpu1_pe3_mp_c_txp(14)") )
				( member ( signalRef "@baseboard_fab2_lib.baseboard_fab2(sch_1):p3e_cpu1_pe3_mp_c_txp(15)") )
				( member ( signalRef "@baseboard_fab2_lib.baseboard_fab2(sch_1):p3e_cpu1_pe3_mp_txn(12)") )
				( member ( signalRef "@baseboard_fab2_lib.baseboard_fab2(sch_1):p3e_cpu1_pe3_mp_txn(13)") )
				( member ( signalRef "@baseboard_fab2_lib.baseboard_fab2(sch_1):p3e_cpu1_pe3_mp_txn(14)") )
				( member ( signalRef "@baseboard_fab2_lib.baseboard_fab2(sch_1):p3e_cpu1_pe3_mp_txn(15)") )
				( member ( signalRef "@baseboard_fab2_lib.baseboard_fab2(sch_1):p3e_cpu1_pe3_mp_txp(11)") )
				( member ( signalRef "@baseboard_fab2_lib.baseboard_fab2(sch_1):p3e_cpu1_pe3_mp_txp(12)") )
				( member ( signalRef "@baseboard_fab2_lib.baseboard_fab2(sch_1):p3e_cpu1_pe3_mp_txp(13)") )
				( member ( signalRef "@baseboard_fab2_lib.baseboard_fab2(sch_1):p3e_cpu1_pe3_mp_txp(14)") )
				( member ( signalRef "@baseboard_fab2_lib.baseboard_fab2(sch_1):p3e_cpu1_pe3_mp_txp(15)") )
				( member ( signalRef "@baseboard_fab2_lib.baseboard_fab2(sch_1):p3e_cpu1_pe3_mp_c_txn(8)") )
				( member ( signalRef "@baseboard_fab2_lib.baseboard_fab2(sch_1):p3e_cpu1_pe3_mp_c_txn(10)") )
				( member ( signalRef "@baseboard_fab2_lib.baseboard_fab2(sch_1):p3e_cpu1_pe3_mp_c_txp(8)") )
				( member ( signalRef "@baseboard_fab2_lib.baseboard_fab2(sch_1):p3e_cpu1_pe3_mp_txn(8)") )
				( member ( signalRef "@baseboard_fab2_lib.baseboard_fab2(sch_1):p3e_cpu1_pe3_mp_txn(10)") )
				( member ( signalRef "@baseboard_fab2_lib.baseboard_fab2(sch_1):p3e_cpu1_pe3_mp_txp(8)") )
				( member ( signalRef "@baseboard_fab2_lib.baseboard_fab2(sch_1):p3e_cpu1_pe3_mp_c_txn(9)") )
				( member ( signalRef "@baseboard_fab2_lib.baseboard_fab2(sch_1):p3e_cpu1_pe3_mp_c_txn(11)") )
				( member ( signalRef "@baseboard_fab2_lib.baseboard_fab2(sch_1):p3e_cpu1_pe3_mp_c_txp(9)") )
				( member ( signalRef "@baseboard_fab2_lib.baseboard_fab2(sch_1):p3e_cpu1_pe3_mp_txn(9)") )
				( member ( signalRef "@baseboard_fab2_lib.baseboard_fab2(sch_1):p3e_cpu1_pe3_mp_txn(11)") )
				( member ( signalRef "@baseboard_fab2_lib.baseboard_fab2(sch_1):p3e_cpu1_pe3_mp_txp(9)") )
				( member ( signalRef "@baseboard_fab2_lib.baseboard_fab2(sch_1):p3e_cpu1_pe3_mp_c_txp(10)") )
				( member ( signalRef "@baseboard_fab2_lib.baseboard_fab2(sch_1):p3e_cpu1_pe3_mp_txp(10)") )
				( member ( electricalNetRef "@crescent_city_bb_fab1_lib.crescent_city_bb_fab1(sch_1):p3e_cpu1_pe3_mp_c_txn(8)") )
				( member ( electricalNetRef "@crescent_city_bb_fab1_lib.crescent_city_bb_fab1(sch_1):p3e_cpu1_pe3_mp_c_txp(8)") )
				( objectStatus "SNCLS_P3E_CPU1_PE3_MP_TX" )
			)
			( netClass "@sapphirecity_baseboard_lib.sapphirecity_baseboard(sch_1):\P3E_CPU1_PE3C_RISER_RX\"
				( memberType ( signal ) )
				( spacingCSetRef "@sapphirecity_baseboard_lib.sapphirecity_baseboard(sch_1):\11H_US_AND_5H_SL_VIA+3H_A\" )
				( sameNetSpacingCSetRef "@crescent_city_bb_fab1_lib.crescent_city_bb_fab1(sch_1):\7H_US_AND_5H_SL\" )
				( objectFlag fObjectSpacing )
				( objectFlag fObjectSameNetSpacing )
				( member ( diffPairRef "@crescent_city_bb_fab1_lib.crescent_city_bb_fab1(sch_1):\P3E_CPU0_PE1_PCH_PCIEUP_RX\(0)") )
				( member ( diffPairRef "@crescent_city_bb_fab1_lib.crescent_city_bb_fab1(sch_1):\P3E_CPU0_PE1_PCH_PCIEUP_RX\(1)") )
				( member ( diffPairRef "@crescent_city_bb_fab1_lib.crescent_city_bb_fab1(sch_1):\P3E_CPU0_PE1_PCH_PCIEUP_RX\(2)") )
				( member ( diffPairRef "@crescent_city_bb_fab1_lib.crescent_city_bb_fab1(sch_1):\P3E_CPU0_PE1_PCH_PCIEUP_RX\(3)") )
				( member ( diffPairRef "@crescent_city_bb_fab1_lib.crescent_city_bb_fab1(sch_1):\P3E_CPU0_PE1_PCH_PCIEUP_RX\(4)") )
				( member ( diffPairRef "@crescent_city_bb_fab1_lib.crescent_city_bb_fab1(sch_1):\P3E_CPU0_PE1_PCH_PCIEUP_RX\(5)") )
				( member ( diffPairRef "@crescent_city_bb_fab1_lib.crescent_city_bb_fab1(sch_1):\P3E_CPU0_PE1_PCH_PCIEUP_RX\(6)") )
				( member ( diffPairRef "@crescent_city_bb_fab1_lib.crescent_city_bb_fab1(sch_1):\P3E_CPU0_PE1_PCH_PCIEUP_RX\(8)") )
				( member ( diffPairRef "@crescent_city_bb_fab1_lib.crescent_city_bb_fab1(sch_1):\P3E_CPU0_PE1_PCH_PCIEUP_RX\(9)") )
				( member ( diffPairRef "@crescent_city_bb_fab1_lib.crescent_city_bb_fab1(sch_1):\P3E_CPU0_PE1_PCH_RX\(10)") )
				( member ( diffPairRef "@crescent_city_bb_fab1_lib.crescent_city_bb_fab1(sch_1):\P3E_CPU0_PE1_PCH_RX\(11)") )
				( member ( diffPairRef "@crescent_city_bb_fab1_lib.crescent_city_bb_fab1(sch_1):\P3E_CPU0_PE1_PCH_RX\(12)") )
				( member ( diffPairRef "@crescent_city_bb_fab1_lib.crescent_city_bb_fab1(sch_1):\P3E_CPU0_PE1_PCH_RX\(13)") )
				( member ( diffPairRef "@crescent_city_bb_fab1_lib.crescent_city_bb_fab1(sch_1):\P3E_CPU0_PE1_PCH_RX\(14)") )
				( member ( diffPairRef "@crescent_city_bb_fab1_lib.crescent_city_bb_fab1(sch_1):\P3E_CPU0_PE1_PCH_RX\(15)") )
				( member ( diffPairRef "@crescent_city_bb_fab1_lib.crescent_city_bb_fab1(sch_1):\DP_5\") )
				( objectStatus "SNCLS_P3E_CPU0_PE1_PCH_PCIEUP_RX" )
			)
			( netClass "@sapphirecity_baseboard_lib.sapphirecity_baseboard(sch_1):\P3E_CPU1_PE3C_RISER2_TX\"
				( memberType ( signal ) )
				( spacingCSetRef "@sapphirecity_baseboard_lib.sapphirecity_baseboard(sch_1):\11H_US_AND_5H_SL_VIA+3H_A\" )
				( sameNetSpacingCSetRef "@crescent_city_bb_fab1_lib.crescent_city_bb_fab1(sch_1):\7H_US_AND_5H_SL\" )
				( objectFlag fObjectSpacing )
				( objectFlag fObjectSameNetSpacing )
				( member ( diffPairRef "@crescent_city_bb_fab1_lib.crescent_city_bb_fab1(sch_1):\DP_6\") )
				( member ( diffPairRef "@crescent_city_bb_fab1_lib.crescent_city_bb_fab1(sch_1):\DP_7\") )
				( member ( diffPairRef "@crescent_city_bb_fab1_lib.crescent_city_bb_fab1(sch_1):\DP_8\") )
				( member ( diffPairRef "@crescent_city_bb_fab1_lib.crescent_city_bb_fab1(sch_1):\DP_9\") )
				( member ( diffPairRef "@crescent_city_bb_fab1_lib.crescent_city_bb_fab1(sch_1):\DP_10\") )
				( member ( diffPairRef "@crescent_city_bb_fab1_lib.crescent_city_bb_fab1(sch_1):\DP_11\") )
				( member ( diffPairRef "@crescent_city_bb_fab1_lib.crescent_city_bb_fab1(sch_1):\DP_12\") )
				( member ( diffPairRef "@crescent_city_bb_fab1_lib.crescent_city_bb_fab1(sch_1):\DP_13\") )
				( member ( diffPairRef "@crescent_city_bb_fab1_lib.crescent_city_bb_fab1(sch_1):\DP_15\") )
				( member ( diffPairRef "@crescent_city_bb_fab1_lib.crescent_city_bb_fab1(sch_1):\DP_16\") )
				( member ( diffPairRef "@crescent_city_bb_fab1_lib.crescent_city_bb_fab1(sch_1):\DP_17\") )
				( member ( diffPairRef "@crescent_city_bb_fab1_lib.crescent_city_bb_fab1(sch_1):\DP_18\") )
				( member ( diffPairRef "@crescent_city_bb_fab1_lib.crescent_city_bb_fab1(sch_1):\DP_19\") )
				( member ( diffPairRef "@crescent_city_bb_fab1_lib.crescent_city_bb_fab1(sch_1):\DP_20\") )
				( member ( diffPairRef "@crescent_city_bb_fab1_lib.crescent_city_bb_fab1(sch_1):\DP_21\") )
				( member ( diffPairRef "@crescent_city_bb_fab1_lib.crescent_city_bb_fab1(sch_1):\DP_22\") )
				( objectStatus "SNCLS_P3E_CPU0_PE1_PCH_PCIEUP_TX" )
			)
			( netClass "@sapphirecity_baseboard_lib.sapphirecity_baseboard(sch_1):\P3E_CPU1_PE3D_RISER2_RX\"
				( memberType ( signal ) )
				( spacingCSetRef "@sapphirecity_baseboard_lib.sapphirecity_baseboard(sch_1):\11H_US_AND_5H_SL_VIA+3H_A\" )
				( sameNetSpacingCSetRef "@crescent_city_bb_fab1_lib.crescent_city_bb_fab1(sch_1):\7H_US_AND_5H_SL\" )
				( objectFlag fObjectSpacing )
				( objectFlag fObjectSameNetSpacing )
				( member ( diffPairRef "@crescent_city_bb_fab1_lib.crescent_city_bb_fab1(sch_1):\P3E_CPU0_PE3_OCP_RX\(0)") )
				( member ( diffPairRef "@crescent_city_bb_fab1_lib.crescent_city_bb_fab1(sch_1):\P3E_CPU0_PE3_OCP_RX\(1)") )
				( member ( diffPairRef "@crescent_city_bb_fab1_lib.crescent_city_bb_fab1(sch_1):\P3E_CPU0_PE3_OCP_RX\(2)") )
				( member ( diffPairRef "@crescent_city_bb_fab1_lib.crescent_city_bb_fab1(sch_1):\P3E_CPU0_PE3_OCP_RX\(3)") )
				( member ( diffPairRef "@crescent_city_bb_fab1_lib.crescent_city_bb_fab1(sch_1):\P3E_CPU0_PE3_OCP_RX\(6)") )
				( member ( diffPairRef "@crescent_city_bb_fab1_lib.crescent_city_bb_fab1(sch_1):\P3E_CPU0_PE3_OCP_RX\(7)") )
				( member ( diffPairRef "@crescent_city_bb_fab1_lib.crescent_city_bb_fab1(sch_1):\P3E_CPU0_PE3_OCP_RX\(8)") )
				( member ( diffPairRef "@crescent_city_bb_fab1_lib.crescent_city_bb_fab1(sch_1):\P3E_CPU0_PE3_OCP_RX\(9)") )
				( member ( diffPairRef "@crescent_city_bb_fab1_lib.crescent_city_bb_fab1(sch_1):\P3E_CPU0_PE3_OCP_RX\(10)") )
				( member ( diffPairRef "@crescent_city_bb_fab1_lib.crescent_city_bb_fab1(sch_1):\P3E_CPU0_PE3_OCP_RX\(11)") )
				( member ( diffPairRef "@crescent_city_bb_fab1_lib.crescent_city_bb_fab1(sch_1):\P3E_CPU0_PE3_OCP_RX\(12)") )
				( member ( diffPairRef "@crescent_city_bb_fab1_lib.crescent_city_bb_fab1(sch_1):\P3E_CPU0_PE3_OCP_RX\(13)") )
				( member ( diffPairRef "@crescent_city_bb_fab1_lib.crescent_city_bb_fab1(sch_1):\P3E_CPU0_PE3_OCP_RX\(14)") )
				( member ( diffPairRef "@crescent_city_bb_fab1_lib.crescent_city_bb_fab1(sch_1):\P3E_CPU0_PE3_OCP_RX\(15)") )
				( member ( diffPairRef "@crescent_city_bb_fab1_lib.crescent_city_bb_fab1(sch_1):\P3E_CPU0_PE3_OCP_RXN\(4)") )
				( member ( diffPairRef "@crescent_city_bb_fab1_lib.crescent_city_bb_fab1(sch_1):\P3E_CPU0_PE3_OCP_RXN\(5)") )
				( member ( signalRef "@baseboard_fab2_lib.baseboard_fab2(sch_1):p3e_cpu0_pe3_ocp_rxn(0)") )
				( member ( signalRef "@baseboard_fab2_lib.baseboard_fab2(sch_1):p3e_cpu0_pe3_ocp_rxn(1)") )
				( member ( signalRef "@baseboard_fab2_lib.baseboard_fab2(sch_1):p3e_cpu0_pe3_ocp_rxn(2)") )
				( member ( signalRef "@baseboard_fab2_lib.baseboard_fab2(sch_1):p3e_cpu0_pe3_ocp_rxn(3)") )
				( member ( signalRef "@baseboard_fab2_lib.baseboard_fab2(sch_1):p3e_cpu0_pe3_ocp_rxn(4)") )
				( member ( signalRef "@baseboard_fab2_lib.baseboard_fab2(sch_1):p3e_cpu0_pe3_ocp_rxn(5)") )
				( member ( signalRef "@baseboard_fab2_lib.baseboard_fab2(sch_1):p3e_cpu0_pe3_ocp_rxn(6)") )
				( member ( signalRef "@baseboard_fab2_lib.baseboard_fab2(sch_1):p3e_cpu0_pe3_ocp_rxn(7)") )
				( member ( signalRef "@baseboard_fab2_lib.baseboard_fab2(sch_1):p3e_cpu0_pe3_ocp_rxn(8)") )
				( member ( signalRef "@baseboard_fab2_lib.baseboard_fab2(sch_1):p3e_cpu0_pe3_ocp_rxn(9)") )
				( member ( signalRef "@baseboard_fab2_lib.baseboard_fab2(sch_1):p3e_cpu0_pe3_ocp_rxn(10)") )
				( member ( signalRef "@baseboard_fab2_lib.baseboard_fab2(sch_1):p3e_cpu0_pe3_ocp_rxn(11)") )
				( member ( signalRef "@baseboard_fab2_lib.baseboard_fab2(sch_1):p3e_cpu0_pe3_ocp_rxn(12)") )
				( member ( signalRef "@baseboard_fab2_lib.baseboard_fab2(sch_1):p3e_cpu0_pe3_ocp_rxn(13)") )
				( member ( signalRef "@baseboard_fab2_lib.baseboard_fab2(sch_1):p3e_cpu0_pe3_ocp_rxn(14)") )
				( member ( signalRef "@baseboard_fab2_lib.baseboard_fab2(sch_1):p3e_cpu0_pe3_ocp_rxn(15)") )
				( member ( signalRef "@baseboard_fab2_lib.baseboard_fab2(sch_1):p3e_cpu0_pe3_ocp_rxp(0)") )
				( member ( signalRef "@baseboard_fab2_lib.baseboard_fab2(sch_1):p3e_cpu0_pe3_ocp_rxp(1)") )
				( member ( signalRef "@baseboard_fab2_lib.baseboard_fab2(sch_1):p3e_cpu0_pe3_ocp_rxp(2)") )
				( member ( signalRef "@baseboard_fab2_lib.baseboard_fab2(sch_1):p3e_cpu0_pe3_ocp_rxp(3)") )
				( member ( signalRef "@baseboard_fab2_lib.baseboard_fab2(sch_1):p3e_cpu0_pe3_ocp_rxp(4)") )
				( member ( signalRef "@baseboard_fab2_lib.baseboard_fab2(sch_1):p3e_cpu0_pe3_ocp_rxp(5)") )
				( member ( signalRef "@baseboard_fab2_lib.baseboard_fab2(sch_1):p3e_cpu0_pe3_ocp_rxp(6)") )
				( member ( signalRef "@baseboard_fab2_lib.baseboard_fab2(sch_1):p3e_cpu0_pe3_ocp_rxp(7)") )
				( member ( signalRef "@baseboard_fab2_lib.baseboard_fab2(sch_1):p3e_cpu0_pe3_ocp_rxp(8)") )
				( member ( signalRef "@baseboard_fab2_lib.baseboard_fab2(sch_1):p3e_cpu0_pe3_ocp_rxp(9)") )
				( member ( signalRef "@baseboard_fab2_lib.baseboard_fab2(sch_1):p3e_cpu0_pe3_ocp_rxp(10)") )
				( member ( signalRef "@baseboard_fab2_lib.baseboard_fab2(sch_1):p3e_cpu0_pe3_ocp_rxp(11)") )
				( member ( signalRef "@baseboard_fab2_lib.baseboard_fab2(sch_1):p3e_cpu0_pe3_ocp_rxp(12)") )
				( member ( signalRef "@baseboard_fab2_lib.baseboard_fab2(sch_1):p3e_cpu0_pe3_ocp_rxp(13)") )
				( member ( signalRef "@baseboard_fab2_lib.baseboard_fab2(sch_1):p3e_cpu0_pe3_ocp_rxp(14)") )
				( member ( signalRef "@baseboard_fab2_lib.baseboard_fab2(sch_1):p3e_cpu0_pe3_ocp_rxp(15)") )
				( objectStatus "SNCLS_P3E_CPU0_PE3_OCP_RX" )
			)
			( netClass "@sapphirecity_baseboard_lib.sapphirecity_baseboard(sch_1):\P3E_CPU1_PE3D_RISER2_TX\"
				( memberType ( signal ) )
				( spacingCSetRef "@sapphirecity_baseboard_lib.sapphirecity_baseboard(sch_1):\11H_US_AND_5H_SL_VIA+3H_A\" )
				( sameNetSpacingCSetRef "@crescent_city_bb_fab1_lib.crescent_city_bb_fab1(sch_1):\7H_US_AND_5H_SL\" )
				( objectFlag fObjectSpacing )
				( objectFlag fObjectSameNetSpacing )
				( member ( diffPairRef "@crescent_city_bb_fab1_lib.crescent_city_bb_fab1(sch_1):\DP_39\") )
				( member ( diffPairRef "@crescent_city_bb_fab1_lib.crescent_city_bb_fab1(sch_1):\DP_40\") )
				( member ( diffPairRef "@crescent_city_bb_fab1_lib.crescent_city_bb_fab1(sch_1):\DP_41\") )
				( member ( diffPairRef "@crescent_city_bb_fab1_lib.crescent_city_bb_fab1(sch_1):\DP_42\") )
				( member ( diffPairRef "@crescent_city_bb_fab1_lib.crescent_city_bb_fab1(sch_1):\DP_43\") )
				( member ( diffPairRef "@crescent_city_bb_fab1_lib.crescent_city_bb_fab1(sch_1):\DP_44\") )
				( member ( diffPairRef "@crescent_city_bb_fab1_lib.crescent_city_bb_fab1(sch_1):\DP_45\") )
				( member ( diffPairRef "@crescent_city_bb_fab1_lib.crescent_city_bb_fab1(sch_1):\DP_46\") )
				( member ( diffPairRef "@crescent_city_bb_fab1_lib.crescent_city_bb_fab1(sch_1):\DP_47\") )
				( member ( diffPairRef "@crescent_city_bb_fab1_lib.crescent_city_bb_fab1(sch_1):\DP_48\") )
				( member ( diffPairRef "@crescent_city_bb_fab1_lib.crescent_city_bb_fab1(sch_1):\DP_49\") )
				( member ( diffPairRef "@crescent_city_bb_fab1_lib.crescent_city_bb_fab1(sch_1):\DP_50\") )
				( member ( diffPairRef "@crescent_city_bb_fab1_lib.crescent_city_bb_fab1(sch_1):\DP_51\") )
				( member ( diffPairRef "@crescent_city_bb_fab1_lib.crescent_city_bb_fab1(sch_1):\DP_52\") )
				( member ( diffPairRef "@crescent_city_bb_fab1_lib.crescent_city_bb_fab1(sch_1):\DP_53\") )
				( member ( diffPairRef "@crescent_city_bb_fab1_lib.crescent_city_bb_fab1(sch_1):\DP_54\") )
				( member ( electricalNetRef "@crescent_city_bb_fab1_lib.crescent_city_bb_fab1(sch_1):p3e_cpu0_pe3_ocp_txn(0)") )
				( member ( electricalNetRef "@crescent_city_bb_fab1_lib.crescent_city_bb_fab1(sch_1):p3e_cpu0_pe3_ocp_txn(1)") )
				( member ( electricalNetRef "@crescent_city_bb_fab1_lib.crescent_city_bb_fab1(sch_1):p3e_cpu0_pe3_ocp_txn(2)") )
				( member ( electricalNetRef "@crescent_city_bb_fab1_lib.crescent_city_bb_fab1(sch_1):p3e_cpu0_pe3_ocp_txn(3)") )
				( member ( electricalNetRef "@crescent_city_bb_fab1_lib.crescent_city_bb_fab1(sch_1):p3e_cpu0_pe3_ocp_txn(4)") )
				( member ( electricalNetRef "@crescent_city_bb_fab1_lib.crescent_city_bb_fab1(sch_1):p3e_cpu0_pe3_ocp_txn(5)") )
				( member ( electricalNetRef "@crescent_city_bb_fab1_lib.crescent_city_bb_fab1(sch_1):p3e_cpu0_pe3_ocp_txn(6)") )
				( member ( electricalNetRef "@crescent_city_bb_fab1_lib.crescent_city_bb_fab1(sch_1):p3e_cpu0_pe3_ocp_txn(7)") )
				( member ( electricalNetRef "@crescent_city_bb_fab1_lib.crescent_city_bb_fab1(sch_1):p3e_cpu0_pe3_ocp_txn(8)") )
				( member ( electricalNetRef "@crescent_city_bb_fab1_lib.crescent_city_bb_fab1(sch_1):p3e_cpu0_pe3_ocp_txn(9)") )
				( member ( electricalNetRef "@crescent_city_bb_fab1_lib.crescent_city_bb_fab1(sch_1):p3e_cpu0_pe3_ocp_txn(10)") )
				( member ( electricalNetRef "@crescent_city_bb_fab1_lib.crescent_city_bb_fab1(sch_1):p3e_cpu0_pe3_ocp_txn(11)") )
				( member ( electricalNetRef "@crescent_city_bb_fab1_lib.crescent_city_bb_fab1(sch_1):p3e_cpu0_pe3_ocp_txn(12)") )
				( member ( electricalNetRef "@crescent_city_bb_fab1_lib.crescent_city_bb_fab1(sch_1):p3e_cpu0_pe3_ocp_txn(13)") )
				( member ( electricalNetRef "@crescent_city_bb_fab1_lib.crescent_city_bb_fab1(sch_1):p3e_cpu0_pe3_ocp_txn(14)") )
				( member ( electricalNetRef "@crescent_city_bb_fab1_lib.crescent_city_bb_fab1(sch_1):p3e_cpu0_pe3_ocp_txn(15)") )
				( member ( electricalNetRef "@crescent_city_bb_fab1_lib.crescent_city_bb_fab1(sch_1):p3e_cpu0_pe3_ocp_txp(0)") )
				( member ( electricalNetRef "@crescent_city_bb_fab1_lib.crescent_city_bb_fab1(sch_1):p3e_cpu0_pe3_ocp_txp(1)") )
				( member ( electricalNetRef "@crescent_city_bb_fab1_lib.crescent_city_bb_fab1(sch_1):p3e_cpu0_pe3_ocp_txp(2)") )
				( member ( electricalNetRef "@crescent_city_bb_fab1_lib.crescent_city_bb_fab1(sch_1):p3e_cpu0_pe3_ocp_txp(3)") )
				( member ( electricalNetRef "@crescent_city_bb_fab1_lib.crescent_city_bb_fab1(sch_1):p3e_cpu0_pe3_ocp_txp(4)") )
				( member ( electricalNetRef "@crescent_city_bb_fab1_lib.crescent_city_bb_fab1(sch_1):p3e_cpu0_pe3_ocp_txp(5)") )
				( member ( electricalNetRef "@crescent_city_bb_fab1_lib.crescent_city_bb_fab1(sch_1):p3e_cpu0_pe3_ocp_txp(6)") )
				( member ( electricalNetRef "@crescent_city_bb_fab1_lib.crescent_city_bb_fab1(sch_1):p3e_cpu0_pe3_ocp_txp(7)") )
				( member ( electricalNetRef "@crescent_city_bb_fab1_lib.crescent_city_bb_fab1(sch_1):p3e_cpu0_pe3_ocp_txp(8)") )
				( member ( electricalNetRef "@crescent_city_bb_fab1_lib.crescent_city_bb_fab1(sch_1):p3e_cpu0_pe3_ocp_txp(9)") )
				( member ( electricalNetRef "@crescent_city_bb_fab1_lib.crescent_city_bb_fab1(sch_1):p3e_cpu0_pe3_ocp_txp(10)") )
				( member ( electricalNetRef "@crescent_city_bb_fab1_lib.crescent_city_bb_fab1(sch_1):p3e_cpu0_pe3_ocp_txp(11)") )
				( member ( electricalNetRef "@crescent_city_bb_fab1_lib.crescent_city_bb_fab1(sch_1):p3e_cpu0_pe3_ocp_txp(12)") )
				( member ( electricalNetRef "@crescent_city_bb_fab1_lib.crescent_city_bb_fab1(sch_1):p3e_cpu0_pe3_ocp_txp(13)") )
				( member ( electricalNetRef "@crescent_city_bb_fab1_lib.crescent_city_bb_fab1(sch_1):p3e_cpu0_pe3_ocp_txp(14)") )
				( member ( electricalNetRef "@crescent_city_bb_fab1_lib.crescent_city_bb_fab1(sch_1):p3e_cpu0_pe3_ocp_txp(15)") )
				( objectStatus "SNCLS_P3E_CPU0_PE3_OCP_TX" )
			)
			( netClass "@baseboard_fab2_lib.baseboard_fab2(sch_1):\PNCLS_SENSE_10MIL\"
				( memberType ( signal ) )
				( physicalCSetRef "@sapphirecity_baseboard_lib.sapphirecity_baseboard(sch_1):\10-5-10_DIFF\" )
				( objectFlag fObjectPhysical )
				( member ( diffPairRef "@crescent_city_bb_fab1_lib.crescent_city_bb_fab1(sch_1):\DP_ISENSE_TMP421_1_DX\") )
				( member ( diffPairRef "@crescent_city_bb_fab1_lib.crescent_city_bb_fab1(sch_1):\DP_ISENSE_TMP421_2_DX\") )
				( member ( signalRef "@baseboard_fab2_lib.baseboard_fab2(sch_1):a_tsense_pvccin_cpu0") )
				( member ( signalRef "@baseboard_fab2_lib.baseboard_fab2(sch_1):a_tsense_pvccin_cpu1") )
				( member ( signalRef "@baseboard_fab2_lib.baseboard_fab2(sch_1):a_tsense_pvccio_cpu0") )
				( member ( signalRef "@baseboard_fab2_lib.baseboard_fab2(sch_1):a_tsense_pvccio_cpu1") )
				( member ( signalRef "@baseboard_fab2_lib.baseboard_fab2(sch_1):a_tsense_pvddq_abc") )
				( member ( signalRef "@baseboard_fab2_lib.baseboard_fab2(sch_1):a_tsense_pvddq_def") )
				( member ( signalRef "@baseboard_fab2_lib.baseboard_fab2(sch_1):a_tsense_pvddq_ghj") )
				( member ( signalRef "@baseboard_fab2_lib.baseboard_fab2(sch_1):a_tsense_pvddq_klm") )
				( member ( signalRef "@baseboard_fab2_lib.baseboard_fab2(sch_1):a_tsense_pvnn_pch_tmon") )
				( member ( signalRef "@baseboard_fab2_lib.baseboard_fab2(sch_1):a_tsense_pvsa_cpu0") )
				( member ( signalRef "@baseboard_fab2_lib.baseboard_fab2(sch_1):a_tsense_pvsa_cpu1") )
				( member ( signalRef "@baseboard_fab2_lib.baseboard_fab2(sch_1):a_tsense_p1v05_pch_stby_tmon") )
				( member ( signalRef "@baseboard_fab2_lib.baseboard_fab2(sch_1):vsense_pmax_cpu0") )
				( member ( signalRef "@baseboard_fab2_lib.baseboard_fab2(sch_1):vsense_pmax_cpu1") )
				( member ( signalRef "@baseboard_fab2_lib.baseboard_fab2(sch_1):vsense_p12v_adm1085") )
				( member ( signalRef "@baseboard_fab2_lib.baseboard_fab2(sch_1):vsense_pvddq_abc_vtt") )
				( member ( signalRef "@baseboard_fab2_lib.baseboard_fab2(sch_1):vsense_pvddq_def_vtt") )
				( member ( signalRef "@baseboard_fab2_lib.baseboard_fab2(sch_1):vsense_pvddq_ghj_vtt") )
				( member ( signalRef "@baseboard_fab2_lib.baseboard_fab2(sch_1):vsense_pvddq_klm_vtt") )
				( member ( signalRef "@baseboard_fab2_lib.baseboard_fab2(sch_1):vsense_pvpp_abc") )
				( member ( signalRef "@baseboard_fab2_lib.baseboard_fab2(sch_1):vsense_pvpp_def") )
				( member ( signalRef "@baseboard_fab2_lib.baseboard_fab2(sch_1):vsense_pvpp_ghj") )
				( member ( signalRef "@baseboard_fab2_lib.baseboard_fab2(sch_1):vsense_pvpp_klm") )
				( member ( signalRef "@baseboard_fab2_lib.baseboard_fab2(sch_1):vsense_pvsa_cpu1_bvsp") )
				( member ( signalRef "@baseboard_fab2_lib.baseboard_fab2(sch_1):vsense_vccinr2pmax_cpu0") )
				( member ( signalRef "@baseboard_fab2_lib.baseboard_fab2(sch_1):vsense_vccinr2pmax_cpu1") )
				( member ( electricalNetRef "@crescent_city_bb_fab1_lib.crescent_city_bb_fab1(sch_1):vsense_p3v3_stby") )
				( objectStatus "PNCLS_SENSE_10MIL" )
			)
			( netClass "@baseboard_fab2_lib.baseboard_fab2(sch_1):\SNCLS_KR_TX\"
				( memberType ( signal ) )
				( spacingCSetRef "@baseboard_fab2_lib.baseboard_fab2(sch_1):\NEW_KR_15H_US_&_7H_SL_VIA_2H+A\" )
				( objectFlag fObjectSpacing )
				( objectFlag fObjectSameNetSpacing )
				( member ( diffPairRef "@baseboard_fab2_lib.baseboard_fab2(sch_1):\DP_KR_P0_OCP_TX\") )
				( member ( diffPairRef "@baseboard_fab2_lib.baseboard_fab2(sch_1):\DP_KR_P1_OCP_TX\") )
				( member ( diffPairRef "@baseboard_fab2_lib.baseboard_fab2(sch_1):\DP_KR_P2_OCP_TX\") )
				( member ( diffPairRef "@baseboard_fab2_lib.baseboard_fab2(sch_1):\DP_KR_P3_OCP_TX\") )
				( objectStatus "SNCLS_KR_TX" )
			)
			( netClass "@baseboard_fab2_lib.baseboard_fab2(sch_1):\SNCSL_KR_RX\"
				( memberType ( signal ) )
				( spacingCSetRef "@baseboard_fab2_lib.baseboard_fab2(sch_1):\NEW_KR_15H_US_&_7H_SL_VIA_2H+A\" )
				( objectFlag fObjectSpacing )
				( objectFlag fObjectSameNetSpacing )
				( member ( diffPairRef "@baseboard_fab2_lib.baseboard_fab2(sch_1):\DP_KR_P0_OCP_RX\") )
				( member ( diffPairRef "@baseboard_fab2_lib.baseboard_fab2(sch_1):\DP_KR_P1_OCP_RX\") )
				( member ( diffPairRef "@baseboard_fab2_lib.baseboard_fab2(sch_1):\DP_KR_P2_OCP_RX\") )
				( member ( diffPairRef "@baseboard_fab2_lib.baseboard_fab2(sch_1):\DP_KR_P3_OCP_RX\") )
				( objectStatus "SNCLS_KR_RX" )
			)
			( netClass "@sapphirecity_baseboard_lib.sapphirecity_baseboard(sch_1):\POWER\"
				( memberType ( signal ) )
				( physicalCSetRef "@sapphirecity_baseboard_lib.sapphirecity_baseboard(sch_1):\10-MILS-POWER\" )
				( spacingCSetRef "@sapphirecity_baseboard_lib.sapphirecity_baseboard(sch_1):\10MIL\" )
				( sameNetSpacingCSetRef "@crescent_city_bb_fab1_lib.crescent_city_bb_fab1(sch_1):\10_MILS\" )
				( objectFlag fObjectPhysical )
				( objectFlag fObjectSpacing )
				( objectFlag fObjectSameNetSpacing )
				( member ( signalRef "@baseboard_fab2_lib.baseboard_fab2(sch_1):p5v") )
				( member ( signalRef "@baseboard_fab2_lib.baseboard_fab2(sch_1):p5v_usb") )
				( member ( signalRef "@baseboard_fab2_lib.baseboard_fab2(sch_1):p12v") )
				( member ( signalRef "@baseboard_fab2_lib.baseboard_fab2(sch_1):p3v_bat_source") )
				( member ( signalRef "@baseboard_fab2_lib.baseboard_fab2(sch_1):p3v3") )
				( member ( signalRef "@baseboard_fab2_lib.baseboard_fab2(sch_1):p5v_stby") )
				( member ( signalRef "@baseboard_fab2_lib.baseboard_fab2(sch_1):p12v_stby") )
				( member ( signalRef "@baseboard_fab2_lib.baseboard_fab2(sch_1):p12v_hsc_senn0") )
				( member ( signalRef "@baseboard_fab2_lib.baseboard_fab2(sch_1):p12v_hsc_senn1") )
				( member ( signalRef "@baseboard_fab2_lib.baseboard_fab2(sch_1):p12v_hsc_senp0") )
				( member ( signalRef "@baseboard_fab2_lib.baseboard_fab2(sch_1):p12v_hsc_senp1") )
				( member ( signalRef "@baseboard_fab2_lib.baseboard_fab2(sch_1):p12v_mb0_sw") )
				( member ( signalRef "@baseboard_fab2_lib.baseboard_fab2(sch_1):p12v_psu") )
				( member ( signalRef "@baseboard_fab2_lib.baseboard_fab2(sch_1):pvddq_abc") )
				( member ( signalRef "@baseboard_fab2_lib.baseboard_fab2(sch_1):pvddq_def") )
				( member ( signalRef "@baseboard_fab2_lib.baseboard_fab2(sch_1):pvddq_ghj") )
				( member ( signalRef "@baseboard_fab2_lib.baseboard_fab2(sch_1):pvddq_klm") )
				( member ( signalRef "@baseboard_fab2_lib.baseboard_fab2(sch_1):pvsa_cpu0") )
				( member ( signalRef "@baseboard_fab2_lib.baseboard_fab2(sch_1):pvsa_cpu1") )
				( member ( signalRef "@baseboard_fab2_lib.baseboard_fab2(sch_1):pvtt_abc") )
				( member ( signalRef "@baseboard_fab2_lib.baseboard_fab2(sch_1):pvtt_def") )
				( member ( signalRef "@baseboard_fab2_lib.baseboard_fab2(sch_1):pvtt_ghj") )
				( member ( signalRef "@baseboard_fab2_lib.baseboard_fab2(sch_1):pvtt_klm") )
				( member ( signalRef "@baseboard_fab2_lib.baseboard_fab2(sch_1):pvpp_abc") )
				( member ( signalRef "@baseboard_fab2_lib.baseboard_fab2(sch_1):pvpp_def") )
				( member ( signalRef "@baseboard_fab2_lib.baseboard_fab2(sch_1):pvpp_ghj") )
				( member ( signalRef "@baseboard_fab2_lib.baseboard_fab2(sch_1):pvpp_klm") )
				( member ( signalRef "@baseboard_fab2_lib.baseboard_fab2(sch_1):p12v_nvdimm_abc") )
				( member ( signalRef "@baseboard_fab2_lib.baseboard_fab2(sch_1):p12v_nvdimm_def") )
				( member ( signalRef "@baseboard_fab2_lib.baseboard_fab2(sch_1):p12v_nvdimm_ghj") )
				( member ( signalRef "@baseboard_fab2_lib.baseboard_fab2(sch_1):p12v_nvdimm_klm") )
				( member ( signalRef "@baseboard_fab2_lib.baseboard_fab2(sch_1):p3v3_stby") )
				( member ( signalRef "@baseboard_fab2_lib.baseboard_fab2(sch_1):pvccin_cpu0") )
				( member ( signalRef "@baseboard_fab2_lib.baseboard_fab2(sch_1):pvccin_cpu1") )
				( member ( signalRef "@baseboard_fab2_lib.baseboard_fab2(sch_1):pvccin_pvsa_cpu0_iinsen") )
				( member ( signalRef "@baseboard_fab2_lib.baseboard_fab2(sch_1):pvccin_pvsa_cpu1_iinsen") )
				( member ( signalRef "@baseboard_fab2_lib.baseboard_fab2(sch_1):pvccio_cpu0") )
				( member ( signalRef "@baseboard_fab2_lib.baseboard_fab2(sch_1):pvccio_cpu1") )
				( member ( signalRef "@baseboard_fab2_lib.baseboard_fab2(sch_1):pvnn_pch_stby") )
				( member ( signalRef "@baseboard_fab2_lib.baseboard_fab2(sch_1):p12v_fan") )
				( member ( signalRef "@baseboard_fab2_lib.baseboard_fab2(sch_1):vr_pvccin_cpu1_vdd") )
				( member ( signalRef "@baseboard_fab2_lib.baseboard_fab2(sch_1):p0v9_lan") )
				( member ( signalRef "@baseboard_fab2_lib.baseboard_fab2(sch_1):p1v5_lan") )
				( member ( signalRef "@baseboard_fab2_lib.baseboard_fab2(sch_1):p1v8_pch_stby") )
				( member ( signalRef "@baseboard_fab2_lib.baseboard_fab2(sch_1):p1v05_pch_stby") )
				( member ( signalRef "@baseboard_fab2_lib.baseboard_fab2(sch_1):p1v26_bmc_stby") )
				( member ( signalRef "@baseboard_fab2_lib.baseboard_fab2(sch_1):p0v7_gtl2014_2") )
				( member ( signalRef "@baseboard_fab2_lib.baseboard_fab2(sch_1):p1v8_bmc_stby_pcie") )
				( member ( signalRef "@baseboard_fab2_lib.baseboard_fab2(sch_1):p1v8_bmc_stby_pciea") )
				( member ( signalRef "@baseboard_fab2_lib.baseboard_fab2(sch_1):p1v05_pch_stby_isclk_pll") )
				( member ( signalRef "@baseboard_fab2_lib.baseboard_fab2(sch_1):p1v05_pch_stby_kr_pll") )
				( member ( signalRef "@baseboard_fab2_lib.baseboard_fab2(sch_1):p1v05_pch_stby_vcca_pll1") )
				( member ( signalRef "@baseboard_fab2_lib.baseboard_fab2(sch_1):p1v05_pch_stby_vcca_pll0") )
				( member ( signalRef "@baseboard_fab2_lib.baseboard_fab2(sch_1):p1v05_pch_stby_wm20_pll") )
				( member ( signalRef "@baseboard_fab2_lib.baseboard_fab2(sch_1):p1v05_pch_stby_wm26_pll") )
				( member ( signalRef "@baseboard_fab2_lib.baseboard_fab2(sch_1):p1v26_bmc_stby_v1pllav12") )
				( member ( signalRef "@baseboard_fab2_lib.baseboard_fab2(sch_1):p1v538_bmc_stby") )
				( member ( signalRef "@baseboard_fab2_lib.baseboard_fab2(sch_1):p3v3_db1200") )
				( member ( signalRef "@baseboard_fab2_lib.baseboard_fab2(sch_1):p3v3_db1200_a") )
				( member ( signalRef "@baseboard_fab2_lib.baseboard_fab2(sch_1):p3v3_db1200_r") )
				( member ( signalRef "@baseboard_fab2_lib.baseboard_fab2(sch_1):p3v_bat_source_r") )
				( member ( signalRef "@baseboard_fab2_lib.baseboard_fab2(sch_1):p3v3_stby_bmc_adcav33") )
				( member ( signalRef "@baseboard_fab2_lib.baseboard_fab2(sch_1):p3v3_stby_bmc_hpllav33") )
				( member ( signalRef "@baseboard_fab2_lib.baseboard_fab2(sch_1):p3v3_stby_mng") )
				( member ( signalRef "@baseboard_fab2_lib.baseboard_fab2(sch_1):p3v3_stby_mng_cpu") )
				( member ( signalRef "@baseboard_fab2_lib.baseboard_fab2(sch_1):p3v3_stby_mng_rgmii") )
				( member ( signalRef "@baseboard_fab2_lib.baseboard_fab2(sch_1):p3v3_stby_mng_rmii") )
				( member ( signalRef "@baseboard_fab2_lib.baseboard_fab2(sch_1):p3v3_stby_pld_d") )
				( member ( signalRef "@baseboard_fab2_lib.baseboard_fab2(sch_1):p5v_hdd_sata") )
				( member ( signalRef "@baseboard_fab2_lib.baseboard_fab2(sch_1):p12v_hdd_sata") )
				( member ( signalRef "@baseboard_fab2_lib.baseboard_fab2(sch_1):p12v_switch_g") )
				( member ( signalRef "@baseboard_fab2_lib.baseboard_fab2(sch_1):gnd_lan_trct1234_c") )
				( member ( signalRef "@baseboard_fab2_lib.baseboard_fab2(sch_1):p12v_fan_switch_g") )
				( member ( signalRef "@baseboard_fab2_lib.baseboard_fab2(sch_1):p3v3_switch_g") )
				( member ( signalRef "@baseboard_fab2_lib.baseboard_fab2(sch_1):p5v_stby_dbg") )
				( member ( signalRef "@baseboard_fab2_lib.baseboard_fab2(sch_1):p5v_switch_g") )
				( member ( signalRef "@baseboard_fab2_lib.baseboard_fab2(sch_1):p12v_hsc_vcc") )
				( member ( signalRef "@baseboard_fab2_lib.baseboard_fab2(sch_1):spa_5v_sin_sw") )
				( member ( signalRef "@baseboard_fab2_lib.baseboard_fab2(sch_1):p5v_stby_dgb_fs") )
				( member ( signalRef "@baseboard_fab2_lib.baseboard_fab2(sch_1):p1v05_pch_stby_vcca_xtal") )
				( member ( signalRef "@baseboard_fab2_lib.baseboard_fab2(sch_1):p0v9_lan_i210") )
				( member ( signalRef "@baseboard_fab2_lib.baseboard_fab2(sch_1):p1v5_lan_i210") )
				( member ( signalRef "@baseboard_fab2_lib.baseboard_fab2(sch_1):p3v3_stby_p1v5_lan_i210") )
				( member ( signalRef "@baseboard_fab2_lib.baseboard_fab2(sch_1):p3v3_fb_adc128_vcc") )
				( member ( signalRef "@baseboard_fab2_lib.baseboard_fab2(sch_1):pvcciomcp_cpu0") )
				( member ( signalRef "@baseboard_fab2_lib.baseboard_fab2(sch_1):pvcciomcp_cpu1") )
				( member ( signalRef "@baseboard_fab2_lib.baseboard_fab2(sch_1):pvccmcp_cpu0") )
				( member ( signalRef "@baseboard_fab2_lib.baseboard_fab2(sch_1):pvccmcp_cpu1") )
				( member ( signalRef "@baseboard_fab2_lib.baseboard_fab2(sch_1):p1v8_mcp_cpu0") )
				( member ( signalRef "@baseboard_fab2_lib.baseboard_fab2(sch_1):p1v8_mcp_cpu1") )
				( member ( signalRef "@baseboard_fab2_lib.baseboard_fab2(sch_1):p3v3_rtc_stby") )
				( objectStatus "POWER" )
			)
			( netClass "@baseboard_fab2_lib.baseboard_fab2(sch_1):\SNCLS_ISENSE\"
				( memberType ( signal ) )
				( spacingCSetRef "@sapphirecity_baseboard_lib.sapphirecity_baseboard(sch_1):\10MIL\" )
				( objectFlag fObjectSpacing )
				( objectFlag fObjectSameNetSpacing )
				( member ( diffPairRef "@baseboard_fab2_lib.baseboard_fab2(sch_1):\DP_ISENSE_PVCCIN_CPU1_PH1\") )
				( member ( diffPairRef "@baseboard_fab2_lib.baseboard_fab2(sch_1):\DP_ISENSE_PVCCIN_CPU1_PH2\") )
				( member ( diffPairRef "@baseboard_fab2_lib.baseboard_fab2(sch_1):\DP_ISENSE_PVCCIN_CPU1_PH4\") )
				( member ( diffPairRef "@baseboard_fab2_lib.baseboard_fab2(sch_1):\DP_ISENSE_PVCCIN_CPU1_PH5\") )
				( member ( diffPairRef "@baseboard_fab2_lib.baseboard_fab2(sch_1):\DP_ISENSE_PVSA_CPU1_PH\") )
				( member ( diffPairRef "@baseboard_fab2_lib.baseboard_fab2(sch_1):\DP_ISENSE_PVCCIN_CPU1_PH3\") )
				( member ( diffPairRef "@baseboard_fab2_lib.baseboard_fab2(sch_1):\DIFFPAIR0\") )
				( member ( diffPairRef "@baseboard_fab2_lib.baseboard_fab2(sch_1):\DIFFPAIR1\") )
				( member ( diffPairRef "@baseboard_fab2_lib.baseboard_fab2(sch_1):\DIFFPAIR2\") )
				( member ( diffPairRef "@baseboard_fab2_lib.baseboard_fab2(sch_1):\DIFFPAIR3\") )
				( member ( diffPairRef "@baseboard_fab2_lib.baseboard_fab2(sch_1):\DIFFPAIR4\") )
				( member ( diffPairRef "@baseboard_fab2_lib.baseboard_fab2(sch_1):\DIFFPAIR5\") )
				( member ( diffPairRef "@baseboard_fab2_lib.baseboard_fab2(sch_1):\DIFFPAIR6\") )
				( member ( diffPairRef "@baseboard_fab2_lib.baseboard_fab2(sch_1):\DIFFPAIR7\") )
				( member ( diffPairRef "@baseboard_fab2_lib.baseboard_fab2(sch_1):\DIFFPAIR8\") )
				( member ( diffPairRef "@baseboard_fab2_lib.baseboard_fab2(sch_1):\DIFFPAIR9\") )
				( member ( diffPairRef "@baseboard_fab2_lib.baseboard_fab2(sch_1):\DIFFPAIR10\") )
				( member ( diffPairRef "@baseboard_fab2_lib.baseboard_fab2(sch_1):\DIFFPAIR11\") )
				( member ( diffPairRef "@baseboard_fab2_lib.baseboard_fab2(sch_1):\DIFFPAIR12\") )
				( member ( diffPairRef "@baseboard_fab2_lib.baseboard_fab2(sch_1):\DIFFPAIR13\") )
				( member ( diffPairRef "@baseboard_fab2_lib.baseboard_fab2(sch_1):\DIFFPAIR14\") )
				( member ( diffPairRef "@baseboard_fab2_lib.baseboard_fab2(sch_1):\DIFFPAIR15\") )
				( member ( diffPairRef "@baseboard_fab2_lib.baseboard_fab2(sch_1):\DIFFPAIR16\") )
				( member ( diffPairRef "@baseboard_fab2_lib.baseboard_fab2(sch_1):\DIFFPAIR17\") )
				( member ( signalRef "@baseboard_fab2_lib.baseboard_fab2(sch_1):isense_pvccin_cpu1_ph3_imon") )
				( member ( signalRef "@baseboard_fab2_lib.baseboard_fab2(sch_1):vr_pvccin_cpu1_airef3") )
				( member ( signalRef "@baseboard_fab2_lib.baseboard_fab2(sch_1):isense_pvccin_cpu0_ph1_imon") )
				( member ( signalRef "@baseboard_fab2_lib.baseboard_fab2(sch_1):isense_pvccin_cpu0_ph2_imon") )
				( member ( signalRef "@baseboard_fab2_lib.baseboard_fab2(sch_1):isense_pvccin_cpu0_ph3_imon") )
				( member ( signalRef "@baseboard_fab2_lib.baseboard_fab2(sch_1):isense_pvccin_cpu0_ph4_imon") )
				( member ( signalRef "@baseboard_fab2_lib.baseboard_fab2(sch_1):isense_pvccin_cpu0_ph5_imon") )
				( member ( signalRef "@baseboard_fab2_lib.baseboard_fab2(sch_1):isense_pvccio_cpu0_ph1_imon") )
				( member ( signalRef "@baseboard_fab2_lib.baseboard_fab2(sch_1):isense_pvddq_ghj_ph2_imon") )
				( member ( signalRef "@baseboard_fab2_lib.baseboard_fab2(sch_1):isense_pvnn_pch_ph1_imon") )
				( member ( signalRef "@baseboard_fab2_lib.baseboard_fab2(sch_1):isense_pvsa_cpu0_imon") )
				( member ( signalRef "@baseboard_fab2_lib.baseboard_fab2(sch_1):isense_p1v05_pch_stby_ph1_imon") )
				( member ( signalRef "@baseboard_fab2_lib.baseboard_fab2(sch_1):isense_pvccio_cpu1_ph1_imon") )
				( member ( signalRef "@baseboard_fab2_lib.baseboard_fab2(sch_1):vr_pvccio_cpu1_airef1") )
				( objectStatus "SNCLS_ISENSE" )
			)
			( netClass "@crescent_city_bb_fab1_lib.crescent_city_bb_fab1(sch_1):\SNCLS_NOISY_NETS\"
				( memberType ( signal ) )
				( spacingCSetRef "@sapphirecity_baseboard_lib.sapphirecity_baseboard(sch_1):\10MIL\" )
				( objectFlag fObjectSpacing )
				( objectFlag fObjectSameNetSpacing )
				( member ( signalRef "@baseboard_fab2_lib.baseboard_fab2(sch_1):vr_pvpp_klm_boot") )
				( member ( signalRef "@baseboard_fab2_lib.baseboard_fab2(sch_1):vr_pvpp_klm_boot_r") )
				( member ( signalRef "@baseboard_fab2_lib.baseboard_fab2(sch_1):vr_pvddq_def_ph1_boot") )
				( member ( signalRef "@baseboard_fab2_lib.baseboard_fab2(sch_1):vr_pvddq_def_ph1_phase") )
				( member ( signalRef "@baseboard_fab2_lib.baseboard_fab2(sch_1):vr_pvddq_def_ph2_boot") )
				( member ( signalRef "@baseboard_fab2_lib.baseboard_fab2(sch_1):vr_pvddq_def_ph2_phase") )
				( member ( signalRef "@baseboard_fab2_lib.baseboard_fab2(sch_1):vr_pvddq_ghj_ph1_boot") )
				( member ( signalRef "@baseboard_fab2_lib.baseboard_fab2(sch_1):vr_pvddq_ghj_ph1_phase") )
				( member ( signalRef "@baseboard_fab2_lib.baseboard_fab2(sch_1):vr_pvddq_ghj_ph2_boot") )
				( member ( signalRef "@baseboard_fab2_lib.baseboard_fab2(sch_1):vr_pvddq_ghj_ph2_phase") )
				( member ( signalRef "@baseboard_fab2_lib.baseboard_fab2(sch_1):vr_pvddq_klm_ph1_boot") )
				( member ( signalRef "@baseboard_fab2_lib.baseboard_fab2(sch_1):vr_pvddq_klm_ph1_phase") )
				( member ( signalRef "@baseboard_fab2_lib.baseboard_fab2(sch_1):vr_pvddq_klm_ph2_boot") )
				( member ( signalRef "@baseboard_fab2_lib.baseboard_fab2(sch_1):vr_pvddq_klm_ph2_phase") )
				( member ( signalRef "@baseboard_fab2_lib.baseboard_fab2(sch_1):vr_pvnn_pch_ph1_boot") )
				( member ( signalRef "@baseboard_fab2_lib.baseboard_fab2(sch_1):vr_pvnn_pch_ph1_phase") )
				( member ( signalRef "@baseboard_fab2_lib.baseboard_fab2(sch_1):vr_pvsa_cpu0_boot") )
				( member ( signalRef "@baseboard_fab2_lib.baseboard_fab2(sch_1):vr_pvsa_cpu0_phase") )
				( member ( signalRef "@baseboard_fab2_lib.baseboard_fab2(sch_1):vr_pvsa_cpu1_boot") )
				( member ( signalRef "@baseboard_fab2_lib.baseboard_fab2(sch_1):vr_pvsa_cpu1_phase") )
				( member ( signalRef "@baseboard_fab2_lib.baseboard_fab2(sch_1):vr_p1v05_pch_stby_ph1_boot") )
				( member ( signalRef "@baseboard_fab2_lib.baseboard_fab2(sch_1):vr_p1v05_pch_stby_ph1_phase") )
				( member ( signalRef "@baseboard_fab2_lib.baseboard_fab2(sch_1):vr_p3v3_stby_boot") )
				( member ( signalRef "@baseboard_fab2_lib.baseboard_fab2(sch_1):vr_p3v3_stby_boot_r") )
				( member ( signalRef "@baseboard_fab2_lib.baseboard_fab2(sch_1):vr_p3v3_stby_phase") )
				( member ( signalRef "@baseboard_fab2_lib.baseboard_fab2(sch_1):vr_p3v3_stby_ugate") )
				( member ( signalRef "@baseboard_fab2_lib.baseboard_fab2(sch_1):vr_p5v_stby_boot") )
				( member ( signalRef "@baseboard_fab2_lib.baseboard_fab2(sch_1):vr_p5v_stby_phase") )
				( member ( signalRef "@baseboard_fab2_lib.baseboard_fab2(sch_1):vr_pvnn_pch_ph1_phase_sw") )
				( member ( signalRef "@baseboard_fab2_lib.baseboard_fab2(sch_1):vr_pvsa_cpu0_phase_sw") )
				( member ( signalRef "@baseboard_fab2_lib.baseboard_fab2(sch_1):vr_pvsa_cpu1_phase_sw") )
				( member ( signalRef "@baseboard_fab2_lib.baseboard_fab2(sch_1):vr_p1v05_pch_stby_ph1_phase_sw") )
				( member ( signalRef "@baseboard_fab2_lib.baseboard_fab2(sch_1):vr_pvccio_cpu0_ph1_boot") )
				( member ( signalRef "@baseboard_fab2_lib.baseboard_fab2(sch_1):vr_pvccio_cpu0_ph1_phase") )
				( member ( signalRef "@baseboard_fab2_lib.baseboard_fab2(sch_1):vr_pvccio_cpu1_ph1_boot") )
				( member ( signalRef "@baseboard_fab2_lib.baseboard_fab2(sch_1):vr_pvccio_cpu1_ph1_phase") )
				( member ( signalRef "@baseboard_fab2_lib.baseboard_fab2(sch_1):vr_pvddq_abc_ph1_boot") )
				( member ( signalRef "@baseboard_fab2_lib.baseboard_fab2(sch_1):vr_pvddq_abc_ph1_phase") )
				( member ( signalRef "@baseboard_fab2_lib.baseboard_fab2(sch_1):vr_pvddq_abc_ph2_boot") )
				( member ( signalRef "@baseboard_fab2_lib.baseboard_fab2(sch_1):vr_pvddq_abc_ph2_phase") )
				( member ( signalRef "@baseboard_fab2_lib.baseboard_fab2(sch_1):vr_pvpp_abc_boot") )
				( member ( signalRef "@baseboard_fab2_lib.baseboard_fab2(sch_1):vr_pvpp_abc_boot_r") )
				( member ( signalRef "@baseboard_fab2_lib.baseboard_fab2(sch_1):vr_pvpp_abc_phase") )
				( member ( signalRef "@baseboard_fab2_lib.baseboard_fab2(sch_1):vr_pvpp_def_boot") )
				( member ( signalRef "@baseboard_fab2_lib.baseboard_fab2(sch_1):vr_fet_sw_p12v_stby_pvddq_abc") )
				( member ( signalRef "@baseboard_fab2_lib.baseboard_fab2(sch_1):vr_fet_sw_p12v_stby_pvddq_def") )
				( member ( signalRef "@baseboard_fab2_lib.baseboard_fab2(sch_1):vr_fet_sw_p12v_stby_pvddq_ghj") )
				( member ( signalRef "@baseboard_fab2_lib.baseboard_fab2(sch_1):vr_fet_sw_p12v_stby_pvddq_klm") )
				( member ( signalRef "@baseboard_fab2_lib.baseboard_fab2(sch_1):vr_fet_sw_p12v_pvccin_cpu0_r") )
				( member ( signalRef "@baseboard_fab2_lib.baseboard_fab2(sch_1):vr_fet_sw_p12v_pvccin_cpu1_r") )
				( member ( signalRef "@baseboard_fab2_lib.baseboard_fab2(sch_1):vr_fet_sw_p12v_stby_pvccin_cpu0") )
				( member ( signalRef "@baseboard_fab2_lib.baseboard_fab2(sch_1):vr_fet_sw_p12v_stby_pvccin_cpu1") )
				( member ( signalRef "@baseboard_fab2_lib.baseboard_fab2(sch_1):vr_fet_sw_p12v_stby_pvpp_abc") )
				( member ( signalRef "@baseboard_fab2_lib.baseboard_fab2(sch_1):vr_fet_sw_p12v_stby_pvpp_def") )
				( member ( signalRef "@baseboard_fab2_lib.baseboard_fab2(sch_1):vr_fet_sw_p12v_stby_pvpp_ghj") )
				( member ( signalRef "@baseboard_fab2_lib.baseboard_fab2(sch_1):vr_fet_sw_p12v_stby_pvpp_klm") )
				( member ( signalRef "@baseboard_fab2_lib.baseboard_fab2(sch_1):vr_fet_sw_p12v_stby_p3v3_stby") )
				( member ( signalRef "@baseboard_fab2_lib.baseboard_fab2(sch_1):vr_pvccin_cpu0_phase1") )
				( member ( signalRef "@baseboard_fab2_lib.baseboard_fab2(sch_1):vr_pvccin_cpu0_phase2") )
				( member ( signalRef "@baseboard_fab2_lib.baseboard_fab2(sch_1):vr_pvccin_cpu0_phase3") )
				( member ( signalRef "@baseboard_fab2_lib.baseboard_fab2(sch_1):vr_pvccin_cpu0_phase4") )
				( member ( signalRef "@baseboard_fab2_lib.baseboard_fab2(sch_1):vr_pvccin_cpu0_phase5") )
				( member ( signalRef "@baseboard_fab2_lib.baseboard_fab2(sch_1):vr_pvccin_cpu0_ph1_phase") )
				( member ( signalRef "@baseboard_fab2_lib.baseboard_fab2(sch_1):vr_pvccin_cpu0_ph2_phase") )
				( member ( signalRef "@baseboard_fab2_lib.baseboard_fab2(sch_1):vr_pvccin_cpu0_ph3_phase") )
				( member ( signalRef "@baseboard_fab2_lib.baseboard_fab2(sch_1):vr_pvccin_cpu0_ph4_phase") )
				( member ( signalRef "@baseboard_fab2_lib.baseboard_fab2(sch_1):vr_pvccin_cpu0_ph5_phase") )
				( member ( signalRef "@baseboard_fab2_lib.baseboard_fab2(sch_1):vr_pvccin_cpu1_phase1") )
				( member ( signalRef "@baseboard_fab2_lib.baseboard_fab2(sch_1):vr_pvccin_cpu1_phase2") )
				( member ( signalRef "@baseboard_fab2_lib.baseboard_fab2(sch_1):vr_pvccin_cpu1_phase3") )
				( member ( signalRef "@baseboard_fab2_lib.baseboard_fab2(sch_1):vr_pvccin_cpu1_phase4") )
				( member ( signalRef "@baseboard_fab2_lib.baseboard_fab2(sch_1):vr_pvccin_cpu1_phase5") )
				( member ( signalRef "@baseboard_fab2_lib.baseboard_fab2(sch_1):vr_pvccin_cpu1_ph1_phase") )
				( member ( signalRef "@baseboard_fab2_lib.baseboard_fab2(sch_1):vr_pvccin_cpu1_ph2_phase") )
				( member ( signalRef "@baseboard_fab2_lib.baseboard_fab2(sch_1):vr_pvccin_cpu1_ph3_phase") )
				( member ( signalRef "@baseboard_fab2_lib.baseboard_fab2(sch_1):vr_pvccin_cpu1_ph4_phase") )
				( member ( signalRef "@baseboard_fab2_lib.baseboard_fab2(sch_1):vr_pvccin_cpu1_ph5_phase") )
				( member ( signalRef "@baseboard_fab2_lib.baseboard_fab2(sch_1):vr_pvpp_def_phase") )
				( member ( signalRef "@baseboard_fab2_lib.baseboard_fab2(sch_1):vr_pvpp_ghj_phase") )
				( member ( signalRef "@baseboard_fab2_lib.baseboard_fab2(sch_1):vr_pvpp_klm_phase") )
				( member ( signalRef "@baseboard_fab2_lib.baseboard_fab2(sch_1):vr_pvccin_cpu0_ph1_boot") )
				( member ( signalRef "@baseboard_fab2_lib.baseboard_fab2(sch_1):vr_pvccin_cpu0_ph1_vcin") )
				( member ( signalRef "@baseboard_fab2_lib.baseboard_fab2(sch_1):vr_pvccin_cpu0_ph2_boot") )
				( member ( signalRef "@baseboard_fab2_lib.baseboard_fab2(sch_1):vr_pvccin_cpu0_ph2_vcin") )
				( member ( signalRef "@baseboard_fab2_lib.baseboard_fab2(sch_1):vr_pvccin_cpu0_ph3_boot") )
				( member ( signalRef "@baseboard_fab2_lib.baseboard_fab2(sch_1):vr_pvccin_cpu0_ph3_vcin") )
				( member ( signalRef "@baseboard_fab2_lib.baseboard_fab2(sch_1):vr_pvccin_cpu0_ph4_boot") )
				( member ( signalRef "@baseboard_fab2_lib.baseboard_fab2(sch_1):vr_pvccin_cpu0_ph4_vcin") )
				( member ( signalRef "@baseboard_fab2_lib.baseboard_fab2(sch_1):vr_pvccin_cpu0_ph5_boot") )
				( member ( signalRef "@baseboard_fab2_lib.baseboard_fab2(sch_1):vr_pvccin_cpu0_ph5_vcin") )
				( member ( signalRef "@baseboard_fab2_lib.baseboard_fab2(sch_1):vr_pvccin_cpu1_ph1_boot") )
				( member ( signalRef "@baseboard_fab2_lib.baseboard_fab2(sch_1):vr_pvccin_cpu1_ph1_vcin") )
				( member ( signalRef "@baseboard_fab2_lib.baseboard_fab2(sch_1):vr_pvccin_cpu1_ph2_boot") )
				( member ( signalRef "@baseboard_fab2_lib.baseboard_fab2(sch_1):vr_pvccin_cpu1_ph2_vcin") )
				( member ( signalRef "@baseboard_fab2_lib.baseboard_fab2(sch_1):vr_pvccin_cpu1_ph3_boot") )
				( member ( signalRef "@baseboard_fab2_lib.baseboard_fab2(sch_1):vr_pvccin_cpu1_ph3_vcin") )
				( member ( signalRef "@baseboard_fab2_lib.baseboard_fab2(sch_1):vr_pvccin_cpu1_ph4_boot") )
				( member ( signalRef "@baseboard_fab2_lib.baseboard_fab2(sch_1):vr_pvccin_cpu1_ph4_vcin") )
				( member ( signalRef "@baseboard_fab2_lib.baseboard_fab2(sch_1):vr_pvccin_cpu1_ph5_boot") )
				( member ( signalRef "@baseboard_fab2_lib.baseboard_fab2(sch_1):vr_pvccin_cpu1_ph5_vcin") )
				( member ( signalRef "@baseboard_fab2_lib.baseboard_fab2(sch_1):vr_pvccio_cpu1_ph1_sw") )
				( member ( signalRef "@baseboard_fab2_lib.baseboard_fab2(sch_1):vr_pvddq_abc_ph1_sw") )
				( member ( signalRef "@baseboard_fab2_lib.baseboard_fab2(sch_1):vr_pvddq_abc_ph2_sw") )
				( member ( signalRef "@baseboard_fab2_lib.baseboard_fab2(sch_1):vr_pvddq_def_ph1_sw") )
				( member ( signalRef "@baseboard_fab2_lib.baseboard_fab2(sch_1):vr_pvddq_def_ph2_sw") )
				( member ( signalRef "@baseboard_fab2_lib.baseboard_fab2(sch_1):vr_pvddq_ghj_ph1_sw") )
				( member ( signalRef "@baseboard_fab2_lib.baseboard_fab2(sch_1):vr_pvddq_ghj_ph2_sw") )
				( member ( signalRef "@baseboard_fab2_lib.baseboard_fab2(sch_1):vr_pvddq_klm_ph1_sw") )
				( member ( signalRef "@baseboard_fab2_lib.baseboard_fab2(sch_1):vr_pvddq_klm_ph2_sw") )
				( member ( signalRef "@baseboard_fab2_lib.baseboard_fab2(sch_1):vr_fet_sw_p5v_stby_pvin") )
				( member ( signalRef "@baseboard_fab2_lib.baseboard_fab2(sch_1):vr_fet_sw_p12v_stby_pvccio_cpu0") )
				( member ( signalRef "@baseboard_fab2_lib.baseboard_fab2(sch_1):vr_pvpp_def_boot_r") )
				( member ( signalRef "@baseboard_fab2_lib.baseboard_fab2(sch_1):vr_pvpp_ghj_boot") )
				( member ( signalRef "@baseboard_fab2_lib.baseboard_fab2(sch_1):vr_pvpp_ghj_boot_r") )
				( objectStatus "SNCLS_VR_NOISY_NETS" )
			)
			( netClass "@sapphirecity_baseboard_lib.sapphirecity_baseboard(sch_1):\VR_CPU_PWM\"
				( memberType ( signal ) )
				( spacingCSetRef "@crescent_city_bb_fab1_lib.crescent_city_bb_fab1(sch_1):\5MIL_US_&_4MIL_SL\" )
				( objectFlag fObjectSpacing )
				( objectFlag fObjectSameNetSpacing )
				( member ( signalRef "@baseboard_fab2_lib.baseboard_fab2(sch_1):vr_pvccin_cpu0_pwm1") )
				( member ( signalRef "@baseboard_fab2_lib.baseboard_fab2(sch_1):vr_pvccin_cpu0_pwm2") )
				( member ( signalRef "@baseboard_fab2_lib.baseboard_fab2(sch_1):vr_pvccin_cpu0_pwm3") )
				( member ( signalRef "@baseboard_fab2_lib.baseboard_fab2(sch_1):vr_pvccin_cpu0_pwm4") )
				( member ( signalRef "@baseboard_fab2_lib.baseboard_fab2(sch_1):vr_pvccin_cpu0_pwm5") )
				( member ( signalRef "@baseboard_fab2_lib.baseboard_fab2(sch_1):vr_pvccin_cpu1_pwm1") )
				( member ( signalRef "@baseboard_fab2_lib.baseboard_fab2(sch_1):vr_pvccin_cpu1_pwm2") )
				( member ( signalRef "@baseboard_fab2_lib.baseboard_fab2(sch_1):vr_pvccin_cpu1_pwm3") )
				( member ( signalRef "@baseboard_fab2_lib.baseboard_fab2(sch_1):vr_pvccin_cpu1_pwm4") )
				( member ( signalRef "@baseboard_fab2_lib.baseboard_fab2(sch_1):vr_pvccin_cpu1_pwm5") )
				( member ( signalRef "@baseboard_fab2_lib.baseboard_fab2(sch_1):vr_pvccio_cpu0_pwm1") )
				( member ( signalRef "@baseboard_fab2_lib.baseboard_fab2(sch_1):vr_pvccio_cpu1_pwm1") )
				( member ( signalRef "@baseboard_fab2_lib.baseboard_fab2(sch_1):vr_pvddq_abc_pwm1") )
				( member ( signalRef "@baseboard_fab2_lib.baseboard_fab2(sch_1):vr_pvddq_abc_pwm2") )
				( member ( signalRef "@baseboard_fab2_lib.baseboard_fab2(sch_1):vr_pvddq_def_pwm1") )
				( member ( signalRef "@baseboard_fab2_lib.baseboard_fab2(sch_1):vr_pvddq_def_pwm2") )
				( member ( signalRef "@baseboard_fab2_lib.baseboard_fab2(sch_1):vr_pvddq_ghj_pwm1") )
				( member ( signalRef "@baseboard_fab2_lib.baseboard_fab2(sch_1):vr_pvddq_ghj_pwm2") )
				( member ( signalRef "@baseboard_fab2_lib.baseboard_fab2(sch_1):vr_pvddq_klm_pwm1") )
				( member ( signalRef "@baseboard_fab2_lib.baseboard_fab2(sch_1):vr_pvddq_klm_pwm2") )
				( member ( signalRef "@baseboard_fab2_lib.baseboard_fab2(sch_1):vr_pvnn_pch_pwm1") )
				( member ( signalRef "@baseboard_fab2_lib.baseboard_fab2(sch_1):vr_pvsa_cpu0_pwm") )
				( member ( signalRef "@baseboard_fab2_lib.baseboard_fab2(sch_1):vr_pvsa_cpu1_pwm") )
				( member ( signalRef "@baseboard_fab2_lib.baseboard_fab2(sch_1):vr_p1v05_pch_stby_pwm1") )
				( objectStatus "SNCLS_VR_PWM" )
			)
			( netClass "@crescent_city_bb_fab1_lib.crescent_city_bb_fab1(sch_1):\SNCLS_VR_NET\"
				( memberType ( signal ) )
				( spacingCSetRef "@sapphirecity_baseboard_lib.sapphirecity_baseboard(sch_1):\8_MILS\" )
				( objectFlag fObjectSpacing )
				( objectFlag fObjectSameNetSpacing )
				( member ( signalRef "@baseboard_fab2_lib.baseboard_fab2(sch_1):vr_pvddq_abc_avsp") )
				( member ( signalRef "@baseboard_fab2_lib.baseboard_fab2(sch_1):vr_pvddq_abc_ph1_vcin") )
				( member ( signalRef "@baseboard_fab2_lib.baseboard_fab2(sch_1):vr_pvddq_abc_ph2_vcin") )
				( member ( signalRef "@baseboard_fab2_lib.baseboard_fab2(sch_1):vr_pvddq_abc_vdd") )
				( member ( signalRef "@baseboard_fab2_lib.baseboard_fab2(sch_1):vr_pvddq_abc_vd12") )
				( member ( signalRef "@baseboard_fab2_lib.baseboard_fab2(sch_1):vr_pvddq_abc_vinsen") )
				( member ( signalRef "@baseboard_fab2_lib.baseboard_fab2(sch_1):vr_pvddq_abc_xaddr1") )
				( member ( signalRef "@baseboard_fab2_lib.baseboard_fab2(sch_1):vr_pvddq_abc_xaddr2") )
				( member ( signalRef "@baseboard_fab2_lib.baseboard_fab2(sch_1):vr_pvddq_def_avsp") )
				( member ( signalRef "@baseboard_fab2_lib.baseboard_fab2(sch_1):vr_pvddq_def_ph1_vcin") )
				( member ( signalRef "@baseboard_fab2_lib.baseboard_fab2(sch_1):vr_pvddq_def_ph2_vcin") )
				( member ( signalRef "@baseboard_fab2_lib.baseboard_fab2(sch_1):vr_pvddq_def_vdd") )
				( member ( signalRef "@baseboard_fab2_lib.baseboard_fab2(sch_1):vr_pvddq_def_vd12") )
				( member ( signalRef "@baseboard_fab2_lib.baseboard_fab2(sch_1):vr_pvddq_def_vinsen") )
				( member ( signalRef "@baseboard_fab2_lib.baseboard_fab2(sch_1):vr_pvddq_def_xaddr1") )
				( member ( signalRef "@baseboard_fab2_lib.baseboard_fab2(sch_1):vr_pvddq_def_xaddr2") )
				( member ( signalRef "@baseboard_fab2_lib.baseboard_fab2(sch_1):vr_pvddq_ghj_avsp") )
				( member ( signalRef "@baseboard_fab2_lib.baseboard_fab2(sch_1):vr_pvddq_ghj_ph1_vcin") )
				( member ( signalRef "@baseboard_fab2_lib.baseboard_fab2(sch_1):vr_pvddq_ghj_ph2_vcin") )
				( member ( signalRef "@baseboard_fab2_lib.baseboard_fab2(sch_1):vr_pvddq_ghj_vdd") )
				( member ( signalRef "@baseboard_fab2_lib.baseboard_fab2(sch_1):vr_pvddq_ghj_vd12") )
				( member ( signalRef "@baseboard_fab2_lib.baseboard_fab2(sch_1):vr_pvddq_ghj_vinsen") )
				( member ( signalRef "@baseboard_fab2_lib.baseboard_fab2(sch_1):vr_pvddq_ghj_xaddr1") )
				( member ( signalRef "@baseboard_fab2_lib.baseboard_fab2(sch_1):vr_pvddq_ghj_xaddr2") )
				( member ( signalRef "@baseboard_fab2_lib.baseboard_fab2(sch_1):vr_pvddq_klm_avsp") )
				( member ( signalRef "@baseboard_fab2_lib.baseboard_fab2(sch_1):vr_pvddq_klm_ph1_vcin") )
				( member ( signalRef "@baseboard_fab2_lib.baseboard_fab2(sch_1):vr_pvddq_klm_ph2_vcin") )
				( member ( signalRef "@baseboard_fab2_lib.baseboard_fab2(sch_1):vr_pvddq_klm_vdd") )
				( member ( signalRef "@baseboard_fab2_lib.baseboard_fab2(sch_1):vr_pvddq_klm_vd12") )
				( member ( signalRef "@baseboard_fab2_lib.baseboard_fab2(sch_1):vr_pvddq_klm_vinsen") )
				( member ( signalRef "@baseboard_fab2_lib.baseboard_fab2(sch_1):vr_pvddq_klm_xaddr1") )
				( member ( signalRef "@baseboard_fab2_lib.baseboard_fab2(sch_1):vr_pvddq_klm_xaddr2") )
				( member ( electricalNetRef "@crescent_city_bb_fab1_lib.crescent_city_bb_fab1(sch_1):vr_pvddq_abc_aiinsen") )
				( member ( electricalNetRef "@crescent_city_bb_fab1_lib.crescent_city_bb_fab1(sch_1):vr_pvddq_abc_ph1_boot") )
				( member ( electricalNetRef "@crescent_city_bb_fab1_lib.crescent_city_bb_fab1(sch_1):vr_pvddq_abc_ph2_boot") )
				( member ( electricalNetRef "@crescent_city_bb_fab1_lib.crescent_city_bb_fab1(sch_1):vr_pvddq_def_aiinsen") )
				( member ( electricalNetRef "@crescent_city_bb_fab1_lib.crescent_city_bb_fab1(sch_1):vr_pvddq_def_ph1_boot") )
				( member ( electricalNetRef "@crescent_city_bb_fab1_lib.crescent_city_bb_fab1(sch_1):vr_pvddq_def_ph2_boot") )
				( member ( electricalNetRef "@crescent_city_bb_fab1_lib.crescent_city_bb_fab1(sch_1):vr_pvddq_ghj_aiinsen") )
				( member ( electricalNetRef "@crescent_city_bb_fab1_lib.crescent_city_bb_fab1(sch_1):vr_pvddq_ghj_ph1_boot") )
				( member ( electricalNetRef "@crescent_city_bb_fab1_lib.crescent_city_bb_fab1(sch_1):vr_pvddq_ghj_ph2_boot") )
				( member ( electricalNetRef "@crescent_city_bb_fab1_lib.crescent_city_bb_fab1(sch_1):vr_pvddq_klm_aiinsen") )
				( member ( electricalNetRef "@crescent_city_bb_fab1_lib.crescent_city_bb_fab1(sch_1):vr_pvddq_klm_ph1_boot") )
				( member ( electricalNetRef "@crescent_city_bb_fab1_lib.crescent_city_bb_fab1(sch_1):vr_pvddq_klm_ph2_boot") )
				( objectStatus "SNCLS_VR_NET" )
			)
			( netClass "@crescent_city_bb_fab1_lib.crescent_city_bb_fab1(sch_1):\PNCLS_85\"
				( memberType ( signal ) )
				( physicalCSetRef "@crescent_city_bb_fab1_lib.crescent_city_bb_fab1(sch_1):\85_OHM_DIFF_CLK\" )
				( objectFlag fObjectPhysical )
				( member ( diffPairRef "@crescent_city_bb_fab1_lib.crescent_city_bb_fab1(sch_1):\CLK_100M_AIRMAX8_PE1\") )
				( member ( diffPairRef "@crescent_city_bb_fab1_lib.crescent_city_bb_fab1(sch_1):\DP_CLK_100M_BMC_PE\") )
				( member ( diffPairRef "@sapphirecity_baseboard_lib.sapphirecity_baseboard(sch_1):\CLK_100M_CPU0_BCLK0\") )
				( member ( diffPairRef "@sapphirecity_baseboard_lib.sapphirecity_baseboard(sch_1):\CLK_100M_CPU0_BCLK1\") )
				( member ( diffPairRef "@sapphirecity_baseboard_lib.sapphirecity_baseboard(sch_1):\CLK_100M_CPU0_BCLK2\") )
				( member ( diffPairRef "@crescent_city_bb_fab1_lib.crescent_city_bb_fab1(sch_1):\CLK_100M_CPU0_MCP_CLK1_R_D\") )
				( member ( diffPairRef "@crescent_city_bb_fab1_lib.crescent_city_bb_fab1(sch_1):\CLK_100M_CPU0_MCP_CLK2\") )
				( member ( diffPairRef "@crescent_city_bb_fab1_lib.crescent_city_bb_fab1(sch_1):\CLK_100M_CPU0_PE_REFCLK_R_D\") )
				( member ( diffPairRef "@sapphirecity_baseboard_lib.sapphirecity_baseboard(sch_1):\CLK_100M_CPU1_BCLK0\") )
				( member ( diffPairRef "@sapphirecity_baseboard_lib.sapphirecity_baseboard(sch_1):\CLK_100M_CPU1_BCLK1\") )
				( member ( diffPairRef "@sapphirecity_baseboard_lib.sapphirecity_baseboard(sch_1):\CLK_100M_CPU1_BCLK2\") )
				( member ( diffPairRef "@crescent_city_bb_fab1_lib.crescent_city_bb_fab1(sch_1):\CLK_100M_CPU1_MCP_CLK1_R_D\") )
				( member ( diffPairRef "@crescent_city_bb_fab1_lib.crescent_city_bb_fab1(sch_1):\CLK_100M_CPU1_PE_REFCLK_R_D\") )
				( member ( diffPairRef "@crescent_city_bb_fab1_lib.crescent_city_bb_fab1(sch_1):\CLK_100M_DB1200\") )
				( member ( diffPairRef "@crescent_city_bb_fab1_lib.crescent_city_bb_fab1(sch_1):\CLK_100M_MEZZ1\") )
				( member ( diffPairRef "@crescent_city_bb_fab1_lib.crescent_city_bb_fab1(sch_1):\CLK_100M_MEZZ2\") )
				( member ( diffPairRef "@crescent_city_bb_fab1_lib.crescent_city_bb_fab1(sch_1):\DP_CLK_100M_MEZZ3_D\") )
				( member ( diffPairRef "@crescent_city_bb_fab1_lib.crescent_city_bb_fab1(sch_1):\DP_CLK_100M_MEZZ4_D\") )
				( member ( diffPairRef "@crescent_city_bb_fab1_lib.crescent_city_bb_fab1(sch_1):\CLK_100M_M2\") )
				( member ( diffPairRef "@crescent_city_bb_fab1_lib.crescent_city_bb_fab1(sch_1):\DP_CLK_100M_PCH_SLOTX24_S0\") )
				( member ( diffPairRef "@crescent_city_bb_fab1_lib.crescent_city_bb_fab1(sch_1):\CLK_100M_PCH_SLOTX24_S1\") )
				( member ( diffPairRef "@crescent_city_bb_fab1_lib.crescent_city_bb_fab1(sch_1):\CLK_100M_PCH_SLOTX24_S2\") )
				( member ( diffPairRef "@crescent_city_bb_fab1_lib.crescent_city_bb_fab1(sch_1):\CLK_100M_PCH_SLOTX24_S3\") )
				( member ( diffPairRef "@crescent_city_bb_fab1_lib.crescent_city_bb_fab1(sch_1):\DP_CLK_100M_PCH_SLOTX24_S4\") )
				( member ( diffPairRef "@crescent_city_bb_fab1_lib.crescent_city_bb_fab1(sch_1):\DP_CLK_100M_PCH_SLOTX24_S5\") )
				( member ( diffPairRef "@sapphirecity_baseboard_lib.sapphirecity_baseboard(sch_1):\CLK_100M_PCH_XDP\") )
				( member ( diffPairRef "@crescent_city_bb_fab1_lib.crescent_city_bb_fab1(sch_1):\CLK_100M_SPRV_D\") )
				( member ( diffPairRef "@crescent_city_bb_fab1_lib.crescent_city_bb_fab1(sch_1):\DP_CLK_156M_OSC_CPU0_HFI\") )
				( member ( diffPairRef "@crescent_city_bb_fab1_lib.crescent_city_bb_fab1(sch_1):\DP_CLK_156M_OSC_CPU1_HFI\") )
				( member ( diffPairRef "@crescent_city_bb_fab1_lib.crescent_city_bb_fab1(sch_1):\CLK_100M_CPU1_MCP_CLK2\") )
				( member ( diffPairRef "@baseboard_fab2_lib.baseboard_fab2(sch_1):\DP_CLK_156M_OSC_BRD_CPU0\") )
				( member ( diffPairRef "@baseboard_fab2_lib.baseboard_fab2(sch_1):\DP_CLK_156M_OSC_BRD_CPU1\") )
				( member ( diffPairRef "@baseboard_fab2_lib.baseboard_fab2(sch_1):\DP_CLK_156M_OSC_CPU0_HFI\") )
				( member ( diffPairRef "@baseboard_fab2_lib.baseboard_fab2(sch_1):\DP_CLK_156M_OSC_CPU1_HFI\") )
				( member ( diffPairRef "@baseboard_fab2_lib.baseboard_fab2(sch_1):\DP_CLK_322M_156M_CPU0_OSC_VRM\") )
				( member ( diffPairRef "@baseboard_fab2_lib.baseboard_fab2(sch_1):\DP_CLK_322M_156M_CPU1_OSC_VRM\") )
				( member ( signalRef "@baseboard_fab2_lib.baseboard_fab2(sch_1):clk_100m_cpu0_pe_refclk_dn") )
				( member ( signalRef "@baseboard_fab2_lib.baseboard_fab2(sch_1):clk_100m_cpu0_pe_refclk_dp") )
				( member ( signalRef "@baseboard_fab2_lib.baseboard_fab2(sch_1):clk_100m_cpu0_pe_refclk_r_dn") )
				( member ( signalRef "@baseboard_fab2_lib.baseboard_fab2(sch_1):clk_100m_cpu0_pe_refclk_r_dp") )
				( member ( signalRef "@baseboard_fab2_lib.baseboard_fab2(sch_1):clk_100m_cpu1_pe_refclk_dn") )
				( member ( signalRef "@baseboard_fab2_lib.baseboard_fab2(sch_1):clk_100m_cpu1_pe_refclk_dp") )
				( member ( signalRef "@baseboard_fab2_lib.baseboard_fab2(sch_1):clk_100m_cpu1_pe_refclk_r_dn") )
				( member ( signalRef "@baseboard_fab2_lib.baseboard_fab2(sch_1):clk_100m_cpu1_pe_refclk_r_dp") )
				( objectStatus "PNCLS_85-OHM_DIFF_CLK" )
			)
			( netClass "@crescent_city_bb_fab1_lib.crescent_city_bb_fab1(sch_1):\SNCLS_TDT\"
				( memberType ( signal ) )
				( spacingCSetRef "@crescent_city_bb_fab1_lib.crescent_city_bb_fab1(sch_1):\25MIL_TDT\" )
				( sameNetSpacingCSetRef "@crescent_city_bb_fab1_lib.crescent_city_bb_fab1(sch_1):\25_MILS\" )
				( objectFlag fObjectSpacing )
				( objectFlag fObjectSameNetSpacing )
				( objectStatus "SNCLS_TDT" )
			)
			( netClass "@crescent_city_bb_fab1_lib.crescent_city_bb_fab1(sch_1):\EV_CLOCKS_TEMP\"
				( memberType ( signal ) )
				( physicalCSetRef "@crescent_city_bb_fab1_lib.crescent_city_bb_fab1(sch_1):\85_OHM_DIFF_EV_CLOCKS\" )
				( objectFlag fObjectPhysical )
				( objectStatus "EV_CLOCKS_TEMP" )
			)
			( netClass "@crescent_city_bb_fab1_lib.crescent_city_bb_fab1(sch_1):\SNCLS_VR_SENSITIVE_NETS\"
				( memberType ( signal ) )
				( spacingCSetRef "@crescent_city_bb_fab1_lib.crescent_city_bb_fab1(sch_1):\5MIL_US_&_4MIL_SL\" )
				( objectFlag fObjectSpacing )
				( objectFlag fObjectSameNetSpacing )
				( member ( signalRef "@baseboard_fab2_lib.baseboard_fab2(sch_1):vr_comp_pvpp_ghj") )
				( member ( signalRef "@baseboard_fab2_lib.baseboard_fab2(sch_1):vr_comp_pvpp_ghj_3") )
				( member ( signalRef "@baseboard_fab2_lib.baseboard_fab2(sch_1):vr_comp_pvpp_klm") )
				( member ( signalRef "@baseboard_fab2_lib.baseboard_fab2(sch_1):vr_comp_pvpp_klm_3") )
				( member ( signalRef "@baseboard_fab2_lib.baseboard_fab2(sch_1):vr_comp_rc_pvpp_ghj") )
				( member ( signalRef "@baseboard_fab2_lib.baseboard_fab2(sch_1):vr_comp_rc_pvpp_klm") )
				( member ( signalRef "@baseboard_fab2_lib.baseboard_fab2(sch_1):vr_fb_pvpp_ghj") )
				( member ( signalRef "@baseboard_fab2_lib.baseboard_fab2(sch_1):vr_fb_pvpp_klm") )
				( member ( signalRef "@baseboard_fab2_lib.baseboard_fab2(sch_1):vsense_pvpp_ghj") )
				( member ( signalRef "@baseboard_fab2_lib.baseboard_fab2(sch_1):vsense_pvpp_klm") )
				( member ( signalRef "@baseboard_fab2_lib.baseboard_fab2(sch_1):vr_p1v8_pch_stby_fb") )
				( member ( signalRef "@baseboard_fab2_lib.baseboard_fab2(sch_1):vr_p1v26_bmc_stby_fb") )
				( member ( signalRef "@baseboard_fab2_lib.baseboard_fab2(sch_1):vr_p1v538_bmc_stby_fb") )
				( member ( signalRef "@baseboard_fab2_lib.baseboard_fab2(sch_1):vr_comp_pvpp_abc") )
				( member ( signalRef "@baseboard_fab2_lib.baseboard_fab2(sch_1):vr_comp_pvpp_abc_3") )
				( member ( signalRef "@baseboard_fab2_lib.baseboard_fab2(sch_1):vr_comp_pvpp_def") )
				( member ( signalRef "@baseboard_fab2_lib.baseboard_fab2(sch_1):vr_comp_pvpp_def_3") )
				( member ( signalRef "@baseboard_fab2_lib.baseboard_fab2(sch_1):vr_comp_rc_pvpp_abc") )
				( member ( signalRef "@baseboard_fab2_lib.baseboard_fab2(sch_1):vr_comp_rc_pvpp_def") )
				( member ( signalRef "@baseboard_fab2_lib.baseboard_fab2(sch_1):vr_fb_pvpp_abc") )
				( member ( signalRef "@baseboard_fab2_lib.baseboard_fab2(sch_1):vr_fb_pvpp_def") )
				( member ( signalRef "@baseboard_fab2_lib.baseboard_fab2(sch_1):vsense_pvpp_abc") )
				( member ( signalRef "@baseboard_fab2_lib.baseboard_fab2(sch_1):vsense_pvpp_def") )
				( member ( signalRef "@baseboard_fab2_lib.baseboard_fab2(sch_1):vsense_pvccin_cpu0_avsp") )
				( member ( signalRef "@baseboard_fab2_lib.baseboard_fab2(sch_1):vsense_pvccin_cpu1_avsp") )
				( member ( signalRef "@baseboard_fab2_lib.baseboard_fab2(sch_1):vsense_pvccio_cpu1_avsn") )
				( member ( signalRef "@baseboard_fab2_lib.baseboard_fab2(sch_1):vsense_pvccio_cpu1_avsp") )
				( member ( signalRef "@baseboard_fab2_lib.baseboard_fab2(sch_1):vsense_pvddq_abc_vtt") )
				( member ( signalRef "@baseboard_fab2_lib.baseboard_fab2(sch_1):vsense_pvddq_def_vtt") )
				( member ( signalRef "@baseboard_fab2_lib.baseboard_fab2(sch_1):vsense_pvddq_ghj_vtt") )
				( member ( signalRef "@baseboard_fab2_lib.baseboard_fab2(sch_1):vsense_pvddq_klm_vtt") )
				( member ( signalRef "@baseboard_fab2_lib.baseboard_fab2(sch_1):vsense_pvsa_cpu0_bvsp") )
				( member ( signalRef "@baseboard_fab2_lib.baseboard_fab2(sch_1):vsense_pvsa_cpu1_bvsp") )
				( member ( electricalNetRef "@crescent_city_bb_fab1_lib.crescent_city_bb_fab1(sch_1):vr_comp_pvpp_abc") )
				( member ( electricalNetRef "@crescent_city_bb_fab1_lib.crescent_city_bb_fab1(sch_1):vr_comp_pvpp_def") )
				( member ( electricalNetRef "@crescent_city_bb_fab1_lib.crescent_city_bb_fab1(sch_1):vr_comp_pvpp_ghj") )
				( member ( electricalNetRef "@crescent_city_bb_fab1_lib.crescent_city_bb_fab1(sch_1):vr_comp_pvpp_klm") )
				( objectStatus "SNCLS_VR_SENSITIVE_NETS" )
			)
			( netClass "@crescent_city_bb_fab1_lib.crescent_city_bb_fab1(sch_1):\SNCLS_RMII_RX\"
				( memberType ( signal ) )
				( spacingCSetRef "@sapphirecity_baseboard_lib.sapphirecity_baseboard(sch_1):\8MIL_SL_10MIL_MS\" )
				( objectFlag fObjectSpacing )
				( objectFlag fObjectSameNetSpacing )
				( member ( signalRef "@baseboard_fab2_lib.baseboard_fab2(sch_1):rmii_sprngvlle_bmc_pch_rxd1_r1") )
				( member ( signalRef "@baseboard_fab2_lib.baseboard_fab2(sch_1):rmii_sprngvlle_bmc_pch_rxd0_r1") )
				( member ( signalRef "@baseboard_fab2_lib.baseboard_fab2(sch_1):rmii_bmc_ocp_rxd0_r") )
				( member ( signalRef "@baseboard_fab2_lib.baseboard_fab2(sch_1):rmii_bmc_ocp_rxd1_r") )
				( member ( signalRef "@baseboard_fab2_lib.baseboard_fab2(sch_1):rmii_bmc_ocp_rxer_r") )
				( member ( signalRef "@baseboard_fab2_lib.baseboard_fab2(sch_1):rmii_bmc_pch_sprngvlle_rxer_r") )
				( member ( signalRef "@baseboard_fab2_lib.baseboard_fab2(sch_1):rmii_bmc_ocp_rxd0") )
				( member ( signalRef "@baseboard_fab2_lib.baseboard_fab2(sch_1):rmii_bmc_ocp_rxd1") )
				( member ( signalRef "@baseboard_fab2_lib.baseboard_fab2(sch_1):rmii_sprngvlle_bmc_pch_rxd1") )
				( member ( signalRef "@baseboard_fab2_lib.baseboard_fab2(sch_1):rmii_sprngvlle_bmc_pch_rxd1_r") )
				( member ( signalRef "@baseboard_fab2_lib.baseboard_fab2(sch_1):rmii_sprngvlle_bmc_pch_rxd0") )
				( member ( signalRef "@baseboard_fab2_lib.baseboard_fab2(sch_1):rmii_sprngvlle_bmc_pch_rxd0_r") )
				( member ( signalRef "@baseboard_fab2_lib.baseboard_fab2(sch_1):rmii_bmc_ocp_rxer") )
				( member ( signalRef "@baseboard_fab2_lib.baseboard_fab2(sch_1):rmii_bmc_pch_sprngvlle_rxer") )
				( member ( electricalNetRef "@crescent_city_bb_fab1_lib.crescent_city_bb_fab1(sch_1):rmii_sprngvlle_bmc_pch_rxd0") )
				( member ( electricalNetRef "@crescent_city_bb_fab1_lib.crescent_city_bb_fab1(sch_1):rmii_sprngvlle_bmc_pch_rxd1") )
				( objectStatus "SNCLS_RMII_RX" )
			)
			( netClass "@sapphirecity_baseboard_lib.sapphirecity_baseboard(sch_1):\MISC_INTEL_STATIC\"
				( memberType ( signal ) )
				( spacingCSetRef "@crescent_city_bb_fab1_lib.crescent_city_bb_fab1(sch_1):\4_MILS\" )
				( sameNetSpacingCSetRef "@crescent_city_bb_fab1_lib.crescent_city_bb_fab1(sch_1):\3.7H_US_AND_2H_SL\" )
				( objectFlag fObjectSpacing )
				( objectFlag fObjectSameNetSpacing )
				( member ( signalRef "@baseboard_fab2_lib.baseboard_fab2(sch_1):fm_sys_throttle_lvc3") )
				( member ( signalRef "@baseboard_fab2_lib.baseboard_fab2(sch_1):fm_thermtrip_dly") )
				( member ( signalRef "@baseboard_fab2_lib.baseboard_fab2(sch_1):fm_fast_prochot_and_out_1_n") )
				( member ( signalRef "@baseboard_fab2_lib.baseboard_fab2(sch_1):fm_throttle_n") )
				( member ( signalRef "@baseboard_fab2_lib.baseboard_fab2(sch_1):fm_tpm_pres_n") )
				( member ( signalRef "@baseboard_fab2_lib.baseboard_fab2(sch_1):fm_bmc_cpu_init_n") )
				( member ( signalRef "@baseboard_fab2_lib.baseboard_fab2(sch_1):fm_cpld_adr_trigger_r_n") )
				( member ( signalRef "@baseboard_fab2_lib.baseboard_fab2(sch_1):fm_oc0_usb_n") )
				( member ( signalRef "@baseboard_fab2_lib.baseboard_fab2(sch_1):fm_uv_adr_trigger_en") )
				( member ( signalRef "@baseboard_fab2_lib.baseboard_fab2(sch_1):fm_xrc_present_n") )
				( member ( signalRef "@baseboard_fab2_lib.baseboard_fab2(sch_1):fm_xrc_ready_n") )
				( member ( signalRef "@baseboard_fab2_lib.baseboard_fab2(sch_1):fm_10gbe_lom_disable_n") )
				( member ( signalRef "@baseboard_fab2_lib.baseboard_fab2(sch_1):pu_10gbe_lom_pci_disable_n") )
				( member ( signalRef "@baseboard_fab2_lib.baseboard_fab2(sch_1):a_hsc_c") )
				( member ( signalRef "@baseboard_fab2_lib.baseboard_fab2(sch_1):a_hsc_gate") )
				( member ( signalRef "@baseboard_fab2_lib.baseboard_fab2(sch_1):a_hsc_timer_r") )
				( member ( signalRef "@baseboard_fab2_lib.baseboard_fab2(sch_1):fm_adr_mode_sel_r") )
				( member ( signalRef "@baseboard_fab2_lib.baseboard_fab2(sch_1):fm_bios_top_swap") )
				( member ( signalRef "@baseboard_fab2_lib.baseboard_fab2(sch_1):fm_bmc_cpld_gpo") )
				( member ( signalRef "@baseboard_fab2_lib.baseboard_fab2(sch_1):a_hsc_mop") )
				( member ( signalRef "@baseboard_fab2_lib.baseboard_fab2(sch_1):fm_cpld_adr_trigger_n") )
				( member ( signalRef "@baseboard_fab2_lib.baseboard_fab2(sch_1):fm_cpu0_stl_brd_osc_en") )
				( member ( signalRef "@baseboard_fab2_lib.baseboard_fab2(sch_1):fm_cpu0_vrm_osc_en") )
				( member ( signalRef "@baseboard_fab2_lib.baseboard_fab2(sch_1):fm_db1200_pwrgd") )
				( member ( signalRef "@baseboard_fab2_lib.baseboard_fab2(sch_1):fm_dimm_event_cod_n") )
				( member ( signalRef "@baseboard_fab2_lib.baseboard_fab2(sch_1):a_hsc_gate3_r") )
				( member ( signalRef "@baseboard_fab2_lib.baseboard_fab2(sch_1):fm_fast_prochot_and_out_0_n") )
				( member ( signalRef "@baseboard_fab2_lib.baseboard_fab2(sch_1):fm_fast_prochot_throttle_dly_buf_n") )
				( member ( signalRef "@baseboard_fab2_lib.baseboard_fab2(sch_1):fm_fast_prochot_throttle_dly_n") )
				( member ( signalRef "@baseboard_fab2_lib.baseboard_fab2(sch_1):fm_fast_prochot_throttle_in_n") )
				( member ( signalRef "@baseboard_fab2_lib.baseboard_fab2(sch_1):a_hsc_ov") )
				( member ( signalRef "@baseboard_fab2_lib.baseboard_fab2(sch_1):a_hsc_temp") )
				( member ( signalRef "@baseboard_fab2_lib.baseboard_fab2(sch_1):a_hsc_uv") )
				( member ( signalRef "@baseboard_fab2_lib.baseboard_fab2(sch_1):fm_ie_disable_n") )
				( member ( signalRef "@baseboard_fab2_lib.baseboard_fab2(sch_1):fm_jtag_pld_en_debug") )
				( member ( signalRef "@baseboard_fab2_lib.baseboard_fab2(sch_1):a_hsc_gate2_r") )
				( member ( signalRef "@baseboard_fab2_lib.baseboard_fab2(sch_1):fm_modprst_hfi0_cpu0_lvt2_n") )
				( member ( signalRef "@baseboard_fab2_lib.baseboard_fab2(sch_1):fm_modprst_hfi1_cpu0_lvt2_n") )
				( member ( signalRef "@baseboard_fab2_lib.baseboard_fab2(sch_1):fm_ocp_mezzb_pres_n") )
				( member ( signalRef "@baseboard_fab2_lib.baseboard_fab2(sch_1):fm_oc_detect_n") )
				( member ( signalRef "@baseboard_fab2_lib.baseboard_fab2(sch_1):fm_pi7c9x1172_a0") )
				( member ( signalRef "@baseboard_fab2_lib.baseboard_fab2(sch_1):fm_pi7c9x1172_a1") )
				( member ( signalRef "@baseboard_fab2_lib.baseboard_fab2(sch_1):fm_mp_ps_fail_n") )
				( member ( signalRef "@baseboard_fab2_lib.baseboard_fab2(sch_1):fm_mp_ps_redundant_lost_n") )
				( member ( signalRef "@baseboard_fab2_lib.baseboard_fab2(sch_1):fm_bb_bmc_mp_gpio") )
				( member ( signalRef "@baseboard_fab2_lib.baseboard_fab2(sch_1):fm_cpld_bmc_pwrdn_n") )
				( member ( signalRef "@baseboard_fab2_lib.baseboard_fab2(sch_1):fm_prsnt_2_1_n") )
				( member ( signalRef "@baseboard_fab2_lib.baseboard_fab2(sch_1):fm_prsnt_2_2_n") )
				( member ( signalRef "@baseboard_fab2_lib.baseboard_fab2(sch_1):fm_cpu_err0_lvt3_bmc_n") )
				( member ( signalRef "@baseboard_fab2_lib.baseboard_fab2(sch_1):a_hsc_mon") )
				( member ( signalRef "@baseboard_fab2_lib.baseboard_fab2(sch_1):fm_prsnt_2_3_n") )
				( member ( signalRef "@baseboard_fab2_lib.baseboard_fab2(sch_1):a_hsc_timer") )
				( member ( signalRef "@baseboard_fab2_lib.baseboard_fab2(sch_1):fm_speaker_pch_n") )
				( member ( signalRef "@baseboard_fab2_lib.baseboard_fab2(sch_1):a_hsc_hsp") )
				( member ( signalRef "@baseboard_fab2_lib.baseboard_fab2(sch_1):fm_cpu_bmc_init") )
				( member ( signalRef "@baseboard_fab2_lib.baseboard_fab2(sch_1):fm_wbg_prsnt_n") )
				( member ( signalRef "@baseboard_fab2_lib.baseboard_fab2(sch_1):a_hsc_gate1_r") )
				( member ( signalRef "@baseboard_fab2_lib.baseboard_fab2(sch_1):a_hsc_hsn") )
				( member ( signalRef "@baseboard_fab2_lib.baseboard_fab2(sch_1):tp_gpio0_dsrb_n") )
				( member ( signalRef "@baseboard_fab2_lib.baseboard_fab2(sch_1):tp_gpio1_dtrb_n") )
				( member ( signalRef "@baseboard_fab2_lib.baseboard_fab2(sch_1):tp_gpio2_cdb_n") )
				( member ( signalRef "@baseboard_fab2_lib.baseboard_fab2(sch_1):tp_gpio3_rib_n") )
				( member ( signalRef "@baseboard_fab2_lib.baseboard_fab2(sch_1):tp_gpio4_dsra_n") )
				( member ( signalRef "@baseboard_fab2_lib.baseboard_fab2(sch_1):tp_gpio5_dtra_n") )
				( member ( signalRef "@baseboard_fab2_lib.baseboard_fab2(sch_1):tp_gpio6_cda_n") )
				( member ( signalRef "@baseboard_fab2_lib.baseboard_fab2(sch_1):tp_gpio7_ria_n") )
				( member ( signalRef "@baseboard_fab2_lib.baseboard_fab2(sch_1):fm_cpu_caterr_dly_lvt3_n") )
				( member ( signalRef "@baseboard_fab2_lib.baseboard_fab2(sch_1):fm_fast_prochot_en_n") )
				( member ( signalRef "@baseboard_fab2_lib.baseboard_fab2(sch_1):fm_gbe0_lvc3_mod_abs") )
				( member ( signalRef "@baseboard_fab2_lib.baseboard_fab2(sch_1):fm_pch_bmc_thermtrip_n") )
				( member ( signalRef "@baseboard_fab2_lib.baseboard_fab2(sch_1):tp_led_m2_act_n") )
				( member ( signalRef "@baseboard_fab2_lib.baseboard_fab2(sch_1):fm_pch_pwrbtn_r_n") )
				( member ( signalRef "@baseboard_fab2_lib.baseboard_fab2(sch_1):tp_pi7c9x1172_enir_n") )
				( member ( signalRef "@baseboard_fab2_lib.baseboard_fab2(sch_1):tp_pi7c9x1172_en485_n") )
				( member ( signalRef "@baseboard_fab2_lib.baseboard_fab2(sch_1):tp_pi7c9x1172_rtsa_n") )
				( member ( signalRef "@baseboard_fab2_lib.baseboard_fab2(sch_1):tp_pi7c9x1172_rtsb_n") )
				( member ( signalRef "@baseboard_fab2_lib.baseboard_fab2(sch_1):tp_pi7c9x1172_so") )
				( member ( signalRef "@baseboard_fab2_lib.baseboard_fab2(sch_1):nc_pi7c9x1172_1") )
				( member ( signalRef "@baseboard_fab2_lib.baseboard_fab2(sch_1):nc_pi7c9x1172_8") )
				( member ( signalRef "@baseboard_fab2_lib.baseboard_fab2(sch_1):fm_gbe1_lvc3_mod_abs") )
				( member ( signalRef "@baseboard_fab2_lib.baseboard_fab2(sch_1):nc_pvddq_abc_dnc0") )
				( member ( signalRef "@baseboard_fab2_lib.baseboard_fab2(sch_1):nc_pvddq_abc_dnc1") )
				( member ( signalRef "@baseboard_fab2_lib.baseboard_fab2(sch_1):tp_pvddq_abc_ph1_gl_0") )
				( member ( signalRef "@baseboard_fab2_lib.baseboard_fab2(sch_1):tp_pvddq_abc_ph2_gl_0") )
				( member ( signalRef "@baseboard_fab2_lib.baseboard_fab2(sch_1):nc_pvddq_def_dnc0") )
				( member ( signalRef "@baseboard_fab2_lib.baseboard_fab2(sch_1):nc_pvddq_def_dnc1") )
				( member ( signalRef "@baseboard_fab2_lib.baseboard_fab2(sch_1):tp_pvddq_def_ph1_gl_0") )
				( member ( signalRef "@baseboard_fab2_lib.baseboard_fab2(sch_1):tp_pvddq_def_ph2_gl_0") )
				( member ( signalRef "@baseboard_fab2_lib.baseboard_fab2(sch_1):nc_pvddq_ghj_dnc0") )
				( member ( signalRef "@baseboard_fab2_lib.baseboard_fab2(sch_1):nc_pvddq_ghj_dnc1") )
				( member ( signalRef "@baseboard_fab2_lib.baseboard_fab2(sch_1):tp_pvddq_ghj_ph1_gl_0") )
				( member ( signalRef "@baseboard_fab2_lib.baseboard_fab2(sch_1):tp_pvddq_ghj_ph2_gl_0") )
				( member ( signalRef "@baseboard_fab2_lib.baseboard_fab2(sch_1):nc_pvddq_klm_dnc0") )
				( member ( signalRef "@baseboard_fab2_lib.baseboard_fab2(sch_1):fm_pe_ocp_wake_n") )
				( member ( signalRef "@baseboard_fab2_lib.baseboard_fab2(sch_1):fm_m2_ssd_pedet") )
				( member ( signalRef "@baseboard_fab2_lib.baseboard_fab2(sch_1):fm_ocp_mezza_pres_n") )
				( member ( signalRef "@baseboard_fab2_lib.baseboard_fab2(sch_1):fm_oc_detect_en") )
				( member ( signalRef "@baseboard_fab2_lib.baseboard_fab2(sch_1):tp_pvddq_klm_ph2_gl_0") )
				( member ( signalRef "@baseboard_fab2_lib.baseboard_fab2(sch_1):fm_password_clear_n") )
				( member ( signalRef "@baseboard_fab2_lib.baseboard_fab2(sch_1):fm_pwr_led") )
				( member ( signalRef "@baseboard_fab2_lib.baseboard_fab2(sch_1):tp_clk_100m_src12_dn") )
				( member ( signalRef "@baseboard_fab2_lib.baseboard_fab2(sch_1):fm_pch_lvc1_thermtrip_n") )
				( member ( signalRef "@baseboard_fab2_lib.baseboard_fab2(sch_1):fm_pch_prsnt_n") )
				( member ( signalRef "@baseboard_fab2_lib.baseboard_fab2(sch_1):fm_pch_pwrbtn_n") )
				( member ( signalRef "@baseboard_fab2_lib.baseboard_fab2(sch_1):fm_pe_slotx24_wake_n") )
				( member ( signalRef "@baseboard_fab2_lib.baseboard_fab2(sch_1):tp_cpu1_dmi_rx_dn0") )
				( member ( signalRef "@baseboard_fab2_lib.baseboard_fab2(sch_1):tp_clk_100m_src13_dn") )
				( member ( signalRef "@baseboard_fab2_lib.baseboard_fab2(sch_1):tp_clk_100m_src13_dp") )
				( member ( signalRef "@baseboard_fab2_lib.baseboard_fab2(sch_1):tp_cpld1_pr12d") )
				( member ( signalRef "@baseboard_fab2_lib.baseboard_fab2(sch_1):fm_pld_debug_mode_n") )
				( member ( signalRef "@baseboard_fab2_lib.baseboard_fab2(sch_1):fm_pmbus_alert_buf_en") )
				( member ( signalRef "@baseboard_fab2_lib.baseboard_fab2(sch_1):nc_pvnn_pch_dnc2") )
				( member ( signalRef "@baseboard_fab2_lib.baseboard_fab2(sch_1):fm_pmbus_alert_buf_en_n") )
				( member ( signalRef "@baseboard_fab2_lib.baseboard_fab2(sch_1):fm_post_card_pres_bmc_n") )
				( member ( signalRef "@baseboard_fab2_lib.baseboard_fab2(sch_1):fm_pwr_led_a") )
				( member ( signalRef "@baseboard_fab2_lib.baseboard_fab2(sch_1):fm_ps_en") )
				( member ( signalRef "@baseboard_fab2_lib.baseboard_fab2(sch_1):fm_adr_mode_sel") )
				( member ( signalRef "@baseboard_fab2_lib.baseboard_fab2(sch_1):fm_pvccin_cpu0_pwr_in_alert_n") )
				( member ( signalRef "@baseboard_fab2_lib.baseboard_fab2(sch_1):fm_pvccin_cpu1_pwr_in_alert_n") )
				( member ( signalRef "@baseboard_fab2_lib.baseboard_fab2(sch_1):fm_slt_cfg1") )
				( member ( signalRef "@baseboard_fab2_lib.baseboard_fab2(sch_1):fm_pwrbrk_slot_n") )
				( member ( signalRef "@baseboard_fab2_lib.baseboard_fab2(sch_1):fm_pvccio_cpu0_en") )
				( member ( signalRef "@baseboard_fab2_lib.baseboard_fab2(sch_1):fm_pvccio_cpu1_en") )
				( member ( signalRef "@baseboard_fab2_lib.baseboard_fab2(sch_1):fm_cpu_err0_lvt3_k_n") )
				( member ( signalRef "@baseboard_fab2_lib.baseboard_fab2(sch_1):fm_pvccmcp_cpu1_en") )
				( member ( signalRef "@baseboard_fab2_lib.baseboard_fab2(sch_1):nc_pvnn_pch_dnc4") )
				( member ( signalRef "@baseboard_fab2_lib.baseboard_fab2(sch_1):tp_bmc_disable") )
				( member ( signalRef "@baseboard_fab2_lib.baseboard_fab2(sch_1):tp_pvnn_pch_gl_0") )
				( member ( signalRef "@baseboard_fab2_lib.baseboard_fab2(sch_1):tp_p1v05_pch_gl_0") )
				( member ( signalRef "@baseboard_fab2_lib.baseboard_fab2(sch_1):tp_cpld1_pt24b") )
				( member ( signalRef "@baseboard_fab2_lib.baseboard_fab2(sch_1):tp_cpld1_pb16a_pclkt2_1") )
				( member ( signalRef "@baseboard_fab2_lib.baseboard_fab2(sch_1):tp_cpu0_rsvd_255") )
				( member ( signalRef "@baseboard_fab2_lib.baseboard_fab2(sch_1):fm_pe_sprv_wake_n") )
				( member ( signalRef "@baseboard_fab2_lib.baseboard_fab2(sch_1):nc_pvnn_pch_dnc0") )
				( member ( signalRef "@baseboard_fab2_lib.baseboard_fab2(sch_1):nc_pvnn_pch_dnc1") )
				( member ( signalRef "@baseboard_fab2_lib.baseboard_fab2(sch_1):tp_cpld1_pb8d") )
				( member ( signalRef "@baseboard_fab2_lib.baseboard_fab2(sch_1):tp_cpld1_pt22d") )
				( member ( signalRef "@baseboard_fab2_lib.baseboard_fab2(sch_1):nc_pvddq_klm_dnc1") )
				( member ( signalRef "@baseboard_fab2_lib.baseboard_fab2(sch_1):tp_pvddq_klm_ph1_gl_0") )
				( member ( signalRef "@baseboard_fab2_lib.baseboard_fab2(sch_1):fm_p3v3_cpld_en") )
				( member ( signalRef "@baseboard_fab2_lib.baseboard_fab2(sch_1):nc_pvnn_pch_dnc3") )
				( member ( signalRef "@baseboard_fab2_lib.baseboard_fab2(sch_1):tp_clk_24m_pmsync2") )
				( member ( signalRef "@baseboard_fab2_lib.baseboard_fab2(sch_1):fm_p12v_hotswap0_en") )
				( member ( signalRef "@baseboard_fab2_lib.baseboard_fab2(sch_1):fm_p12v_hsc_adr1") )
				( member ( signalRef "@baseboard_fab2_lib.baseboard_fab2(sch_1):fm_p12v_hsc_adr2") )
				( member ( signalRef "@baseboard_fab2_lib.baseboard_fab2(sch_1):fm_p12v_main_sw_en") )
				( member ( signalRef "@baseboard_fab2_lib.baseboard_fab2(sch_1):fm_qat_en_n") )
				( member ( signalRef "@baseboard_fab2_lib.baseboard_fab2(sch_1):fm_pwr_led_n") )
				( member ( signalRef "@baseboard_fab2_lib.baseboard_fab2(sch_1):fm_slt_cfg0") )
				( member ( signalRef "@baseboard_fab2_lib.baseboard_fab2(sch_1):fm_prsnt_2_4_n") )
				( member ( signalRef "@baseboard_fab2_lib.baseboard_fab2(sch_1):fm_roma(0)") )
				( member ( signalRef "@baseboard_fab2_lib.baseboard_fab2(sch_1):fm_roma(1)") )
				( member ( signalRef "@baseboard_fab2_lib.baseboard_fab2(sch_1):fm_roma(2)") )
				( member ( signalRef "@baseboard_fab2_lib.baseboard_fab2(sch_1):fm_roma(3)") )
				( member ( signalRef "@baseboard_fab2_lib.baseboard_fab2(sch_1):fm_roma(4)") )
				( member ( signalRef "@baseboard_fab2_lib.baseboard_fab2(sch_1):fm_roma(5)") )
				( member ( signalRef "@baseboard_fab2_lib.baseboard_fab2(sch_1):fm_roma(6)") )
				( member ( signalRef "@baseboard_fab2_lib.baseboard_fab2(sch_1):fm_roma(7)") )
				( member ( signalRef "@baseboard_fab2_lib.baseboard_fab2(sch_1):fm_roma(8)") )
				( member ( signalRef "@baseboard_fab2_lib.baseboard_fab2(sch_1):fm_roma(9)") )
				( member ( signalRef "@baseboard_fab2_lib.baseboard_fab2(sch_1):fm_roma(10)") )
				( member ( signalRef "@baseboard_fab2_lib.baseboard_fab2(sch_1):fm_roma(11)") )
				( member ( signalRef "@baseboard_fab2_lib.baseboard_fab2(sch_1):fm_roma(12)") )
				( member ( signalRef "@baseboard_fab2_lib.baseboard_fab2(sch_1):fm_roma(13)") )
				( member ( signalRef "@baseboard_fab2_lib.baseboard_fab2(sch_1):fm_roma(14)") )
				( member ( signalRef "@baseboard_fab2_lib.baseboard_fab2(sch_1):fm_roma(15)") )
				( member ( signalRef "@baseboard_fab2_lib.baseboard_fab2(sch_1):fm_roma(16)") )
				( member ( signalRef "@baseboard_fab2_lib.baseboard_fab2(sch_1):fm_roma(17)") )
				( member ( signalRef "@baseboard_fab2_lib.baseboard_fab2(sch_1):fm_roma(18)") )
				( member ( signalRef "@baseboard_fab2_lib.baseboard_fab2(sch_1):fm_roma(19)") )
				( member ( signalRef "@baseboard_fab2_lib.baseboard_fab2(sch_1):fm_roma(20)") )
				( member ( signalRef "@baseboard_fab2_lib.baseboard_fab2(sch_1):fm_roma(21)") )
				( member ( signalRef "@baseboard_fab2_lib.baseboard_fab2(sch_1):fm_roma(22)") )
				( member ( signalRef "@baseboard_fab2_lib.baseboard_fab2(sch_1):fm_roma(23)") )
				( member ( signalRef "@baseboard_fab2_lib.baseboard_fab2(sch_1):pu_rst_perst_bit0") )
				( member ( signalRef "@baseboard_fab2_lib.baseboard_fab2(sch_1):pu_rst_perst_bit1") )
				( member ( signalRef "@baseboard_fab2_lib.baseboard_fab2(sch_1):fm_slps3_n") )
				( member ( signalRef "@baseboard_fab2_lib.baseboard_fab2(sch_1):fm_slps4_n") )
				( member ( signalRef "@baseboard_fab2_lib.baseboard_fab2(sch_1):fm_cpu0_rc_en") )
				( member ( signalRef "@baseboard_fab2_lib.baseboard_fab2(sch_1):tp_slp_lan_n") )
				( member ( signalRef "@baseboard_fab2_lib.baseboard_fab2(sch_1):fm_slp_sus_n") )
				( member ( signalRef "@baseboard_fab2_lib.baseboard_fab2(sch_1):tp_clk_100m_src12_dp") )
				( member ( signalRef "@baseboard_fab2_lib.baseboard_fab2(sch_1):fm_sol_uart_ch_sel") )
				( member ( signalRef "@baseboard_fab2_lib.baseboard_fab2(sch_1):fm_pwr_led_k") )
				( member ( signalRef "@baseboard_fab2_lib.baseboard_fab2(sch_1):fm_pe_bmc_wake_n") )
				( member ( signalRef "@baseboard_fab2_lib.baseboard_fab2(sch_1):fm_pe_m2_wake_n") )
				( member ( signalRef "@baseboard_fab2_lib.baseboard_fab2(sch_1):fm_mem_therm_event_lvt3_n") )
				( member ( signalRef "@baseboard_fab2_lib.baseboard_fab2(sch_1):fm_pch_pld_data_r") )
				( member ( signalRef "@baseboard_fab2_lib.baseboard_fab2(sch_1):fm_board_sku_id4") )
				( member ( signalRef "@baseboard_fab2_lib.baseboard_fab2(sch_1):fm_cpu_caterr_dly_lvt3_r_n") )
				( member ( signalRef "@baseboard_fab2_lib.baseboard_fab2(sch_1):fm_bmc_nmi_n") )
				( member ( signalRef "@baseboard_fab2_lib.baseboard_fab2(sch_1):tp_jumper_block_1_2") )
				( member ( signalRef "@baseboard_fab2_lib.baseboard_fab2(sch_1):fm_bmc_sys_throttle_r_n") )
				( member ( signalRef "@baseboard_fab2_lib.baseboard_fab2(sch_1):fm_nmi_event_n") )
				( member ( signalRef "@baseboard_fab2_lib.baseboard_fab2(sch_1):fm_cpu0_pkgid0") )
				( member ( signalRef "@baseboard_fab2_lib.baseboard_fab2(sch_1):fm_cpu0_pkgid1") )
				( member ( signalRef "@baseboard_fab2_lib.baseboard_fab2(sch_1):fm_cpu0_pkgid2") )
				( member ( signalRef "@baseboard_fab2_lib.baseboard_fab2(sch_1):fm_cpu0_proc_id0") )
				( member ( signalRef "@baseboard_fab2_lib.baseboard_fab2(sch_1):fm_cpu0_proc_id1") )
				( member ( signalRef "@baseboard_fab2_lib.baseboard_fab2(sch_1):fm_cpu0_sktocc_lvt3_n") )
				( member ( signalRef "@baseboard_fab2_lib.baseboard_fab2(sch_1):fm_cpu0_thermtrip_latch_lvt3_n") )
				( member ( signalRef "@baseboard_fab2_lib.baseboard_fab2(sch_1):fm_dimm_event_fet") )
				( member ( signalRef "@baseboard_fab2_lib.baseboard_fab2(sch_1):fm_cpu_caterr_lvt3_n") )
				( member ( signalRef "@baseboard_fab2_lib.baseboard_fab2(sch_1):tp_jumper_block_1_8") )
				( member ( signalRef "@baseboard_fab2_lib.baseboard_fab2(sch_1):fm_cpu1_pkgid0") )
				( member ( signalRef "@baseboard_fab2_lib.baseboard_fab2(sch_1):fm_cpu1_pkgid1") )
				( member ( signalRef "@baseboard_fab2_lib.baseboard_fab2(sch_1):fm_cpu1_pkgid2") )
				( member ( signalRef "@baseboard_fab2_lib.baseboard_fab2(sch_1):fm_cpu_err0_lvt3_r_n") )
				( member ( signalRef "@baseboard_fab2_lib.baseboard_fab2(sch_1):fm_cpu1_proc_id0") )
				( member ( signalRef "@baseboard_fab2_lib.baseboard_fab2(sch_1):fm_cpu1_proc_id1") )
				( member ( signalRef "@baseboard_fab2_lib.baseboard_fab2(sch_1):fm_cpu1_sktocc_lvt3_n") )
				( member ( signalRef "@baseboard_fab2_lib.baseboard_fab2(sch_1):fm_cpu1_thermtrip_latch_lvt3_n") )
				( member ( signalRef "@baseboard_fab2_lib.baseboard_fab2(sch_1):fm_cpu_err0_lvt3_n") )
				( member ( signalRef "@baseboard_fab2_lib.baseboard_fab2(sch_1):fm_db_present") )
				( member ( signalRef "@baseboard_fab2_lib.baseboard_fab2(sch_1):fm_cpu_err1_lvt3_n") )
				( member ( signalRef "@baseboard_fab2_lib.baseboard_fab2(sch_1):fm_db_uart_sel1_n") )
				( member ( signalRef "@baseboard_fab2_lib.baseboard_fab2(sch_1):fm_db_uart_sel2_n") )
				( member ( signalRef "@baseboard_fab2_lib.baseboard_fab2(sch_1):fm_db_uart_sel3_n") )
				( member ( signalRef "@baseboard_fab2_lib.baseboard_fab2(sch_1):fm_db_uart_sel4_n") )
				( member ( signalRef "@baseboard_fab2_lib.baseboard_fab2(sch_1):fm_cpu0_mcp_clk_en_n") )
				( member ( signalRef "@baseboard_fab2_lib.baseboard_fab2(sch_1):fm_db1200_smb_sa0") )
				( member ( signalRef "@baseboard_fab2_lib.baseboard_fab2(sch_1):fm_db1200_smb_sa1") )
				( member ( signalRef "@baseboard_fab2_lib.baseboard_fab2(sch_1):fm_disable_fan_n") )
				( member ( signalRef "@baseboard_fab2_lib.baseboard_fab2(sch_1):fm_dis_adr_dly") )
				( member ( signalRef "@baseboard_fab2_lib.baseboard_fab2(sch_1):fm_dual_bios_sel_n") )
				( member ( signalRef "@baseboard_fab2_lib.baseboard_fab2(sch_1):fm_enable_fan_power") )
				( member ( signalRef "@baseboard_fab2_lib.baseboard_fab2(sch_1):a_cpu0_abc_rcomp0") )
				( member ( signalRef "@baseboard_fab2_lib.baseboard_fab2(sch_1):fm_fast_prochot_en") )
				( member ( signalRef "@baseboard_fab2_lib.baseboard_fab2(sch_1):tp_cpu0_rsvd_64") )
				( member ( signalRef "@baseboard_fab2_lib.baseboard_fab2(sch_1):fm_gbe_lom_disable_n") )
				( member ( signalRef "@baseboard_fab2_lib.baseboard_fab2(sch_1):fm_gbe2_lvc3_mod_abs") )
				( member ( signalRef "@baseboard_fab2_lib.baseboard_fab2(sch_1):tp_ext_mdio_i2c_sel") )
				( member ( signalRef "@baseboard_fab2_lib.baseboard_fab2(sch_1):fm_hbw_bypass_lowbw_n") )
				( member ( signalRef "@baseboard_fab2_lib.baseboard_fab2(sch_1):fm_heartbeat_led_a") )
				( member ( signalRef "@baseboard_fab2_lib.baseboard_fab2(sch_1):fm_heartbeat_led_k") )
				( member ( signalRef "@baseboard_fab2_lib.baseboard_fab2(sch_1):fm_bios_usb_recovery") )
				( member ( signalRef "@baseboard_fab2_lib.baseboard_fab2(sch_1):tp_jumper_block_1_1") )
				( member ( signalRef "@baseboard_fab2_lib.baseboard_fab2(sch_1):fm_bios_top_swap_spkr") )
				( member ( signalRef "@baseboard_fab2_lib.baseboard_fab2(sch_1):fm_1gb_lom_disable_n") )
				( member ( signalRef "@baseboard_fab2_lib.baseboard_fab2(sch_1):a_hsc_low_en") )
				( member ( signalRef "@baseboard_fab2_lib.baseboard_fab2(sch_1):fm_hsc_timer_exp_n") )
				( member ( signalRef "@baseboard_fab2_lib.baseboard_fab2(sch_1):fm_bios_top_swap_spkr_r") )
				( member ( signalRef "@baseboard_fab2_lib.baseboard_fab2(sch_1):a_cpu1_ghj_rcomp0") )
				( member ( signalRef "@baseboard_fab2_lib.baseboard_fab2(sch_1):a_cpu0_abc_rcomp2") )
				( member ( signalRef "@baseboard_fab2_lib.baseboard_fab2(sch_1):tp_pch_gpp_d12") )
				( member ( signalRef "@baseboard_fab2_lib.baseboard_fab2(sch_1):fm_intruder_hdr_pch_n") )
				( member ( signalRef "@baseboard_fab2_lib.baseboard_fab2(sch_1):pu_lpc_pme_n") )
				( member ( signalRef "@baseboard_fab2_lib.baseboard_fab2(sch_1):fm_mated_in_d1_n") )
				( member ( signalRef "@baseboard_fab2_lib.baseboard_fab2(sch_1):fm_mated_in_d2_n") )
				( member ( signalRef "@baseboard_fab2_lib.baseboard_fab2(sch_1):fm_mated_in_n") )
				( member ( signalRef "@baseboard_fab2_lib.baseboard_fab2(sch_1):fm_mb_slot_id0") )
				( member ( signalRef "@baseboard_fab2_lib.baseboard_fab2(sch_1):fm_mb_slot_id1") )
				( member ( signalRef "@baseboard_fab2_lib.baseboard_fab2(sch_1):fm_mb_slot_id2") )
				( member ( signalRef "@baseboard_fab2_lib.baseboard_fab2(sch_1):fm_mezz_prsntb1_n") )
				( member ( signalRef "@baseboard_fab2_lib.baseboard_fab2(sch_1):fm_mezza_prsnt1_n") )
				( member ( signalRef "@baseboard_fab2_lib.baseboard_fab2(sch_1):fm_me_recover_n") )
				( member ( signalRef "@baseboard_fab2_lib.baseboard_fab2(sch_1):\tp_jumper_block_ 1_7\") )
				( member ( signalRef "@baseboard_fab2_lib.baseboard_fab2(sch_1):tp_cpu1_dmi_rx_dn1") )
				( member ( signalRef "@baseboard_fab2_lib.baseboard_fab2(sch_1):tp_cpu1_dmi_rx_dn2") )
				( member ( signalRef "@baseboard_fab2_lib.baseboard_fab2(sch_1):tp_cpu1_dmi_rx_dn3") )
				( member ( signalRef "@baseboard_fab2_lib.baseboard_fab2(sch_1):tp_cpu1_dmi_rx_dp0") )
				( member ( signalRef "@baseboard_fab2_lib.baseboard_fab2(sch_1):tp_cpu1_dmi_rx_dp1") )
				( member ( signalRef "@baseboard_fab2_lib.baseboard_fab2(sch_1):tp_cpu1_dmi_rx_dp2") )
				( member ( signalRef "@baseboard_fab2_lib.baseboard_fab2(sch_1):tp_cpu1_dmi_rx_dp3") )
				( member ( signalRef "@baseboard_fab2_lib.baseboard_fab2(sch_1):tp_cpld1_pt20b") )
				( member ( signalRef "@baseboard_fab2_lib.baseboard_fab2(sch_1):tp_cpld1_pt20a") )
				( member ( signalRef "@baseboard_fab2_lib.baseboard_fab2(sch_1):fm_cpu_err0_pch_n") )
				( member ( signalRef "@baseboard_fab2_lib.baseboard_fab2(sch_1):tp_cpld1_pt22c") )
				( member ( signalRef "@baseboard_fab2_lib.baseboard_fab2(sch_1):fm_cpu0_vrm_322m_156m_osc_en") )
				( member ( signalRef "@baseboard_fab2_lib.baseboard_fab2(sch_1):tp_cpld1_pl1a_l_gpllt_fb") )
				( member ( signalRef "@baseboard_fab2_lib.baseboard_fab2(sch_1):fm_uart_pres_n") )
				( member ( signalRef "@baseboard_fab2_lib.baseboard_fab2(sch_1):fm_prsnt_2_5_n") )
				( member ( signalRef "@baseboard_fab2_lib.baseboard_fab2(sch_1):tp_clk_100m_nsscc0_dn") )
				( member ( signalRef "@baseboard_fab2_lib.baseboard_fab2(sch_1):tp_hfi_io_conn0_rsvd_17") )
				( member ( signalRef "@baseboard_fab2_lib.baseboard_fab2(sch_1):tp_fm_wake_n") )
				( member ( signalRef "@baseboard_fab2_lib.baseboard_fab2(sch_1):fm_prsnt_2_6_n") )
				( member ( signalRef "@baseboard_fab2_lib.baseboard_fab2(sch_1):tp_ioe4") )
				( member ( signalRef "@baseboard_fab2_lib.baseboard_fab2(sch_1):tp_iof4") )
				( member ( signalRef "@baseboard_fab2_lib.baseboard_fab2(sch_1):tp_iog3") )
				( member ( signalRef "@baseboard_fab2_lib.baseboard_fab2(sch_1):tp_ioh3") )
				( member ( signalRef "@baseboard_fab2_lib.baseboard_fab2(sch_1):tp_ioh4") )
				( member ( signalRef "@baseboard_fab2_lib.baseboard_fab2(sch_1):tp_ioi4") )
				( member ( signalRef "@baseboard_fab2_lib.baseboard_fab2(sch_1):pu_irq_pch_sci_whea_n") )
				( member ( signalRef "@baseboard_fab2_lib.baseboard_fab2(sch_1):tp_pvccio_cpu0_gl_1") )
				( member ( signalRef "@baseboard_fab2_lib.baseboard_fab2(sch_1):pd_adcrext") )
				( member ( signalRef "@baseboard_fab2_lib.baseboard_fab2(sch_1):tp_cpu0_rsvd_275") )
				( member ( signalRef "@baseboard_fab2_lib.baseboard_fab2(sch_1):pd_ckmng_oe") )
				( member ( signalRef "@baseboard_fab2_lib.baseboard_fab2(sch_1):pd_cpu0_bist_enable") )
				( member ( signalRef "@baseboard_fab2_lib.baseboard_fab2(sch_1):pd_cpu0_dmimode_override") )
				( member ( signalRef "@baseboard_fab2_lib.baseboard_fab2(sch_1):pd_cpu0_ksfc_dis") )
				( member ( signalRef "@baseboard_fab2_lib.baseboard_fab2(sch_1):pd_cpu0_txt_plten") )
				( member ( signalRef "@baseboard_fab2_lib.baseboard_fab2(sch_1):pd_cpu1_bist_enable") )
				( member ( signalRef "@baseboard_fab2_lib.baseboard_fab2(sch_1):pd_cpu1_dmimode_override") )
				( member ( signalRef "@baseboard_fab2_lib.baseboard_fab2(sch_1):pd_cpu1_ksfc_dis") )
				( member ( signalRef "@baseboard_fab2_lib.baseboard_fab2(sch_1):pd_cpu1_txt_plten") )
				( member ( signalRef "@baseboard_fab2_lib.baseboard_fab2(sch_1):pd_dir_2") )
				( member ( signalRef "@baseboard_fab2_lib.baseboard_fab2(sch_1):pd_fru_wp") )
				( member ( signalRef "@baseboard_fab2_lib.baseboard_fab2(sch_1):pd_gtl2014_1_vref") )
				( member ( signalRef "@baseboard_fab2_lib.baseboard_fab2(sch_1):pd_gtl2014_2_vref") )
				( member ( signalRef "@baseboard_fab2_lib.baseboard_fab2(sch_1):pd_gtl2104_dir_0") )
				( member ( signalRef "@baseboard_fab2_lib.baseboard_fab2(sch_1):pd_gtl2104_dir_1") )
				( member ( signalRef "@baseboard_fab2_lib.baseboard_fab2(sch_1):pd_gtl2104_4_dir") )
				( member ( signalRef "@baseboard_fab2_lib.baseboard_fab2(sch_1):pd_hsc_retry_n") )
				( member ( signalRef "@baseboard_fab2_lib.baseboard_fab2(sch_1):pd_ie_debug_mode") )
				( member ( signalRef "@baseboard_fab2_lib.baseboard_fab2(sch_1):tp_clk_100m_plat1_dn") )
				( member ( signalRef "@baseboard_fab2_lib.baseboard_fab2(sch_1):pd_me_rcvr_n") )
				( member ( signalRef "@baseboard_fab2_lib.baseboard_fab2(sch_1):a_m_bmc_zq") )
				( member ( signalRef "@baseboard_fab2_lib.baseboard_fab2(sch_1):pd_password_clear") )
				( member ( signalRef "@baseboard_fab2_lib.baseboard_fab2(sch_1):fm_global_rst_warn_n") )
				( member ( signalRef "@baseboard_fab2_lib.baseboard_fab2(sch_1):pd_perext") )
				( member ( signalRef "@baseboard_fab2_lib.baseboard_fab2(sch_1):fm_pch_pld_data") )
				( member ( signalRef "@baseboard_fab2_lib.baseboard_fab2(sch_1):pd_rst_rtcrst_n") )
				( member ( signalRef "@baseboard_fab2_lib.baseboard_fab2(sch_1):tp_pvccio_cpu1_gl_1") )
				( member ( signalRef "@baseboard_fab2_lib.baseboard_fab2(sch_1):pd_sata0_controller_type_r") )
				( member ( signalRef "@baseboard_fab2_lib.baseboard_fab2(sch_1):tp_cpld1_pl1b_l_gpllc_fb") )
				( member ( signalRef "@baseboard_fab2_lib.baseboard_fab2(sch_1):pd_sata1_controller_type_r") )
				( member ( signalRef "@baseboard_fab2_lib.baseboard_fab2(sch_1):pd_sata2_controller_type") )
				( member ( signalRef "@baseboard_fab2_lib.baseboard_fab2(sch_1):fm_cpu1_rc_error_n") )
				( member ( signalRef "@baseboard_fab2_lib.baseboard_fab2(sch_1):fm_cpu0_rc_error_n") )
				( member ( signalRef "@baseboard_fab2_lib.baseboard_fab2(sch_1):pd_sprv_rset") )
				( member ( signalRef "@baseboard_fab2_lib.baseboard_fab2(sch_1):pd_sp_entest") )
				( member ( signalRef "@baseboard_fab2_lib.baseboard_fab2(sch_1):tp_cpld1_pt16b") )
				( member ( signalRef "@baseboard_fab2_lib.baseboard_fab2(sch_1):pd_tmp421_1_a0") )
				( member ( signalRef "@baseboard_fab2_lib.baseboard_fab2(sch_1):tp_clk_100m_plat1_dp") )
				( member ( signalRef "@baseboard_fab2_lib.baseboard_fab2(sch_1):pd_tmp421_2_a1") )
				( member ( signalRef "@baseboard_fab2_lib.baseboard_fab2(sch_1):fm_oc_detect_en_n") )
				( member ( signalRef "@baseboard_fab2_lib.baseboard_fab2(sch_1):tp_clk_100m_nsscc0_dp") )
				( member ( signalRef "@baseboard_fab2_lib.baseboard_fab2(sch_1):tp_cpu1_rsvd_64") )
				( member ( signalRef "@baseboard_fab2_lib.baseboard_fab2(sch_1):pd_usb_bmc_p1_dn") )
				( member ( signalRef "@baseboard_fab2_lib.baseboard_fab2(sch_1):pd_usb_bmc_p1_dp") )
				( member ( signalRef "@baseboard_fab2_lib.baseboard_fab2(sch_1):tp_pvccin_cpu0_ph4_gl_1") )
				( member ( signalRef "@baseboard_fab2_lib.baseboard_fab2(sch_1):a_cpu0_def_rcomp2") )
				( member ( signalRef "@baseboard_fab2_lib.baseboard_fab2(sch_1):fp_id_led_xor_r") )
				( member ( signalRef "@baseboard_fab2_lib.baseboard_fab2(sch_1):a_cpu0_def_rcomp1") )
				( member ( signalRef "@baseboard_fab2_lib.baseboard_fab2(sch_1):a_cpu0_def_rcomp0") )
				( member ( signalRef "@baseboard_fab2_lib.baseboard_fab2(sch_1):fm_bmc_fault_led_n") )
				( member ( signalRef "@baseboard_fab2_lib.baseboard_fab2(sch_1):fp_nmi_btn_n") )
				( member ( signalRef "@baseboard_fab2_lib.baseboard_fab2(sch_1):fp_pwr_btn_buf1_n") )
				( member ( signalRef "@baseboard_fab2_lib.baseboard_fab2(sch_1):fm_cpu_err1_lvt3_r_n") )
				( member ( signalRef "@baseboard_fab2_lib.baseboard_fab2(sch_1):fp_pwr_id_led_n") )
				( member ( signalRef "@baseboard_fab2_lib.baseboard_fab2(sch_1):fm_cpu0_and_cpu1_mcp_pres") )
				( member ( signalRef "@baseboard_fab2_lib.baseboard_fab2(sch_1):fm_cpu0_cd_pres") )
				( member ( signalRef "@baseboard_fab2_lib.baseboard_fab2(sch_1):fp_rst_btn_buf1_n") )
				( member ( signalRef "@baseboard_fab2_lib.baseboard_fab2(sch_1):fm_adc128_a0") )
				( member ( signalRef "@baseboard_fab2_lib.baseboard_fab2(sch_1):fm_adc128_a1") )
				( member ( signalRef "@baseboard_fab2_lib.baseboard_fab2(sch_1):fm_adr_complete") )
				( member ( signalRef "@baseboard_fab2_lib.baseboard_fab2(sch_1):fm_cpld_dbg_pwr_en_r_n") )
				( member ( signalRef "@baseboard_fab2_lib.baseboard_fab2(sch_1):fm_bmc_cpld_mp_rst_n") )
				( member ( signalRef "@baseboard_fab2_lib.baseboard_fab2(sch_1):fm_adr_smi_gpio_n") )
				( member ( signalRef "@baseboard_fab2_lib.baseboard_fab2(sch_1):fm_all_wake_n") )
				( member ( signalRef "@baseboard_fab2_lib.baseboard_fab2(sch_1):fm_backup_bios_sel_n") )
				( member ( signalRef "@baseboard_fab2_lib.baseboard_fab2(sch_1):tp_pvccin_cpu0_ph5_gl_1") )
				( member ( signalRef "@baseboard_fab2_lib.baseboard_fab2(sch_1):fm_battery_sense_en") )
				( member ( signalRef "@baseboard_fab2_lib.baseboard_fab2(sch_1):tp_pvccin_cpu0_ph1_gl_1") )
				( member ( signalRef "@baseboard_fab2_lib.baseboard_fab2(sch_1):fm_beep_led_p") )
				( member ( signalRef "@baseboard_fab2_lib.baseboard_fab2(sch_1):fm_cpu_err1_pch_n") )
				( member ( signalRef "@baseboard_fab2_lib.baseboard_fab2(sch_1):fm_cpu1_rc_en") )
				( member ( signalRef "@baseboard_fab2_lib.baseboard_fab2(sch_1):tp_pvccin_cpu0_ph2_gl_1") )
				( member ( signalRef "@baseboard_fab2_lib.baseboard_fab2(sch_1):tp_pvccin_cpu0_ph1_gl_0") )
				( member ( signalRef "@baseboard_fab2_lib.baseboard_fab2(sch_1):tp_gpior5_roma25_vpor7") )
				( member ( signalRef "@baseboard_fab2_lib.baseboard_fab2(sch_1):fm_bios_mrc_debug_msg_dis_n") )
				( member ( signalRef "@baseboard_fab2_lib.baseboard_fab2(sch_1):fm_bios_post_cmplt_n") )
				( member ( signalRef "@baseboard_fab2_lib.baseboard_fab2(sch_1):fm_bios_prefrb2_good") )
				( member ( signalRef "@baseboard_fab2_lib.baseboard_fab2(sch_1):fm_bios_smi_active_n") )
				( member ( signalRef "@baseboard_fab2_lib.baseboard_fab2(sch_1):fm_bios_spi_bmc_ctrl") )
				( member ( signalRef "@baseboard_fab2_lib.baseboard_fab2(sch_1):fm_bmc_heartbeat_n") )
				( member ( signalRef "@baseboard_fab2_lib.baseboard_fab2(sch_1):fm_cpu_err2_lvt3_n") )
				( member ( signalRef "@baseboard_fab2_lib.baseboard_fab2(sch_1):fm_bmc_onctl_n") )
				( member ( signalRef "@baseboard_fab2_lib.baseboard_fab2(sch_1):fm_bmc_onctl_r_n") )
				( member ( signalRef "@baseboard_fab2_lib.baseboard_fab2(sch_1):a_cpu0_abc_rcomp1") )
				( member ( signalRef "@baseboard_fab2_lib.baseboard_fab2(sch_1):tp_pvccin_cpu0_ph3_gl_1") )
				( member ( signalRef "@baseboard_fab2_lib.baseboard_fab2(sch_1):fm_bmc_pwrbtn_out_n") )
				( member ( signalRef "@baseboard_fab2_lib.baseboard_fab2(sch_1):fm_bmc_ready_n") )
				( member ( signalRef "@baseboard_fab2_lib.baseboard_fab2(sch_1):tp_jumper_block_2_8") )
				( member ( signalRef "@baseboard_fab2_lib.baseboard_fab2(sch_1):fm_board_rev_id0") )
				( member ( signalRef "@baseboard_fab2_lib.baseboard_fab2(sch_1):fm_board_rev_id1") )
				( member ( signalRef "@baseboard_fab2_lib.baseboard_fab2(sch_1):fm_board_rev_id2") )
				( member ( signalRef "@baseboard_fab2_lib.baseboard_fab2(sch_1):fm_board_sku_id0") )
				( member ( signalRef "@baseboard_fab2_lib.baseboard_fab2(sch_1):fm_board_sku_id1") )
				( member ( signalRef "@baseboard_fab2_lib.baseboard_fab2(sch_1):fm_board_sku_id2") )
				( member ( signalRef "@baseboard_fab2_lib.baseboard_fab2(sch_1):fm_board_sku_id3") )
				( member ( signalRef "@baseboard_fab2_lib.baseboard_fab2(sch_1):tp_pvccin_cpu0_apwm6") )
				( member ( signalRef "@baseboard_fab2_lib.baseboard_fab2(sch_1):fm_cpu1_vrm_322m_156m_osc_en") )
				( member ( signalRef "@baseboard_fab2_lib.baseboard_fab2(sch_1):tp_pvddq_abc_ph1_gl_1") )
				( member ( signalRef "@baseboard_fab2_lib.baseboard_fab2(sch_1):tp_pvddq_abc_ph2_gl_1") )
				( member ( signalRef "@baseboard_fab2_lib.baseboard_fab2(sch_1):tp_pvddq_def_ph1_gl_1") )
				( member ( signalRef "@baseboard_fab2_lib.baseboard_fab2(sch_1):tp_pvccin_cpu0_reset") )
				( member ( signalRef "@baseboard_fab2_lib.baseboard_fab2(sch_1):tp_pvccin_cpu1_airef6") )
				( member ( signalRef "@baseboard_fab2_lib.baseboard_fab2(sch_1):fm_bmc_fault_led") )
				( member ( signalRef "@baseboard_fab2_lib.baseboard_fab2(sch_1):tp_pvccin_cpu1_apwm6") )
				( member ( signalRef "@baseboard_fab2_lib.baseboard_fab2(sch_1):fm_db1200zl_bclks_en_n") )
				( member ( signalRef "@baseboard_fab2_lib.baseboard_fab2(sch_1):fm_pch_bmc_thermtrip_exi_strap_n") )
				( member ( signalRef "@baseboard_fab2_lib.baseboard_fab2(sch_1):fm_cpu1_mcp_clk_en_n") )
				( member ( signalRef "@baseboard_fab2_lib.baseboard_fab2(sch_1):fm_cpu1_stl_brd_osc_en") )
				( member ( signalRef "@baseboard_fab2_lib.baseboard_fab2(sch_1):fm_cpu1_vrm_osc_en") )
				( member ( signalRef "@baseboard_fab2_lib.baseboard_fab2(sch_1):tp_pvccin_cpu1_reset_n") )
				( member ( signalRef "@baseboard_fab2_lib.baseboard_fab2(sch_1):tp_pvccio_cpu0_bpwm1") )
				( member ( signalRef "@baseboard_fab2_lib.baseboard_fab2(sch_1):tp_pvddq_def_ph2_gl_1") )
				( member ( signalRef "@baseboard_fab2_lib.baseboard_fab2(sch_1):tp_pvccio_cpu0_reset_n") )
				( member ( signalRef "@baseboard_fab2_lib.baseboard_fab2(sch_1):tp_pvccio_cpu1_bpwm1") )
				( member ( signalRef "@baseboard_fab2_lib.baseboard_fab2(sch_1):tp_pvddq_ghj_ph1_gl_1") )
				( member ( signalRef "@baseboard_fab2_lib.baseboard_fab2(sch_1):tp_pvccio_cpu1_reset_n") )
				( member ( signalRef "@baseboard_fab2_lib.baseboard_fab2(sch_1):tp_fet_q56_3") )
				( member ( signalRef "@baseboard_fab2_lib.baseboard_fab2(sch_1):tp_pch_rsvd6") )
				( member ( signalRef "@baseboard_fab2_lib.baseboard_fab2(sch_1):tp_pch_rsvd22") )
				( member ( signalRef "@baseboard_fab2_lib.baseboard_fab2(sch_1):tp_pm_sync_gtl") )
				( member ( signalRef "@baseboard_fab2_lib.baseboard_fab2(sch_1):tp_pvccin_cpu0_airef6") )
				( member ( signalRef "@baseboard_fab2_lib.baseboard_fab2(sch_1):tp_fet_q56_4") )
				( member ( signalRef "@baseboard_fab2_lib.baseboard_fab2(sch_1):tp_cpu0_rsvd_test_4") )
				( member ( signalRef "@baseboard_fab2_lib.baseboard_fab2(sch_1):a_cpu1_klm_rcomp0") )
				( member ( signalRef "@baseboard_fab2_lib.baseboard_fab2(sch_1):pu_adr_timer_hold_off_n") )
				( member ( signalRef "@baseboard_fab2_lib.baseboard_fab2(sch_1):fm_battery_sense_en_n") )
				( member ( signalRef "@baseboard_fab2_lib.baseboard_fab2(sch_1):pu_bios_recover_boot") )
				( member ( signalRef "@baseboard_fab2_lib.baseboard_fab2(sch_1):tp_cpu0_rsvd_test_3") )
				( member ( signalRef "@baseboard_fab2_lib.baseboard_fab2(sch_1):a_cpu1_ghj_rcomp1") )
				( member ( signalRef "@baseboard_fab2_lib.baseboard_fab2(sch_1):h_cpu0_bmcinit") )
				( member ( signalRef "@baseboard_fab2_lib.baseboard_fab2(sch_1):pu_cpu0_ear_n") )
				( member ( signalRef "@baseboard_fab2_lib.baseboard_fab2(sch_1):pu_cpu0_frmagent") )
				( member ( signalRef "@baseboard_fab2_lib.baseboard_fab2(sch_1):pu_cpu0_legacy_skt") )
				( member ( signalRef "@baseboard_fab2_lib.baseboard_fab2(sch_1):pu_cpu0_safe_mode_boot") )
				( member ( signalRef "@baseboard_fab2_lib.baseboard_fab2(sch_1):pu_cpu0_socket_id_0") )
				( member ( signalRef "@baseboard_fab2_lib.baseboard_fab2(sch_1):pu_cpu0_socket_id_1") )
				( member ( signalRef "@baseboard_fab2_lib.baseboard_fab2(sch_1):pu_cpu0_tsc_sync") )
				( member ( signalRef "@baseboard_fab2_lib.baseboard_fab2(sch_1):pu_cpu0_txt_agent") )
				( member ( signalRef "@baseboard_fab2_lib.baseboard_fab2(sch_1):h_cpu1_bmcinit") )
				( member ( signalRef "@baseboard_fab2_lib.baseboard_fab2(sch_1):pu_cpu1_ear_n") )
				( member ( signalRef "@baseboard_fab2_lib.baseboard_fab2(sch_1):pu_cpu1_frmagent") )
				( member ( signalRef "@baseboard_fab2_lib.baseboard_fab2(sch_1):pu_cpu1_legacy_skt") )
				( member ( signalRef "@baseboard_fab2_lib.baseboard_fab2(sch_1):pu_cpu1_safe_mode_boot") )
				( member ( signalRef "@baseboard_fab2_lib.baseboard_fab2(sch_1):pu_cpu1_socket_id_0") )
				( member ( signalRef "@baseboard_fab2_lib.baseboard_fab2(sch_1):pu_cpu1_socket_id_1") )
				( member ( signalRef "@baseboard_fab2_lib.baseboard_fab2(sch_1):pu_cpu1_tsc_sync") )
				( member ( signalRef "@baseboard_fab2_lib.baseboard_fab2(sch_1):pu_cpu1_txt_agent") )
				( member ( signalRef "@baseboard_fab2_lib.baseboard_fab2(sch_1):fm_cpu_msmi_lvt3_n") )
				( member ( signalRef "@baseboard_fab2_lib.baseboard_fab2(sch_1):pu_datain1_sata_0_r") )
				( member ( signalRef "@baseboard_fab2_lib.baseboard_fab2(sch_1):fm_uartsw_msb_n") )
				( member ( signalRef "@baseboard_fab2_lib.baseboard_fab2(sch_1):pu_datain1_sata_1_r") )
				( member ( signalRef "@baseboard_fab2_lib.baseboard_fab2(sch_1):pu_datain1_sata_2") )
				( member ( signalRef "@baseboard_fab2_lib.baseboard_fab2(sch_1):fm_sint_prsnt_n") )
				( member ( signalRef "@baseboard_fab2_lib.baseboard_fab2(sch_1):pu_fm_rcin_n") )
				( member ( signalRef "@baseboard_fab2_lib.baseboard_fab2(sch_1):pu_gtl2014_1_dir") )
				( member ( signalRef "@baseboard_fab2_lib.baseboard_fab2(sch_1):pu_gtl2014_2_dir") )
				( member ( signalRef "@baseboard_fab2_lib.baseboard_fab2(sch_1):a_hsc_vout") )
				( member ( signalRef "@baseboard_fab2_lib.baseboard_fab2(sch_1):pu_irq_vralert_n") )
				( member ( signalRef "@baseboard_fab2_lib.baseboard_fab2(sch_1):pu_key_conn_pin2_r") )
				( member ( signalRef "@baseboard_fab2_lib.baseboard_fab2(sch_1):tp_jumper_block_2_10") )
				( member ( signalRef "@baseboard_fab2_lib.baseboard_fab2(sch_1):pu_nv_hold_n") )
				( member ( signalRef "@baseboard_fab2_lib.baseboard_fab2(sch_1):pu_nv_wp_n") )
				( member ( signalRef "@baseboard_fab2_lib.baseboard_fab2(sch_1):fm_uartsw_lsb_r_n") )
				( member ( signalRef "@baseboard_fab2_lib.baseboard_fab2(sch_1):pu_pch_tls_enable_strap") )
				( member ( signalRef "@baseboard_fab2_lib.baseboard_fab2(sch_1):fm_uartsw_lsb_n") )
				( member ( signalRef "@baseboard_fab2_lib.baseboard_fab2(sch_1):tp_fan_0") )
				( member ( signalRef "@baseboard_fab2_lib.baseboard_fab2(sch_1):pu_fab2_marker_cpld") )
				( member ( signalRef "@baseboard_fab2_lib.baseboard_fab2(sch_1):tp_cpld1_pb11b_pclkc2_0") )
				( member ( signalRef "@baseboard_fab2_lib.baseboard_fab2(sch_1):tp_pvddq_ghj_ph2_gl_1") )
				( member ( signalRef "@baseboard_fab2_lib.baseboard_fab2(sch_1):tp_pvddq_klm_ph1_gl_1") )
				( member ( signalRef "@baseboard_fab2_lib.baseboard_fab2(sch_1):fm_cpu0_or_cpu1_mcp_pres") )
				( member ( signalRef "@baseboard_fab2_lib.baseboard_fab2(sch_1):tp_jumper_block_2_12") )
				( member ( signalRef "@baseboard_fab2_lib.baseboard_fab2(sch_1):fm_gbe3_lvc3_mod_abs") )
				( member ( signalRef "@baseboard_fab2_lib.baseboard_fab2(sch_1):tp_slg55021_p12v_main_8") )
				( member ( signalRef "@baseboard_fab2_lib.baseboard_fab2(sch_1):fm_pvcciomcp_cpu0_en") )
				( member ( signalRef "@baseboard_fab2_lib.baseboard_fab2(sch_1):fm_cpu_err1_lvt3_bmc_n") )
				( member ( signalRef "@baseboard_fab2_lib.baseboard_fab2(sch_1):tp_fan_1") )
				( member ( signalRef "@baseboard_fab2_lib.baseboard_fab2(sch_1):pu_spi_bmc_bt_hold_n") )
				( member ( signalRef "@baseboard_fab2_lib.baseboard_fab2(sch_1):pu_spi_bmc_bt_wp_n") )
				( member ( signalRef "@baseboard_fab2_lib.baseboard_fab2(sch_1):pu_spi_flash_reset_2_n") )
				( member ( signalRef "@baseboard_fab2_lib.baseboard_fab2(sch_1):pu_spi0_rst") )
				( member ( signalRef "@baseboard_fab2_lib.baseboard_fab2(sch_1):pu_spi1_rst") )
				( member ( signalRef "@baseboard_fab2_lib.baseboard_fab2(sch_1):pu_sprv_lan_pwr_good") )
				( member ( signalRef "@baseboard_fab2_lib.baseboard_fab2(sch_1):pu_tmp421_2_a0") )
				( member ( signalRef "@baseboard_fab2_lib.baseboard_fab2(sch_1):pu_tri_state_en") )
				( member ( signalRef "@baseboard_fab2_lib.baseboard_fab2(sch_1):pu_vr_pvccin_cpu0_imon") )
				( member ( signalRef "@baseboard_fab2_lib.baseboard_fab2(sch_1):pu_vr_pvccio_cpu0_fault1") )
				( member ( signalRef "@baseboard_fab2_lib.baseboard_fab2(sch_1):pu_vr_pvccio_cpu1_fault1") )
				( member ( signalRef "@baseboard_fab2_lib.baseboard_fab2(sch_1):pu_vr_pvddq_abc_fault1") )
				( member ( signalRef "@baseboard_fab2_lib.baseboard_fab2(sch_1):pu_vr_pvddq_def_fault1") )
				( member ( signalRef "@baseboard_fab2_lib.baseboard_fab2(sch_1):pu_vr_pvddq_ghj_fault1") )
				( member ( signalRef "@baseboard_fab2_lib.baseboard_fab2(sch_1):pu_vr_pvddq_klm_fault1") )
				( member ( signalRef "@baseboard_fab2_lib.baseboard_fab2(sch_1):pu_vr_pvnn_pch_fault1") )
				( member ( signalRef "@baseboard_fab2_lib.baseboard_fab2(sch_1):tp_pvddq_def_pinalrt_n") )
				( member ( signalRef "@baseboard_fab2_lib.baseboard_fab2(sch_1):tp_pvddq_def_pwm3") )
				( member ( signalRef "@baseboard_fab2_lib.baseboard_fab2(sch_1):tp_pvddq_ghj_bref1") )
				( member ( signalRef "@baseboard_fab2_lib.baseboard_fab2(sch_1):tp_pvddq_ghj_btsen") )
				( member ( signalRef "@baseboard_fab2_lib.baseboard_fab2(sch_1):tp_pvddq_ghj_bvref") )
				( member ( signalRef "@baseboard_fab2_lib.baseboard_fab2(sch_1):tp_pvddq_ghj_bvsen") )
				( member ( signalRef "@baseboard_fab2_lib.baseboard_fab2(sch_1):fm_pvccmcp_cpu0_en") )
				( member ( signalRef "@baseboard_fab2_lib.baseboard_fab2(sch_1):tp_pvddq_ghj_mp1") )
				( member ( signalRef "@baseboard_fab2_lib.baseboard_fab2(sch_1):tp_pvddq_ghj_ph3_imon") )
				( member ( signalRef "@baseboard_fab2_lib.baseboard_fab2(sch_1):tp_pvddq_ghj_ph3_imon_ref") )
				( member ( signalRef "@baseboard_fab2_lib.baseboard_fab2(sch_1):nc_pvddq_ghj_pinalrt_n") )
				( member ( signalRef "@baseboard_fab2_lib.baseboard_fab2(sch_1):tp_pvddq_ghj_pwm3") )
				( member ( signalRef "@baseboard_fab2_lib.baseboard_fab2(sch_1):tp_pvddq_klm_bref1") )
				( member ( signalRef "@baseboard_fab2_lib.baseboard_fab2(sch_1):tp_pvddq_klm_btsen") )
				( member ( signalRef "@baseboard_fab2_lib.baseboard_fab2(sch_1):tp_pvddq_klm_bvref") )
				( member ( signalRef "@baseboard_fab2_lib.baseboard_fab2(sch_1):tp_pvddq_klm_bvsen") )
				( member ( signalRef "@baseboard_fab2_lib.baseboard_fab2(sch_1):nc_pvddq_klm_gp0") )
				( member ( signalRef "@baseboard_fab2_lib.baseboard_fab2(sch_1):nc_pvddq_klm_gp1") )
				( member ( signalRef "@baseboard_fab2_lib.baseboard_fab2(sch_1):tp_pvddq_klm_ph3_imon") )
				( member ( signalRef "@baseboard_fab2_lib.baseboard_fab2(sch_1):tp_pvddq_klm_ph3_imon_ref") )
				( member ( signalRef "@baseboard_fab2_lib.baseboard_fab2(sch_1):nc_pvddq_klm_pinalrt_n") )
				( member ( signalRef "@baseboard_fab2_lib.baseboard_fab2(sch_1):nc_pvddq_klm_pwm3") )
				( member ( signalRef "@baseboard_fab2_lib.baseboard_fab2(sch_1):tp_pvnn_pch_pinalrt_n") )
				( member ( signalRef "@baseboard_fab2_lib.baseboard_fab2(sch_1):tp_pvnn_pch_vclk") )
				( member ( signalRef "@baseboard_fab2_lib.baseboard_fab2(sch_1):tp_pvsa_cpu0_gl_0") )
				( member ( signalRef "@baseboard_fab2_lib.baseboard_fab2(sch_1):tp_pvsa_cpu1_gl_0") )
				( member ( signalRef "@baseboard_fab2_lib.baseboard_fab2(sch_1):fm_cpu1_cd_pres") )
				( member ( signalRef "@baseboard_fab2_lib.baseboard_fab2(sch_1):tp_rgmii1txctl_gpiot1") )
				( member ( signalRef "@baseboard_fab2_lib.baseboard_fab2(sch_1):tp_rgmii1txd2_gpiot4") )
				( member ( signalRef "@baseboard_fab2_lib.baseboard_fab2(sch_1):tp_rgmii1txd3_gpiot5") )
				( member ( signalRef "@baseboard_fab2_lib.baseboard_fab2(sch_1):tp_rgmii2txctl_gpiot7") )
				( member ( signalRef "@baseboard_fab2_lib.baseboard_fab2(sch_1):tp_rgmii2txd2_gpiot4") )
				( member ( signalRef "@baseboard_fab2_lib.baseboard_fab2(sch_1):tp_rgmii2txd3_gpiot5") )
				( member ( signalRef "@baseboard_fab2_lib.baseboard_fab2(sch_1):tp_rst_cpu1_cd_hfi0_n") )
				( member ( signalRef "@baseboard_fab2_lib.baseboard_fab2(sch_1):tp_cpld1_pt17b_pclkc0_1") )
				( member ( signalRef "@baseboard_fab2_lib.baseboard_fab2(sch_1):tp_cpld1_pt13a") )
				( member ( signalRef "@baseboard_fab2_lib.baseboard_fab2(sch_1):tp_cpld1_pt11b") )
				( member ( signalRef "@baseboard_fab2_lib.baseboard_fab2(sch_1):tp_cpld1_pt11a") )
				( member ( signalRef "@baseboard_fab2_lib.baseboard_fab2(sch_1):fm_cpu_msmi_lvt3_r_n") )
				( member ( signalRef "@baseboard_fab2_lib.baseboard_fab2(sch_1):fm_mem_event_func") )
				( member ( signalRef "@baseboard_fab2_lib.baseboard_fab2(sch_1):tp_gpioe7_rxd3") )
				( member ( signalRef "@baseboard_fab2_lib.baseboard_fab2(sch_1):tp_cpu1_rsvd_test_3") )
				( member ( signalRef "@baseboard_fab2_lib.baseboard_fab2(sch_1):fm_uartsw_msb_r_n") )
				( member ( signalRef "@baseboard_fab2_lib.baseboard_fab2(sch_1):fm_pvpp_cpu0_en") )
				( member ( signalRef "@baseboard_fab2_lib.baseboard_fab2(sch_1):tp_smb_cpu1_cd_hfi0_i2cclk") )
				( member ( signalRef "@baseboard_fab2_lib.baseboard_fab2(sch_1):tp_smb_cpu1_cd_hfi0_i2cdat") )
				( member ( signalRef "@baseboard_fab2_lib.baseboard_fab2(sch_1):tp_spi_pch_bios_clk_r") )
				( member ( signalRef "@baseboard_fab2_lib.baseboard_fab2(sch_1):tp_spi_pch_bios_cs0_r_n") )
				( member ( signalRef "@baseboard_fab2_lib.baseboard_fab2(sch_1):tp_spi_pch_bios_miso_r") )
				( member ( signalRef "@baseboard_fab2_lib.baseboard_fab2(sch_1):tp_spi_pch_bios_mosi_r") )
				( member ( signalRef "@baseboard_fab2_lib.baseboard_fab2(sch_1):fm_pvpp_cpu1_en") )
				( member ( signalRef "@baseboard_fab2_lib.baseboard_fab2(sch_1):tp_spi_switch1_3") )
				( member ( signalRef "@baseboard_fab2_lib.baseboard_fab2(sch_1):tp_spi_switch1_6") )
				( member ( signalRef "@baseboard_fab2_lib.baseboard_fab2(sch_1):tp_spi_switch1_9") )
				( member ( signalRef "@baseboard_fab2_lib.baseboard_fab2(sch_1):tp_spi_switch1_10") )
				( member ( signalRef "@baseboard_fab2_lib.baseboard_fab2(sch_1):tp_spi_switch1_11") )
				( member ( signalRef "@baseboard_fab2_lib.baseboard_fab2(sch_1):tp_spi_switch1_12") )
				( member ( signalRef "@baseboard_fab2_lib.baseboard_fab2(sch_1):tp_spi_switch1_13") )
				( member ( signalRef "@baseboard_fab2_lib.baseboard_fab2(sch_1):tp_spi_switch1_14") )
				( member ( signalRef "@baseboard_fab2_lib.baseboard_fab2(sch_1):nc_sprngvlle_22") )
				( member ( signalRef "@baseboard_fab2_lib.baseboard_fab2(sch_1):tp_sprv_sdp0") )
				( member ( signalRef "@baseboard_fab2_lib.baseboard_fab2(sch_1):tp_sprv_sdp1") )
				( member ( signalRef "@baseboard_fab2_lib.baseboard_fab2(sch_1):tp_sprv_sdp2") )
				( member ( signalRef "@baseboard_fab2_lib.baseboard_fab2(sch_1):tp_sprv_sdp3") )
				( member ( signalRef "@baseboard_fab2_lib.baseboard_fab2(sch_1):tp_usb_esd_ac2") )
				( member ( signalRef "@baseboard_fab2_lib.baseboard_fab2(sch_1):tp_usb_esd_ac3") )
				( member ( signalRef "@baseboard_fab2_lib.baseboard_fab2(sch_1):tp_usb_esd_out2") )
				( member ( signalRef "@baseboard_fab2_lib.baseboard_fab2(sch_1):tp_usb_esd_out3") )
				( member ( signalRef "@baseboard_fab2_lib.baseboard_fab2(sch_1):fm_156m_cpu1_brd_osc_en") )
				( member ( signalRef "@baseboard_fab2_lib.baseboard_fab2(sch_1):tp_cpld1_pl12b_pclkc3_0") )
				( member ( signalRef "@baseboard_fab2_lib.baseboard_fab2(sch_1):a_cpu1_ghj_rcomp2") )
				( member ( signalRef "@baseboard_fab2_lib.baseboard_fab2(sch_1):fm_156m_cpu0_brd_osc_en") )
				( member ( signalRef "@baseboard_fab2_lib.baseboard_fab2(sch_1):tp_pvccin_cpu0_ph2_gl_0") )
				( member ( signalRef "@baseboard_fab2_lib.baseboard_fab2(sch_1):tp_pvccin_cpu0_ph3_gl_0") )
				( member ( signalRef "@baseboard_fab2_lib.baseboard_fab2(sch_1):tp_pvccin_cpu0_ph4_gl_0") )
				( member ( signalRef "@baseboard_fab2_lib.baseboard_fab2(sch_1):tp_pvccin_cpu0_ph5_gl_0") )
				( member ( signalRef "@baseboard_fab2_lib.baseboard_fab2(sch_1):tp_pvccinc_cpu1_ph1_gl_0") )
				( member ( signalRef "@baseboard_fab2_lib.baseboard_fab2(sch_1):tp_pvccinc_cpu1_ph2_gl_0") )
				( member ( signalRef "@baseboard_fab2_lib.baseboard_fab2(sch_1):tp_pvccin_cpu1_ph3_gl_0") )
				( member ( signalRef "@baseboard_fab2_lib.baseboard_fab2(sch_1):tp_pvccin_cpu1_ph4_gl_0") )
				( member ( signalRef "@baseboard_fab2_lib.baseboard_fab2(sch_1):tp_pvccin_cpu1_ph5_gl_0") )
				( member ( signalRef "@baseboard_fab2_lib.baseboard_fab2(sch_1):tp_vgahs_gpioj4") )
				( member ( signalRef "@baseboard_fab2_lib.baseboard_fab2(sch_1):tp_vgavs_gpioj5") )
				( member ( signalRef "@baseboard_fab2_lib.baseboard_fab2(sch_1):tp_pvddq_abc_bpwm1") )
				( member ( signalRef "@baseboard_fab2_lib.baseboard_fab2(sch_1):tp_pvddq_abc_reset_n") )
				( member ( signalRef "@baseboard_fab2_lib.baseboard_fab2(sch_1):tp_pvddq_def_bpwm1") )
				( member ( signalRef "@baseboard_fab2_lib.baseboard_fab2(sch_1):tp_pvddq_def_reset_n") )
				( member ( signalRef "@baseboard_fab2_lib.baseboard_fab2(sch_1):tp_pvddq_ghj_bpwm1") )
				( member ( signalRef "@baseboard_fab2_lib.baseboard_fab2(sch_1):tp_pvddq_ghj_reset_n") )
				( member ( signalRef "@baseboard_fab2_lib.baseboard_fab2(sch_1):tp_pvddq_klm_bpwm1") )
				( member ( signalRef "@baseboard_fab2_lib.baseboard_fab2(sch_1):tp_pvddq_klm_reset_n") )
				( member ( signalRef "@baseboard_fab2_lib.baseboard_fab2(sch_1):tp_pvddq_klm_ph2_gl_1") )
				( member ( signalRef "@baseboard_fab2_lib.baseboard_fab2(sch_1):tp_pvnn_pch_gl_1") )
				( member ( signalRef "@baseboard_fab2_lib.baseboard_fab2(sch_1):tp_pvsa_cpu0_gl_1") )
				( member ( signalRef "@baseboard_fab2_lib.baseboard_fab2(sch_1):tp_p1v05_pch_gl_1") )
				( member ( signalRef "@baseboard_fab2_lib.baseboard_fab2(sch_1):tp_shared_kr_mdc_0") )
				( member ( signalRef "@baseboard_fab2_lib.baseboard_fab2(sch_1):tp_rsvd(0)") )
				( member ( signalRef "@baseboard_fab2_lib.baseboard_fab2(sch_1):nc_pvccin_cpu0_ph1_p31") )
				( member ( signalRef "@baseboard_fab2_lib.baseboard_fab2(sch_1):nc_pvccin_cpu0_ph2_p31") )
				( member ( signalRef "@baseboard_fab2_lib.baseboard_fab2(sch_1):nc_pvccin_cpu0_ph3_p31") )
				( member ( signalRef "@baseboard_fab2_lib.baseboard_fab2(sch_1):tp_dacg") )
				( member ( signalRef "@baseboard_fab2_lib.baseboard_fab2(sch_1):tp_dacr") )
				( member ( signalRef "@baseboard_fab2_lib.baseboard_fab2(sch_1):nc_m2(7)") )
				( member ( signalRef "@baseboard_fab2_lib.baseboard_fab2(sch_1):nc_m2(6)") )
				( member ( signalRef "@baseboard_fab2_lib.baseboard_fab2(sch_1):nc_m2(5)") )
				( member ( signalRef "@baseboard_fab2_lib.baseboard_fab2(sch_1):tp_ddcclk_gpioj6") )
				( member ( signalRef "@baseboard_fab2_lib.baseboard_fab2(sch_1):tp_ddcdat_gpioj7") )
				( member ( signalRef "@baseboard_fab2_lib.baseboard_fab2(sch_1):nc_m2(4)") )
				( member ( signalRef "@baseboard_fab2_lib.baseboard_fab2(sch_1):tp_cpld1_pl2b_l_gpllc_in") )
				( member ( signalRef "@baseboard_fab2_lib.baseboard_fab2(sch_1):tp_cpld1_pb8a_mclk_cclk") )
				( member ( signalRef "@baseboard_fab2_lib.baseboard_fab2(sch_1):tp_cpld1_pb5a_csspin") )
				( member ( signalRef "@baseboard_fab2_lib.baseboard_fab2(sch_1):tp_cpld1_pb8b_so_spiso") )
				( member ( signalRef "@baseboard_fab2_lib.baseboard_fab2(sch_1):nc_m2(3)") )
				( member ( signalRef "@baseboard_fab2_lib.baseboard_fab2(sch_1):tp_fm_cpu1_cd_hfi0_modprst_n") )
				( member ( signalRef "@baseboard_fab2_lib.baseboard_fab2(sch_1):tp_cpld1_pl7d_pclkt4_0") )
				( member ( signalRef "@baseboard_fab2_lib.baseboard_fab2(sch_1):tp_pvccin_cpu1_ph4_gl_1") )
				( member ( signalRef "@baseboard_fab2_lib.baseboard_fab2(sch_1):tp_irq_cpu1_cd_hfi0_n") )
				( member ( signalRef "@baseboard_fab2_lib.baseboard_fab2(sch_1):tp_jtag_bmc_rtck") )
				( member ( signalRef "@baseboard_fab2_lib.baseboard_fab2(sch_1):nc_pvccin_cpu0_ph4_p31") )
				( member ( signalRef "@baseboard_fab2_lib.baseboard_fab2(sch_1):tp_pvnn_pch_reset_n") )
				( member ( signalRef "@baseboard_fab2_lib.baseboard_fab2(sch_1):nc_m2(8)") )
				( member ( signalRef "@baseboard_fab2_lib.baseboard_fab2(sch_1):nc_m2(2)") )
				( member ( signalRef "@baseboard_fab2_lib.baseboard_fab2(sch_1):tp_cpld1_pb16b_pclkc2_1") )
				( member ( signalRef "@baseboard_fab2_lib.baseboard_fab2(sch_1):fm_ocp_mezzc_pres_n") )
				( member ( signalRef "@baseboard_fab2_lib.baseboard_fab2(sch_1):tp_led_cpu1_cd_hfi0_n") )
				( member ( signalRef "@baseboard_fab2_lib.baseboard_fab2(sch_1):nc_m2(9)") )
				( member ( signalRef "@baseboard_fab2_lib.baseboard_fab2(sch_1):tp_m_bmc_ddr3_mioz") )
				( member ( signalRef "@baseboard_fab2_lib.baseboard_fab2(sch_1):nc_m2(1)") )
				( member ( signalRef "@baseboard_fab2_lib.baseboard_fab2(sch_1):nc_m2(0)") )
				( member ( signalRef "@baseboard_fab2_lib.baseboard_fab2(sch_1):led_pch_ssata_hdd_n") )
				( member ( signalRef "@baseboard_fab2_lib.baseboard_fab2(sch_1):a_p12v_stby_adr_trigger") )
				( member ( signalRef "@baseboard_fab2_lib.baseboard_fab2(sch_1):a_hsc_pwgin") )
				( member ( signalRef "@baseboard_fab2_lib.baseboard_fab2(sch_1):nc_db1200zl(1)") )
				( member ( signalRef "@baseboard_fab2_lib.baseboard_fab2(sch_1):nc_db1200zl(2)") )
				( member ( signalRef "@baseboard_fab2_lib.baseboard_fab2(sch_1):nc_db1200zl(0)") )
				( member ( signalRef "@baseboard_fab2_lib.baseboard_fab2(sch_1):a_hsc_ocp_sel") )
				( member ( signalRef "@baseboard_fab2_lib.baseboard_fab2(sch_1):a_hsc_low_gate") )
				( member ( signalRef "@baseboard_fab2_lib.baseboard_fab2(sch_1):a_hsc_low") )
				( member ( signalRef "@baseboard_fab2_lib.baseboard_fab2(sch_1):led_pch_sata_hdd_n") )
				( member ( signalRef "@baseboard_fab2_lib.baseboard_fab2(sch_1):a_hsc_high_en") )
				( member ( signalRef "@baseboard_fab2_lib.baseboard_fab2(sch_1):a_hsc_high") )
				( member ( signalRef "@baseboard_fab2_lib.baseboard_fab2(sch_1):a_hsc_csout") )
				( member ( signalRef "@baseboard_fab2_lib.baseboard_fab2(sch_1):a_cpu1_klm_rcomp2") )
				( member ( signalRef "@baseboard_fab2_lib.baseboard_fab2(sch_1):fm_cpu0_fivr_fault_lvt3") )
				( member ( signalRef "@baseboard_fab2_lib.baseboard_fab2(sch_1):fm_cpld_dbg_pwr_en") )
				( member ( signalRef "@baseboard_fab2_lib.baseboard_fab2(sch_1):tp_cpu0_rsvd_282") )
				( member ( signalRef "@baseboard_fab2_lib.baseboard_fab2(sch_1):tp_m2_devslp") )
				( member ( signalRef "@baseboard_fab2_lib.baseboard_fab2(sch_1):tp_m2_32m_susclk") )
				( member ( signalRef "@baseboard_fab2_lib.baseboard_fab2(sch_1):a_cpu1_klm_rcomp1") )
				( member ( signalRef "@baseboard_fab2_lib.baseboard_fab2(sch_1):fm_uart_alert_n") )
				( member ( signalRef "@baseboard_fab2_lib.baseboard_fab2(sch_1):tp_pvccin_cpu0_gp1") )
				( member ( signalRef "@baseboard_fab2_lib.baseboard_fab2(sch_1):tp_pvccin_cpu1_gp1") )
				( member ( signalRef "@baseboard_fab2_lib.baseboard_fab2(sch_1):tp_pvccio_cpu0_biref1") )
				( member ( signalRef "@baseboard_fab2_lib.baseboard_fab2(sch_1):tp_pvccio_cpu0_btsen") )
				( member ( signalRef "@baseboard_fab2_lib.baseboard_fab2(sch_1):tp_pvccio_cpu0_bvref") )
				( member ( signalRef "@baseboard_fab2_lib.baseboard_fab2(sch_1):tp_pvccio_cpu0_bvsen") )
				( member ( signalRef "@baseboard_fab2_lib.baseboard_fab2(sch_1):nc_pvccio_cpu0_dnc0") )
				( member ( signalRef "@baseboard_fab2_lib.baseboard_fab2(sch_1):nc_pvccio_cpu0_dnc1") )
				( member ( signalRef "@baseboard_fab2_lib.baseboard_fab2(sch_1):nc_pvccio_cpu0_dnc2") )
				( member ( signalRef "@baseboard_fab2_lib.baseboard_fab2(sch_1):nc_pvccio_cpu0_dnc3") )
				( member ( signalRef "@baseboard_fab2_lib.baseboard_fab2(sch_1):nc_pvccio_cpu0_dnc4") )
				( member ( signalRef "@baseboard_fab2_lib.baseboard_fab2(sch_1):led_gbe_p2_1") )
				( member ( signalRef "@baseboard_fab2_lib.baseboard_fab2(sch_1):tp_vr_pvccio_cpu0_mp0") )
				( member ( signalRef "@baseboard_fab2_lib.baseboard_fab2(sch_1):tp_vr_pvccio_cpu0_mp1") )
				( member ( signalRef "@baseboard_fab2_lib.baseboard_fab2(sch_1):tp_pvccio_cpu0_gl_0") )
				( member ( signalRef "@baseboard_fab2_lib.baseboard_fab2(sch_1):tp_pvccio_cpu0_pinalrt_n") )
				( member ( signalRef "@baseboard_fab2_lib.baseboard_fab2(sch_1):tp_pvccio_cpu1_biref1") )
				( member ( signalRef "@baseboard_fab2_lib.baseboard_fab2(sch_1):tp_pvccio_cpu1_btsen") )
				( member ( signalRef "@baseboard_fab2_lib.baseboard_fab2(sch_1):tp_pvccio_cpu1_bvref") )
				( member ( signalRef "@baseboard_fab2_lib.baseboard_fab2(sch_1):tp_pvccio_cpu1_bvsen") )
				( member ( signalRef "@baseboard_fab2_lib.baseboard_fab2(sch_1):nc_pvccio_cpu1_dnc0") )
				( member ( signalRef "@baseboard_fab2_lib.baseboard_fab2(sch_1):nc_pvccio_cpu1_dnc1") )
				( member ( signalRef "@baseboard_fab2_lib.baseboard_fab2(sch_1):nc_pvccio_cpu1_dnc2") )
				( member ( signalRef "@baseboard_fab2_lib.baseboard_fab2(sch_1):nc_pvccio_cpu1_dnc3") )
				( member ( signalRef "@baseboard_fab2_lib.baseboard_fab2(sch_1):nc_pvccio_cpu1_dnc4") )
				( member ( signalRef "@baseboard_fab2_lib.baseboard_fab2(sch_1):led_gbe_p3_0") )
				( member ( signalRef "@baseboard_fab2_lib.baseboard_fab2(sch_1):tp_vr_pvccio_cpu1_mp0") )
				( member ( signalRef "@baseboard_fab2_lib.baseboard_fab2(sch_1):tp_vr_pvccio_cpu1_mp1") )
				( member ( signalRef "@baseboard_fab2_lib.baseboard_fab2(sch_1):tp_pvccio_cpu1_gl_0") )
				( member ( signalRef "@baseboard_fab2_lib.baseboard_fab2(sch_1):tp_pvccio_cpu1_pinalrt_n") )
				( member ( signalRef "@baseboard_fab2_lib.baseboard_fab2(sch_1):tp_pvddq_abc_bref1") )
				( member ( signalRef "@baseboard_fab2_lib.baseboard_fab2(sch_1):tp_pvddq_abc_btsen") )
				( member ( signalRef "@baseboard_fab2_lib.baseboard_fab2(sch_1):tp_pvddq_abc_bvref") )
				( member ( signalRef "@baseboard_fab2_lib.baseboard_fab2(sch_1):tp_pvddq_abc_bvsen") )
				( member ( signalRef "@baseboard_fab2_lib.baseboard_fab2(sch_1):fm_p1v8mcp_cpu0_en") )
				( member ( signalRef "@baseboard_fab2_lib.baseboard_fab2(sch_1):tp_pvddq_abc_mp1") )
				( member ( signalRef "@baseboard_fab2_lib.baseboard_fab2(sch_1):tp_pvddq_abc_ph3_imon") )
				( member ( signalRef "@baseboard_fab2_lib.baseboard_fab2(sch_1):tp_pvddq_abc_ph3_imon_ref") )
				( member ( signalRef "@baseboard_fab2_lib.baseboard_fab2(sch_1):tp_pvddq_abc_pinalrt_n") )
				( member ( signalRef "@baseboard_fab2_lib.baseboard_fab2(sch_1):tp_pvddq_abc_pwm3") )
				( member ( signalRef "@baseboard_fab2_lib.baseboard_fab2(sch_1):tp_pvddq_def_bref1") )
				( member ( signalRef "@baseboard_fab2_lib.baseboard_fab2(sch_1):tp_pvddq_def_btsen") )
				( member ( signalRef "@baseboard_fab2_lib.baseboard_fab2(sch_1):tp_pvddq_def_bvref") )
				( member ( signalRef "@baseboard_fab2_lib.baseboard_fab2(sch_1):tp_pvddq_def_bvsen") )
				( member ( signalRef "@baseboard_fab2_lib.baseboard_fab2(sch_1):led_gbe_p2_0") )
				( member ( signalRef "@baseboard_fab2_lib.baseboard_fab2(sch_1):tp_pvddq_def_mp1") )
				( member ( signalRef "@baseboard_fab2_lib.baseboard_fab2(sch_1):tp_pvddq_def_ph3_imon") )
				( member ( signalRef "@baseboard_fab2_lib.baseboard_fab2(sch_1):tp_pvddq_def_ph3_imon_ref") )
				( member ( signalRef "@baseboard_fab2_lib.baseboard_fab2(sch_1):fm_cpu0_prochot_lvt3_bmc_n") )
				( member ( signalRef "@baseboard_fab2_lib.baseboard_fab2(sch_1):fm_pch_pwrbtn_out_n") )
				( member ( signalRef "@baseboard_fab2_lib.baseboard_fab2(sch_1):tp_cpu1_rsvd_90") )
				( member ( signalRef "@baseboard_fab2_lib.baseboard_fab2(sch_1):tp_cpu1_rsvd_91") )
				( member ( signalRef "@baseboard_fab2_lib.baseboard_fab2(sch_1):fm_mem_therm_event_pch_n") )
				( member ( signalRef "@baseboard_fab2_lib.baseboard_fab2(sch_1):tp_pch_gpp_l10") )
				( member ( signalRef "@baseboard_fab2_lib.baseboard_fab2(sch_1):tp_cpu1_rsvd_94") )
				( member ( signalRef "@baseboard_fab2_lib.baseboard_fab2(sch_1):tp_cpu1_rsvd_95") )
				( member ( signalRef "@baseboard_fab2_lib.baseboard_fab2(sch_1):fm_flash_desc_override_r") )
				( member ( signalRef "@baseboard_fab2_lib.baseboard_fab2(sch_1):tp_cpu1_rsvd_97") )
				( member ( signalRef "@baseboard_fab2_lib.baseboard_fab2(sch_1):fm_flash_desc_override") )
				( member ( signalRef "@baseboard_fab2_lib.baseboard_fab2(sch_1):tp_cpu1_rsvd_99") )
				( member ( signalRef "@baseboard_fab2_lib.baseboard_fab2(sch_1):tp_cpu1_rsvd_100") )
				( member ( signalRef "@baseboard_fab2_lib.baseboard_fab2(sch_1):tp_cpu1_rsvd_101") )
				( member ( signalRef "@baseboard_fab2_lib.baseboard_fab2(sch_1):fm_cpld_uart_ch_lock_n") )
				( member ( signalRef "@baseboard_fab2_lib.baseboard_fab2(sch_1):fm_cpld_dbg_pwr_en_n") )
				( member ( signalRef "@baseboard_fab2_lib.baseboard_fab2(sch_1):fm_bmc_enable_n") )
				( member ( signalRef "@baseboard_fab2_lib.baseboard_fab2(sch_1):tp_cpu1_rsvd_105") )
				( member ( signalRef "@baseboard_fab2_lib.baseboard_fab2(sch_1):tp_cpu1_rsvd_106") )
				( member ( signalRef "@baseboard_fab2_lib.baseboard_fab2(sch_1):tp_cpu0_rsvd_6") )
				( member ( signalRef "@baseboard_fab2_lib.baseboard_fab2(sch_1):tp_cpu1_rsvd_108") )
				( member ( signalRef "@baseboard_fab2_lib.baseboard_fab2(sch_1):fm_bmc_disable") )
				( member ( signalRef "@baseboard_fab2_lib.baseboard_fab2(sch_1):fm_adr_smi_gpio_r_n") )
				( member ( signalRef "@baseboard_fab2_lib.baseboard_fab2(sch_1):tp_cpu1_rsvd_111") )
				( member ( signalRef "@baseboard_fab2_lib.baseboard_fab2(sch_1):tp_cpu0_rsvd_8") )
				( member ( signalRef "@baseboard_fab2_lib.baseboard_fab2(sch_1):tp_cpu1_rsvd_113") )
				( member ( signalRef "@baseboard_fab2_lib.baseboard_fab2(sch_1):tp_cpu1_rsvd_114") )
				( member ( signalRef "@baseboard_fab2_lib.baseboard_fab2(sch_1):fm_adr_complete_r1") )
				( member ( signalRef "@baseboard_fab2_lib.baseboard_fab2(sch_1):tp_cpu0_rsvd_7") )
				( member ( signalRef "@baseboard_fab2_lib.baseboard_fab2(sch_1):tp_cpu1_rsvd_117") )
				( member ( signalRef "@baseboard_fab2_lib.baseboard_fab2(sch_1):fm_adr_complete_r") )
				( member ( signalRef "@baseboard_fab2_lib.baseboard_fab2(sch_1):tp_cpu1_rsvd_119") )
				( member ( signalRef "@baseboard_fab2_lib.baseboard_fab2(sch_1):fm_adr_complete_dly") )
				( member ( signalRef "@baseboard_fab2_lib.baseboard_fab2(sch_1):tp_cpu1_rsvd_121") )
				( member ( signalRef "@baseboard_fab2_lib.baseboard_fab2(sch_1):tp_cpu0_kti2_amonv") )
				( member ( signalRef "@baseboard_fab2_lib.baseboard_fab2(sch_1):tp_cpu1_rsvd_123") )
				( member ( signalRef "@baseboard_fab2_lib.baseboard_fab2(sch_1):tp_cpu1_rsvd_124") )
				( member ( signalRef "@baseboard_fab2_lib.baseboard_fab2(sch_1):tp_cpu0_rsvd_4") )
				( member ( signalRef "@baseboard_fab2_lib.baseboard_fab2(sch_1):fm_thermtrip_dly_r") )
				( member ( signalRef "@baseboard_fab2_lib.baseboard_fab2(sch_1):tp_cpu0_rsvd_3") )
				( member ( signalRef "@baseboard_fab2_lib.baseboard_fab2(sch_1):tp_cpu0_rsvd_2") )
				( member ( signalRef "@baseboard_fab2_lib.baseboard_fab2(sch_1):tp_cpu0_rsvd_1") )
				( member ( signalRef "@baseboard_fab2_lib.baseboard_fab2(sch_1):tp_cpu0_rsvd_0") )
				( member ( signalRef "@baseboard_fab2_lib.baseboard_fab2(sch_1):fm_pvpp_pvddq_cpu1_en_klm") )
				( member ( signalRef "@baseboard_fab2_lib.baseboard_fab2(sch_1):tp_cpu0_kti2_dfx_dn") )
				( member ( signalRef "@baseboard_fab2_lib.baseboard_fab2(sch_1):a_p12v_stby_fp_trigger") )
				( member ( signalRef "@baseboard_fab2_lib.baseboard_fab2(sch_1):fm_pvpp_pvddq_cpu1_en_ghj") )
				( member ( signalRef "@baseboard_fab2_lib.baseboard_fab2(sch_1):fm_cpu0_fivr_fault_lvt3_n") )
				( member ( signalRef "@baseboard_fab2_lib.baseboard_fab2(sch_1):nc_m2(18)") )
				( member ( signalRef "@baseboard_fab2_lib.baseboard_fab2(sch_1):fm_pvpp_pvddq_cpu0_en_def") )
				( member ( signalRef "@baseboard_fab2_lib.baseboard_fab2(sch_1):nc_m2(17)") )
				( member ( signalRef "@baseboard_fab2_lib.baseboard_fab2(sch_1):nc_m2(16)") )
				( member ( signalRef "@baseboard_fab2_lib.baseboard_fab2(sch_1):nc_m2(15)") )
				( member ( signalRef "@baseboard_fab2_lib.baseboard_fab2(sch_1):fm_pvpp_pvddq_cpu0_en_abc") )
				( member ( signalRef "@baseboard_fab2_lib.baseboard_fab2(sch_1):fm_p1v8mcp_cpu1_en") )
				( member ( signalRef "@baseboard_fab2_lib.baseboard_fab2(sch_1):nc_m2(14)") )
				( member ( signalRef "@baseboard_fab2_lib.baseboard_fab2(sch_1):tp_cpu1_rsvd_144") )
				( member ( signalRef "@baseboard_fab2_lib.baseboard_fab2(sch_1):tp_cpu1_rsvd_145") )
				( member ( signalRef "@baseboard_fab2_lib.baseboard_fab2(sch_1):tp_cpu1_rsvd_146") )
				( member ( signalRef "@baseboard_fab2_lib.baseboard_fab2(sch_1):tp_cpu1_rsvd_147") )
				( member ( signalRef "@baseboard_fab2_lib.baseboard_fab2(sch_1):tp_cpu1_rsvd_148") )
				( member ( signalRef "@baseboard_fab2_lib.baseboard_fab2(sch_1):tp_cpu1_rsvd_149") )
				( member ( signalRef "@baseboard_fab2_lib.baseboard_fab2(sch_1):tp_cpu1_rsvd_150") )
				( member ( signalRef "@baseboard_fab2_lib.baseboard_fab2(sch_1):tp_cpu1_rsvd_151") )
				( member ( signalRef "@baseboard_fab2_lib.baseboard_fab2(sch_1):tp_cpu1_rsvd_152") )
				( member ( signalRef "@baseboard_fab2_lib.baseboard_fab2(sch_1):tp_cpu1_rsvd_154") )
				( member ( signalRef "@baseboard_fab2_lib.baseboard_fab2(sch_1):tp_cpu1_rsvd_155") )
				( member ( signalRef "@baseboard_fab2_lib.baseboard_fab2(sch_1):tp_cpu1_rsvd_156") )
				( member ( signalRef "@baseboard_fab2_lib.baseboard_fab2(sch_1):tp_cpu1_rsvd_157") )
				( member ( signalRef "@baseboard_fab2_lib.baseboard_fab2(sch_1):tp_cpu1_rsvd_158") )
				( member ( signalRef "@baseboard_fab2_lib.baseboard_fab2(sch_1):tp_cpu1_rsvd_159") )
				( member ( signalRef "@baseboard_fab2_lib.baseboard_fab2(sch_1):tp_cpu1_rsvd_160") )
				( member ( signalRef "@baseboard_fab2_lib.baseboard_fab2(sch_1):tp_cpu1_rsvd_161") )
				( member ( signalRef "@baseboard_fab2_lib.baseboard_fab2(sch_1):tp_cpu1_rsvd_162") )
				( member ( signalRef "@baseboard_fab2_lib.baseboard_fab2(sch_1):tp_cpu1_rsvd_163") )
				( member ( signalRef "@baseboard_fab2_lib.baseboard_fab2(sch_1):tp_cpu1_rsvd_164") )
				( member ( signalRef "@baseboard_fab2_lib.baseboard_fab2(sch_1):tp_cpu1_rsvd_166") )
				( member ( signalRef "@baseboard_fab2_lib.baseboard_fab2(sch_1):tp_cpu1_rsvd_167") )
				( member ( signalRef "@baseboard_fab2_lib.baseboard_fab2(sch_1):tp_cpu1_rsvd_168") )
				( member ( signalRef "@baseboard_fab2_lib.baseboard_fab2(sch_1):tp_cpu1_rsvd_169") )
				( member ( signalRef "@baseboard_fab2_lib.baseboard_fab2(sch_1):tp_cpu1_rsvd_170") )
				( member ( signalRef "@baseboard_fab2_lib.baseboard_fab2(sch_1):tp_cpu1_rsvd_171") )
				( member ( signalRef "@baseboard_fab2_lib.baseboard_fab2(sch_1):tp_cpu1_rsvd_172") )
				( member ( signalRef "@baseboard_fab2_lib.baseboard_fab2(sch_1):tp_cpu1_rsvd_173") )
				( member ( signalRef "@baseboard_fab2_lib.baseboard_fab2(sch_1):nc_m2(13)") )
				( member ( signalRef "@baseboard_fab2_lib.baseboard_fab2(sch_1):tp_cpu1_rsvd_175") )
				( member ( signalRef "@baseboard_fab2_lib.baseboard_fab2(sch_1):tp_cpu0_rsvd_5") )
				( member ( signalRef "@baseboard_fab2_lib.baseboard_fab2(sch_1):vr_pvccio_cpu0_en") )
				( member ( signalRef "@baseboard_fab2_lib.baseboard_fab2(sch_1):nc_m2(12)") )
				( member ( signalRef "@baseboard_fab2_lib.baseboard_fab2(sch_1):nc_m2(11)") )
				( member ( signalRef "@baseboard_fab2_lib.baseboard_fab2(sch_1):nc_m2(10)") )
				( member ( signalRef "@baseboard_fab2_lib.baseboard_fab2(sch_1):tp_pvccin_cpu1_aisen6") )
				( member ( signalRef "@baseboard_fab2_lib.baseboard_fab2(sch_1):tp_pvccin_cpu0_aisen6") )
				( member ( signalRef "@baseboard_fab2_lib.baseboard_fab2(sch_1):tp_ioa5") )
				( member ( signalRef "@baseboard_fab2_lib.baseboard_fab2(sch_1):tp_cpu1_test_7") )
				( member ( signalRef "@baseboard_fab2_lib.baseboard_fab2(sch_1):tp_cpu1_test_8") )
				( member ( signalRef "@baseboard_fab2_lib.baseboard_fab2(sch_1):tp_cpu1_test_10") )
				( member ( signalRef "@baseboard_fab2_lib.baseboard_fab2(sch_1):tp_cpu1_test_9") )
				( member ( signalRef "@baseboard_fab2_lib.baseboard_fab2(sch_1):tp_cpu1_rsvd_test_11") )
				( member ( signalRef "@baseboard_fab2_lib.baseboard_fab2(sch_1):tp_dacb") )
				( member ( signalRef "@baseboard_fab2_lib.baseboard_fab2(sch_1):tp_cpu0_rsvd_95") )
				( member ( signalRef "@baseboard_fab2_lib.baseboard_fab2(sch_1):tp_cpu0_rsvd_97") )
				( member ( signalRef "@baseboard_fab2_lib.baseboard_fab2(sch_1):tp_cpu0_rsvd_99") )
				( member ( signalRef "@baseboard_fab2_lib.baseboard_fab2(sch_1):tp_cpu0_rsvd_100") )
				( member ( signalRef "@baseboard_fab2_lib.baseboard_fab2(sch_1):tp_cpu0_rsvd_101") )
				( member ( signalRef "@baseboard_fab2_lib.baseboard_fab2(sch_1):tp_cpu0_rsvd_105") )
				( member ( signalRef "@baseboard_fab2_lib.baseboard_fab2(sch_1):tp_cpu0_rsvd_106") )
				( member ( signalRef "@baseboard_fab2_lib.baseboard_fab2(sch_1):tp_cpu0_rsvd_108") )
				( member ( signalRef "@baseboard_fab2_lib.baseboard_fab2(sch_1):tp_cpu0_rsvd_111") )
				( member ( signalRef "@baseboard_fab2_lib.baseboard_fab2(sch_1):tp_cpu0_rsvd_113") )
				( member ( signalRef "@baseboard_fab2_lib.baseboard_fab2(sch_1):tp_cpu0_rsvd_114") )
				( member ( signalRef "@baseboard_fab2_lib.baseboard_fab2(sch_1):tp_cpu0_rsvd_117") )
				( member ( signalRef "@baseboard_fab2_lib.baseboard_fab2(sch_1):tp_cpu0_rsvd_119") )
				( member ( signalRef "@baseboard_fab2_lib.baseboard_fab2(sch_1):tp_cpu0_rsvd_121") )
				( member ( signalRef "@baseboard_fab2_lib.baseboard_fab2(sch_1):tp_cpu0_rsvd_123") )
				( member ( signalRef "@baseboard_fab2_lib.baseboard_fab2(sch_1):tp_cpu0_rsvd_124") )
				( member ( signalRef "@baseboard_fab2_lib.baseboard_fab2(sch_1):tp_cpu0_rsvd_144") )
				( member ( signalRef "@baseboard_fab2_lib.baseboard_fab2(sch_1):tp_cpu0_rsvd_145") )
				( member ( signalRef "@baseboard_fab2_lib.baseboard_fab2(sch_1):tp_cpu0_rsvd_146") )
				( member ( signalRef "@baseboard_fab2_lib.baseboard_fab2(sch_1):tp_cpu0_rsvd_147") )
				( member ( signalRef "@baseboard_fab2_lib.baseboard_fab2(sch_1):tp_cpu0_rsvd_148") )
				( member ( signalRef "@baseboard_fab2_lib.baseboard_fab2(sch_1):tp_cpu0_rsvd_149") )
				( member ( signalRef "@baseboard_fab2_lib.baseboard_fab2(sch_1):tp_cpu0_rsvd_150") )
				( member ( signalRef "@baseboard_fab2_lib.baseboard_fab2(sch_1):tp_cpu0_rsvd_151") )
				( member ( signalRef "@baseboard_fab2_lib.baseboard_fab2(sch_1):tp_cpu0_rsvd_152") )
				( member ( signalRef "@baseboard_fab2_lib.baseboard_fab2(sch_1):tp_cpu0_rsvd_154") )
				( member ( signalRef "@baseboard_fab2_lib.baseboard_fab2(sch_1):tp_cpu0_rsvd_155") )
				( member ( signalRef "@baseboard_fab2_lib.baseboard_fab2(sch_1):tp_cpu0_rsvd_156") )
				( member ( signalRef "@baseboard_fab2_lib.baseboard_fab2(sch_1):tp_cpu0_rsvd_157") )
				( member ( signalRef "@baseboard_fab2_lib.baseboard_fab2(sch_1):tp_cpu0_rsvd_158") )
				( member ( signalRef "@baseboard_fab2_lib.baseboard_fab2(sch_1):tp_cpu0_rsvd_159") )
				( member ( signalRef "@baseboard_fab2_lib.baseboard_fab2(sch_1):tp_cpu0_rsvd_160") )
				( member ( signalRef "@baseboard_fab2_lib.baseboard_fab2(sch_1):tp_cpu0_rsvd_161") )
				( member ( signalRef "@baseboard_fab2_lib.baseboard_fab2(sch_1):tp_cpu0_rsvd_162") )
				( member ( signalRef "@baseboard_fab2_lib.baseboard_fab2(sch_1):tp_cpu0_rsvd_163") )
				( member ( signalRef "@baseboard_fab2_lib.baseboard_fab2(sch_1):tp_cpu0_rsvd_164") )
				( member ( signalRef "@baseboard_fab2_lib.baseboard_fab2(sch_1):tp_cpu0_rsvd_166") )
				( member ( signalRef "@baseboard_fab2_lib.baseboard_fab2(sch_1):tp_cpu0_rsvd_167") )
				( member ( signalRef "@baseboard_fab2_lib.baseboard_fab2(sch_1):tp_cpu0_rsvd_168") )
				( member ( signalRef "@baseboard_fab2_lib.baseboard_fab2(sch_1):tp_cpu0_rsvd_169") )
				( member ( signalRef "@baseboard_fab2_lib.baseboard_fab2(sch_1):tp_cpu0_rsvd_170") )
				( member ( signalRef "@baseboard_fab2_lib.baseboard_fab2(sch_1):tp_cpu0_rsvd_171") )
				( member ( signalRef "@baseboard_fab2_lib.baseboard_fab2(sch_1):tp_cpu0_rsvd_172") )
				( member ( signalRef "@baseboard_fab2_lib.baseboard_fab2(sch_1):tp_cpu0_rsvd_173") )
				( member ( signalRef "@baseboard_fab2_lib.baseboard_fab2(sch_1):tp_cpu0_rsvd_174") )
				( member ( signalRef "@baseboard_fab2_lib.baseboard_fab2(sch_1):tp_cpu0_rsvd_175") )
				( member ( signalRef "@baseboard_fab2_lib.baseboard_fab2(sch_1):tp_cpu0_rsvd_176") )
				( member ( signalRef "@baseboard_fab2_lib.baseboard_fab2(sch_1):tp_cpu0_rsvd_177") )
				( member ( signalRef "@baseboard_fab2_lib.baseboard_fab2(sch_1):tp_cpu0_rsvd_178") )
				( member ( signalRef "@baseboard_fab2_lib.baseboard_fab2(sch_1):tp_cpu0_rsvd_179") )
				( member ( signalRef "@baseboard_fab2_lib.baseboard_fab2(sch_1):tp_cpu0_rsvd_180") )
				( member ( signalRef "@baseboard_fab2_lib.baseboard_fab2(sch_1):tp_cpu0_rsvd_181") )
				( member ( signalRef "@baseboard_fab2_lib.baseboard_fab2(sch_1):tp_cpu0_rsvd_182") )
				( member ( signalRef "@baseboard_fab2_lib.baseboard_fab2(sch_1):tp_cpu0_rsvd_183") )
				( member ( signalRef "@baseboard_fab2_lib.baseboard_fab2(sch_1):tp_cpu0_test_7") )
				( member ( signalRef "@baseboard_fab2_lib.baseboard_fab2(sch_1):tp_cpu0_test_8") )
				( member ( signalRef "@baseboard_fab2_lib.baseboard_fab2(sch_1):tp_cpu0_test_10") )
				( member ( signalRef "@baseboard_fab2_lib.baseboard_fab2(sch_1):tp_cpu0_test_9") )
				( member ( signalRef "@baseboard_fab2_lib.baseboard_fab2(sch_1):tp_cpu0_rsvd_test_11") )
				( member ( signalRef "@baseboard_fab2_lib.baseboard_fab2(sch_1):tp_cpu1_rsvd_82") )
				( member ( signalRef "@baseboard_fab2_lib.baseboard_fab2(sch_1):tp_cpu1_rsvd_85") )
				( member ( signalRef "@baseboard_fab2_lib.baseboard_fab2(sch_1):tp_cpu0_rsvd_9") )
				( member ( signalRef "@baseboard_fab2_lib.baseboard_fab2(sch_1):tp_cpu0_rsvd_10") )
				( member ( signalRef "@baseboard_fab2_lib.baseboard_fab2(sch_1):tp_cpu0_rsvd_11") )
				( member ( signalRef "@baseboard_fab2_lib.baseboard_fab2(sch_1):tp_cpu0_rsvd_12") )
				( member ( signalRef "@baseboard_fab2_lib.baseboard_fab2(sch_1):tp_cpu0_rsvd_13") )
				( member ( signalRef "@baseboard_fab2_lib.baseboard_fab2(sch_1):tp_cpu0_rsvd_14") )
				( member ( signalRef "@baseboard_fab2_lib.baseboard_fab2(sch_1):tp_cpu0_rsvd_15") )
				( member ( signalRef "@baseboard_fab2_lib.baseboard_fab2(sch_1):tp_cpu0_rsvd_16") )
				( member ( signalRef "@baseboard_fab2_lib.baseboard_fab2(sch_1):tp_cpu0_rsvd_17") )
				( member ( signalRef "@baseboard_fab2_lib.baseboard_fab2(sch_1):tp_cpu0_rsvd_18") )
				( member ( signalRef "@baseboard_fab2_lib.baseboard_fab2(sch_1):tp_cpu0_rsvd_19") )
				( member ( signalRef "@baseboard_fab2_lib.baseboard_fab2(sch_1):tp_cpu0_rsvd_20") )
				( member ( signalRef "@baseboard_fab2_lib.baseboard_fab2(sch_1):tp_cpu0_rsvd_21") )
				( member ( signalRef "@baseboard_fab2_lib.baseboard_fab2(sch_1):tp_cpu0_rsvd_22") )
				( member ( signalRef "@baseboard_fab2_lib.baseboard_fab2(sch_1):tp_cpu0_rsvd_23") )
				( member ( signalRef "@baseboard_fab2_lib.baseboard_fab2(sch_1):tp_cpu0_rsvd_24") )
				( member ( signalRef "@baseboard_fab2_lib.baseboard_fab2(sch_1):tp_cpu0_rsvd_25") )
				( member ( signalRef "@baseboard_fab2_lib.baseboard_fab2(sch_1):tp_cpu0_rsvd_26") )
				( member ( signalRef "@baseboard_fab2_lib.baseboard_fab2(sch_1):tp_cpu0_rsvd_27") )
				( member ( signalRef "@baseboard_fab2_lib.baseboard_fab2(sch_1):tp_cpu0_rsvd_28") )
				( member ( signalRef "@baseboard_fab2_lib.baseboard_fab2(sch_1):tp_cpu0_rsvd_29") )
				( member ( signalRef "@baseboard_fab2_lib.baseboard_fab2(sch_1):tp_cpu0_rsvd_30") )
				( member ( signalRef "@baseboard_fab2_lib.baseboard_fab2(sch_1):tp_cpu0_rsvd_31") )
				( member ( signalRef "@baseboard_fab2_lib.baseboard_fab2(sch_1):tp_cpu0_rsvd_32") )
				( member ( signalRef "@baseboard_fab2_lib.baseboard_fab2(sch_1):tp_cpu0_rsvd_33") )
				( member ( signalRef "@baseboard_fab2_lib.baseboard_fab2(sch_1):tp_cpu0_rsvd_34") )
				( member ( signalRef "@baseboard_fab2_lib.baseboard_fab2(sch_1):tp_cpu0_rsvd_35") )
				( member ( signalRef "@baseboard_fab2_lib.baseboard_fab2(sch_1):tp_cpu0_rsvd_36") )
				( member ( signalRef "@baseboard_fab2_lib.baseboard_fab2(sch_1):tp_cpu0_rsvd_37") )
				( member ( signalRef "@baseboard_fab2_lib.baseboard_fab2(sch_1):tp_cpu0_rsvd_38") )
				( member ( signalRef "@baseboard_fab2_lib.baseboard_fab2(sch_1):tp_cpu0_rsvd_39") )
				( member ( signalRef "@baseboard_fab2_lib.baseboard_fab2(sch_1):tp_cpu0_rsvd_40") )
				( member ( signalRef "@baseboard_fab2_lib.baseboard_fab2(sch_1):tp_cpu0_rsvd_41") )
				( member ( signalRef "@baseboard_fab2_lib.baseboard_fab2(sch_1):tp_cpu0_rsvd_42") )
				( member ( signalRef "@baseboard_fab2_lib.baseboard_fab2(sch_1):tp_cpu0_rsvd_43") )
				( member ( signalRef "@baseboard_fab2_lib.baseboard_fab2(sch_1):tp_cpu0_rsvd_44") )
				( member ( signalRef "@baseboard_fab2_lib.baseboard_fab2(sch_1):tp_cpu0_rsvd_45") )
				( member ( signalRef "@baseboard_fab2_lib.baseboard_fab2(sch_1):tp_cpu0_rsvd_46") )
				( member ( signalRef "@baseboard_fab2_lib.baseboard_fab2(sch_1):tp_cpu0_rsvd_47") )
				( member ( signalRef "@baseboard_fab2_lib.baseboard_fab2(sch_1):fp_nmi_btn_r_n") )
				( member ( signalRef "@baseboard_fab2_lib.baseboard_fab2(sch_1):tp_cpu0_rsvd_61") )
				( member ( signalRef "@baseboard_fab2_lib.baseboard_fab2(sch_1):tp_bios_usb_recovery") )
				( member ( signalRef "@baseboard_fab2_lib.baseboard_fab2(sch_1):tp_10gbe_kr0_mon_dn") )
				( member ( signalRef "@baseboard_fab2_lib.baseboard_fab2(sch_1):tp_10gbe_kr0_mon_dp") )
				( member ( signalRef "@baseboard_fab2_lib.baseboard_fab2(sch_1):tp_10gbe_kr1_mon_dn") )
				( member ( signalRef "@baseboard_fab2_lib.baseboard_fab2(sch_1):tp_usb3_p04_rxn") )
				( member ( signalRef "@baseboard_fab2_lib.baseboard_fab2(sch_1):tp_usb3_p04_rxp") )
				( member ( signalRef "@baseboard_fab2_lib.baseboard_fab2(sch_1):tp_usb3_p04_txn") )
				( member ( signalRef "@baseboard_fab2_lib.baseboard_fab2(sch_1):tp_usb3_p04_txp") )
				( member ( signalRef "@baseboard_fab2_lib.baseboard_fab2(sch_1):tp_cpld1_pt19d") )
				( member ( signalRef "@baseboard_fab2_lib.baseboard_fab2(sch_1):tp_pch_gpp_l11") )
				( member ( signalRef "@baseboard_fab2_lib.baseboard_fab2(sch_1):tp_slg55021_p5v_8") )
				( member ( signalRef "@baseboard_fab2_lib.baseboard_fab2(sch_1):tp_slg55021_p12v_fan_8") )
				( member ( signalRef "@baseboard_fab2_lib.baseboard_fab2(sch_1):tp_pch_gpp_f12") )
				( member ( signalRef "@baseboard_fab2_lib.baseboard_fab2(sch_1):tp_slg55021_p3v3_8") )
				( member ( signalRef "@baseboard_fab2_lib.baseboard_fab2(sch_1):tp_cpu0_rsvd_69") )
				( member ( signalRef "@baseboard_fab2_lib.baseboard_fab2(sch_1):tp_vr_pvccio_cpu0_aiinsen") )
				( member ( signalRef "@baseboard_fab2_lib.baseboard_fab2(sch_1):tp_vr_pvccio_cpu1_aiinsen") )
				( member ( signalRef "@baseboard_fab2_lib.baseboard_fab2(sch_1):tp_vr_pvnn_pch_aiinsen") )
				( member ( signalRef "@baseboard_fab2_lib.baseboard_fab2(sch_1):tp_cpu0_rsvd_60") )
				( member ( signalRef "@baseboard_fab2_lib.baseboard_fab2(sch_1):tp_cpu0_rsvd_59") )
				( member ( signalRef "@baseboard_fab2_lib.baseboard_fab2(sch_1):tp_cpu0_rsvd_57") )
				( member ( signalRef "@baseboard_fab2_lib.baseboard_fab2(sch_1):tp_cpu0_rsvd_56") )
				( member ( signalRef "@baseboard_fab2_lib.baseboard_fab2(sch_1):tp_cpu0_rsvd_55") )
				( member ( signalRef "@baseboard_fab2_lib.baseboard_fab2(sch_1):tp_cpu0_rsvd_54") )
				( member ( signalRef "@baseboard_fab2_lib.baseboard_fab2(sch_1):tp_cpu0_rsvd_53") )
				( member ( signalRef "@baseboard_fab2_lib.baseboard_fab2(sch_1):tp_cpu0_rsvd_51") )
				( member ( signalRef "@baseboard_fab2_lib.baseboard_fab2(sch_1):tp_cpld1_pb25b_si_sispi") )
				( member ( signalRef "@baseboard_fab2_lib.baseboard_fab2(sch_1):tp_cpu0_rsvd_67") )
				( member ( signalRef "@baseboard_fab2_lib.baseboard_fab2(sch_1):tp_cpu0_rsvd_49") )
				( member ( signalRef "@baseboard_fab2_lib.baseboard_fab2(sch_1):tp_cpu0_rsvd_48") )
				( member ( signalRef "@baseboard_fab2_lib.baseboard_fab2(sch_1):tp_cpu0_rsvd_50") )
				( member ( signalRef "@baseboard_fab2_lib.baseboard_fab2(sch_1):tp_xdp_cpu_obsdata_d3") )
				( member ( signalRef "@baseboard_fab2_lib.baseboard_fab2(sch_1):tp_xdp_cpu_obsdata_d2") )
				( member ( signalRef "@baseboard_fab2_lib.baseboard_fab2(sch_1):tp_xdp_cpu_obsdata_d1") )
				( member ( signalRef "@baseboard_fab2_lib.baseboard_fab2(sch_1):tp_xdp_cpu_obsfn_c0") )
				( member ( signalRef "@baseboard_fab2_lib.baseboard_fab2(sch_1):tp_xdp_cpu_obsdata_d0") )
				( member ( signalRef "@baseboard_fab2_lib.baseboard_fab2(sch_1):tp_xdp_cpu_obsdata_c3") )
				( member ( signalRef "@baseboard_fab2_lib.baseboard_fab2(sch_1):tp_xdp_cpu_obsdata_c2") )
				( member ( signalRef "@baseboard_fab2_lib.baseboard_fab2(sch_1):tp_xdp_cpu0_obsdata_a0_mbp2_n") )
				( member ( signalRef "@baseboard_fab2_lib.baseboard_fab2(sch_1):tp_xdp_cpu0_obsdata_a1_mbp3_n") )
				( member ( signalRef "@baseboard_fab2_lib.baseboard_fab2(sch_1):tp_xdp_cpu0_obsdata_a2_mbp4_n") )
				( member ( signalRef "@baseboard_fab2_lib.baseboard_fab2(sch_1):tp_xdp_cpu0_obsdata_a3_mbp5_n") )
				( member ( signalRef "@baseboard_fab2_lib.baseboard_fab2(sch_1):tp_xdp_cpu1_obsdata_b0_mbp2_n") )
				( member ( signalRef "@baseboard_fab2_lib.baseboard_fab2(sch_1):tp_xdp_cpu1_obsdata_b1_mbp3_n") )
				( member ( signalRef "@baseboard_fab2_lib.baseboard_fab2(sch_1):tp_xdp_cpu1_obsdata_b2_mbp4_n") )
				( member ( signalRef "@baseboard_fab2_lib.baseboard_fab2(sch_1):tp_xdp_cpu1_obsdata_b3_mbp5_n") )
				( member ( signalRef "@baseboard_fab2_lib.baseboard_fab2(sch_1):tp_33p_33m_smbadr") )
				( member ( signalRef "@baseboard_fab2_lib.baseboard_fab2(sch_1):tp_adc128_vref") )
				( member ( signalRef "@baseboard_fab2_lib.baseboard_fab2(sch_1):nc_clk_156m_cpu0_osc") )
				( member ( signalRef "@baseboard_fab2_lib.baseboard_fab2(sch_1):nc_clk_156m_cpu1_osc") )
				( member ( signalRef "@baseboard_fab2_lib.baseboard_fab2(sch_1):tp_cpld1_pr9c") )
				( member ( signalRef "@baseboard_fab2_lib.baseboard_fab2(sch_1):tp_xdp_cpu_obsdata_c1") )
				( member ( signalRef "@baseboard_fab2_lib.baseboard_fab2(sch_1):tp_usb2_p02_dn") )
				( member ( signalRef "@baseboard_fab2_lib.baseboard_fab2(sch_1):tp_cpld1_pr9d") )
				( member ( signalRef "@baseboard_fab2_lib.baseboard_fab2(sch_1):tp_cpld1_pr7c") )
				( member ( signalRef "@baseboard_fab2_lib.baseboard_fab2(sch_1):tp_cpld1_pr9a") )
				( member ( signalRef "@baseboard_fab2_lib.baseboard_fab2(sch_1):tp_cpld1_pr7d") )
				( member ( signalRef "@baseboard_fab2_lib.baseboard_fab2(sch_1):fm_heartbeat_led") )
				( member ( signalRef "@baseboard_fab2_lib.baseboard_fab2(sch_1):fm_throttle_r_n") )
				( member ( signalRef "@baseboard_fab2_lib.baseboard_fab2(sch_1):tp_10gbe_kr1_mon_dp") )
				( member ( signalRef "@baseboard_fab2_lib.baseboard_fab2(sch_1):nc_pvccin_cpu0_ph5_p31") )
				( member ( signalRef "@baseboard_fab2_lib.baseboard_fab2(sch_1):tp_smb_pehpcpu1_en") )
				( member ( signalRef "@baseboard_fab2_lib.baseboard_fab2(sch_1):tp_cpld1_pr7a_pclkt1_0") )
				( member ( signalRef "@baseboard_fab2_lib.baseboard_fab2(sch_1):fm_force_adr_n") )
				( member ( signalRef "@baseboard_fab2_lib.baseboard_fab2(sch_1):tp_cpld1_pr7b_pclkc1_0") )
				( member ( signalRef "@baseboard_fab2_lib.baseboard_fab2(sch_1):nc_cpld1") )
				( member ( signalRef "@baseboard_fab2_lib.baseboard_fab2(sch_1):tp_usb3_p02_txp") )
				( member ( signalRef "@baseboard_fab2_lib.baseboard_fab2(sch_1):tp_usb3_p02_rxp") )
				( member ( signalRef "@baseboard_fab2_lib.baseboard_fab2(sch_1):tp_usb2_p02_dp") )
				( member ( signalRef "@baseboard_fab2_lib.baseboard_fab2(sch_1):tp_xdp_cpu_obsdata_c0") )
				( member ( signalRef "@baseboard_fab2_lib.baseboard_fab2(sch_1):fm_throttle_r1_n") )
				( member ( signalRef "@baseboard_fab2_lib.baseboard_fab2(sch_1):tp_usb3_p02_txn") )
				( member ( signalRef "@baseboard_fab2_lib.baseboard_fab2(sch_1):tp_cpu0_rsvd_70") )
				( member ( signalRef "@baseboard_fab2_lib.baseboard_fab2(sch_1):tp_cpu0_rsvd_72") )
				( member ( signalRef "@baseboard_fab2_lib.baseboard_fab2(sch_1):tp_cpu0_rsvd_73") )
				( member ( signalRef "@baseboard_fab2_lib.baseboard_fab2(sch_1):fm_uv_adr_trigger_n") )
				( member ( signalRef "@baseboard_fab2_lib.baseboard_fab2(sch_1):fm_100m_n") )
				( member ( signalRef "@baseboard_fab2_lib.baseboard_fab2(sch_1):tp_cpld1_pt20d_programn") )
				( member ( signalRef "@baseboard_fab2_lib.baseboard_fab2(sch_1):tp_cpld1_pt24c_initn") )
				( member ( signalRef "@baseboard_fab2_lib.baseboard_fab2(sch_1):tp_cpld1_pt24d_done") )
				( member ( signalRef "@baseboard_fab2_lib.baseboard_fab2(sch_1):tp_usb3_p02_rxn") )
				( member ( signalRef "@baseboard_fab2_lib.baseboard_fab2(sch_1):tp_xdp_obsdata_b3") )
				( member ( signalRef "@baseboard_fab2_lib.baseboard_fab2(sch_1):tp_cpu0_rsvd_82") )
				( member ( signalRef "@baseboard_fab2_lib.baseboard_fab2(sch_1):tp_xdp_obsdata_b2") )
				( member ( signalRef "@baseboard_fab2_lib.baseboard_fab2(sch_1):tp_xdp_obsdata_b1") )
				( member ( signalRef "@baseboard_fab2_lib.baseboard_fab2(sch_1):tp_cpu0_rsvd_85") )
				( member ( signalRef "@baseboard_fab2_lib.baseboard_fab2(sch_1):tp_xdp_obsdata_b0") )
				( member ( signalRef "@baseboard_fab2_lib.baseboard_fab2(sch_1):tp_xdp_obsdata_a3") )
				( member ( signalRef "@baseboard_fab2_lib.baseboard_fab2(sch_1):tp_xdp_obsdata_a2") )
				( member ( signalRef "@baseboard_fab2_lib.baseboard_fab2(sch_1):tp_xdp_obsdata_a1") )
				( member ( signalRef "@baseboard_fab2_lib.baseboard_fab2(sch_1):tp_cpu0_rsvd_90") )
				( member ( signalRef "@baseboard_fab2_lib.baseboard_fab2(sch_1):tp_cpu0_rsvd_91") )
				( member ( signalRef "@baseboard_fab2_lib.baseboard_fab2(sch_1):tp_xdp_obsdata_a0") )
				( member ( signalRef "@baseboard_fab2_lib.baseboard_fab2(sch_1):tp_cpu0_rsvd_66") )
				( member ( signalRef "@baseboard_fab2_lib.baseboard_fab2(sch_1):tp_cpu0_rsvd_94") )
				( member ( signalRef "@baseboard_fab2_lib.baseboard_fab2(sch_1):tp_rst_rtcrst_n") )
				( member ( signalRef "@baseboard_fab2_lib.baseboard_fab2(sch_1):tp_rsvd_b1") )
				( member ( signalRef "@baseboard_fab2_lib.baseboard_fab2(sch_1):tp_sgpio_sata_clock1_r") )
				( member ( signalRef "@baseboard_fab2_lib.baseboard_fab2(sch_1):tp_sgpio_sata_data1_r") )
				( member ( signalRef "@baseboard_fab2_lib.baseboard_fab2(sch_1):tp_sgpio_sata_load1_r") )
				( member ( signalRef "@baseboard_fab2_lib.baseboard_fab2(sch_1):tp_smb_ddr_abc_en") )
				( member ( signalRef "@baseboard_fab2_lib.baseboard_fab2(sch_1):tp_smb_ddr_def_en") )
				( member ( signalRef "@baseboard_fab2_lib.baseboard_fab2(sch_1):tp_smb_ddr_ghj_en") )
				( member ( signalRef "@baseboard_fab2_lib.baseboard_fab2(sch_1):tp_smb_ddr_klm_en") )
				( member ( signalRef "@baseboard_fab2_lib.baseboard_fab2(sch_1):fm_cpu0_sm_wp") )
				( member ( signalRef "@baseboard_fab2_lib.baseboard_fab2(sch_1):tp_spi_bmc_bt_d2") )
				( member ( signalRef "@baseboard_fab2_lib.baseboard_fab2(sch_1):tp_spi_pch_cs1_r1_n") )
				( member ( signalRef "@baseboard_fab2_lib.baseboard_fab2(sch_1):tp_spi_0_0") )
				( member ( signalRef "@baseboard_fab2_lib.baseboard_fab2(sch_1):tp_spi_0_1") )
				( member ( signalRef "@baseboard_fab2_lib.baseboard_fab2(sch_1):tp_spi_0_2") )
				( member ( signalRef "@baseboard_fab2_lib.baseboard_fab2(sch_1):tp_spi_0_3") )
				( member ( signalRef "@baseboard_fab2_lib.baseboard_fab2(sch_1):tp_spi_0_4") )
				( member ( signalRef "@baseboard_fab2_lib.baseboard_fab2(sch_1):tp_spi_0_5") )
				( member ( signalRef "@baseboard_fab2_lib.baseboard_fab2(sch_1):tp_spi_0_6") )
				( member ( signalRef "@baseboard_fab2_lib.baseboard_fab2(sch_1):tp_spi_1_0") )
				( member ( signalRef "@baseboard_fab2_lib.baseboard_fab2(sch_1):tp_spi_1_1") )
				( member ( signalRef "@baseboard_fab2_lib.baseboard_fab2(sch_1):tp_spi_1_2") )
				( member ( signalRef "@baseboard_fab2_lib.baseboard_fab2(sch_1):tp_spi_1_3") )
				( member ( signalRef "@baseboard_fab2_lib.baseboard_fab2(sch_1):tp_spi_1_4") )
				( member ( signalRef "@baseboard_fab2_lib.baseboard_fab2(sch_1):tp_spi_1_5") )
				( member ( signalRef "@baseboard_fab2_lib.baseboard_fab2(sch_1):tp_spi_1_6") )
				( member ( signalRef "@baseboard_fab2_lib.baseboard_fab2(sch_1):tp_spi_2_6") )
				( member ( signalRef "@baseboard_fab2_lib.baseboard_fab2(sch_1):tp_spi_2_5") )
				( member ( signalRef "@baseboard_fab2_lib.baseboard_fab2(sch_1):tp_spi_2_4") )
				( member ( signalRef "@baseboard_fab2_lib.baseboard_fab2(sch_1):tp_spi_2_3") )
				( member ( signalRef "@baseboard_fab2_lib.baseboard_fab2(sch_1):tp_spi_2_2") )
				( member ( signalRef "@baseboard_fab2_lib.baseboard_fab2(sch_1):tp_spi_2_1") )
				( member ( signalRef "@baseboard_fab2_lib.baseboard_fab2(sch_1):tp_spi_2_0") )
				( member ( signalRef "@baseboard_fab2_lib.baseboard_fab2(sch_1):tp_pvnn_pch_svid_alert") )
				( member ( signalRef "@baseboard_fab2_lib.baseboard_fab2(sch_1):tp_pvnn_pch_vdio") )
				( member ( signalRef "@baseboard_fab2_lib.baseboard_fab2(sch_1):tp_usb2_p8_dn") )
				( member ( signalRef "@baseboard_fab2_lib.baseboard_fab2(sch_1):tp_usb2_p8_dp") )
				( member ( signalRef "@baseboard_fab2_lib.baseboard_fab2(sch_1):tp_usb2_p9_dn") )
				( member ( signalRef "@baseboard_fab2_lib.baseboard_fab2(sch_1):tp_usb2_p9_dp") )
				( member ( signalRef "@baseboard_fab2_lib.baseboard_fab2(sch_1):tp_usb2_p03_dn") )
				( member ( signalRef "@baseboard_fab2_lib.baseboard_fab2(sch_1):tp_usb2_p03_dp") )
				( member ( signalRef "@baseboard_fab2_lib.baseboard_fab2(sch_1):tp_usb2_p06_dn") )
				( member ( signalRef "@baseboard_fab2_lib.baseboard_fab2(sch_1):tp_usb2_p06_dp") )
				( member ( signalRef "@baseboard_fab2_lib.baseboard_fab2(sch_1):tp_usb2_p07_dn") )
				( member ( signalRef "@baseboard_fab2_lib.baseboard_fab2(sch_1):tp_usb2_p07_dp") )
				( member ( signalRef "@baseboard_fab2_lib.baseboard_fab2(sch_1):tp_usb2_p10_dn") )
				( member ( signalRef "@baseboard_fab2_lib.baseboard_fab2(sch_1):tp_usb2_p10_dp") )
				( member ( signalRef "@baseboard_fab2_lib.baseboard_fab2(sch_1):tp_usb2_p11_dn") )
				( member ( signalRef "@baseboard_fab2_lib.baseboard_fab2(sch_1):tp_usb2_p11_dp") )
				( member ( signalRef "@baseboard_fab2_lib.baseboard_fab2(sch_1):tp_usb2_p12_dn") )
				( member ( signalRef "@baseboard_fab2_lib.baseboard_fab2(sch_1):tp_usb2_p12_dp") )
				( member ( signalRef "@baseboard_fab2_lib.baseboard_fab2(sch_1):tp_usb2_p13_dn") )
				( member ( signalRef "@baseboard_fab2_lib.baseboard_fab2(sch_1):tp_usb2_p13_dp") )
				( member ( signalRef "@baseboard_fab2_lib.baseboard_fab2(sch_1):tp_usb2_p14_dn") )
				( member ( signalRef "@baseboard_fab2_lib.baseboard_fab2(sch_1):tp_usb2_p14_dp") )
				( member ( signalRef "@baseboard_fab2_lib.baseboard_fab2(sch_1):tp_usb3_p03_rxn") )
				( member ( signalRef "@baseboard_fab2_lib.baseboard_fab2(sch_1):tp_usb3_p03_rxp") )
				( member ( signalRef "@baseboard_fab2_lib.baseboard_fab2(sch_1):tp_usb3_p03_txn") )
				( member ( signalRef "@baseboard_fab2_lib.baseboard_fab2(sch_1):tp_usb3_p03_txp") )
				( member ( signalRef "@baseboard_fab2_lib.baseboard_fab2(sch_1):fp_id_led_p5v_stby_n") )
				( member ( signalRef "@baseboard_fab2_lib.baseboard_fab2(sch_1):fp_nmi_btn") )
				( member ( signalRef "@baseboard_fab2_lib.baseboard_fab2(sch_1):fp_nmi_btn_out_n") )
				( member ( signalRef "@baseboard_fab2_lib.baseboard_fab2(sch_1):fp_nmi_btn_out_r_n") )
				( member ( signalRef "@baseboard_fab2_lib.baseboard_fab2(sch_1):pd_cpu0_rsvd_test_1") )
				( member ( signalRef "@baseboard_fab2_lib.baseboard_fab2(sch_1):pd_cpu0_rsvd_test_2") )
				( member ( signalRef "@baseboard_fab2_lib.baseboard_fab2(sch_1):tp_cpu1_rsvd_test_4") )
				( member ( signalRef "@baseboard_fab2_lib.baseboard_fab2(sch_1):pd_cpu1_rsvd_test_1") )
				( member ( signalRef "@baseboard_fab2_lib.baseboard_fab2(sch_1):pd_cpu1_rsvd_test_2") )
				( member ( signalRef "@baseboard_fab2_lib.baseboard_fab2(sch_1):led_hfi0_cpu0_n") )
				( member ( signalRef "@baseboard_fab2_lib.baseboard_fab2(sch_1):led_hfi1_cpu0_n") )
				( member ( signalRef "@baseboard_fab2_lib.baseboard_fab2(sch_1):pu_at24c64_a2") )
				( member ( signalRef "@baseboard_fab2_lib.baseboard_fab2(sch_1):pu_bios_spi_hold0_n") )
				( member ( signalRef "@baseboard_fab2_lib.baseboard_fab2(sch_1):pu_bios_spi_hold1_n") )
				( member ( signalRef "@baseboard_fab2_lib.baseboard_fab2(sch_1):pu_bios_spi_wp1_n") )
				( member ( signalRef "@baseboard_fab2_lib.baseboard_fab2(sch_1):pu_bios_usb_recovery") )
				( member ( signalRef "@baseboard_fab2_lib.baseboard_fab2(sch_1):pu_lpc_clkrun_n") )
				( member ( signalRef "@baseboard_fab2_lib.baseboard_fab2(sch_1):pu_pi7c9x1172_i2c_spi_n") )
				( member ( signalRef "@baseboard_fab2_lib.baseboard_fab2(sch_1):fm_cpu0_fivr_fault_lvt3_r_n") )
				( member ( signalRef "@baseboard_fab2_lib.baseboard_fab2(sch_1):pu_thermtrip_force_n") )
				( member ( signalRef "@baseboard_fab2_lib.baseboard_fab2(sch_1):pu_tmp421_1_a1") )
				( member ( signalRef "@baseboard_fab2_lib.baseboard_fab2(sch_1):tp_cpu1_rsvd_194") )
				( member ( signalRef "@baseboard_fab2_lib.baseboard_fab2(sch_1):tp_cpu1_rsvd_198") )
				( member ( signalRef "@baseboard_fab2_lib.baseboard_fab2(sch_1):tp_cpu1_rsvd_199") )
				( member ( signalRef "@baseboard_fab2_lib.baseboard_fab2(sch_1):tp_cpu1_kti2_amonv") )
				( member ( signalRef "@baseboard_fab2_lib.baseboard_fab2(sch_1):tp_cpu1_kti2_dfx_dn") )
				( member ( signalRef "@baseboard_fab2_lib.baseboard_fab2(sch_1):tp_cpu1_rsvd_0") )
				( member ( signalRef "@baseboard_fab2_lib.baseboard_fab2(sch_1):tp_cpu1_rsvd_1") )
				( member ( signalRef "@baseboard_fab2_lib.baseboard_fab2(sch_1):tp_cpu1_rsvd_2") )
				( member ( signalRef "@baseboard_fab2_lib.baseboard_fab2(sch_1):tp_cpu1_rsvd_3") )
				( member ( signalRef "@baseboard_fab2_lib.baseboard_fab2(sch_1):tp_cpu1_rsvd_4") )
				( member ( signalRef "@baseboard_fab2_lib.baseboard_fab2(sch_1):tp_cpu1_rsvd_5") )
				( member ( signalRef "@baseboard_fab2_lib.baseboard_fab2(sch_1):tp_cpu1_rsvd_6") )
				( member ( signalRef "@baseboard_fab2_lib.baseboard_fab2(sch_1):tp_cpu1_rsvd_7") )
				( member ( signalRef "@baseboard_fab2_lib.baseboard_fab2(sch_1):tp_cpu1_rsvd_8") )
				( member ( signalRef "@baseboard_fab2_lib.baseboard_fab2(sch_1):tp_cpu1_rsvd_9") )
				( member ( signalRef "@baseboard_fab2_lib.baseboard_fab2(sch_1):tp_cpu1_rsvd_10") )
				( member ( signalRef "@baseboard_fab2_lib.baseboard_fab2(sch_1):tp_cpu1_rsvd_11") )
				( member ( signalRef "@baseboard_fab2_lib.baseboard_fab2(sch_1):tp_p3e_cpu1_pe1_rsr3_rxn(15)") )
				( member ( signalRef "@baseboard_fab2_lib.baseboard_fab2(sch_1):tp_p3e_cpu1_pe1_rsr3_rxp(8)") )
				( member ( signalRef "@baseboard_fab2_lib.baseboard_fab2(sch_1):tp_p3e_cpu1_pe1_rsr3_rxp(9)") )
				( member ( signalRef "@baseboard_fab2_lib.baseboard_fab2(sch_1):tp_p3e_cpu1_pe1_rsr3_rxp(10)") )
				( member ( signalRef "@baseboard_fab2_lib.baseboard_fab2(sch_1):tp_p3e_cpu1_pe1_rsr3_rxp(11)") )
				( member ( signalRef "@baseboard_fab2_lib.baseboard_fab2(sch_1):tp_p3e_cpu1_pe1_rsr3_rxp(12)") )
				( member ( signalRef "@baseboard_fab2_lib.baseboard_fab2(sch_1):tp_p3e_cpu1_pe1_rsr3_rxp(13)") )
				( member ( signalRef "@baseboard_fab2_lib.baseboard_fab2(sch_1):tp_p3e_cpu1_pe1_rsr3_rxp(14)") )
				( member ( signalRef "@baseboard_fab2_lib.baseboard_fab2(sch_1):tp_p3e_cpu1_pe1_rsr3_rxp(15)") )
				( member ( signalRef "@baseboard_fab2_lib.baseboard_fab2(sch_1):tp_p3e_cpu1_pe1_rsr3_txn(8)") )
				( member ( signalRef "@baseboard_fab2_lib.baseboard_fab2(sch_1):tp_p3e_cpu1_pe1_rsr3_txn(9)") )
				( member ( signalRef "@baseboard_fab2_lib.baseboard_fab2(sch_1):tp_p3e_cpu1_pe1_rsr3_txn(10)") )
				( member ( signalRef "@baseboard_fab2_lib.baseboard_fab2(sch_1):tp_p3e_cpu1_pe1_rsr3_txn(11)") )
				( member ( signalRef "@baseboard_fab2_lib.baseboard_fab2(sch_1):tp_p3e_cpu1_pe1_rsr3_txn(12)") )
				( member ( signalRef "@baseboard_fab2_lib.baseboard_fab2(sch_1):tp_p3e_cpu1_pe1_rsr3_txn(13)") )
				( member ( signalRef "@baseboard_fab2_lib.baseboard_fab2(sch_1):tp_p3e_cpu1_pe1_rsr3_txn(14)") )
				( member ( signalRef "@baseboard_fab2_lib.baseboard_fab2(sch_1):tp_p3e_cpu1_pe1_rsr3_txn(15)") )
				( member ( signalRef "@baseboard_fab2_lib.baseboard_fab2(sch_1):tp_p3e_cpu1_pe1_rsr3_txp(8)") )
				( member ( signalRef "@baseboard_fab2_lib.baseboard_fab2(sch_1):tp_p3e_cpu1_pe1_rsr3_txp(9)") )
				( member ( signalRef "@baseboard_fab2_lib.baseboard_fab2(sch_1):tp_p3e_cpu1_pe1_rsr3_txp(10)") )
				( member ( signalRef "@baseboard_fab2_lib.baseboard_fab2(sch_1):tp_p3e_cpu1_pe1_rsr3_txp(11)") )
				( member ( signalRef "@baseboard_fab2_lib.baseboard_fab2(sch_1):tp_p3e_cpu1_pe1_rsr3_txp(12)") )
				( member ( signalRef "@baseboard_fab2_lib.baseboard_fab2(sch_1):tp_p3e_cpu1_pe1_rsr3_txp(13)") )
				( member ( signalRef "@baseboard_fab2_lib.baseboard_fab2(sch_1):tp_p3e_cpu1_pe1_rsr3_txp(14)") )
				( member ( signalRef "@baseboard_fab2_lib.baseboard_fab2(sch_1):tp_p3e_cpu1_pe1_rsr3_txp(15)") )
				( member ( signalRef "@baseboard_fab2_lib.baseboard_fab2(sch_1):tp_p3e_cpu1_pe2_rsr_rxn(0)") )
				( member ( signalRef "@baseboard_fab2_lib.baseboard_fab2(sch_1):tp_p3e_cpu1_pe2_rsr_rxn(1)") )
				( member ( signalRef "@baseboard_fab2_lib.baseboard_fab2(sch_1):tp_p3e_cpu1_pe2_rsr_rxn(2)") )
				( member ( signalRef "@baseboard_fab2_lib.baseboard_fab2(sch_1):tp_p3e_cpu1_pe2_rsr_rxn(3)") )
				( member ( signalRef "@baseboard_fab2_lib.baseboard_fab2(sch_1):tp_p3e_cpu1_pe2_rsr_rxn(4)") )
				( member ( signalRef "@baseboard_fab2_lib.baseboard_fab2(sch_1):tp_p3e_cpu1_pe2_rsr_rxn(5)") )
				( member ( signalRef "@baseboard_fab2_lib.baseboard_fab2(sch_1):tp_p3e_cpu1_pe2_rsr_rxn(6)") )
				( member ( signalRef "@baseboard_fab2_lib.baseboard_fab2(sch_1):tp_p3e_cpu1_pe2_rsr_rxn(7)") )
				( member ( signalRef "@baseboard_fab2_lib.baseboard_fab2(sch_1):tp_p3e_cpu1_pe2_rsr_rxn(8)") )
				( member ( signalRef "@baseboard_fab2_lib.baseboard_fab2(sch_1):tp_p3e_cpu1_pe2_rsr_rxn(9)") )
				( member ( signalRef "@baseboard_fab2_lib.baseboard_fab2(sch_1):tp_p3e_cpu1_pe2_rsr_rxn(10)") )
				( member ( signalRef "@baseboard_fab2_lib.baseboard_fab2(sch_1):tp_p3e_cpu1_pe2_rsr_rxn(11)") )
				( member ( signalRef "@baseboard_fab2_lib.baseboard_fab2(sch_1):tp_p3e_cpu1_pe2_rsr_rxn(12)") )
				( member ( signalRef "@baseboard_fab2_lib.baseboard_fab2(sch_1):tp_p3e_cpu1_pe2_rsr_rxn(13)") )
				( member ( signalRef "@baseboard_fab2_lib.baseboard_fab2(sch_1):tp_p3e_cpu1_pe2_rsr_rxn(14)") )
				( member ( signalRef "@baseboard_fab2_lib.baseboard_fab2(sch_1):tp_p3e_cpu1_pe2_rsr_rxn(15)") )
				( member ( signalRef "@baseboard_fab2_lib.baseboard_fab2(sch_1):tp_p3e_cpu1_pe2_rsr_rxp(0)") )
				( member ( signalRef "@baseboard_fab2_lib.baseboard_fab2(sch_1):tp_p3e_cpu1_pe2_rsr_rxp(1)") )
				( member ( signalRef "@baseboard_fab2_lib.baseboard_fab2(sch_1):tp_p3e_cpu1_pe2_rsr_rxp(2)") )
				( member ( signalRef "@baseboard_fab2_lib.baseboard_fab2(sch_1):tp_p3e_cpu1_pe2_rsr_rxp(3)") )
				( member ( signalRef "@baseboard_fab2_lib.baseboard_fab2(sch_1):tp_p3e_cpu1_pe2_rsr_rxp(4)") )
				( member ( signalRef "@baseboard_fab2_lib.baseboard_fab2(sch_1):tp_p3e_cpu1_pe2_rsr_rxp(5)") )
				( member ( signalRef "@baseboard_fab2_lib.baseboard_fab2(sch_1):tp_p3e_cpu1_pe2_rsr_rxp(6)") )
				( member ( signalRef "@baseboard_fab2_lib.baseboard_fab2(sch_1):tp_p3e_cpu1_pe2_rsr_rxp(7)") )
				( member ( signalRef "@baseboard_fab2_lib.baseboard_fab2(sch_1):tp_p3e_cpu1_pe2_rsr_rxp(8)") )
				( member ( signalRef "@baseboard_fab2_lib.baseboard_fab2(sch_1):tp_p3e_cpu1_pe2_rsr_rxp(9)") )
				( member ( signalRef "@baseboard_fab2_lib.baseboard_fab2(sch_1):tp_p3e_cpu1_pe2_rsr_rxp(10)") )
				( member ( signalRef "@baseboard_fab2_lib.baseboard_fab2(sch_1):tp_p3e_cpu1_pe2_rsr_rxp(11)") )
				( member ( signalRef "@baseboard_fab2_lib.baseboard_fab2(sch_1):tp_p3e_cpu1_pe2_rsr_rxp(12)") )
				( member ( signalRef "@baseboard_fab2_lib.baseboard_fab2(sch_1):tp_p3e_cpu1_pe2_rsr_rxp(13)") )
				( member ( signalRef "@baseboard_fab2_lib.baseboard_fab2(sch_1):tp_p3e_cpu1_pe2_rsr_rxp(14)") )
				( member ( signalRef "@baseboard_fab2_lib.baseboard_fab2(sch_1):tp_p3e_cpu1_pe2_rsr_rxp(15)") )
				( member ( signalRef "@baseboard_fab2_lib.baseboard_fab2(sch_1):tp_p3e_cpu1_pe2_rsr_txn(0)") )
				( member ( signalRef "@baseboard_fab2_lib.baseboard_fab2(sch_1):tp_p3e_cpu1_pe2_rsr_txn(1)") )
				( member ( signalRef "@baseboard_fab2_lib.baseboard_fab2(sch_1):tp_p3e_cpu1_pe2_rsr_txn(2)") )
				( member ( signalRef "@baseboard_fab2_lib.baseboard_fab2(sch_1):tp_p3e_cpu1_pe2_rsr_txn(3)") )
				( member ( signalRef "@baseboard_fab2_lib.baseboard_fab2(sch_1):tp_p3e_cpu1_pe2_rsr_txn(4)") )
				( member ( signalRef "@baseboard_fab2_lib.baseboard_fab2(sch_1):tp_p3e_cpu1_pe2_rsr_txn(5)") )
				( member ( signalRef "@baseboard_fab2_lib.baseboard_fab2(sch_1):tp_p3e_cpu1_pe2_rsr_txn(6)") )
				( member ( signalRef "@baseboard_fab2_lib.baseboard_fab2(sch_1):tp_p3e_cpu1_pe2_rsr_txn(7)") )
				( member ( signalRef "@baseboard_fab2_lib.baseboard_fab2(sch_1):tp_p3e_cpu1_pe2_rsr_txn(8)") )
				( member ( signalRef "@baseboard_fab2_lib.baseboard_fab2(sch_1):tp_p3e_cpu1_pe2_rsr_txn(9)") )
				( member ( signalRef "@baseboard_fab2_lib.baseboard_fab2(sch_1):tp_p3e_cpu1_pe2_rsr_txn(10)") )
				( member ( signalRef "@baseboard_fab2_lib.baseboard_fab2(sch_1):tp_p3e_cpu1_pe2_rsr_txn(11)") )
				( member ( signalRef "@baseboard_fab2_lib.baseboard_fab2(sch_1):tp_p3e_cpu1_pe2_rsr_txn(12)") )
				( member ( signalRef "@baseboard_fab2_lib.baseboard_fab2(sch_1):tp_p3e_cpu1_pe2_rsr_txn(13)") )
				( member ( signalRef "@baseboard_fab2_lib.baseboard_fab2(sch_1):tp_p3e_cpu1_pe2_rsr_txn(14)") )
				( member ( signalRef "@baseboard_fab2_lib.baseboard_fab2(sch_1):tp_p3e_cpu1_pe2_rsr_txn(15)") )
				( member ( signalRef "@baseboard_fab2_lib.baseboard_fab2(sch_1):tp_p3e_cpu1_pe2_rsr_txp(0)") )
				( member ( signalRef "@baseboard_fab2_lib.baseboard_fab2(sch_1):tp_p3e_cpu1_pe2_rsr_txp(1)") )
				( member ( signalRef "@baseboard_fab2_lib.baseboard_fab2(sch_1):tp_p3e_cpu1_pe2_rsr_txp(2)") )
				( member ( signalRef "@baseboard_fab2_lib.baseboard_fab2(sch_1):tp_p3e_cpu1_pe2_rsr_txp(3)") )
				( member ( signalRef "@baseboard_fab2_lib.baseboard_fab2(sch_1):tp_p3e_cpu1_pe2_rsr_txp(4)") )
				( member ( signalRef "@baseboard_fab2_lib.baseboard_fab2(sch_1):tp_p3e_cpu1_pe2_rsr_txp(5)") )
				( member ( signalRef "@baseboard_fab2_lib.baseboard_fab2(sch_1):tp_p3e_cpu1_pe2_rsr_txp(6)") )
				( member ( signalRef "@baseboard_fab2_lib.baseboard_fab2(sch_1):tp_p3e_cpu1_pe2_rsr_txp(7)") )
				( member ( signalRef "@baseboard_fab2_lib.baseboard_fab2(sch_1):tp_p3e_cpu1_pe2_rsr_txp(8)") )
				( member ( signalRef "@baseboard_fab2_lib.baseboard_fab2(sch_1):tp_p3e_cpu1_pe2_rsr_txp(9)") )
				( member ( signalRef "@baseboard_fab2_lib.baseboard_fab2(sch_1):tp_p3e_cpu1_pe2_rsr_txp(10)") )
				( member ( signalRef "@baseboard_fab2_lib.baseboard_fab2(sch_1):tp_p3e_cpu1_pe2_rsr_txp(11)") )
				( member ( signalRef "@baseboard_fab2_lib.baseboard_fab2(sch_1):tp_p3e_cpu1_pe2_rsr_txp(12)") )
				( member ( signalRef "@baseboard_fab2_lib.baseboard_fab2(sch_1):tp_p3e_cpu1_pe2_rsr_txp(13)") )
				( member ( signalRef "@baseboard_fab2_lib.baseboard_fab2(sch_1):tp_p3e_cpu1_pe2_rsr_txp(14)") )
				( member ( signalRef "@baseboard_fab2_lib.baseboard_fab2(sch_1):tp_p3e_cpu1_pe2_rsr_txp(15)") )
				( member ( signalRef "@baseboard_fab2_lib.baseboard_fab2(sch_1):tp_cpu1_rsvd_12") )
				( member ( signalRef "@baseboard_fab2_lib.baseboard_fab2(sch_1):tp_cpu1_rsvd_13") )
				( member ( signalRef "@baseboard_fab2_lib.baseboard_fab2(sch_1):tp_cpu1_rsvd_14") )
				( member ( signalRef "@baseboard_fab2_lib.baseboard_fab2(sch_1):tp_cpu1_rsvd_21") )
				( member ( signalRef "@baseboard_fab2_lib.baseboard_fab2(sch_1):tp_cpu1_rsvd_22") )
				( member ( signalRef "@baseboard_fab2_lib.baseboard_fab2(sch_1):tp_cpu1_rsvd_25") )
				( member ( signalRef "@baseboard_fab2_lib.baseboard_fab2(sch_1):tp_cpu1_rsvd_23") )
				( member ( signalRef "@baseboard_fab2_lib.baseboard_fab2(sch_1):tp_cpu1_rsvd_24") )
				( member ( signalRef "@baseboard_fab2_lib.baseboard_fab2(sch_1):tp_cpu1_rsvd_15") )
				( member ( signalRef "@baseboard_fab2_lib.baseboard_fab2(sch_1):tp_cpu1_rsvd_16") )
				( member ( signalRef "@baseboard_fab2_lib.baseboard_fab2(sch_1):tp_cpu1_rsvd_17") )
				( member ( signalRef "@baseboard_fab2_lib.baseboard_fab2(sch_1):tp_pch_rsvd34") )
				( member ( signalRef "@baseboard_fab2_lib.baseboard_fab2(sch_1):tp_pch_rsvd35") )
				( member ( signalRef "@baseboard_fab2_lib.baseboard_fab2(sch_1):tp_pch_rsvd36") )
				( member ( signalRef "@baseboard_fab2_lib.baseboard_fab2(sch_1):tp_pch_rsvd37") )
				( member ( signalRef "@baseboard_fab2_lib.baseboard_fab2(sch_1):tp_pch_rsvd38") )
				( member ( signalRef "@baseboard_fab2_lib.baseboard_fab2(sch_1):tp_pch_rsvd41") )
				( member ( signalRef "@baseboard_fab2_lib.baseboard_fab2(sch_1):tp_pch_rsvd42") )
				( member ( signalRef "@baseboard_fab2_lib.baseboard_fab2(sch_1):tp_pch_rsvd45") )
				( member ( signalRef "@baseboard_fab2_lib.baseboard_fab2(sch_1):tp_pch_rsvd46") )
				( member ( signalRef "@baseboard_fab2_lib.baseboard_fab2(sch_1):tp_pch_rsvd47") )
				( member ( signalRef "@baseboard_fab2_lib.baseboard_fab2(sch_1):tp_pch_rsvd48") )
				( member ( signalRef "@baseboard_fab2_lib.baseboard_fab2(sch_1):tp_pch_rsvd49") )
				( member ( signalRef "@baseboard_fab2_lib.baseboard_fab2(sch_1):tp_pch_rsvd50") )
				( member ( signalRef "@baseboard_fab2_lib.baseboard_fab2(sch_1):tp_pch_rsvd51") )
				( member ( signalRef "@baseboard_fab2_lib.baseboard_fab2(sch_1):tp_pch_rsvd52") )
				( member ( signalRef "@baseboard_fab2_lib.baseboard_fab2(sch_1):tp_pch_rsvd53") )
				( member ( signalRef "@baseboard_fab2_lib.baseboard_fab2(sch_1):tp_pch_rsvd54") )
				( member ( signalRef "@baseboard_fab2_lib.baseboard_fab2(sch_1):tp_pch_rsvd55") )
				( member ( signalRef "@baseboard_fab2_lib.baseboard_fab2(sch_1):tp_cpu1_rsvd_50") )
				( member ( signalRef "@baseboard_fab2_lib.baseboard_fab2(sch_1):tp_pch_rsvd58") )
				( member ( signalRef "@baseboard_fab2_lib.baseboard_fab2(sch_1):tp_pch_rsvd59") )
				( member ( signalRef "@baseboard_fab2_lib.baseboard_fab2(sch_1):tp_cpu1_rsvd_54") )
				( member ( signalRef "@baseboard_fab2_lib.baseboard_fab2(sch_1):tp_cpu1_rsvd_55") )
				( member ( signalRef "@baseboard_fab2_lib.baseboard_fab2(sch_1):tp_cpu1_rsvd_37") )
				( member ( signalRef "@baseboard_fab2_lib.baseboard_fab2(sch_1):tp_cpu1_rsvd_46") )
				( member ( signalRef "@baseboard_fab2_lib.baseboard_fab2(sch_1):tp_pch_rsvd64") )
				( member ( signalRef "@baseboard_fab2_lib.baseboard_fab2(sch_1):tp_pch_rsvd65") )
				( member ( signalRef "@baseboard_fab2_lib.baseboard_fab2(sch_1):tp_cpu1_rsvd_45") )
				( member ( signalRef "@baseboard_fab2_lib.baseboard_fab2(sch_1):tp_cpu1_rsvd_44") )
				( member ( signalRef "@baseboard_fab2_lib.baseboard_fab2(sch_1):tp_cpu1_rsvd_43") )
				( member ( signalRef "@baseboard_fab2_lib.baseboard_fab2(sch_1):tp_cpu1_rsvd_20") )
				( member ( signalRef "@baseboard_fab2_lib.baseboard_fab2(sch_1):tp_cpu1_rsvd_19") )
				( member ( signalRef "@baseboard_fab2_lib.baseboard_fab2(sch_1):tp_cpu1_rsvd_18") )
				( member ( signalRef "@baseboard_fab2_lib.baseboard_fab2(sch_1):fm_cpu0_prochot_pch_n") )
				( member ( signalRef "@baseboard_fab2_lib.baseboard_fab2(sch_1):fm_cpu1_prochot_pch_n") )
				( member ( signalRef "@baseboard_fab2_lib.baseboard_fab2(sch_1):fm_usb_p0_en_boot_bios_strap_n") )
				( member ( signalRef "@baseboard_fab2_lib.baseboard_fab2(sch_1):tp_pltrst_cpu_n") )
				( member ( signalRef "@baseboard_fab2_lib.baseboard_fab2(sch_1):vr_pvccin_cpu1_ph4_ocset") )
				( member ( signalRef "@baseboard_fab2_lib.baseboard_fab2(sch_1):nc_pvccio_cpu0_ph1_p31") )
				( member ( signalRef "@baseboard_fab2_lib.baseboard_fab2(sch_1):nc_pvsa_cpu0_p31") )
				( member ( signalRef "@baseboard_fab2_lib.baseboard_fab2(sch_1):nc_p1v05_pch_stby_ph1_p31") )
				( member ( signalRef "@baseboard_fab2_lib.baseboard_fab2(sch_1):nc_pvccio_cpu1_ph1_p31") )
				( member ( signalRef "@baseboard_fab2_lib.baseboard_fab2(sch_1):nc_pvccin_cpu1_ph1_p31") )
				( member ( signalRef "@baseboard_fab2_lib.baseboard_fab2(sch_1):nc_pvccin_cpu1_ph2_p31") )
				( member ( signalRef "@baseboard_fab2_lib.baseboard_fab2(sch_1):nc_pvccin_cpu1_ph3_p31") )
				( member ( signalRef "@baseboard_fab2_lib.baseboard_fab2(sch_1):tp_pvccin_cpu1_ph5_gl_1") )
				( member ( signalRef "@baseboard_fab2_lib.baseboard_fab2(sch_1):tp_pvsa_cpu1_gl_1") )
				( member ( signalRef "@baseboard_fab2_lib.baseboard_fab2(sch_1):fm_slt_cfg2_r") )
				( member ( signalRef "@baseboard_fab2_lib.baseboard_fab2(sch_1):led_gbe_p0_0") )
				( member ( signalRef "@baseboard_fab2_lib.baseboard_fab2(sch_1):nc_pvddq_abc_ph1_p31") )
				( member ( signalRef "@baseboard_fab2_lib.baseboard_fab2(sch_1):nc_pvddq_abc_ph2_p31") )
				( member ( signalRef "@baseboard_fab2_lib.baseboard_fab2(sch_1):nc_pvddq_def_ph1_p31") )
				( member ( signalRef "@baseboard_fab2_lib.baseboard_fab2(sch_1):nc_pvddq_def_ph2_p31") )
				( member ( signalRef "@baseboard_fab2_lib.baseboard_fab2(sch_1):nc_pvddq_ghj_ph1_p31") )
				( member ( signalRef "@baseboard_fab2_lib.baseboard_fab2(sch_1):nc_pvddq_ghj_ph2_p31") )
				( member ( signalRef "@baseboard_fab2_lib.baseboard_fab2(sch_1):nc_pvddq_klm_ph1_p31") )
				( member ( signalRef "@baseboard_fab2_lib.baseboard_fab2(sch_1):nc_pvddq_klm_ph2_p31") )
				( member ( signalRef "@baseboard_fab2_lib.baseboard_fab2(sch_1):led_gbe_p1_0") )
				( member ( signalRef "@baseboard_fab2_lib.baseboard_fab2(sch_1):nc_pvnn_pch_ph1_p31") )
				( member ( signalRef "@baseboard_fab2_lib.baseboard_fab2(sch_1):vr_pvccin_cpu1_ph5_ocset") )
				( member ( signalRef "@baseboard_fab2_lib.baseboard_fab2(sch_1):led_gbe_p0_1") )
				( member ( signalRef "@baseboard_fab2_lib.baseboard_fab2(sch_1):tp_p3e_cpu1_pe1_mp_rxn(0)") )
				( member ( signalRef "@baseboard_fab2_lib.baseboard_fab2(sch_1):tp_p3e_cpu1_pe1_mp_rxn(1)") )
				( member ( signalRef "@baseboard_fab2_lib.baseboard_fab2(sch_1):tp_p3e_cpu1_pe1_mp_rxn(2)") )
				( member ( signalRef "@baseboard_fab2_lib.baseboard_fab2(sch_1):tp_p3e_cpu1_pe1_mp_rxn(3)") )
				( member ( signalRef "@baseboard_fab2_lib.baseboard_fab2(sch_1):tp_p3e_cpu1_pe1_mp_rxn(4)") )
				( member ( signalRef "@baseboard_fab2_lib.baseboard_fab2(sch_1):tp_p3e_cpu1_pe1_mp_rxn(5)") )
				( member ( signalRef "@baseboard_fab2_lib.baseboard_fab2(sch_1):tp_p3e_cpu1_pe1_mp_rxn(6)") )
				( member ( signalRef "@baseboard_fab2_lib.baseboard_fab2(sch_1):tp_p3e_cpu1_pe1_mp_rxn(7)") )
				( member ( signalRef "@baseboard_fab2_lib.baseboard_fab2(sch_1):tp_p3e_cpu1_pe1_mp_rxp(0)") )
				( member ( signalRef "@baseboard_fab2_lib.baseboard_fab2(sch_1):tp_p3e_cpu1_pe1_mp_rxp(1)") )
				( member ( signalRef "@baseboard_fab2_lib.baseboard_fab2(sch_1):tp_p3e_cpu1_pe1_mp_rxp(2)") )
				( member ( signalRef "@baseboard_fab2_lib.baseboard_fab2(sch_1):tp_p3e_cpu1_pe1_mp_rxp(3)") )
				( member ( signalRef "@baseboard_fab2_lib.baseboard_fab2(sch_1):tp_p3e_cpu1_pe1_mp_rxp(4)") )
				( member ( signalRef "@baseboard_fab2_lib.baseboard_fab2(sch_1):tp_p3e_cpu1_pe1_mp_rxp(5)") )
				( member ( signalRef "@baseboard_fab2_lib.baseboard_fab2(sch_1):tp_p3e_cpu1_pe1_mp_rxp(6)") )
				( member ( signalRef "@baseboard_fab2_lib.baseboard_fab2(sch_1):tp_p3e_cpu1_pe1_mp_rxp(7)") )
				( member ( signalRef "@baseboard_fab2_lib.baseboard_fab2(sch_1):tp_p3e_cpu1_pe1_mp_txn(0)") )
				( member ( signalRef "@baseboard_fab2_lib.baseboard_fab2(sch_1):tp_p3e_cpu1_pe1_mp_txn(1)") )
				( member ( signalRef "@baseboard_fab2_lib.baseboard_fab2(sch_1):tp_p3e_cpu1_pe1_mp_txn(2)") )
				( member ( signalRef "@baseboard_fab2_lib.baseboard_fab2(sch_1):tp_p3e_cpu1_pe1_mp_txn(3)") )
				( member ( signalRef "@baseboard_fab2_lib.baseboard_fab2(sch_1):tp_p3e_cpu1_pe1_mp_txn(4)") )
				( member ( signalRef "@baseboard_fab2_lib.baseboard_fab2(sch_1):tp_p3e_cpu1_pe1_mp_txn(5)") )
				( member ( signalRef "@baseboard_fab2_lib.baseboard_fab2(sch_1):tp_p3e_cpu1_pe1_mp_txn(6)") )
				( member ( signalRef "@baseboard_fab2_lib.baseboard_fab2(sch_1):tp_p3e_cpu1_pe1_mp_txn(7)") )
				( member ( signalRef "@baseboard_fab2_lib.baseboard_fab2(sch_1):tp_p3e_cpu1_pe1_mp_txp(0)") )
				( member ( signalRef "@baseboard_fab2_lib.baseboard_fab2(sch_1):tp_p3e_cpu1_pe1_mp_txp(1)") )
				( member ( signalRef "@baseboard_fab2_lib.baseboard_fab2(sch_1):tp_p3e_cpu1_pe1_mp_txp(2)") )
				( member ( signalRef "@baseboard_fab2_lib.baseboard_fab2(sch_1):tp_p3e_cpu1_pe1_mp_txp(3)") )
				( member ( signalRef "@baseboard_fab2_lib.baseboard_fab2(sch_1):tp_p3e_cpu1_pe1_mp_txp(4)") )
				( member ( signalRef "@baseboard_fab2_lib.baseboard_fab2(sch_1):tp_p3e_cpu1_pe1_mp_txp(5)") )
				( member ( signalRef "@baseboard_fab2_lib.baseboard_fab2(sch_1):tp_p3e_cpu1_pe1_mp_txp(6)") )
				( member ( signalRef "@baseboard_fab2_lib.baseboard_fab2(sch_1):tp_p3e_cpu1_pe1_mp_txp(7)") )
				( member ( signalRef "@baseboard_fab2_lib.baseboard_fab2(sch_1):tp_p3e_cpu1_pe1_rsr3_rxn(8)") )
				( member ( signalRef "@baseboard_fab2_lib.baseboard_fab2(sch_1):tp_p3e_cpu1_pe1_rsr3_rxn(9)") )
				( member ( signalRef "@baseboard_fab2_lib.baseboard_fab2(sch_1):tp_p3e_cpu1_pe1_rsr3_rxn(10)") )
				( member ( signalRef "@baseboard_fab2_lib.baseboard_fab2(sch_1):tp_p3e_cpu1_pe1_rsr3_rxn(11)") )
				( member ( signalRef "@baseboard_fab2_lib.baseboard_fab2(sch_1):tp_p3e_cpu1_pe1_rsr3_rxn(12)") )
				( member ( signalRef "@baseboard_fab2_lib.baseboard_fab2(sch_1):tp_p3e_cpu1_pe1_rsr3_rxn(13)") )
				( member ( signalRef "@baseboard_fab2_lib.baseboard_fab2(sch_1):tp_p3e_cpu1_pe1_rsr3_rxn(14)") )
				( member ( signalRef "@baseboard_fab2_lib.baseboard_fab2(sch_1):tp_hsc_mdat") )
				( member ( signalRef "@baseboard_fab2_lib.baseboard_fab2(sch_1):tp_hsc_spissn") )
				( member ( signalRef "@baseboard_fab2_lib.baseboard_fab2(sch_1):tp_ie_debug_mode") )
				( member ( signalRef "@baseboard_fab2_lib.baseboard_fab2(sch_1):pu_vr_pvccin_cpu0_flt1_smbalt_n_imon") )
				( member ( signalRef "@baseboard_fab2_lib.baseboard_fab2(sch_1):tp_pvccin_cpu1_fault1_20") )
				( member ( signalRef "@baseboard_fab2_lib.baseboard_fab2(sch_1):pd_cpu1_test14") )
				( member ( signalRef "@baseboard_fab2_lib.baseboard_fab2(sch_1):pu_vr_pvccin_cpu1_flt1_smbalt_n_imon") )
				( member ( signalRef "@baseboard_fab2_lib.baseboard_fab2(sch_1):tp_k4b1g16_bmc_nc0") )
				( member ( signalRef "@baseboard_fab2_lib.baseboard_fab2(sch_1):tp_k4b1g16_bmc_nc1") )
				( member ( signalRef "@baseboard_fab2_lib.baseboard_fab2(sch_1):tp_k4b1g16_bmc_nc2") )
				( member ( signalRef "@baseboard_fab2_lib.baseboard_fab2(sch_1):tp_k4b1g16_bmc_nc3") )
				( member ( signalRef "@baseboard_fab2_lib.baseboard_fab2(sch_1):tp_k4b1g16_bmc_nc4") )
				( member ( signalRef "@baseboard_fab2_lib.baseboard_fab2(sch_1):tp_cpu1_rsvd_69") )
				( member ( signalRef "@baseboard_fab2_lib.baseboard_fab2(sch_1):tp_pch_gpp_j21") )
				( member ( signalRef "@baseboard_fab2_lib.baseboard_fab2(sch_1):tp_pvccin_cpu0_fault1_20") )
				( member ( signalRef "@baseboard_fab2_lib.baseboard_fab2(sch_1):pd_cpu1_test13") )
				( member ( signalRef "@baseboard_fab2_lib.baseboard_fab2(sch_1):tp_pch_gpp_j23") )
				( member ( signalRef "@baseboard_fab2_lib.baseboard_fab2(sch_1):fm_cpu1_prochot_lvt3_bmc_n") )
				( member ( signalRef "@baseboard_fab2_lib.baseboard_fab2(sch_1):tp_me_rcvr_boot") )
				( member ( signalRef "@baseboard_fab2_lib.baseboard_fab2(sch_1):tp_nmi_cpu0") )
				( member ( signalRef "@baseboard_fab2_lib.baseboard_fab2(sch_1):tp_password_clear") )
				( member ( signalRef "@baseboard_fab2_lib.baseboard_fab2(sch_1):tp_pch_dispa_bclk") )
				( member ( signalRef "@baseboard_fab2_lib.baseboard_fab2(sch_1):tp_pch_dispa_sdi") )
				( member ( signalRef "@baseboard_fab2_lib.baseboard_fab2(sch_1):tp_pch_dispa_sdo") )
				( member ( signalRef "@baseboard_fab2_lib.baseboard_fab2(sch_1):pu_vr_pvccin_cpu1_imon") )
				( member ( signalRef "@baseboard_fab2_lib.baseboard_fab2(sch_1):tp_cpu1_rsvd_67") )
				( member ( signalRef "@baseboard_fab2_lib.baseboard_fab2(sch_1):tp_cpu1_rsvd_53") )
				( member ( signalRef "@baseboard_fab2_lib.baseboard_fab2(sch_1):tp_cpu1_rsvd_51") )
				( member ( signalRef "@baseboard_fab2_lib.baseboard_fab2(sch_1):tp_cpu1_rsvd_27") )
				( member ( signalRef "@baseboard_fab2_lib.baseboard_fab2(sch_1):tp_cpu1_rsvd_42") )
				( member ( signalRef "@baseboard_fab2_lib.baseboard_fab2(sch_1):tp_cpu1_rsvd_41") )
				( member ( signalRef "@baseboard_fab2_lib.baseboard_fab2(sch_1):tp_cpu1_rsvd_40") )
				( member ( signalRef "@baseboard_fab2_lib.baseboard_fab2(sch_1):tp_cpu1_rsvd_26") )
				( member ( signalRef "@baseboard_fab2_lib.baseboard_fab2(sch_1):tp_cpu1_rsvd_39") )
				( member ( signalRef "@baseboard_fab2_lib.baseboard_fab2(sch_1):tp_cpu1_rsvd_38") )
				( member ( signalRef "@baseboard_fab2_lib.baseboard_fab2(sch_1):tp_cpu1_rsvd_34") )
				( member ( signalRef "@baseboard_fab2_lib.baseboard_fab2(sch_1):tp_cpu1_rsvd_60") )
				( member ( signalRef "@baseboard_fab2_lib.baseboard_fab2(sch_1):tp_cpu1_rsvd_57") )
				( member ( signalRef "@baseboard_fab2_lib.baseboard_fab2(sch_1):tp_cpu1_rsvd_59") )
				( member ( signalRef "@baseboard_fab2_lib.baseboard_fab2(sch_1):tp_cpu1_rsvd_56") )
				( member ( signalRef "@baseboard_fab2_lib.baseboard_fab2(sch_1):tp_cpu1_rsvd_47") )
				( member ( signalRef "@baseboard_fab2_lib.baseboard_fab2(sch_1):tp_cpu1_rsvd_48") )
				( member ( signalRef "@baseboard_fab2_lib.baseboard_fab2(sch_1):tp_cpu1_rsvd_33") )
				( member ( signalRef "@baseboard_fab2_lib.baseboard_fab2(sch_1):tp_cpu1_rsvd_29") )
				( member ( signalRef "@baseboard_fab2_lib.baseboard_fab2(sch_1):tp_cpu1_rsvd_32") )
				( member ( signalRef "@baseboard_fab2_lib.baseboard_fab2(sch_1):tp_cpu1_rsvd_31") )
				( member ( signalRef "@baseboard_fab2_lib.baseboard_fab2(sch_1):tp_cpu1_rsvd_28") )
				( member ( signalRef "@baseboard_fab2_lib.baseboard_fab2(sch_1):tp_cpu1_rsvd_30") )
				( member ( signalRef "@baseboard_fab2_lib.baseboard_fab2(sch_1):tp_cpu1_rsvd_35") )
				( member ( signalRef "@baseboard_fab2_lib.baseboard_fab2(sch_1):tp_cpu1_rsvd_49") )
				( member ( signalRef "@baseboard_fab2_lib.baseboard_fab2(sch_1):tp_vr_pvccio_cpu1_mp3") )
				( member ( signalRef "@baseboard_fab2_lib.baseboard_fab2(sch_1):fm_cpu0_prochot_lvt3_r_n") )
				( member ( signalRef "@baseboard_fab2_lib.baseboard_fab2(sch_1):tp_ie_fm_uv_threshold_set") )
				( member ( signalRef "@baseboard_fab2_lib.baseboard_fab2(sch_1):fm_cpu0_prochot_lvt3_k_n") )
				( member ( signalRef "@baseboard_fab2_lib.baseboard_fab2(sch_1):tp_pvddq_abc_mp2") )
				( member ( signalRef "@baseboard_fab2_lib.baseboard_fab2(sch_1):tp_pvddq_def_mp2") )
				( member ( signalRef "@baseboard_fab2_lib.baseboard_fab2(sch_1):tp_pvddq_ghj_mp2") )
				( member ( signalRef "@baseboard_fab2_lib.baseboard_fab2(sch_1):tp_pvnn_pch_mp2") )
				( member ( signalRef "@baseboard_fab2_lib.baseboard_fab2(sch_1):tp_pvnn_pch_mp3") )
				( member ( signalRef "@baseboard_fab2_lib.baseboard_fab2(sch_1):tp_vr_pvccio_cpu0_mp2") )
				( member ( signalRef "@baseboard_fab2_lib.baseboard_fab2(sch_1):tp_vr_pvccio_cpu0_mp3") )
				( member ( signalRef "@baseboard_fab2_lib.baseboard_fab2(sch_1):tp_vr_pvccio_cpu1_mp2") )
				( member ( signalRef "@baseboard_fab2_lib.baseboard_fab2(sch_1):tp_pch_hda_bclk") )
				( member ( signalRef "@baseboard_fab2_lib.baseboard_fab2(sch_1):tp_pch_hda_sdi_0") )
				( member ( signalRef "@baseboard_fab2_lib.baseboard_fab2(sch_1):tp_pch_hda_sdi_1") )
				( member ( signalRef "@baseboard_fab2_lib.baseboard_fab2(sch_1):tp_pch_hda_sync") )
				( member ( signalRef "@baseboard_fab2_lib.baseboard_fab2(sch_1):tp_pch_hsa_rst_n") )
				( member ( signalRef "@baseboard_fab2_lib.baseboard_fab2(sch_1):tp_pch_rsvd0") )
				( member ( signalRef "@baseboard_fab2_lib.baseboard_fab2(sch_1):tp_pch_rsvd1") )
				( member ( signalRef "@baseboard_fab2_lib.baseboard_fab2(sch_1):tp_pch_rsvd2") )
				( member ( signalRef "@baseboard_fab2_lib.baseboard_fab2(sch_1):tp_pch_rsvd3") )
				( member ( signalRef "@baseboard_fab2_lib.baseboard_fab2(sch_1):tp_pch_rsvd4") )
				( member ( signalRef "@baseboard_fab2_lib.baseboard_fab2(sch_1):tp_pch_rsvd5") )
				( member ( signalRef "@baseboard_fab2_lib.baseboard_fab2(sch_1):tp_pch_rsvd7") )
				( member ( signalRef "@baseboard_fab2_lib.baseboard_fab2(sch_1):tp_pch_rsvd8") )
				( member ( signalRef "@baseboard_fab2_lib.baseboard_fab2(sch_1):tp_pch_rsvd9") )
				( member ( signalRef "@baseboard_fab2_lib.baseboard_fab2(sch_1):tp_cpu1_rsvd_36") )
				( member ( signalRef "@baseboard_fab2_lib.baseboard_fab2(sch_1):led_gbe_p1_1") )
				( member ( signalRef "@baseboard_fab2_lib.baseboard_fab2(sch_1):tp_pch_rsvd12") )
				( member ( signalRef "@baseboard_fab2_lib.baseboard_fab2(sch_1):tp_pch_rsvd13") )
				( member ( signalRef "@baseboard_fab2_lib.baseboard_fab2(sch_1):tp_pch_rsvd14") )
				( member ( signalRef "@baseboard_fab2_lib.baseboard_fab2(sch_1):tp_pch_rsvd15") )
				( member ( signalRef "@baseboard_fab2_lib.baseboard_fab2(sch_1):tp_pch_rsvd16") )
				( member ( signalRef "@baseboard_fab2_lib.baseboard_fab2(sch_1):tp_pch_rsvd17") )
				( member ( signalRef "@baseboard_fab2_lib.baseboard_fab2(sch_1):tp_pch_rsvd18") )
				( member ( signalRef "@baseboard_fab2_lib.baseboard_fab2(sch_1):tp_pch_rsvd19") )
				( member ( signalRef "@baseboard_fab2_lib.baseboard_fab2(sch_1):tp_pch_rsvd20") )
				( member ( signalRef "@baseboard_fab2_lib.baseboard_fab2(sch_1):tp_pch_rsvd21") )
				( member ( signalRef "@baseboard_fab2_lib.baseboard_fab2(sch_1):tp_pch_rsvd23") )
				( member ( signalRef "@baseboard_fab2_lib.baseboard_fab2(sch_1):tp_pch_rsvd24") )
				( member ( signalRef "@baseboard_fab2_lib.baseboard_fab2(sch_1):tp_pch_rsvd25") )
				( member ( signalRef "@baseboard_fab2_lib.baseboard_fab2(sch_1):tp_pch_rsvd26") )
				( member ( signalRef "@baseboard_fab2_lib.baseboard_fab2(sch_1):tp_pch_rsvd27") )
				( member ( signalRef "@baseboard_fab2_lib.baseboard_fab2(sch_1):tp_pch_rsvd28") )
				( member ( signalRef "@baseboard_fab2_lib.baseboard_fab2(sch_1):tp_pch_rsvd29") )
				( member ( signalRef "@baseboard_fab2_lib.baseboard_fab2(sch_1):tp_pch_rsvd30") )
				( member ( signalRef "@baseboard_fab2_lib.baseboard_fab2(sch_1):tp_pch_rsvd31") )
				( member ( signalRef "@baseboard_fab2_lib.baseboard_fab2(sch_1):tp_pch_rsvd32") )
				( member ( signalRef "@baseboard_fab2_lib.baseboard_fab2(sch_1):tp_pch_rsvd33") )
				( member ( signalRef "@baseboard_fab2_lib.baseboard_fab2(sch_1):tp_cpu1_upi2_rsvd_cb11") )
				( member ( signalRef "@baseboard_fab2_lib.baseboard_fab2(sch_1):fm_cpu1_fivr_fault_lvt3_r_n") )
				( member ( signalRef "@baseboard_fab2_lib.baseboard_fab2(sch_1):tp_cpu1_upi2_rsvd_cc10") )
				( member ( signalRef "@baseboard_fab2_lib.baseboard_fab2(sch_1):tp_cpu1_upi2_rsvd_cc12") )
				( member ( signalRef "@baseboard_fab2_lib.baseboard_fab2(sch_1):fm_cpu0_prochot_lvt3_n") )
				( member ( signalRef "@baseboard_fab2_lib.baseboard_fab2(sch_1):tp_cpu1_upi2_rsvd_cd11") )
				( member ( signalRef "@baseboard_fab2_lib.baseboard_fab2(sch_1):fm_cpu1_fivr_fault_lvt3_n") )
				( member ( signalRef "@baseboard_fab2_lib.baseboard_fab2(sch_1):fm_cpu1_prochot_lvt3_k_n") )
				( member ( signalRef "@baseboard_fab2_lib.baseboard_fab2(sch_1):tp_cpu1_upi2_rsvd_ce12") )
				( member ( signalRef "@baseboard_fab2_lib.baseboard_fab2(sch_1):tp_cpu1_upi2_rsvd_cf11") )
				( member ( signalRef "@baseboard_fab2_lib.baseboard_fab2(sch_1):tp_cpu1_upi2_rsvd_cf13") )
				( member ( signalRef "@baseboard_fab2_lib.baseboard_fab2(sch_1):fm_cpu0_fivr_fault_lvt3_r2_n") )
				( member ( signalRef "@baseboard_fab2_lib.baseboard_fab2(sch_1):led_sata_act_r_n") )
				( member ( signalRef "@baseboard_fab2_lib.baseboard_fab2(sch_1):tp_cpu1_upi2_rsvd_cg12") )
				( member ( signalRef "@baseboard_fab2_lib.baseboard_fab2(sch_1):led_sas_act_r_n") )
				( member ( signalRef "@baseboard_fab2_lib.baseboard_fab2(sch_1):tp_cpu1_upi2_rsvd_ch11") )
				( member ( signalRef "@baseboard_fab2_lib.baseboard_fab2(sch_1):tp_cpu1_upi2_rsvd_ch13") )
				( member ( signalRef "@baseboard_fab2_lib.baseboard_fab2(sch_1):fm_cpu1_fivr_fault_lvt3") )
				( member ( signalRef "@baseboard_fab2_lib.baseboard_fab2(sch_1):tp_cpu1_upi2_rsvd_cj14") )
				( member ( signalRef "@baseboard_fab2_lib.baseboard_fab2(sch_1):a_comp_ckmng") )
				( member ( signalRef "@baseboard_fab2_lib.baseboard_fab2(sch_1):vr_pvddq_ghj_vren") )
				( member ( signalRef "@baseboard_fab2_lib.baseboard_fab2(sch_1):tp_cpu1_upi2_rsvd_ck13") )
				( member ( signalRef "@baseboard_fab2_lib.baseboard_fab2(sch_1):fm_pvddq_ghj_en") )
				( member ( signalRef "@baseboard_fab2_lib.baseboard_fab2(sch_1):vr_pvddq_abc_vren") )
				( member ( signalRef "@baseboard_fab2_lib.baseboard_fab2(sch_1):tp_cpu1_upi2_rsvd_cm13") )
				( member ( signalRef "@baseboard_fab2_lib.baseboard_fab2(sch_1):fm_pvddq_abc_en") )
				( member ( signalRef "@baseboard_fab2_lib.baseboard_fab2(sch_1):tp_pvccinc_cpu1_ph2_gl_1") )
				( member ( signalRef "@baseboard_fab2_lib.baseboard_fab2(sch_1):tp_cpu1_rsvd_66") )
				( member ( signalRef "@baseboard_fab2_lib.baseboard_fab2(sch_1):tp_cpu1_rsvd_61") )
				( member ( signalRef "@baseboard_fab2_lib.baseboard_fab2(sch_1):nic_led_act_anode_r") )
				( member ( signalRef "@baseboard_fab2_lib.baseboard_fab2(sch_1):tp_cpu1_upi2_rsvd_cr14") )
				( member ( signalRef "@baseboard_fab2_lib.baseboard_fab2(sch_1):tp_pvccinc_cpu1_ph1_gl_1") )
				( member ( signalRef "@baseboard_fab2_lib.baseboard_fab2(sch_1):fm_pvccin_pvccsa_cpu1_en_lvc1") )
				( member ( signalRef "@baseboard_fab2_lib.baseboard_fab2(sch_1):pd_cpu0_test14") )
				( member ( signalRef "@baseboard_fab2_lib.baseboard_fab2(sch_1):tp_cpu1_upi2_rsvd_cu14") )
				( member ( signalRef "@baseboard_fab2_lib.baseboard_fab2(sch_1):tp_cpu1_upi2_rsvd_cv13") )
				( member ( signalRef "@baseboard_fab2_lib.baseboard_fab2(sch_1):tp_cpu1_rsvd_70") )
				( member ( signalRef "@baseboard_fab2_lib.baseboard_fab2(sch_1):tp_cpu1_upi2_rsvd_cw14") )
				( member ( signalRef "@baseboard_fab2_lib.baseboard_fab2(sch_1):tp_cpu1_upi2_rsvd_cw16") )
				( member ( signalRef "@baseboard_fab2_lib.baseboard_fab2(sch_1):tp_cpu1_rsvd_72") )
				( member ( signalRef "@baseboard_fab2_lib.baseboard_fab2(sch_1):a_p12v_stby_fph_gate") )
				( member ( signalRef "@baseboard_fab2_lib.baseboard_fab2(sch_1):pd_cpu1_mcp01_dmon") )
				( member ( signalRef "@baseboard_fab2_lib.baseboard_fab2(sch_1):tp_cpu1_upi2_rsvd_da16") )
				( member ( signalRef "@baseboard_fab2_lib.baseboard_fab2(sch_1):fm_cpu0_thermtrip_lvt3_r_n") )
				( member ( signalRef "@baseboard_fab2_lib.baseboard_fab2(sch_1):tp_xdp_obsfn_b1") )
				( member ( signalRef "@baseboard_fab2_lib.baseboard_fab2(sch_1):tp_cpu1_upi2_rsvd_db15") )
				( member ( signalRef "@baseboard_fab2_lib.baseboard_fab2(sch_1):fm_cpu0_thermtrip_lvt3_n") )
				( member ( signalRef "@baseboard_fab2_lib.baseboard_fab2(sch_1):tp_cpld1_pr11b") )
				( member ( signalRef "@baseboard_fab2_lib.baseboard_fab2(sch_1):tp_cpu1_upi2_rsvd_dc16") )
				( member ( signalRef "@baseboard_fab2_lib.baseboard_fab2(sch_1):vr_pvccin_cpu0_vren") )
				( member ( signalRef "@baseboard_fab2_lib.baseboard_fab2(sch_1):tp_xdp_obsfn_b0") )
				( member ( signalRef "@baseboard_fab2_lib.baseboard_fab2(sch_1):tp_cpu1_upi2_rsvd_dd15") )
				( member ( signalRef "@baseboard_fab2_lib.baseboard_fab2(sch_1):tp_cpu1_upi2_rsvd_dd17") )
				( member ( signalRef "@baseboard_fab2_lib.baseboard_fab2(sch_1):fm_pvccin_pvccsa_cpu0_en_lvc1") )
				( member ( signalRef "@baseboard_fab2_lib.baseboard_fab2(sch_1):fm_pvddq_def_en") )
				( member ( signalRef "@baseboard_fab2_lib.baseboard_fab2(sch_1):tp_cpu1_upi2_rsvd_de16") )
				( member ( signalRef "@baseboard_fab2_lib.baseboard_fab2(sch_1):fm_pvddq_klm_en") )
				( member ( signalRef "@baseboard_fab2_lib.baseboard_fab2(sch_1):tp_cpu1_upi2_rsvd_df15") )
				( member ( signalRef "@baseboard_fab2_lib.baseboard_fab2(sch_1):tp_cpu1_upi2_rsvd_df17") )
				( member ( signalRef "@baseboard_fab2_lib.baseboard_fab2(sch_1):pd_cpu0_mcp01_dmon") )
				( member ( signalRef "@baseboard_fab2_lib.baseboard_fab2(sch_1):tp_cpu1_upi2_rsvd_dg18") )
				( member ( signalRef "@baseboard_fab2_lib.baseboard_fab2(sch_1):tp_cpu1_upi2_rsvd_dg20") )
				( member ( signalRef "@baseboard_fab2_lib.baseboard_fab2(sch_1):pd_cpu0_test12") )
				( member ( signalRef "@baseboard_fab2_lib.baseboard_fab2(sch_1):tp_cpu1_upi2_rsvd_dh17") )
				( member ( signalRef "@baseboard_fab2_lib.baseboard_fab2(sch_1):tp_cpu1_upi2_rsvd_dh19") )
				( member ( signalRef "@baseboard_fab2_lib.baseboard_fab2(sch_1):tp_cpu1_upi2_rsvd_dj18") )
				( member ( signalRef "@baseboard_fab2_lib.baseboard_fab2(sch_1):tp_cpu1_upi2_rsvd_dj20") )
				( member ( signalRef "@baseboard_fab2_lib.baseboard_fab2(sch_1):tp_cpu1_upi2_rsvd_dk17") )
				( member ( signalRef "@baseboard_fab2_lib.baseboard_fab2(sch_1):tp_cpu1_upi2_rsvd_dk19") )
				( member ( signalRef "@baseboard_fab2_lib.baseboard_fab2(sch_1):tp_cpu1_upi2_rsvd_dl20") )
				( member ( signalRef "@baseboard_fab2_lib.baseboard_fab2(sch_1):tp_cpu1_upi2_rsvd_dm21") )
				( member ( signalRef "@baseboard_fab2_lib.baseboard_fab2(sch_1):tp_cpu1_upi2_rsvd_dn20") )
				( member ( signalRef "@baseboard_fab2_lib.baseboard_fab2(sch_1):tp_cpu1_upi2_rsvd_dp21") )
				( member ( signalRef "@baseboard_fab2_lib.baseboard_fab2(sch_1):tp_cpu1_upi2_rsvd_dt21") )
				( member ( signalRef "@baseboard_fab2_lib.baseboard_fab2(sch_1):fm_cpu1_fivr_fault_lvt3_r1_n") )
				( member ( signalRef "@baseboard_fab2_lib.baseboard_fab2(sch_1):vr_pvddq_def_vren") )
				( member ( signalRef "@baseboard_fab2_lib.baseboard_fab2(sch_1):fm_cpu1_prochot_lvt3_n") )
				( member ( signalRef "@baseboard_fab2_lib.baseboard_fab2(sch_1):pd_cpu0_test13") )
				( member ( signalRef "@baseboard_fab2_lib.baseboard_fab2(sch_1):fm_pwrbrk_n") )
				( member ( signalRef "@baseboard_fab2_lib.baseboard_fab2(sch_1):fm_red_led_cathode") )
				( member ( signalRef "@baseboard_fab2_lib.baseboard_fab2(sch_1):tp_fm_qat_cbl_prsnt0_r_n") )
				( member ( signalRef "@baseboard_fab2_lib.baseboard_fab2(sch_1):fm_cpu_err2_lvt3_r_n") )
				( member ( signalRef "@baseboard_fab2_lib.baseboard_fab2(sch_1):tp_fm_qat_cbl_prsnt1_n_r") )
				( member ( signalRef "@baseboard_fab2_lib.baseboard_fab2(sch_1):tp_fm_qat_cbl_prsnt2_n") )
				( member ( signalRef "@baseboard_fab2_lib.baseboard_fab2(sch_1):tp_cpld1_pr10c") )
				( member ( signalRef "@baseboard_fab2_lib.baseboard_fab2(sch_1):pd_cpu1_test12") )
				( member ( signalRef "@baseboard_fab2_lib.baseboard_fab2(sch_1):tp_cpu1_rsvd_73") )
				( member ( signalRef "@baseboard_fab2_lib.baseboard_fab2(sch_1):fm_red_led_anode") )
				( member ( signalRef "@baseboard_fab2_lib.baseboard_fab2(sch_1):vr_pvddq_klm_vren") )
				( member ( signalRef "@baseboard_fab2_lib.baseboard_fab2(sch_1):fm_cpu1_prochot_lvt3_r_n") )
				( member ( signalRef "@baseboard_fab2_lib.baseboard_fab2(sch_1):fm_pvcciomcp_cpu1_en") )
				( member ( signalRef "@baseboard_fab2_lib.baseboard_fab2(sch_1):tp_gpiom5_nrts2_vpib7") )
				( member ( signalRef "@baseboard_fab2_lib.baseboard_fab2(sch_1):tp_hsc_alert2_n") )
				( member ( signalRef "@baseboard_fab2_lib.baseboard_fab2(sch_1):tp_hsc_mclk") )
				( member ( signalRef "@baseboard_fab2_lib.baseboard_fab2(sch_1):tp_cpu1_rsvd_216") )
				( member ( signalRef "@baseboard_fab2_lib.baseboard_fab2(sch_1):tp_cpu1_rsvd_217") )
				( member ( signalRef "@baseboard_fab2_lib.baseboard_fab2(sch_1):tp_cpu1_rsvd_218") )
				( member ( signalRef "@baseboard_fab2_lib.baseboard_fab2(sch_1):tp_cpu1_rsvd_219") )
				( member ( signalRef "@baseboard_fab2_lib.baseboard_fab2(sch_1):tp_cpu1_rsvd_222") )
				( member ( signalRef "@baseboard_fab2_lib.baseboard_fab2(sch_1):tp_cpu1_rsvd_223") )
				( member ( signalRef "@baseboard_fab2_lib.baseboard_fab2(sch_1):tp_cpu1_rsvd_224") )
				( member ( signalRef "@baseboard_fab2_lib.baseboard_fab2(sch_1):tp_cpu1_rsvd_225") )
				( member ( signalRef "@baseboard_fab2_lib.baseboard_fab2(sch_1):tp_cpu1_rsvd_226") )
				( member ( signalRef "@baseboard_fab2_lib.baseboard_fab2(sch_1):tp_cpu1_rsvd_227") )
				( member ( signalRef "@baseboard_fab2_lib.baseboard_fab2(sch_1):tp_cpu1_rsvd_228") )
				( member ( signalRef "@baseboard_fab2_lib.baseboard_fab2(sch_1):tp_cpu1_rsvd_229") )
				( member ( signalRef "@baseboard_fab2_lib.baseboard_fab2(sch_1):tp_cpu1_rsvd_230") )
				( member ( signalRef "@baseboard_fab2_lib.baseboard_fab2(sch_1):tp_cpu1_rsvd_231") )
				( member ( signalRef "@baseboard_fab2_lib.baseboard_fab2(sch_1):tp_cpu1_rsvd_232") )
				( member ( signalRef "@baseboard_fab2_lib.baseboard_fab2(sch_1):tp_cpu1_rsvd_233") )
				( member ( signalRef "@baseboard_fab2_lib.baseboard_fab2(sch_1):tp_cpu1_rsvd_234") )
				( member ( signalRef "@baseboard_fab2_lib.baseboard_fab2(sch_1):tp_cpu1_rsvd_235") )
				( member ( signalRef "@baseboard_fab2_lib.baseboard_fab2(sch_1):tp_cpu1_rsvd_236") )
				( member ( signalRef "@baseboard_fab2_lib.baseboard_fab2(sch_1):tp_cpu1_rsvd_237") )
				( member ( signalRef "@baseboard_fab2_lib.baseboard_fab2(sch_1):tp_cpu1_rsvd_238") )
				( member ( signalRef "@baseboard_fab2_lib.baseboard_fab2(sch_1):tp_cpu1_rsvd_239") )
				( member ( signalRef "@baseboard_fab2_lib.baseboard_fab2(sch_1):tp_cpu1_rsvd_240") )
				( member ( signalRef "@baseboard_fab2_lib.baseboard_fab2(sch_1):tp_cpu1_rsvd_241") )
				( member ( signalRef "@baseboard_fab2_lib.baseboard_fab2(sch_1):tp_cpu1_rsvd_242") )
				( member ( signalRef "@baseboard_fab2_lib.baseboard_fab2(sch_1):tp_cpu1_rsvd_243") )
				( member ( signalRef "@baseboard_fab2_lib.baseboard_fab2(sch_1):tp_cpu1_rsvd_244") )
				( member ( signalRef "@baseboard_fab2_lib.baseboard_fab2(sch_1):tp_cpu1_rsvd_245") )
				( member ( signalRef "@baseboard_fab2_lib.baseboard_fab2(sch_1):tp_cpu1_rsvd_246") )
				( member ( signalRef "@baseboard_fab2_lib.baseboard_fab2(sch_1):tp_cpu1_rsvd_247") )
				( member ( signalRef "@baseboard_fab2_lib.baseboard_fab2(sch_1):tp_cpu1_rsvd_248") )
				( member ( signalRef "@baseboard_fab2_lib.baseboard_fab2(sch_1):tp_cpu1_rsvd_249") )
				( member ( signalRef "@baseboard_fab2_lib.baseboard_fab2(sch_1):tp_cpu1_rsvd_250") )
				( member ( signalRef "@baseboard_fab2_lib.baseboard_fab2(sch_1):tp_cpu1_rsvd_251") )
				( member ( signalRef "@baseboard_fab2_lib.baseboard_fab2(sch_1):tp_cpu1_rsvd_252") )
				( member ( signalRef "@baseboard_fab2_lib.baseboard_fab2(sch_1):tp_cpu1_rsvd_253") )
				( member ( signalRef "@baseboard_fab2_lib.baseboard_fab2(sch_1):tp_cpu1_rsvd_254") )
				( member ( signalRef "@baseboard_fab2_lib.baseboard_fab2(sch_1):tp_cpu1_rsvd_255") )
				( member ( signalRef "@baseboard_fab2_lib.baseboard_fab2(sch_1):tp_cpu1_rsvd_256") )
				( member ( signalRef "@baseboard_fab2_lib.baseboard_fab2(sch_1):tp_cpld1_pt17c") )
				( member ( signalRef "@baseboard_fab2_lib.baseboard_fab2(sch_1):tp_cpu1_rsvd_258") )
				( member ( signalRef "@baseboard_fab2_lib.baseboard_fab2(sch_1):tp_cpu1_rsvd_259") )
				( member ( signalRef "@baseboard_fab2_lib.baseboard_fab2(sch_1):tp_cpu1_rsvd_260") )
				( member ( signalRef "@baseboard_fab2_lib.baseboard_fab2(sch_1):tp_cpu1_rsvd_261") )
				( member ( signalRef "@baseboard_fab2_lib.baseboard_fab2(sch_1):tp_cpu1_rsvd_262") )
				( member ( signalRef "@baseboard_fab2_lib.baseboard_fab2(sch_1):tp_cpu1_rsvd_263") )
				( member ( signalRef "@baseboard_fab2_lib.baseboard_fab2(sch_1):tp_cpu1_rsvd_264") )
				( member ( signalRef "@baseboard_fab2_lib.baseboard_fab2(sch_1):tp_cpu1_rsvd_265") )
				( member ( signalRef "@baseboard_fab2_lib.baseboard_fab2(sch_1):tp_cpu1_rsvd_266") )
				( member ( signalRef "@baseboard_fab2_lib.baseboard_fab2(sch_1):tp_cpu1_rsvd_267") )
				( member ( signalRef "@baseboard_fab2_lib.baseboard_fab2(sch_1):tp_cpu1_rsvd_268") )
				( member ( signalRef "@baseboard_fab2_lib.baseboard_fab2(sch_1):tp_cpu1_rsvd_269") )
				( member ( signalRef "@baseboard_fab2_lib.baseboard_fab2(sch_1):tp_cpu1_rsvd_270") )
				( member ( signalRef "@baseboard_fab2_lib.baseboard_fab2(sch_1):tp_cpu1_rsvd_271") )
				( member ( signalRef "@baseboard_fab2_lib.baseboard_fab2(sch_1):tp_cpu1_rsvd_272") )
				( member ( signalRef "@baseboard_fab2_lib.baseboard_fab2(sch_1):tp_cpu1_rsvd_273") )
				( member ( signalRef "@baseboard_fab2_lib.baseboard_fab2(sch_1):tp_cpu1_rsvd_274") )
				( member ( signalRef "@baseboard_fab2_lib.baseboard_fab2(sch_1):tp_cpu1_rsvd_276") )
				( member ( signalRef "@baseboard_fab2_lib.baseboard_fab2(sch_1):tp_cpu1_rsvd_277") )
				( member ( signalRef "@baseboard_fab2_lib.baseboard_fab2(sch_1):tp_cpu1_rsvd_278") )
				( member ( signalRef "@baseboard_fab2_lib.baseboard_fab2(sch_1):tp_cpu1_rsvd_279") )
				( member ( signalRef "@baseboard_fab2_lib.baseboard_fab2(sch_1):tp_cpu1_rsvd_280") )
				( member ( signalRef "@baseboard_fab2_lib.baseboard_fab2(sch_1):tp_cpu1_rsvd_281") )
				( member ( signalRef "@baseboard_fab2_lib.baseboard_fab2(sch_1):tp_cpu1_rsvd_284") )
				( member ( signalRef "@baseboard_fab2_lib.baseboard_fab2(sch_1):tp_cpu1_rsvd_285") )
				( member ( signalRef "@baseboard_fab2_lib.baseboard_fab2(sch_1):tp_cpu1_rsvd_286") )
				( member ( signalRef "@baseboard_fab2_lib.baseboard_fab2(sch_1):tp_cpu1_rsvd_288") )
				( member ( signalRef "@baseboard_fab2_lib.baseboard_fab2(sch_1):tp_cpu1_rsvd_289") )
				( member ( signalRef "@baseboard_fab2_lib.baseboard_fab2(sch_1):tp_cpu1_rsvd_290") )
				( member ( signalRef "@baseboard_fab2_lib.baseboard_fab2(sch_1):tp_cpu1_rsvd_291") )
				( member ( signalRef "@baseboard_fab2_lib.baseboard_fab2(sch_1):tp_cpu1_rsvd_292") )
				( member ( signalRef "@baseboard_fab2_lib.baseboard_fab2(sch_1):tp_cpu1_rsvd_293") )
				( member ( signalRef "@baseboard_fab2_lib.baseboard_fab2(sch_1):tp_cpu1_rsvd_300") )
				( member ( signalRef "@baseboard_fab2_lib.baseboard_fab2(sch_1):tp_shared_kr_mdio_0") )
				( member ( signalRef "@baseboard_fab2_lib.baseboard_fab2(sch_1):fm_cpu1_sm_wp") )
				( member ( signalRef "@baseboard_fab2_lib.baseboard_fab2(sch_1):tp_cpu1_socket_id_2") )
				( member ( signalRef "@baseboard_fab2_lib.baseboard_fab2(sch_1):tp_cpu1_rsvd_test_5") )
				( member ( signalRef "@baseboard_fab2_lib.baseboard_fab2(sch_1):tp_cpu1_upi2_rsvd_ca12") )
				( member ( signalRef "@baseboard_fab2_lib.baseboard_fab2(sch_1):fp_led_hdd_activity_and_n") )
				( member ( signalRef "@baseboard_fab2_lib.baseboard_fab2(sch_1):fp_led_hdd_activity_and_r_n") )
				( member ( signalRef "@baseboard_fab2_lib.baseboard_fab2(sch_1):led_p5v_stby") )
				( member ( signalRef "@baseboard_fab2_lib.baseboard_fab2(sch_1):fm_cpu_caterr_lvt3_r2_n") )
				( member ( signalRef "@baseboard_fab2_lib.baseboard_fab2(sch_1):fm_cpu1_thermtrip_lvt3_n") )
				( member ( signalRef "@baseboard_fab2_lib.baseboard_fab2(sch_1):fm_cpu1_thermtrip_lvt3_r_n") )
				( member ( signalRef "@baseboard_fab2_lib.baseboard_fab2(sch_1):fm_ctnr_ps_on") )
				( member ( signalRef "@baseboard_fab2_lib.baseboard_fab2(sch_1):fm_ctnr_ps_on_r") )
				( member ( signalRef "@baseboard_fab2_lib.baseboard_fab2(sch_1):fm_db_uart_sel0_n") )
				( member ( signalRef "@baseboard_fab2_lib.baseboard_fab2(sch_1):fm_m2_det_lvc3") )
				( member ( signalRef "@baseboard_fab2_lib.baseboard_fab2(sch_1):fm_pch_sata_raid_key") )
				( member ( signalRef "@baseboard_fab2_lib.baseboard_fab2(sch_1):fm_pch_sata_raid_key_r") )
				( member ( signalRef "@baseboard_fab2_lib.baseboard_fab2(sch_1):tp_cpu0_upi2_rsvd_cm13") )
				( member ( signalRef "@baseboard_fab2_lib.baseboard_fab2(sch_1):tp_pch_gpp_j19") )
				( member ( signalRef "@baseboard_fab2_lib.baseboard_fab2(sch_1):led_lan_0_n") )
				( member ( signalRef "@baseboard_fab2_lib.baseboard_fab2(sch_1):fm_debug_rst_btn_r1_n") )
				( member ( signalRef "@baseboard_fab2_lib.baseboard_fab2(sch_1):pd_pirom_cpu1_addr1") )
				( member ( signalRef "@baseboard_fab2_lib.baseboard_fab2(sch_1):tp_cpu0_upi2_rsvd_cr14") )
				( member ( signalRef "@baseboard_fab2_lib.baseboard_fab2(sch_1):pd_pirom_cpu0_addr2") )
				( member ( signalRef "@baseboard_fab2_lib.baseboard_fab2(sch_1):pd_pirom_cpu1_addr2") )
				( member ( signalRef "@baseboard_fab2_lib.baseboard_fab2(sch_1):tp_cpu0_upi2_rsvd_cu14") )
				( member ( signalRef "@baseboard_fab2_lib.baseboard_fab2(sch_1):tp_usb3_p05_rxn") )
				( member ( signalRef "@baseboard_fab2_lib.baseboard_fab2(sch_1):tp_cpu0_upi2_rsvd_cv13") )
				( member ( signalRef "@baseboard_fab2_lib.baseboard_fab2(sch_1):fp_rst_btn_r_n") )
				( member ( signalRef "@baseboard_fab2_lib.baseboard_fab2(sch_1):tp_cpu0_upi2_rsvd_cw14") )
				( member ( signalRef "@baseboard_fab2_lib.baseboard_fab2(sch_1):tp_cpu0_upi2_rsvd_cw16") )
				( member ( signalRef "@baseboard_fab2_lib.baseboard_fab2(sch_1):pu_24m_osc_oe") )
				( member ( signalRef "@baseboard_fab2_lib.baseboard_fab2(sch_1):pd_pirom_cpu0_addr1") )
				( member ( signalRef "@baseboard_fab2_lib.baseboard_fab2(sch_1):tp_cpu0_upi2_rsvd_da16") )
				( member ( signalRef "@baseboard_fab2_lib.baseboard_fab2(sch_1):tp_cpu0_upi2_rsvd_db15") )
				( member ( signalRef "@baseboard_fab2_lib.baseboard_fab2(sch_1):tp_pvccin_cpu1_ph3_gl_1") )
				( member ( signalRef "@baseboard_fab2_lib.baseboard_fab2(sch_1):fp_pwr_btn_r_n") )
				( member ( signalRef "@baseboard_fab2_lib.baseboard_fab2(sch_1):tp_cpu0_upi2_rsvd_dc16") )
				( member ( signalRef "@baseboard_fab2_lib.baseboard_fab2(sch_1):pu_m2_clk_req_n") )
				( member ( signalRef "@baseboard_fab2_lib.baseboard_fab2(sch_1):tp_cpu0_upi2_rsvd_dd15") )
				( member ( signalRef "@baseboard_fab2_lib.baseboard_fab2(sch_1):tp_cpu0_upi2_rsvd_dd17") )
				( member ( signalRef "@baseboard_fab2_lib.baseboard_fab2(sch_1):fp_pwr_btn_r1_n") )
				( member ( signalRef "@baseboard_fab2_lib.baseboard_fab2(sch_1):tp_cpu0_upi2_rsvd_de16") )
				( member ( signalRef "@baseboard_fab2_lib.baseboard_fab2(sch_1):fm_debug_rst_btn_n") )
				( member ( signalRef "@baseboard_fab2_lib.baseboard_fab2(sch_1):tp_cpu0_upi2_rsvd_df15") )
				( member ( signalRef "@baseboard_fab2_lib.baseboard_fab2(sch_1):tp_cpu0_upi2_rsvd_df17") )
				( member ( signalRef "@baseboard_fab2_lib.baseboard_fab2(sch_1):tp_cpu0_upi2_rsvd_dg18") )
				( member ( signalRef "@baseboard_fab2_lib.baseboard_fab2(sch_1):tp_cpu0_upi2_rsvd_dg20") )
				( member ( signalRef "@baseboard_fab2_lib.baseboard_fab2(sch_1):tp_pch_gpp_j17") )
				( member ( signalRef "@baseboard_fab2_lib.baseboard_fab2(sch_1):tp_cpu0_upi2_rsvd_dh17") )
				( member ( signalRef "@baseboard_fab2_lib.baseboard_fab2(sch_1):tp_cpu0_upi2_rsvd_dh19") )
				( member ( signalRef "@baseboard_fab2_lib.baseboard_fab2(sch_1):tp_cpu0_upi2_rsvd_dj18") )
				( member ( signalRef "@baseboard_fab2_lib.baseboard_fab2(sch_1):tp_cpu0_upi2_rsvd_dj20") )
				( member ( signalRef "@baseboard_fab2_lib.baseboard_fab2(sch_1):tp_cpu0_upi2_rsvd_dk17") )
				( member ( signalRef "@baseboard_fab2_lib.baseboard_fab2(sch_1):tp_cpu0_upi2_rsvd_dk19") )
				( member ( signalRef "@baseboard_fab2_lib.baseboard_fab2(sch_1):tp_cpu0_upi2_rsvd_dl20") )
				( member ( signalRef "@baseboard_fab2_lib.baseboard_fab2(sch_1):tp_cpu0_upi2_rsvd_dm21") )
				( member ( signalRef "@baseboard_fab2_lib.baseboard_fab2(sch_1):tp_cpu0_upi2_rsvd_dn20") )
				( member ( signalRef "@baseboard_fab2_lib.baseboard_fab2(sch_1):tp_cpu0_upi2_rsvd_dp21") )
				( member ( signalRef "@baseboard_fab2_lib.baseboard_fab2(sch_1):tp_cpu0_upi2_rsvd_dt21") )
				( member ( signalRef "@baseboard_fab2_lib.baseboard_fab2(sch_1):tp_cpu1_dmi_tx_dn0") )
				( member ( signalRef "@baseboard_fab2_lib.baseboard_fab2(sch_1):tp_cpu1_dmi_tx_dn1") )
				( member ( signalRef "@baseboard_fab2_lib.baseboard_fab2(sch_1):tp_cpu1_dmi_tx_dn2") )
				( member ( signalRef "@baseboard_fab2_lib.baseboard_fab2(sch_1):tp_cpu1_dmi_tx_dn3") )
				( member ( signalRef "@baseboard_fab2_lib.baseboard_fab2(sch_1):tp_cpu1_dmi_tx_dp0") )
				( member ( signalRef "@baseboard_fab2_lib.baseboard_fab2(sch_1):tp_cpu1_dmi_tx_dp1") )
				( member ( signalRef "@baseboard_fab2_lib.baseboard_fab2(sch_1):tp_cpu1_dmi_tx_dp2") )
				( member ( signalRef "@baseboard_fab2_lib.baseboard_fab2(sch_1):tp_cpu1_dmi_tx_dp3") )
				( member ( signalRef "@baseboard_fab2_lib.baseboard_fab2(sch_1):tp_cpu1_nmi") )
				( member ( signalRef "@baseboard_fab2_lib.baseboard_fab2(sch_1):led_lan_0_r_n") )
				( member ( signalRef "@baseboard_fab2_lib.baseboard_fab2(sch_1):tp_cpu1_proc_dis_g_n") )
				( member ( signalRef "@baseboard_fab2_lib.baseboard_fab2(sch_1):tp_cpu1_rsvd_189") )
				( member ( signalRef "@baseboard_fab2_lib.baseboard_fab2(sch_1):tp_cpu1_rsvd_186") )
				( member ( signalRef "@baseboard_fab2_lib.baseboard_fab2(sch_1):tp_cpu1_rsvd_190") )
				( member ( signalRef "@baseboard_fab2_lib.baseboard_fab2(sch_1):fm_ssata_pcie_m2_sel") )
				( member ( signalRef "@baseboard_fab2_lib.baseboard_fab2(sch_1):tp_cpu1_rsvd_174") )
				( member ( signalRef "@baseboard_fab2_lib.baseboard_fab2(sch_1):tp_cpu1_rsvd_184") )
				( member ( signalRef "@baseboard_fab2_lib.baseboard_fab2(sch_1):tp_cpu1_rsvd_176") )
				( member ( signalRef "@baseboard_fab2_lib.baseboard_fab2(sch_1):tp_cpu1_rsvd_177") )
				( member ( signalRef "@baseboard_fab2_lib.baseboard_fab2(sch_1):tp_cpu1_rsvd_179") )
				( member ( signalRef "@baseboard_fab2_lib.baseboard_fab2(sch_1):tp_cpu1_rsvd_178") )
				( member ( signalRef "@baseboard_fab2_lib.baseboard_fab2(sch_1):tp_cpu1_rsvd_180") )
				( member ( signalRef "@baseboard_fab2_lib.baseboard_fab2(sch_1):fm_uart_sel_n") )
				( member ( signalRef "@baseboard_fab2_lib.baseboard_fab2(sch_1):tp_cpu1_rsvd_181") )
				( member ( signalRef "@baseboard_fab2_lib.baseboard_fab2(sch_1):fm_uart_switch_n") )
				( member ( signalRef "@baseboard_fab2_lib.baseboard_fab2(sch_1):tp_cpu1_rsvd_183") )
				( member ( signalRef "@baseboard_fab2_lib.baseboard_fab2(sch_1):tp_cpu1_rsvd_182") )
				( member ( signalRef "@baseboard_fab2_lib.baseboard_fab2(sch_1):pd_pirom_cpu0_addr0") )
				( member ( signalRef "@baseboard_fab2_lib.baseboard_fab2(sch_1):tp_cpu1_test_6") )
				( member ( signalRef "@baseboard_fab2_lib.baseboard_fab2(sch_1):fm_pwr_btn_n") )
				( member ( signalRef "@baseboard_fab2_lib.baseboard_fab2(sch_1):tp_cpu1_rsvd_204") )
				( member ( signalRef "@baseboard_fab2_lib.baseboard_fab2(sch_1):tp_cpu1_rsvd_205") )
				( member ( signalRef "@baseboard_fab2_lib.baseboard_fab2(sch_1):tp_cpu1_rsvd_208") )
				( member ( signalRef "@baseboard_fab2_lib.baseboard_fab2(sch_1):fm_pwr_btn_r_n") )
				( member ( signalRef "@baseboard_fab2_lib.baseboard_fab2(sch_1):tp_cpu1_rsvd_210") )
				( member ( signalRef "@baseboard_fab2_lib.baseboard_fab2(sch_1):tp_cpu1_rsvd_211") )
				( member ( signalRef "@baseboard_fab2_lib.baseboard_fab2(sch_1):tp_cpu1_rsvd_212") )
				( member ( signalRef "@baseboard_fab2_lib.baseboard_fab2(sch_1):tp_cpu1_rsvd_214") )
				( member ( signalRef "@baseboard_fab2_lib.baseboard_fab2(sch_1):tp_cpu0_rsvd_240") )
				( member ( signalRef "@baseboard_fab2_lib.baseboard_fab2(sch_1):tp_cpu0_rsvd_241") )
				( member ( signalRef "@baseboard_fab2_lib.baseboard_fab2(sch_1):tp_cpu0_rsvd_242") )
				( member ( signalRef "@baseboard_fab2_lib.baseboard_fab2(sch_1):tp_cpu0_rsvd_243") )
				( member ( signalRef "@baseboard_fab2_lib.baseboard_fab2(sch_1):tp_cpu0_rsvd_244") )
				( member ( signalRef "@baseboard_fab2_lib.baseboard_fab2(sch_1):tp_cpu0_rsvd_245") )
				( member ( signalRef "@baseboard_fab2_lib.baseboard_fab2(sch_1):tp_cpu0_rsvd_246") )
				( member ( signalRef "@baseboard_fab2_lib.baseboard_fab2(sch_1):tp_cpu0_rsvd_247") )
				( member ( signalRef "@baseboard_fab2_lib.baseboard_fab2(sch_1):tp_cpu0_rsvd_248") )
				( member ( signalRef "@baseboard_fab2_lib.baseboard_fab2(sch_1):tp_cpu0_rsvd_249") )
				( member ( signalRef "@baseboard_fab2_lib.baseboard_fab2(sch_1):tp_cpu0_rsvd_250") )
				( member ( signalRef "@baseboard_fab2_lib.baseboard_fab2(sch_1):tp_cpu0_rsvd_251") )
				( member ( signalRef "@baseboard_fab2_lib.baseboard_fab2(sch_1):tp_cpu0_rsvd_252") )
				( member ( signalRef "@baseboard_fab2_lib.baseboard_fab2(sch_1):tp_cpu0_rsvd_253") )
				( member ( signalRef "@baseboard_fab2_lib.baseboard_fab2(sch_1):tp_cpu0_rsvd_254") )
				( member ( signalRef "@baseboard_fab2_lib.baseboard_fab2(sch_1):tp_cpu0_rsvd_256") )
				( member ( signalRef "@baseboard_fab2_lib.baseboard_fab2(sch_1):tp_cpu0_rsvd_258") )
				( member ( signalRef "@baseboard_fab2_lib.baseboard_fab2(sch_1):tp_cpu0_rsvd_259") )
				( member ( signalRef "@baseboard_fab2_lib.baseboard_fab2(sch_1):tp_cpu0_rsvd_260") )
				( member ( signalRef "@baseboard_fab2_lib.baseboard_fab2(sch_1):tp_cpu0_rsvd_261") )
				( member ( signalRef "@baseboard_fab2_lib.baseboard_fab2(sch_1):tp_cpu0_rsvd_262") )
				( member ( signalRef "@baseboard_fab2_lib.baseboard_fab2(sch_1):tp_cpu0_rsvd_263") )
				( member ( signalRef "@baseboard_fab2_lib.baseboard_fab2(sch_1):tp_cpu0_rsvd_264") )
				( member ( signalRef "@baseboard_fab2_lib.baseboard_fab2(sch_1):tp_cpu0_rsvd_265") )
				( member ( signalRef "@baseboard_fab2_lib.baseboard_fab2(sch_1):tp_cpu0_rsvd_266") )
				( member ( signalRef "@baseboard_fab2_lib.baseboard_fab2(sch_1):tp_cpu0_rsvd_267") )
				( member ( signalRef "@baseboard_fab2_lib.baseboard_fab2(sch_1):tp_cpu0_rsvd_268") )
				( member ( signalRef "@baseboard_fab2_lib.baseboard_fab2(sch_1):tp_cpu0_rsvd_269") )
				( member ( signalRef "@baseboard_fab2_lib.baseboard_fab2(sch_1):tp_cpu0_rsvd_270") )
				( member ( signalRef "@baseboard_fab2_lib.baseboard_fab2(sch_1):tp_cpu0_rsvd_271") )
				( member ( signalRef "@baseboard_fab2_lib.baseboard_fab2(sch_1):tp_cpu0_rsvd_272") )
				( member ( signalRef "@baseboard_fab2_lib.baseboard_fab2(sch_1):tp_cpu0_rsvd_273") )
				( member ( signalRef "@baseboard_fab2_lib.baseboard_fab2(sch_1):tp_cpu0_rsvd_274") )
				( member ( signalRef "@baseboard_fab2_lib.baseboard_fab2(sch_1):tp_cpu0_rsvd_276") )
				( member ( signalRef "@baseboard_fab2_lib.baseboard_fab2(sch_1):tp_cpu0_rsvd_277") )
				( member ( signalRef "@baseboard_fab2_lib.baseboard_fab2(sch_1):tp_cpu0_rsvd_278") )
				( member ( signalRef "@baseboard_fab2_lib.baseboard_fab2(sch_1):tp_cpu0_rsvd_279") )
				( member ( signalRef "@baseboard_fab2_lib.baseboard_fab2(sch_1):tp_cpu0_rsvd_280") )
				( member ( signalRef "@baseboard_fab2_lib.baseboard_fab2(sch_1):tp_cpu0_rsvd_281") )
				( member ( signalRef "@baseboard_fab2_lib.baseboard_fab2(sch_1):tp_cpu0_rsvd_284") )
				( member ( signalRef "@baseboard_fab2_lib.baseboard_fab2(sch_1):tp_cpu0_rsvd_285") )
				( member ( signalRef "@baseboard_fab2_lib.baseboard_fab2(sch_1):tp_cpu0_rsvd_286") )
				( member ( signalRef "@baseboard_fab2_lib.baseboard_fab2(sch_1):tp_cpu0_rsvd_288") )
				( member ( signalRef "@baseboard_fab2_lib.baseboard_fab2(sch_1):tp_cpu0_rsvd_289") )
				( member ( signalRef "@baseboard_fab2_lib.baseboard_fab2(sch_1):tp_cpu0_rsvd_290") )
				( member ( signalRef "@baseboard_fab2_lib.baseboard_fab2(sch_1):tp_cpu0_rsvd_291") )
				( member ( signalRef "@baseboard_fab2_lib.baseboard_fab2(sch_1):tp_cpu0_rsvd_292") )
				( member ( signalRef "@baseboard_fab2_lib.baseboard_fab2(sch_1):tp_cpu0_rsvd_293") )
				( member ( signalRef "@baseboard_fab2_lib.baseboard_fab2(sch_1):tp_cpu0_rsvd_300") )
				( member ( signalRef "@baseboard_fab2_lib.baseboard_fab2(sch_1):tp_cpu0_socket_id_2") )
				( member ( signalRef "@baseboard_fab2_lib.baseboard_fab2(sch_1):tp_cpu0_rsvd_test_5") )
				( member ( signalRef "@baseboard_fab2_lib.baseboard_fab2(sch_1):tp_cpu0_upi2_rsvd_ca12") )
				( member ( signalRef "@baseboard_fab2_lib.baseboard_fab2(sch_1):tp_cpu0_upi2_rsvd_cb11") )
				( member ( signalRef "@baseboard_fab2_lib.baseboard_fab2(sch_1):tp_cpu0_upi2_rsvd_cc10") )
				( member ( signalRef "@baseboard_fab2_lib.baseboard_fab2(sch_1):tp_cpu0_upi2_rsvd_cc12") )
				( member ( signalRef "@baseboard_fab2_lib.baseboard_fab2(sch_1):tp_cpu0_upi2_rsvd_cd11") )
				( member ( signalRef "@baseboard_fab2_lib.baseboard_fab2(sch_1):tp_cpu0_upi2_rsvd_ce12") )
				( member ( signalRef "@baseboard_fab2_lib.baseboard_fab2(sch_1):tp_cpu0_upi2_rsvd_cf11") )
				( member ( signalRef "@baseboard_fab2_lib.baseboard_fab2(sch_1):tp_cpu0_upi2_rsvd_cf13") )
				( member ( signalRef "@baseboard_fab2_lib.baseboard_fab2(sch_1):tp_cpu0_upi2_rsvd_cg12") )
				( member ( signalRef "@baseboard_fab2_lib.baseboard_fab2(sch_1):tp_cpu0_upi2_rsvd_ch11") )
				( member ( signalRef "@baseboard_fab2_lib.baseboard_fab2(sch_1):tp_cpu0_upi2_rsvd_ch13") )
				( member ( signalRef "@baseboard_fab2_lib.baseboard_fab2(sch_1):tp_cpu0_upi2_rsvd_cj14") )
				( member ( signalRef "@baseboard_fab2_lib.baseboard_fab2(sch_1):tp_cpu0_upi2_rsvd_ck13") )
				( member ( signalRef "@baseboard_fab2_lib.baseboard_fab2(sch_1):led_lan_1_n") )
				( member ( signalRef "@baseboard_fab2_lib.baseboard_fab2(sch_1):led_lan_1_r_n") )
				( member ( signalRef "@baseboard_fab2_lib.baseboard_fab2(sch_1):led_lan_2_n") )
				( member ( signalRef "@baseboard_fab2_lib.baseboard_fab2(sch_1):led_lan_2_r_n") )
				( member ( signalRef "@baseboard_fab2_lib.baseboard_fab2(sch_1):led_postcode_0") )
				( member ( signalRef "@baseboard_fab2_lib.baseboard_fab2(sch_1):led_postcode_0_r") )
				( member ( signalRef "@baseboard_fab2_lib.baseboard_fab2(sch_1):led_postcode_1") )
				( member ( signalRef "@baseboard_fab2_lib.baseboard_fab2(sch_1):led_postcode_1_r") )
				( member ( signalRef "@baseboard_fab2_lib.baseboard_fab2(sch_1):led_postcode_2") )
				( member ( signalRef "@baseboard_fab2_lib.baseboard_fab2(sch_1):led_postcode_2_r") )
				( member ( signalRef "@baseboard_fab2_lib.baseboard_fab2(sch_1):led_postcode_3") )
				( member ( signalRef "@baseboard_fab2_lib.baseboard_fab2(sch_1):led_postcode_3_r") )
				( member ( signalRef "@baseboard_fab2_lib.baseboard_fab2(sch_1):led_postcode_4") )
				( member ( signalRef "@baseboard_fab2_lib.baseboard_fab2(sch_1):led_postcode_4_r") )
				( member ( signalRef "@baseboard_fab2_lib.baseboard_fab2(sch_1):led_postcode_5") )
				( member ( signalRef "@baseboard_fab2_lib.baseboard_fab2(sch_1):led_postcode_5_r") )
				( member ( signalRef "@baseboard_fab2_lib.baseboard_fab2(sch_1):led_postcode_6") )
				( member ( signalRef "@baseboard_fab2_lib.baseboard_fab2(sch_1):led_postcode_6_r") )
				( member ( signalRef "@baseboard_fab2_lib.baseboard_fab2(sch_1):led_postcode_7") )
				( member ( signalRef "@baseboard_fab2_lib.baseboard_fab2(sch_1):led_postcode_7_r") )
				( member ( signalRef "@baseboard_fab2_lib.baseboard_fab2(sch_1):tp_cpu0_rsvd_283") )
				( member ( signalRef "@baseboard_fab2_lib.baseboard_fab2(sch_1):tp_cpu0_rsvd_287") )
				( member ( signalRef "@baseboard_fab2_lib.baseboard_fab2(sch_1):tp_cpu0_rsvd_298") )
				( member ( signalRef "@baseboard_fab2_lib.baseboard_fab2(sch_1):tp_ch_j_dimm_j1_rfu_1") )
				( member ( signalRef "@baseboard_fab2_lib.baseboard_fab2(sch_1):tp_ch_j_dimm_j1_rfu_2") )
				( member ( signalRef "@baseboard_fab2_lib.baseboard_fab2(sch_1):tp_ch_k_dimm_k0_rfu_0") )
				( member ( signalRef "@baseboard_fab2_lib.baseboard_fab2(sch_1):tp_ch_k_dimm_k0_rfu_1") )
				( member ( signalRef "@baseboard_fab2_lib.baseboard_fab2(sch_1):tp_ch_k_dimm_k0_rfu_2") )
				( member ( signalRef "@baseboard_fab2_lib.baseboard_fab2(sch_1):tp_ch_k_dimm0_rfu_0") )
				( member ( signalRef "@baseboard_fab2_lib.baseboard_fab2(sch_1):tp_ch_k_dimm0_rfu_1") )
				( member ( signalRef "@baseboard_fab2_lib.baseboard_fab2(sch_1):tp_ch_k_dimm0_rfu_2") )
				( member ( signalRef "@baseboard_fab2_lib.baseboard_fab2(sch_1):tp_ch_l_dimm_l0_rfu_0") )
				( member ( signalRef "@baseboard_fab2_lib.baseboard_fab2(sch_1):tp_ch_l_dimm_l0_rfu_1") )
				( member ( signalRef "@baseboard_fab2_lib.baseboard_fab2(sch_1):tp_ch_l_dimm_l0_rfu_2") )
				( member ( signalRef "@baseboard_fab2_lib.baseboard_fab2(sch_1):tp_ch_l_dimm0_rfu_0") )
				( member ( signalRef "@baseboard_fab2_lib.baseboard_fab2(sch_1):tp_ch_l_dimm0_rfu_1") )
				( member ( signalRef "@baseboard_fab2_lib.baseboard_fab2(sch_1):tp_ch_l_dimm0_rfu_2") )
				( member ( signalRef "@baseboard_fab2_lib.baseboard_fab2(sch_1):tp_ch_m_dimm_m0_rfu_0") )
				( member ( signalRef "@baseboard_fab2_lib.baseboard_fab2(sch_1):tp_ch_m_dimm_m0_rfu_1") )
				( member ( signalRef "@baseboard_fab2_lib.baseboard_fab2(sch_1):tp_ch_m_dimm_m0_rfu_2") )
				( member ( signalRef "@baseboard_fab2_lib.baseboard_fab2(sch_1):tp_ch_m_dimm_m1_rfu_0") )
				( member ( signalRef "@baseboard_fab2_lib.baseboard_fab2(sch_1):tp_ch_m_dimm_m1_rfu_1") )
				( member ( signalRef "@baseboard_fab2_lib.baseboard_fab2(sch_1):tp_ch_m_dimm_m1_rfu_2") )
				( member ( signalRef "@baseboard_fab2_lib.baseboard_fab2(sch_1):a_extclkp") )
				( member ( signalRef "@baseboard_fab2_lib.baseboard_fab2(sch_1):a_p3v3_scaled") )
				( member ( signalRef "@baseboard_fab2_lib.baseboard_fab2(sch_1):tp_cpu0_rsvd_303") )
				( member ( signalRef "@baseboard_fab2_lib.baseboard_fab2(sch_1):tp_cpu0_rsvd_299") )
				( member ( signalRef "@baseboard_fab2_lib.baseboard_fab2(sch_1):tp_clk_96m_ckmng_n") )
				( member ( signalRef "@baseboard_fab2_lib.baseboard_fab2(sch_1):tp_clk_96m_ckmng_p") )
				( member ( signalRef "@baseboard_fab2_lib.baseboard_fab2(sch_1):tp_clk_100m_nsscc1_dn") )
				( member ( signalRef "@baseboard_fab2_lib.baseboard_fab2(sch_1):tp_clk_100m_nsscc1_dp") )
				( member ( signalRef "@baseboard_fab2_lib.baseboard_fab2(sch_1):tp_clk_100m_r_dn") )
				( member ( signalRef "@baseboard_fab2_lib.baseboard_fab2(sch_1):tp_clk_100m_r_dp") )
				( member ( signalRef "@baseboard_fab2_lib.baseboard_fab2(sch_1):a_p3v3_stby_scaled") )
				( member ( signalRef "@baseboard_fab2_lib.baseboard_fab2(sch_1):a_p5v_scaled") )
				( member ( signalRef "@baseboard_fab2_lib.baseboard_fab2(sch_1):a_p5v_stby_scaled") )
				( member ( signalRef "@baseboard_fab2_lib.baseboard_fab2(sch_1):a_p12v_stby_scaled") )
				( member ( signalRef "@baseboard_fab2_lib.baseboard_fab2(sch_1):tp_clk_125m") )
				( member ( signalRef "@baseboard_fab2_lib.baseboard_fab2(sch_1):tp_clk_125m_bmca") )
				( member ( signalRef "@baseboard_fab2_lib.baseboard_fab2(sch_1):tp_clk5_50m_ckmng") )
				( member ( signalRef "@baseboard_fab2_lib.baseboard_fab2(sch_1):tp_usb3_p05_txp") )
				( member ( signalRef "@baseboard_fab2_lib.baseboard_fab2(sch_1):tp_cpu_pch_trigger_in") )
				( member ( signalRef "@baseboard_fab2_lib.baseboard_fab2(sch_1):tp_cpu_pch_trigger_out") )
				( member ( signalRef "@baseboard_fab2_lib.baseboard_fab2(sch_1):tp_cpu0_pe_hp_scl") )
				( member ( signalRef "@baseboard_fab2_lib.baseboard_fab2(sch_1):tp_cpu0_pe_hp_sda") )
				( member ( signalRef "@baseboard_fab2_lib.baseboard_fab2(sch_1):tp_cpu0_procdis_g_n") )
				( member ( signalRef "@baseboard_fab2_lib.baseboard_fab2(sch_1):tp_cpu0_rsvd_189") )
				( member ( signalRef "@baseboard_fab2_lib.baseboard_fab2(sch_1):tp_cpu0_rsvd_186") )
				( member ( signalRef "@baseboard_fab2_lib.baseboard_fab2(sch_1):tp_cpu0_rsvd_190") )
				( member ( signalRef "@baseboard_fab2_lib.baseboard_fab2(sch_1):tp_cpu1_rsvd_298") )
				( member ( signalRef "@baseboard_fab2_lib.baseboard_fab2(sch_1):tp_cpu0_rsvd_194") )
				( member ( signalRef "@baseboard_fab2_lib.baseboard_fab2(sch_1):tp_cpu0_rsvd_184") )
				( member ( signalRef "@baseboard_fab2_lib.baseboard_fab2(sch_1):tp_cpu1_rsvd_299") )
				( member ( signalRef "@baseboard_fab2_lib.baseboard_fab2(sch_1):tp_cpu1_rsvd_303") )
				( member ( signalRef "@baseboard_fab2_lib.baseboard_fab2(sch_1):tp_cpu1_rsvd_304") )
				( member ( signalRef "@baseboard_fab2_lib.baseboard_fab2(sch_1):pu_pirom_cpu1_addr0") )
				( member ( signalRef "@baseboard_fab2_lib.baseboard_fab2(sch_1):tp_cpu0_rsvd_199") )
				( member ( signalRef "@baseboard_fab2_lib.baseboard_fab2(sch_1):tp_cpu0_rsvd_198") )
				( member ( signalRef "@baseboard_fab2_lib.baseboard_fab2(sch_1):tp_jtag_mcp_io8_rsvd") )
				( member ( signalRef "@baseboard_fab2_lib.baseboard_fab2(sch_1):tp_usb3_p05_rxp") )
				( member ( signalRef "@baseboard_fab2_lib.baseboard_fab2(sch_1):vr_pvccin_cpu1_ph2_ocset") )
				( member ( signalRef "@baseboard_fab2_lib.baseboard_fab2(sch_1):tp_usb3_p05_txn") )
				( member ( signalRef "@baseboard_fab2_lib.baseboard_fab2(sch_1):vr_pvccin_cpu1_ph3_ocset") )
				( member ( signalRef "@baseboard_fab2_lib.baseboard_fab2(sch_1):tp_cpu0_rsvd_304") )
				( member ( signalRef "@baseboard_fab2_lib.baseboard_fab2(sch_1):a_pvnn_stby_pch_sensor") )
				( member ( signalRef "@baseboard_fab2_lib.baseboard_fab2(sch_1):a_p1v05_stby_pch_sensor") )
				( member ( signalRef "@baseboard_fab2_lib.baseboard_fab2(sch_1):a_p3v_bat_r") )
				( member ( signalRef "@baseboard_fab2_lib.baseboard_fab2(sch_1):a_p3v_bat_scaled") )
				( member ( signalRef "@baseboard_fab2_lib.baseboard_fab2(sch_1):tp_cpu0_test_6") )
				( member ( signalRef "@baseboard_fab2_lib.baseboard_fab2(sch_1):tp_cpu1_rsvd_275") )
				( member ( signalRef "@baseboard_fab2_lib.baseboard_fab2(sch_1):tp_cpu0_rsvd_204") )
				( member ( signalRef "@baseboard_fab2_lib.baseboard_fab2(sch_1):tp_cpu0_rsvd_205") )
				( member ( signalRef "@baseboard_fab2_lib.baseboard_fab2(sch_1):tp_cpu1_rsvd_282") )
				( member ( signalRef "@baseboard_fab2_lib.baseboard_fab2(sch_1):tp_cpu0_rsvd_208") )
				( member ( signalRef "@baseboard_fab2_lib.baseboard_fab2(sch_1):a_extclkn") )
				( member ( signalRef "@baseboard_fab2_lib.baseboard_fab2(sch_1):tp_cpu0_rsvd_210") )
				( member ( signalRef "@baseboard_fab2_lib.baseboard_fab2(sch_1):tp_cpu0_rsvd_211") )
				( member ( signalRef "@baseboard_fab2_lib.baseboard_fab2(sch_1):tp_cpu0_rsvd_212") )
				( member ( signalRef "@baseboard_fab2_lib.baseboard_fab2(sch_1):tp_cpu0_rsvd_214") )
				( member ( signalRef "@baseboard_fab2_lib.baseboard_fab2(sch_1):tp_cpu1_rsvd_283") )
				( member ( signalRef "@baseboard_fab2_lib.baseboard_fab2(sch_1):tp_cpu0_rsvd_216") )
				( member ( signalRef "@baseboard_fab2_lib.baseboard_fab2(sch_1):tp_cpu0_rsvd_217") )
				( member ( signalRef "@baseboard_fab2_lib.baseboard_fab2(sch_1):tp_cpu0_rsvd_218") )
				( member ( signalRef "@baseboard_fab2_lib.baseboard_fab2(sch_1):tp_cpu0_rsvd_219") )
				( member ( signalRef "@baseboard_fab2_lib.baseboard_fab2(sch_1):tp_cpu1_rsvd_287") )
				( member ( signalRef "@baseboard_fab2_lib.baseboard_fab2(sch_1):tp_cpu0_rsvd_222") )
				( member ( signalRef "@baseboard_fab2_lib.baseboard_fab2(sch_1):tp_cpu0_rsvd_223") )
				( member ( signalRef "@baseboard_fab2_lib.baseboard_fab2(sch_1):tp_cpu0_rsvd_224") )
				( member ( signalRef "@baseboard_fab2_lib.baseboard_fab2(sch_1):tp_cpu0_rsvd_225") )
				( member ( signalRef "@baseboard_fab2_lib.baseboard_fab2(sch_1):tp_cpu0_rsvd_226") )
				( member ( signalRef "@baseboard_fab2_lib.baseboard_fab2(sch_1):tp_cpu0_rsvd_227") )
				( member ( signalRef "@baseboard_fab2_lib.baseboard_fab2(sch_1):tp_cpu0_rsvd_228") )
				( member ( signalRef "@baseboard_fab2_lib.baseboard_fab2(sch_1):tp_cpu0_rsvd_229") )
				( member ( signalRef "@baseboard_fab2_lib.baseboard_fab2(sch_1):tp_cpu0_rsvd_230") )
				( member ( signalRef "@baseboard_fab2_lib.baseboard_fab2(sch_1):tp_cpu0_rsvd_231") )
				( member ( signalRef "@baseboard_fab2_lib.baseboard_fab2(sch_1):tp_cpu0_rsvd_232") )
				( member ( signalRef "@baseboard_fab2_lib.baseboard_fab2(sch_1):tp_cpu0_rsvd_233") )
				( member ( signalRef "@baseboard_fab2_lib.baseboard_fab2(sch_1):tp_cpu0_rsvd_234") )
				( member ( signalRef "@baseboard_fab2_lib.baseboard_fab2(sch_1):tp_cpu0_rsvd_235") )
				( member ( signalRef "@baseboard_fab2_lib.baseboard_fab2(sch_1):tp_cpu0_rsvd_236") )
				( member ( signalRef "@baseboard_fab2_lib.baseboard_fab2(sch_1):tp_cpu0_rsvd_237") )
				( member ( signalRef "@baseboard_fab2_lib.baseboard_fab2(sch_1):tp_cpu0_rsvd_238") )
				( member ( signalRef "@baseboard_fab2_lib.baseboard_fab2(sch_1):tp_cpu0_rsvd_239") )
				( member ( signalRef "@baseboard_fab2_lib.baseboard_fab2(sch_1):tp_usb3_p06_rxn") )
				( member ( signalRef "@baseboard_fab2_lib.baseboard_fab2(sch_1):tp_usb3_p06_rxp") )
				( member ( signalRef "@baseboard_fab2_lib.baseboard_fab2(sch_1):tp_usb3_p06_txn") )
				( member ( signalRef "@baseboard_fab2_lib.baseboard_fab2(sch_1):tp_usb3_p06_txp") )
				( member ( signalRef "@baseboard_fab2_lib.baseboard_fab2(sch_1):p3v3_stby_bmc_adcvrefn") )
				( member ( signalRef "@baseboard_fab2_lib.baseboard_fab2(sch_1):p3v3_stby_bmc_adcvrefp") )
				( member ( signalRef "@baseboard_fab2_lib.baseboard_fab2(sch_1):nc_pvccin_cpu1_ph4_p31") )
				( member ( signalRef "@baseboard_fab2_lib.baseboard_fab2(sch_1):nc_pvccin_cpu1_ph5_p31") )
				( member ( signalRef "@baseboard_fab2_lib.baseboard_fab2(sch_1):nc_pvsa_cpu1_p31") )
				( member ( signalRef "@baseboard_fab2_lib.baseboard_fab2(sch_1):led_gbe_p3_1") )
				( member ( signalRef "@baseboard_fab2_lib.baseboard_fab2(sch_1):p0v7_gtl2104_vref_0") )
				( member ( signalRef "@baseboard_fab2_lib.baseboard_fab2(sch_1):a_pg_p5v") )
				( member ( signalRef "@baseboard_fab2_lib.baseboard_fab2(sch_1):a_pg_p12v_main") )
				( member ( signalRef "@baseboard_fab2_lib.baseboard_fab2(sch_1):p0v7_gtl2104_vref_1") )
				( member ( signalRef "@baseboard_fab2_lib.baseboard_fab2(sch_1):p0v7_gtl2104_5_vref") )
				( member ( signalRef "@baseboard_fab2_lib.baseboard_fab2(sch_1):tp_bios_recover_boot") )
				( member ( signalRef "@baseboard_fab2_lib.baseboard_fab2(sch_1):tp_cd_hfi1_cpu1_int_n") )
				( member ( signalRef "@baseboard_fab2_lib.baseboard_fab2(sch_1):tp_cd_hfi1_cpu1_i2cdat") )
				( member ( signalRef "@baseboard_fab2_lib.baseboard_fab2(sch_1):tp_cd_hfi1_cpu1_i2clk") )
				( member ( signalRef "@baseboard_fab2_lib.baseboard_fab2(sch_1):tp_cd_hfi1_cpu1_led_n") )
				( member ( signalRef "@baseboard_fab2_lib.baseboard_fab2(sch_1):tp_cd_hfi1_cpu1_modprst_n") )
				( member ( signalRef "@baseboard_fab2_lib.baseboard_fab2(sch_1):tp_cd_hfi1_cpu1_reset_n") )
				( member ( signalRef "@baseboard_fab2_lib.baseboard_fab2(sch_1):tp_ch_a_dimm_a0_rfu_0") )
				( member ( signalRef "@baseboard_fab2_lib.baseboard_fab2(sch_1):tp_ch_a_dimm_a0_rfu_1") )
				( member ( signalRef "@baseboard_fab2_lib.baseboard_fab2(sch_1):tp_ch_a_dimm_a0_rfu_2") )
				( member ( signalRef "@baseboard_fab2_lib.baseboard_fab2(sch_1):tp_ch_a_dimm_a1_rfu_0") )
				( member ( signalRef "@baseboard_fab2_lib.baseboard_fab2(sch_1):tp_ch_a_dimm_a1_rfu_1") )
				( member ( signalRef "@baseboard_fab2_lib.baseboard_fab2(sch_1):tp_ch_a_dimm_a1_rfu_2") )
				( member ( signalRef "@baseboard_fab2_lib.baseboard_fab2(sch_1):tp_ch_b_dimm_b0_rfu_0") )
				( member ( signalRef "@baseboard_fab2_lib.baseboard_fab2(sch_1):tp_ch_b_dimm_b0_rfu_1") )
				( member ( signalRef "@baseboard_fab2_lib.baseboard_fab2(sch_1):tp_ch_b_dimm_b0_rfu_2") )
				( member ( signalRef "@baseboard_fab2_lib.baseboard_fab2(sch_1):tp_ch_b_dimm_b1_rfu_0") )
				( member ( signalRef "@baseboard_fab2_lib.baseboard_fab2(sch_1):tp_ch_b_dimm_b1_rfu_1") )
				( member ( signalRef "@baseboard_fab2_lib.baseboard_fab2(sch_1):tp_ch_b_dimm_b1_rfu_2") )
				( member ( signalRef "@baseboard_fab2_lib.baseboard_fab2(sch_1):tp_ch_c_dimm_c0_rfu_0") )
				( member ( signalRef "@baseboard_fab2_lib.baseboard_fab2(sch_1):tp_ch_c_dimm_c0_rfu_1") )
				( member ( signalRef "@baseboard_fab2_lib.baseboard_fab2(sch_1):tp_ch_c_dimm_c0_rfu_2") )
				( member ( signalRef "@baseboard_fab2_lib.baseboard_fab2(sch_1):tp_ch_c_dimm_c1_rfu_0") )
				( member ( signalRef "@baseboard_fab2_lib.baseboard_fab2(sch_1):tp_ch_c_dimm_c1_rfu_1") )
				( member ( signalRef "@baseboard_fab2_lib.baseboard_fab2(sch_1):tp_ch_c_dimm_c1_rfu_2") )
				( member ( signalRef "@baseboard_fab2_lib.baseboard_fab2(sch_1):tp_ch_d_dimm_d0_rfu_0") )
				( member ( signalRef "@baseboard_fab2_lib.baseboard_fab2(sch_1):tp_ch_d_dimm_d0_rfu_1") )
				( member ( signalRef "@baseboard_fab2_lib.baseboard_fab2(sch_1):tp_ch_d_dimm_d0_rfu_2") )
				( member ( signalRef "@baseboard_fab2_lib.baseboard_fab2(sch_1):tp_ch_d_dimm_d1_rfu_0") )
				( member ( signalRef "@baseboard_fab2_lib.baseboard_fab2(sch_1):tp_ch_d_dimm_d1_rfu_1") )
				( member ( signalRef "@baseboard_fab2_lib.baseboard_fab2(sch_1):tp_ch_d_dimm_d1_rfu_2") )
				( member ( signalRef "@baseboard_fab2_lib.baseboard_fab2(sch_1):tp_ch_e_dimm_e0_rfu_0") )
				( member ( signalRef "@baseboard_fab2_lib.baseboard_fab2(sch_1):tp_ch_e_dimm_e0_rfu_1") )
				( member ( signalRef "@baseboard_fab2_lib.baseboard_fab2(sch_1):tp_ch_e_dimm_e0_rfu_2") )
				( member ( signalRef "@baseboard_fab2_lib.baseboard_fab2(sch_1):tp_ch_e_dimm_e1_rfu_0") )
				( member ( signalRef "@baseboard_fab2_lib.baseboard_fab2(sch_1):tp_ch_e_dimm_e1_rfu_1") )
				( member ( signalRef "@baseboard_fab2_lib.baseboard_fab2(sch_1):tp_ch_e_dimm_e1_rfu_2") )
				( member ( signalRef "@baseboard_fab2_lib.baseboard_fab2(sch_1):tp_ch_f_dimm_f0_rfu_0") )
				( member ( signalRef "@baseboard_fab2_lib.baseboard_fab2(sch_1):tp_ch_f_dimm_f0_rfu_1") )
				( member ( signalRef "@baseboard_fab2_lib.baseboard_fab2(sch_1):tp_ch_f_dimm_f0_rfu_2") )
				( member ( signalRef "@baseboard_fab2_lib.baseboard_fab2(sch_1):tp_ch_f_dimm_f1_rfu_0") )
				( member ( signalRef "@baseboard_fab2_lib.baseboard_fab2(sch_1):tp_ch_f_dimm_f1_rfu_1") )
				( member ( signalRef "@baseboard_fab2_lib.baseboard_fab2(sch_1):tp_ch_f_dimm_f1_rfu_2") )
				( member ( signalRef "@baseboard_fab2_lib.baseboard_fab2(sch_1):tp_ch_g_dimm_g0_rfu_0") )
				( member ( signalRef "@baseboard_fab2_lib.baseboard_fab2(sch_1):tp_ch_g_dimm_g0_rfu_1") )
				( member ( signalRef "@baseboard_fab2_lib.baseboard_fab2(sch_1):tp_ch_g_dimm_g0_rfu_2") )
				( member ( signalRef "@baseboard_fab2_lib.baseboard_fab2(sch_1):tp_ch_g_dimm0_rfu_0") )
				( member ( signalRef "@baseboard_fab2_lib.baseboard_fab2(sch_1):tp_ch_g_dimm0_rfu_1") )
				( member ( signalRef "@baseboard_fab2_lib.baseboard_fab2(sch_1):tp_ch_g_dimm0_rfu_2") )
				( member ( signalRef "@baseboard_fab2_lib.baseboard_fab2(sch_1):tp_ch_h_dimm_h0_rfu_0") )
				( member ( signalRef "@baseboard_fab2_lib.baseboard_fab2(sch_1):tp_ch_h_dimm_h0_rfu_1") )
				( member ( signalRef "@baseboard_fab2_lib.baseboard_fab2(sch_1):tp_ch_h_dimm_h0_rfu_2") )
				( member ( signalRef "@baseboard_fab2_lib.baseboard_fab2(sch_1):tp_ch_h_dimm0_rfu_0") )
				( member ( signalRef "@baseboard_fab2_lib.baseboard_fab2(sch_1):tp_ch_h_dimm0_rfu_1") )
				( member ( signalRef "@baseboard_fab2_lib.baseboard_fab2(sch_1):tp_ch_h_dimm0_rfu_2") )
				( member ( signalRef "@baseboard_fab2_lib.baseboard_fab2(sch_1):tp_ch_j_dimm_j0_rfu_0") )
				( member ( signalRef "@baseboard_fab2_lib.baseboard_fab2(sch_1):tp_ch_j_dimm_j0_rfu_1") )
				( member ( signalRef "@baseboard_fab2_lib.baseboard_fab2(sch_1):tp_ch_j_dimm_j0_rfu_2") )
				( member ( signalRef "@baseboard_fab2_lib.baseboard_fab2(sch_1):tp_ch_j_dimm_j1_rfu_0") )
				( member ( electricalNetRef "@crescent_city_bb_fab1_lib.crescent_city_bb_fab1(sch_1):fm_bmc_enable_n") )
				( member ( electricalNetRef "@baseboard_fab2_lib.baseboard_fab2(sch_1):fm_cpu_err0_lvt3_k_n") )
				( member ( electricalNetRef "@crescent_city_bb_fab1_lib.crescent_city_bb_fab1(sch_1):a_hsc_gate1_r") )
				( member ( electricalNetRef "@crescent_city_bb_fab1_lib.crescent_city_bb_fab1(sch_1):a_hsc_hsn") )
				( member ( electricalNetRef "@crescent_city_bb_fab1_lib.crescent_city_bb_fab1(sch_1):a_hsc_hsp") )
				( member ( electricalNetRef "@crescent_city_bb_fab1_lib.crescent_city_bb_fab1(sch_1):a_hsc_csout") )
				( member ( electricalNetRef "@crescent_city_bb_fab1_lib.crescent_city_bb_fab1(sch_1):a_hsc_timer") )
				( member ( electricalNetRef "@crescent_city_bb_fab1_lib.crescent_city_bb_fab1(sch_1):fm_all_wake_n") )
				( member ( electricalNetRef "@crescent_city_bb_fab1_lib.crescent_city_bb_fab1(sch_1):fm_adr_mode_sel") )
				( member ( electricalNetRef "@crescent_city_bb_fab1_lib.crescent_city_bb_fab1(sch_1):fm_bios_top_swap_spkr") )
				( member ( electricalNetRef "@crescent_city_bb_fab1_lib.crescent_city_bb_fab1(sch_1):fm_adr_complete_r") )
				( member ( electricalNetRef "@crescent_city_bb_fab1_lib.crescent_city_bb_fab1(sch_1):fm_adr_smi_gpio_n") )
				( member ( electricalNetRef "@crescent_city_bb_fab1_lib.crescent_city_bb_fab1(sch_1):fm_bmc_nmi_n") )
				( member ( electricalNetRef "@crescent_city_bb_fab1_lib.crescent_city_bb_fab1(sch_1):fm_cpu_caterr_dly_lvt3_n") )
				( member ( electricalNetRef "@crescent_city_bb_fab1_lib.crescent_city_bb_fab1(sch_1):fm_cpld_adr_trigger_n") )
				( member ( electricalNetRef "@crescent_city_bb_fab1_lib.crescent_city_bb_fab1(sch_1):fm_bmc_sys_throttle_r_n") )
				( member ( electricalNetRef "@crescent_city_bb_fab1_lib.crescent_city_bb_fab1(sch_1):fm_bmc_onctl_r_n") )
				( member ( electricalNetRef "@crescent_city_bb_fab1_lib.crescent_city_bb_fab1(sch_1):fm_cpu_caterr_lvt3_n") )
				( member ( electricalNetRef "@crescent_city_bb_fab1_lib.crescent_city_bb_fab1(sch_1):fm_cpu_err2_lvt3_n") )
				( member ( electricalNetRef "@crescent_city_bb_fab1_lib.crescent_city_bb_fab1(sch_1):fm_cpu_msmi_lvt3_n") )
				( member ( electricalNetRef "@baseboard_fab2_lib.baseboard_fab2(sch_1):vr_pvccio_cpu0_en") )
				( member ( electricalNetRef "@crescent_city_bb_fab1_lib.crescent_city_bb_fab1(sch_1):fm_cpu0_fivr_fault_lvt3") )
				( member ( electricalNetRef "@crescent_city_bb_fab1_lib.crescent_city_bb_fab1(sch_1):fm_cpu0_fivr_fault_lvt3_n") )
				( member ( electricalNetRef "@baseboard_fab2_lib.baseboard_fab2(sch_1):fm_cpu0_prochot_lvt3_k_n") )
				( member ( electricalNetRef "@crescent_city_bb_fab1_lib.crescent_city_bb_fab1(sch_1):fm_cpu1_fivr_fault_lvt3_n") )
				( member ( electricalNetRef "@crescent_city_bb_fab1_lib.crescent_city_bb_fab1(sch_1):fm_cpu0_thermtrip_lvt3_n") )
				( member ( electricalNetRef "@crescent_city_bb_fab1_lib.crescent_city_bb_fab1(sch_1):fm_cpu1_fivr_fault_lvt3") )
				( member ( electricalNetRef "@baseboard_fab2_lib.baseboard_fab2(sch_1):fm_cpu1_prochot_lvt3_k_n") )
				( member ( electricalNetRef "@crescent_city_bb_fab1_lib.crescent_city_bb_fab1(sch_1):fm_cpu1_thermtrip_lvt3_n") )
				( member ( electricalNetRef "@crescent_city_bb_fab1_lib.crescent_city_bb_fab1(sch_1):fm_ctnr_ps_on") )
				( member ( electricalNetRef "@crescent_city_bb_fab1_lib.crescent_city_bb_fab1(sch_1):fm_db_uart_sel0_n") )
				( member ( electricalNetRef "@crescent_city_bb_fab1_lib.crescent_city_bb_fab1(sch_1):fm_flash_desc_override") )
				( member ( electricalNetRef "@crescent_city_bb_fab1_lib.crescent_city_bb_fab1(sch_1):fm_m2_det_lvc3") )
				( member ( electricalNetRef "@crescent_city_bb_fab1_lib.crescent_city_bb_fab1(sch_1):fm_pch_pld_data") )
				( member ( electricalNetRef "@crescent_city_bb_fab1_lib.crescent_city_bb_fab1(sch_1):fm_pch_sata_raid_key") )
				( member ( electricalNetRef "@crescent_city_bb_fab1_lib.crescent_city_bb_fab1(sch_1):fm_pvpp_pvddq_cpu0_en_abc") )
				( member ( electricalNetRef "@crescent_city_bb_fab1_lib.crescent_city_bb_fab1(sch_1):fm_pvpp_pvddq_cpu1_en_ghj") )
				( member ( electricalNetRef "@crescent_city_bb_fab1_lib.crescent_city_bb_fab1(sch_1):vr_pvddq_def_vren") )
				( member ( electricalNetRef "@crescent_city_bb_fab1_lib.crescent_city_bb_fab1(sch_1):fp_pwr_btn_r1_n") )
				( member ( electricalNetRef "@crescent_city_bb_fab1_lib.crescent_city_bb_fab1(sch_1):vr_pvddq_ghj_vren") )
				( member ( electricalNetRef "@crescent_city_bb_fab1_lib.crescent_city_bb_fab1(sch_1):fm_thermtrip_dly_r") )
				( member ( electricalNetRef "@crescent_city_bb_fab1_lib.crescent_city_bb_fab1(sch_1):led_lan_0_n") )
				( member ( electricalNetRef "@crescent_city_bb_fab1_lib.crescent_city_bb_fab1(sch_1):fm_pwr_btn_n") )
				( member ( electricalNetRef "@crescent_city_bb_fab1_lib.crescent_city_bb_fab1(sch_1):fp_nmi_btn_n") )
				( member ( electricalNetRef "@crescent_city_bb_fab1_lib.crescent_city_bb_fab1(sch_1):vr_pvddq_klm_vren") )
				( member ( electricalNetRef "@crescent_city_bb_fab1_lib.crescent_city_bb_fab1(sch_1):fp_rst_btn_r_n") )
				( member ( electricalNetRef "@crescent_city_bb_fab1_lib.crescent_city_bb_fab1(sch_1):fm_throttle_r_n") )
				( member ( electricalNetRef "@crescent_city_bb_fab1_lib.crescent_city_bb_fab1(sch_1):fm_1gb_lom_disable_n") )
				( member ( electricalNetRef "@crescent_city_bb_fab1_lib.crescent_city_bb_fab1(sch_1):vr_pvddq_abc_vren") )
				( member ( electricalNetRef "@crescent_city_bb_fab1_lib.crescent_city_bb_fab1(sch_1):fp_nmi_btn_out_n") )
				( member ( electricalNetRef "@crescent_city_bb_fab1_lib.crescent_city_bb_fab1(sch_1):led_lan_1_n") )
				( member ( electricalNetRef "@crescent_city_bb_fab1_lib.crescent_city_bb_fab1(sch_1):led_lan_2_n") )
				( member ( electricalNetRef "@crescent_city_bb_fab1_lib.crescent_city_bb_fab1(sch_1):led_postcode_0") )
				( member ( electricalNetRef "@crescent_city_bb_fab1_lib.crescent_city_bb_fab1(sch_1):led_postcode_1") )
				( member ( electricalNetRef "@crescent_city_bb_fab1_lib.crescent_city_bb_fab1(sch_1):led_postcode_2") )
				( member ( electricalNetRef "@crescent_city_bb_fab1_lib.crescent_city_bb_fab1(sch_1):led_postcode_3") )
				( member ( electricalNetRef "@crescent_city_bb_fab1_lib.crescent_city_bb_fab1(sch_1):led_postcode_4") )
				( member ( electricalNetRef "@crescent_city_bb_fab1_lib.crescent_city_bb_fab1(sch_1):led_postcode_5") )
				( member ( electricalNetRef "@crescent_city_bb_fab1_lib.crescent_city_bb_fab1(sch_1):led_postcode_6") )
				( member ( electricalNetRef "@crescent_city_bb_fab1_lib.crescent_city_bb_fab1(sch_1):led_postcode_7") )
				( member ( electricalNetRef "@crescent_city_bb_fab1_lib.crescent_city_bb_fab1(sch_1):fm_pch_pwrbtn_n") )
				( objectStatus "SNCLS_MISC_INTEL_STATIC" )
			)
			( netClass "@crescent_city_bb_fab1_lib.crescent_city_bb_fab1(sch_1):\SNCLS_RMII_TX\"
				( memberType ( signal ) )
				( spacingCSetRef "@sapphirecity_baseboard_lib.sapphirecity_baseboard(sch_1):\8MIL_SL_10MIL_MS\" )
				( objectFlag fObjectSpacing )
				( objectFlag fObjectSameNetSpacing )
				( member ( signalRef "@baseboard_fab2_lib.baseboard_fab2(sch_1):rmii_bmc_pch_sprngvlle_txd0") )
				( member ( signalRef "@baseboard_fab2_lib.baseboard_fab2(sch_1):rmii_bmc_pch_sprngvlle_txd0_r") )
				( member ( signalRef "@baseboard_fab2_lib.baseboard_fab2(sch_1):rmii_bmc_pch_sprngvlle_txd1") )
				( member ( signalRef "@baseboard_fab2_lib.baseboard_fab2(sch_1):rmii_bmc_pch_sprngvlle_txd1_r") )
				( member ( signalRef "@baseboard_fab2_lib.baseboard_fab2(sch_1):rmii_bmc_pch_sprngvlle_txen") )
				( member ( signalRef "@baseboard_fab2_lib.baseboard_fab2(sch_1):rmii_bmc_sprngvlle_txen_r") )
				( member ( signalRef "@baseboard_fab2_lib.baseboard_fab2(sch_1):rmii_bmc_ocp_txen") )
				( member ( signalRef "@baseboard_fab2_lib.baseboard_fab2(sch_1):rmii_bmc_ocp_txen_r") )
				( member ( signalRef "@baseboard_fab2_lib.baseboard_fab2(sch_1):rmii_bmc_ocp_txd0") )
				( member ( signalRef "@baseboard_fab2_lib.baseboard_fab2(sch_1):rmii_bmc_ocp_txd0_r") )
				( member ( signalRef "@baseboard_fab2_lib.baseboard_fab2(sch_1):rmii_bmc_ocp_txd1") )
				( member ( signalRef "@baseboard_fab2_lib.baseboard_fab2(sch_1):rmii_bmc_ocp_txd1_r") )
				( member ( electricalNetRef "@crescent_city_bb_fab1_lib.crescent_city_bb_fab1(sch_1):rmii_bmc_ocp_txd0") )
				( member ( electricalNetRef "@crescent_city_bb_fab1_lib.crescent_city_bb_fab1(sch_1):rmii_bmc_ocp_txd1") )
				( member ( electricalNetRef "@crescent_city_bb_fab1_lib.crescent_city_bb_fab1(sch_1):rmii_bmc_ocp_txen") )
				( member ( electricalNetRef "@crescent_city_bb_fab1_lib.crescent_city_bb_fab1(sch_1):rmii_bmc_pch_sprngvlle_txd0") )
				( member ( electricalNetRef "@crescent_city_bb_fab1_lib.crescent_city_bb_fab1(sch_1):rmii_bmc_pch_sprngvlle_txd1") )
				( member ( electricalNetRef "@crescent_city_bb_fab1_lib.crescent_city_bb_fab1(sch_1):rmii_bmc_pch_sprngvlle_txen") )
				( objectStatus "SNCLS_RMII_TX" )
			)
			( netClass "@crescent_city_bb_fab1_lib.crescent_city_bb_fab1(sch_1):\UPI_9H\"
				( memberType ( signal ) )
				( objectFlag fObjectPhysical )
				( objectFlag fObjectSpacing )
				( objectFlag fObjectSameNetSpacing )
				( objectStatus "UPI_9H" )
			)
			( netClass "@crescent_city_bb_fab1_lib.crescent_city_bb_fab1(sch_1):\SNCLS_DDR4_VREF\"
				( memberType ( signal ) )
				( spacingCSetRef "@sapphirecity_baseboard_lib.sapphirecity_baseboard(sch_1):\20_MILS\" )
				( objectFlag fObjectSpacing )
				( objectFlag fObjectSameNetSpacing )
				( member ( signalRef "@baseboard_fab2_lib.baseboard_fab2(sch_1):m_a_cpu_vref") )
				( member ( signalRef "@baseboard_fab2_lib.baseboard_fab2(sch_1):m_b_cpu_vref") )
				( member ( signalRef "@baseboard_fab2_lib.baseboard_fab2(sch_1):m_c_cpu_vref") )
				( member ( signalRef "@baseboard_fab2_lib.baseboard_fab2(sch_1):m_d_cpu_vref") )
				( member ( signalRef "@baseboard_fab2_lib.baseboard_fab2(sch_1):m_e_cpu_vref") )
				( member ( signalRef "@baseboard_fab2_lib.baseboard_fab2(sch_1):m_f_cpu_vref") )
				( member ( signalRef "@baseboard_fab2_lib.baseboard_fab2(sch_1):m_g_cpu_vref") )
				( member ( signalRef "@baseboard_fab2_lib.baseboard_fab2(sch_1):m_h_cpu_vref") )
				( member ( signalRef "@baseboard_fab2_lib.baseboard_fab2(sch_1):m_j_cpu_vref") )
				( member ( signalRef "@baseboard_fab2_lib.baseboard_fab2(sch_1):m_k_cpu_vref") )
				( member ( signalRef "@baseboard_fab2_lib.baseboard_fab2(sch_1):m_l_cpu_vref") )
				( member ( signalRef "@baseboard_fab2_lib.baseboard_fab2(sch_1):m_m_cpu_vref") )
				( member ( signalRef "@baseboard_fab2_lib.baseboard_fab2(sch_1):m_bmc_ddr3_mvref") )
				( member ( signalRef "@baseboard_fab2_lib.baseboard_fab2(sch_1):m_b_vref") )
				( member ( signalRef "@baseboard_fab2_lib.baseboard_fab2(sch_1):m_c_vref") )
				( member ( signalRef "@baseboard_fab2_lib.baseboard_fab2(sch_1):m_d_vref") )
				( member ( signalRef "@baseboard_fab2_lib.baseboard_fab2(sch_1):m_e_vref") )
				( member ( signalRef "@baseboard_fab2_lib.baseboard_fab2(sch_1):m_f_vref") )
				( member ( signalRef "@baseboard_fab2_lib.baseboard_fab2(sch_1):m_g_vref") )
				( member ( signalRef "@baseboard_fab2_lib.baseboard_fab2(sch_1):m_h_vref") )
				( member ( signalRef "@baseboard_fab2_lib.baseboard_fab2(sch_1):m_j_vref") )
				( member ( signalRef "@baseboard_fab2_lib.baseboard_fab2(sch_1):m_k_vref") )
				( member ( signalRef "@baseboard_fab2_lib.baseboard_fab2(sch_1):m_l_vref") )
				( member ( signalRef "@baseboard_fab2_lib.baseboard_fab2(sch_1):m_m_vref") )
				( member ( electricalNetRef "@crescent_city_bb_fab1_lib.crescent_city_bb_fab1(sch_1):m_a_cpu_vref") )
				( member ( electricalNetRef "@crescent_city_bb_fab1_lib.crescent_city_bb_fab1(sch_1):m_b_cpu_vref") )
				( member ( electricalNetRef "@crescent_city_bb_fab1_lib.crescent_city_bb_fab1(sch_1):m_c_cpu_vref") )
				( member ( electricalNetRef "@crescent_city_bb_fab1_lib.crescent_city_bb_fab1(sch_1):m_d_cpu_vref") )
				( member ( electricalNetRef "@crescent_city_bb_fab1_lib.crescent_city_bb_fab1(sch_1):m_e_cpu_vref") )
				( member ( electricalNetRef "@crescent_city_bb_fab1_lib.crescent_city_bb_fab1(sch_1):m_f_cpu_vref") )
				( member ( electricalNetRef "@crescent_city_bb_fab1_lib.crescent_city_bb_fab1(sch_1):m_g_cpu_vref") )
				( member ( electricalNetRef "@crescent_city_bb_fab1_lib.crescent_city_bb_fab1(sch_1):m_h_cpu_vref") )
				( member ( electricalNetRef "@crescent_city_bb_fab1_lib.crescent_city_bb_fab1(sch_1):m_j_cpu_vref") )
				( member ( electricalNetRef "@crescent_city_bb_fab1_lib.crescent_city_bb_fab1(sch_1):m_k_cpu_vref") )
				( member ( electricalNetRef "@crescent_city_bb_fab1_lib.crescent_city_bb_fab1(sch_1):m_l_cpu_vref") )
				( member ( electricalNetRef "@crescent_city_bb_fab1_lib.crescent_city_bb_fab1(sch_1):m_m_cpu_vref") )
				( objectStatus "SNCLS_DDR4_VREF" )
			)
			( netClass "@crescent_city_bb_fab1_lib.crescent_city_bb_fab1(sch_1):\PNCLS_VR_MISC\"
				( memberType ( signal ) )
				( physicalCSetRef "@crescent_city_bb_fab1_lib.crescent_city_bb_fab1(sch_1):\VR_MISC_SIG\" )
				( objectFlag fObjectPhysical )
				( member ( signalRef "@baseboard_fab2_lib.baseboard_fab2(sch_1):vr_pvccio_cpu0_airef1") )
				( member ( signalRef "@baseboard_fab2_lib.baseboard_fab2(sch_1):vr_pvccio_cpu1_airef1") )
				( member ( signalRef "@baseboard_fab2_lib.baseboard_fab2(sch_1):vr_pvddq_abc_airef1") )
				( member ( signalRef "@baseboard_fab2_lib.baseboard_fab2(sch_1):vr_pvddq_abc_airef2") )
				( member ( signalRef "@baseboard_fab2_lib.baseboard_fab2(sch_1):vr_pvddq_def_airef1") )
				( member ( signalRef "@baseboard_fab2_lib.baseboard_fab2(sch_1):vr_pvddq_def_airef2") )
				( member ( signalRef "@baseboard_fab2_lib.baseboard_fab2(sch_1):vr_pvddq_ghj_airef1") )
				( member ( signalRef "@baseboard_fab2_lib.baseboard_fab2(sch_1):vr_pvddq_ghj_airef2") )
				( member ( signalRef "@baseboard_fab2_lib.baseboard_fab2(sch_1):vr_pvddq_klm_airef1") )
				( member ( signalRef "@baseboard_fab2_lib.baseboard_fab2(sch_1):vr_pvddq_klm_airef2") )
				( member ( signalRef "@baseboard_fab2_lib.baseboard_fab2(sch_1):vr_pvnn_pch_airef1") )
				( member ( signalRef "@baseboard_fab2_lib.baseboard_fab2(sch_1):vr_p1v05_pch_biref1") )
				( member ( signalRef "@baseboard_fab2_lib.baseboard_fab2(sch_1):vr_pvcciomcp_cpu0_xaddr1") )
				( member ( signalRef "@baseboard_fab2_lib.baseboard_fab2(sch_1):vr_pvcciomcp_cpu1_xaddr1") )
				( member ( signalRef "@baseboard_fab2_lib.baseboard_fab2(sch_1):vr_pvccmcp_cpu0_xaddr2") )
				( member ( signalRef "@baseboard_fab2_lib.baseboard_fab2(sch_1):vr_pvccmcp_cpu1_xaddr2") )
				( member ( signalRef "@baseboard_fab2_lib.baseboard_fab2(sch_1):vr_pvccin_cpu0_xaddr1") )
				( member ( signalRef "@baseboard_fab2_lib.baseboard_fab2(sch_1):vr_pvccin_cpu0_xaddr2") )
				( member ( signalRef "@baseboard_fab2_lib.baseboard_fab2(sch_1):vr_pvccin_cpu1_xaddr1") )
				( member ( signalRef "@baseboard_fab2_lib.baseboard_fab2(sch_1):vr_pvccin_cpu1_xaddr2") )
				( member ( signalRef "@baseboard_fab2_lib.baseboard_fab2(sch_1):vr_pvddq_ghj_vd12") )
				( member ( signalRef "@baseboard_fab2_lib.baseboard_fab2(sch_1):vr_pvddq_ghj_vinsen") )
				( member ( signalRef "@baseboard_fab2_lib.baseboard_fab2(sch_1):vr_pvddq_ghj_xaddr1") )
				( member ( signalRef "@baseboard_fab2_lib.baseboard_fab2(sch_1):vr_pvddq_ghj_xaddr2") )
				( member ( signalRef "@baseboard_fab2_lib.baseboard_fab2(sch_1):vr_pvddq_klm_aiinsen") )
				( member ( signalRef "@baseboard_fab2_lib.baseboard_fab2(sch_1):vr_pvddq_klm_aiinsen_r") )
				( member ( signalRef "@baseboard_fab2_lib.baseboard_fab2(sch_1):vr_pvddq_klm_ph1_vcin") )
				( member ( signalRef "@baseboard_fab2_lib.baseboard_fab2(sch_1):vr_pvddq_klm_ph2_vcin") )
				( member ( signalRef "@baseboard_fab2_lib.baseboard_fab2(sch_1):vr_pvddq_klm_vdd") )
				( member ( signalRef "@baseboard_fab2_lib.baseboard_fab2(sch_1):vr_pvddq_klm_vd12") )
				( member ( signalRef "@baseboard_fab2_lib.baseboard_fab2(sch_1):vr_pvddq_klm_vinsen") )
				( member ( signalRef "@baseboard_fab2_lib.baseboard_fab2(sch_1):vr_pvddq_klm_xaddr1") )
				( member ( signalRef "@baseboard_fab2_lib.baseboard_fab2(sch_1):vr_pvddq_klm_xaddr2") )
				( member ( signalRef "@baseboard_fab2_lib.baseboard_fab2(sch_1):vr_pvnn_pch_avsp") )
				( member ( signalRef "@baseboard_fab2_lib.baseboard_fab2(sch_1):vr_pvnn_pch_ph1_vcin") )
				( member ( signalRef "@baseboard_fab2_lib.baseboard_fab2(sch_1):vr_pvnn_pch_vdd") )
				( member ( signalRef "@baseboard_fab2_lib.baseboard_fab2(sch_1):vr_pvnn_pch_vinsen") )
				( member ( signalRef "@baseboard_fab2_lib.baseboard_fab2(sch_1):vr_pvnn_pch_xaddr1") )
				( member ( signalRef "@baseboard_fab2_lib.baseboard_fab2(sch_1):vr_pvnn_pch_xaddr2") )
				( member ( signalRef "@baseboard_fab2_lib.baseboard_fab2(sch_1):vr_pvnn_p1v05_pch_vd12") )
				( member ( signalRef "@baseboard_fab2_lib.baseboard_fab2(sch_1):vr_pvpp_abc_iset") )
				( member ( signalRef "@baseboard_fab2_lib.baseboard_fab2(sch_1):vr_pvpp_abc_ss") )
				( member ( signalRef "@baseboard_fab2_lib.baseboard_fab2(sch_1):vr_pvpp_def_iset") )
				( member ( signalRef "@baseboard_fab2_lib.baseboard_fab2(sch_1):vr_pvpp_def_ss") )
				( member ( signalRef "@baseboard_fab2_lib.baseboard_fab2(sch_1):vr_pvpp_ghj_iset") )
				( member ( signalRef "@baseboard_fab2_lib.baseboard_fab2(sch_1):vr_pvpp_ghj_ss") )
				( member ( signalRef "@baseboard_fab2_lib.baseboard_fab2(sch_1):vr_pvpp_klm_iset") )
				( member ( signalRef "@baseboard_fab2_lib.baseboard_fab2(sch_1):vr_pvpp_klm_ss") )
				( member ( signalRef "@baseboard_fab2_lib.baseboard_fab2(sch_1):vr_pvsa_cpu0_vcin") )
				( member ( signalRef "@baseboard_fab2_lib.baseboard_fab2(sch_1):vr_pvsa_cpu1_vcin") )
				( member ( signalRef "@baseboard_fab2_lib.baseboard_fab2(sch_1):vr_pvtt_abc_bias") )
				( member ( signalRef "@baseboard_fab2_lib.baseboard_fab2(sch_1):vr_pvtt_abc_sns") )
				( member ( signalRef "@baseboard_fab2_lib.baseboard_fab2(sch_1):vr_pvtt_abc_vref") )
				( member ( signalRef "@baseboard_fab2_lib.baseboard_fab2(sch_1):vr_pvtt_def_bias") )
				( member ( signalRef "@baseboard_fab2_lib.baseboard_fab2(sch_1):vr_pvtt_def_sns") )
				( member ( signalRef "@baseboard_fab2_lib.baseboard_fab2(sch_1):vr_pvtt_def_vref") )
				( member ( signalRef "@baseboard_fab2_lib.baseboard_fab2(sch_1):vr_pvtt_ghj_bias") )
				( member ( signalRef "@baseboard_fab2_lib.baseboard_fab2(sch_1):vr_pvtt_ghj_sns") )
				( member ( signalRef "@baseboard_fab2_lib.baseboard_fab2(sch_1):vr_pvtt_ghj_vref") )
				( member ( signalRef "@baseboard_fab2_lib.baseboard_fab2(sch_1):vr_pvtt_klm_bias") )
				( member ( signalRef "@baseboard_fab2_lib.baseboard_fab2(sch_1):vr_pvtt_klm_sns") )
				( member ( signalRef "@baseboard_fab2_lib.baseboard_fab2(sch_1):vr_pvtt_klm_vref") )
				( member ( signalRef "@baseboard_fab2_lib.baseboard_fab2(sch_1):vr_p1v05_pch_stby_ph1_vcin") )
				( member ( signalRef "@baseboard_fab2_lib.baseboard_fab2(sch_1):vr_p3v3_stby_ocselect") )
				( member ( signalRef "@baseboard_fab2_lib.baseboard_fab2(sch_1):vr_p5v_stby_rt") )
				( member ( signalRef "@baseboard_fab2_lib.baseboard_fab2(sch_1):vr_p5v_stby_ss") )
				( member ( signalRef "@baseboard_fab2_lib.baseboard_fab2(sch_1):vr_p5v_stby_vin") )
				( member ( signalRef "@baseboard_fab2_lib.baseboard_fab2(sch_1):vr_p5v_stby_vsense") )
				( member ( signalRef "@baseboard_fab2_lib.baseboard_fab2(sch_1):vr_p5v_stby_vsense_r") )
				( member ( signalRef "@baseboard_fab2_lib.baseboard_fab2(sch_1):vr_vb_pvpp_abc") )
				( member ( signalRef "@baseboard_fab2_lib.baseboard_fab2(sch_1):vr_vb_pvpp_def") )
				( member ( signalRef "@baseboard_fab2_lib.baseboard_fab2(sch_1):vr_vb_pvpp_ghj") )
				( member ( signalRef "@baseboard_fab2_lib.baseboard_fab2(sch_1):vr_vb_pvpp_klm") )
				( member ( signalRef "@baseboard_fab2_lib.baseboard_fab2(sch_1):vr_pvccio_cpu0_ph1_sw") )
				( member ( signalRef "@baseboard_fab2_lib.baseboard_fab2(sch_1):vr_pvccio_cpu1_ph1_sw") )
				( member ( signalRef "@baseboard_fab2_lib.baseboard_fab2(sch_1):vr_pvddq_abc_ph1_sw") )
				( member ( signalRef "@baseboard_fab2_lib.baseboard_fab2(sch_1):vr_pvddq_abc_ph2_sw") )
				( member ( signalRef "@baseboard_fab2_lib.baseboard_fab2(sch_1):vr_pvddq_def_ph1_sw") )
				( member ( signalRef "@baseboard_fab2_lib.baseboard_fab2(sch_1):vr_pvddq_def_ph2_sw") )
				( member ( signalRef "@baseboard_fab2_lib.baseboard_fab2(sch_1):vr_pvddq_ghj_ph1_sw") )
				( member ( signalRef "@baseboard_fab2_lib.baseboard_fab2(sch_1):vr_pvddq_ghj_ph2_sw") )
				( member ( signalRef "@baseboard_fab2_lib.baseboard_fab2(sch_1):vr_pvddq_klm_ph1_sw") )
				( member ( signalRef "@baseboard_fab2_lib.baseboard_fab2(sch_1):vr_pvddq_klm_ph2_sw") )
				( member ( signalRef "@baseboard_fab2_lib.baseboard_fab2(sch_1):vr_pvccin_cpu1_vren") )
				( member ( signalRef "@baseboard_fab2_lib.baseboard_fab2(sch_1):vr_pvccio_cpu0_ph1_vcin") )
				( member ( signalRef "@baseboard_fab2_lib.baseboard_fab2(sch_1):vr_pvccio_cpu0_vdd") )
				( member ( signalRef "@baseboard_fab2_lib.baseboard_fab2(sch_1):vr_pvccio_cpu0_vd12") )
				( member ( signalRef "@baseboard_fab2_lib.baseboard_fab2(sch_1):vr_pvccio_cpu0_vinsen") )
				( member ( signalRef "@baseboard_fab2_lib.baseboard_fab2(sch_1):vr_pvccio_cpu0_xaddr1") )
				( member ( signalRef "@baseboard_fab2_lib.baseboard_fab2(sch_1):vr_pvccio_cpu0_xaddr2") )
				( member ( signalRef "@baseboard_fab2_lib.baseboard_fab2(sch_1):vr_pvccio_cpu1_avsp") )
				( member ( signalRef "@baseboard_fab2_lib.baseboard_fab2(sch_1):vr_pvccio_cpu1_en") )
				( member ( signalRef "@baseboard_fab2_lib.baseboard_fab2(sch_1):vr_pvccio_cpu1_ph1_vcin") )
				( member ( signalRef "@baseboard_fab2_lib.baseboard_fab2(sch_1):vr_pvccio_cpu1_vdd") )
				( member ( signalRef "@baseboard_fab2_lib.baseboard_fab2(sch_1):vr_pvccio_cpu1_vd12") )
				( member ( signalRef "@baseboard_fab2_lib.baseboard_fab2(sch_1):vr_pvccio_cpu1_vinsen") )
				( member ( signalRef "@baseboard_fab2_lib.baseboard_fab2(sch_1):vr_pvccio_cpu1_xaddr1") )
				( member ( signalRef "@baseboard_fab2_lib.baseboard_fab2(sch_1):vr_pvccio_cpu1_xaddr2") )
				( member ( signalRef "@baseboard_fab2_lib.baseboard_fab2(sch_1):vr_pvddq_abc_aiinsen") )
				( member ( signalRef "@baseboard_fab2_lib.baseboard_fab2(sch_1):vr_pvddq_abc_aiinsen_r") )
				( member ( signalRef "@baseboard_fab2_lib.baseboard_fab2(sch_1):vr_pvddq_abc_avsp") )
				( member ( signalRef "@baseboard_fab2_lib.baseboard_fab2(sch_1):vr_pvddq_abc_ph1_vcin") )
				( member ( signalRef "@baseboard_fab2_lib.baseboard_fab2(sch_1):vr_pvddq_abc_ph2_vcin") )
				( member ( signalRef "@baseboard_fab2_lib.baseboard_fab2(sch_1):vr_pvddq_abc_vdd") )
				( member ( signalRef "@baseboard_fab2_lib.baseboard_fab2(sch_1):vr_pvddq_abc_vd12") )
				( member ( signalRef "@baseboard_fab2_lib.baseboard_fab2(sch_1):vr_pvddq_abc_vinsen") )
				( member ( signalRef "@baseboard_fab2_lib.baseboard_fab2(sch_1):vr_pvddq_abc_xaddr1") )
				( member ( signalRef "@baseboard_fab2_lib.baseboard_fab2(sch_1):vr_pvddq_abc_xaddr2") )
				( member ( signalRef "@baseboard_fab2_lib.baseboard_fab2(sch_1):vr_pvddq_def_aiinsen") )
				( member ( signalRef "@baseboard_fab2_lib.baseboard_fab2(sch_1):vr_pvddq_def_aiinsen_r") )
				( member ( signalRef "@baseboard_fab2_lib.baseboard_fab2(sch_1):vr_pvddq_def_avsp") )
				( member ( signalRef "@baseboard_fab2_lib.baseboard_fab2(sch_1):vr_pvddq_def_ph1_vcin") )
				( member ( signalRef "@baseboard_fab2_lib.baseboard_fab2(sch_1):vr_pvddq_def_ph2_vcin") )
				( member ( signalRef "@baseboard_fab2_lib.baseboard_fab2(sch_1):vr_pvddq_def_vdd") )
				( member ( signalRef "@baseboard_fab2_lib.baseboard_fab2(sch_1):vr_pvddq_def_vd12") )
				( member ( signalRef "@baseboard_fab2_lib.baseboard_fab2(sch_1):vr_pvddq_def_vinsen") )
				( member ( signalRef "@baseboard_fab2_lib.baseboard_fab2(sch_1):vr_pvddq_def_xaddr1") )
				( member ( signalRef "@baseboard_fab2_lib.baseboard_fab2(sch_1):vr_pvddq_def_xaddr2") )
				( member ( signalRef "@baseboard_fab2_lib.baseboard_fab2(sch_1):vr_pvddq_ghj_aiinsen") )
				( member ( signalRef "@baseboard_fab2_lib.baseboard_fab2(sch_1):vr_pvddq_ghj_aiinsen_r") )
				( member ( signalRef "@baseboard_fab2_lib.baseboard_fab2(sch_1):vr_pvddq_ghj_avsp") )
				( member ( signalRef "@baseboard_fab2_lib.baseboard_fab2(sch_1):vr_pvddq_ghj_ph1_vcin") )
				( member ( signalRef "@baseboard_fab2_lib.baseboard_fab2(sch_1):vr_pvddq_ghj_ph2_vcin") )
				( member ( signalRef "@baseboard_fab2_lib.baseboard_fab2(sch_1):vr_pvddq_ghj_vdd") )
				( member ( electricalNetRef "@crescent_city_bb_fab1_lib.crescent_city_bb_fab1(sch_1):vr_p5v_stby_vsense") )
				( member ( electricalNetRef "@crescent_city_bb_fab1_lib.crescent_city_bb_fab1(sch_1):vr_pvddq_abc_aiinsen") )
				( member ( electricalNetRef "@crescent_city_bb_fab1_lib.crescent_city_bb_fab1(sch_1):vr_pvddq_def_aiinsen") )
				( member ( electricalNetRef "@crescent_city_bb_fab1_lib.crescent_city_bb_fab1(sch_1):vr_pvddq_ghj_aiinsen") )
				( member ( electricalNetRef "@crescent_city_bb_fab1_lib.crescent_city_bb_fab1(sch_1):vr_pvddq_klm_aiinsen") )
				( objectStatus "PNCLS_VR_MISC" )
			)
			( netClass "@crescent_city_bb_fab1_lib.crescent_city_bb_fab1(sch_1):\SNCLS_DDR4_RST\"
				( memberType ( signal ) )
				( spacingCSetRef "@sapphirecity_baseboard_lib.sapphirecity_baseboard(sch_1):\DDR4_2SPC_CAC\" )
				( objectFlag fObjectSpacing )
				( objectFlag fObjectSameNetSpacing )
				( member ( signalRef "@baseboard_fab2_lib.baseboard_fab2(sch_1):m_abc_rst_n") )
				( member ( signalRef "@baseboard_fab2_lib.baseboard_fab2(sch_1):m_def_rst_n") )
				( member ( signalRef "@baseboard_fab2_lib.baseboard_fab2(sch_1):m_ghj_rst_n") )
				( member ( signalRef "@baseboard_fab2_lib.baseboard_fab2(sch_1):m_klm_rst_n") )
				( objectStatus "SNCLS_DDR4_RST" )
			)
			( netClass "@crescent_city_bb_fab1_lib.crescent_city_bb_fab1(sch_1):\CLS_SPI\"
				( memberType ( signal ) )
				( objectFlag fObjectElectrical )
				( member ( signalRef "@baseboard_fab2_lib.baseboard_fab2(sch_1):spi_bmc_clk") )
				( member ( signalRef "@baseboard_fab2_lib.baseboard_fab2(sch_1):spi_bmc_cs0_n") )
				( member ( signalRef "@baseboard_fab2_lib.baseboard_fab2(sch_1):spi_bmc_di") )
				( member ( signalRef "@baseboard_fab2_lib.baseboard_fab2(sch_1):spi_bmc_do") )
				( member ( signalRef "@baseboard_fab2_lib.baseboard_fab2(sch_1):pu_bios_spi_wp1_n") )
				( member ( signalRef "@baseboard_fab2_lib.baseboard_fab2(sch_1):pu_bios_spi_hold1_n") )
				( member ( signalRef "@baseboard_fab2_lib.baseboard_fab2(sch_1):pu_bios_spi_hold0_n") )
				( member ( signalRef "@baseboard_fab2_lib.baseboard_fab2(sch_1):spi_bios_socket_io3") )
				( member ( electricalNetRef "@crescent_city_bb_fab1_lib.crescent_city_bb_fab1(sch_1):spi_cs0_primary_r_n") )
				( member ( electricalNetRef "@crescent_city_bb_fab1_lib.crescent_city_bb_fab1(sch_1):xdp_spi_pch_mosi_boot_halt_n") )
				( member ( electricalNetRef "@crescent_city_bb_fab1_lib.crescent_city_bb_fab1(sch_1):xdp_debug_consent_n") )
				( member ( electricalNetRef "@crescent_city_bb_fab1_lib.crescent_city_bb_fab1(sch_1):spi_switch_mosi") )
				( member ( electricalNetRef "@crescent_city_bb_fab1_lib.crescent_city_bb_fab1(sch_1):spi_pch_tpm_cs_n") )
				( member ( electricalNetRef "@crescent_city_bb_fab1_lib.crescent_city_bb_fab1(sch_1):spi_clk_r0") )
				( member ( electricalNetRef "@crescent_city_bb_fab1_lib.crescent_city_bb_fab1(sch_1):spi_pch_miso_r") )
				( member ( electricalNetRef "@crescent_city_bb_fab1_lib.crescent_city_bb_fab1(sch_1):spi_pch_clk") )
				( member ( electricalNetRef "@crescent_city_bb_fab1_lib.crescent_city_bb_fab1(sch_1):spi_bmc_bt_di") )
				( member ( electricalNetRef "@crescent_city_bb_fab1_lib.crescent_city_bb_fab1(sch_1):spi_bmc_bt_do") )
				( member ( electricalNetRef "@crescent_city_bb_fab1_lib.crescent_city_bb_fab1(sch_1):spi_bmc_bt_clk") )
				( member ( electricalNetRef "@crescent_city_bb_fab1_lib.crescent_city_bb_fab1(sch_1):spi_bmc_bt_cs_n") )
				( member ( electricalNetRef "@crescent_city_bb_fab1_lib.crescent_city_bb_fab1(sch_1):spi_pch_io3") )
				( member ( electricalNetRef "@crescent_city_bb_fab1_lib.crescent_city_bb_fab1(sch_1):pu_bios_spi_wp0_n") )
				( member ( electricalNetRef "@crescent_city_bb_fab1_lib.crescent_city_bb_fab1(sch_1):spi_miso_r0") )
				( member ( electricalNetRef "@crescent_city_bb_fab1_lib.crescent_city_bb_fab1(sch_1):spi_nic_cs_n") )
				( member ( electricalNetRef "@crescent_city_bb_fab1_lib.crescent_city_bb_fab1(sch_1):spi_nic_miso") )
				( member ( electricalNetRef "@crescent_city_bb_fab1_lib.crescent_city_bb_fab1(sch_1):spi_nic_mosi") )
				( member ( electricalNetRef "@crescent_city_bb_fab1_lib.crescent_city_bb_fab1(sch_1):spi_nic_sclk") )
				( member ( electricalNetRef "@baseboard_fab2_lib.baseboard_fab2(sch_1):spi_pch_cs0_n") )
				( objectStatus "CLS_SPI" )
			)
			( netClass "@crescent_city_bb_fab1_lib.crescent_city_bb_fab1(sch_1):\CLS_SVID\"
				( memberType ( signal ) )
				( objectFlag fObjectElectrical )
				( member ( electricalNetRef "@crescent_city_bb_fab1_lib.crescent_city_bb_fab1(sch_1):svid_dio0_cpu1") )
				( member ( electricalNetRef "@crescent_city_bb_fab1_lib.crescent_city_bb_fab1(sch_1):svid_dio0_cpu0") )
				( member ( electricalNetRef "@crescent_city_bb_fab1_lib.crescent_city_bb_fab1(sch_1):svid_clk_pvddq_ghj") )
				( member ( electricalNetRef "@crescent_city_bb_fab1_lib.crescent_city_bb_fab1(sch_1):svid_clk_pvddq_abc") )
				( member ( electricalNetRef "@crescent_city_bb_fab1_lib.crescent_city_bb_fab1(sch_1):svid_clk_pvccio_cpu1") )
				( member ( electricalNetRef "@crescent_city_bb_fab1_lib.crescent_city_bb_fab1(sch_1):svid_clk_pvccio_cpu0") )
				( member ( electricalNetRef "@crescent_city_bb_fab1_lib.crescent_city_bb_fab1(sch_1):svid_alert0_cpu1_n") )
				( member ( electricalNetRef "@crescent_city_bb_fab1_lib.crescent_city_bb_fab1(sch_1):svid_alert0_cpu0_n") )
				( member ( electricalNetRef "@crescent_city_bb_fab1_lib.crescent_city_bb_fab1(sch_1):svid_dio1_cpu1_r") )
				( member ( electricalNetRef "@crescent_city_bb_fab1_lib.crescent_city_bb_fab1(sch_1):svid_dio1_cpu0_r") )
				( member ( electricalNetRef "@crescent_city_bb_fab1_lib.crescent_city_bb_fab1(sch_1):svid_alert1_cpu1_n") )
				( member ( electricalNetRef "@crescent_city_bb_fab1_lib.crescent_city_bb_fab1(sch_1):svid_alert1_cpu0_n") )
				( objectStatus "CLS_SVID" )
			)
			( netClass "@crescent_city_bb_fab1_lib.crescent_city_bb_fab1(sch_1):\SPGIO_SSATA\"
				( memberType ( signal ) )
				( spacingCSetRef "@sapphirecity_baseboard_lib.sapphirecity_baseboard(sch_1):\8MIL_SL_7MIL_MS\" )
				( objectFlag fObjectSpacing )
				( objectFlag fObjectSameNetSpacing )
				( member ( signalRef "@baseboard_fab2_lib.baseboard_fab2(sch_1):sgpio_pch_ssata_clock") )
				( member ( signalRef "@baseboard_fab2_lib.baseboard_fab2(sch_1):sgpio_pch_ssata_clock_r") )
				( member ( signalRef "@baseboard_fab2_lib.baseboard_fab2(sch_1):sgpio_pch_ssata_dout0") )
				( member ( signalRef "@baseboard_fab2_lib.baseboard_fab2(sch_1):sgpio_pch_ssata_dout0_r") )
				( member ( signalRef "@baseboard_fab2_lib.baseboard_fab2(sch_1):sgpio_pch_ssata_load") )
				( member ( signalRef "@baseboard_fab2_lib.baseboard_fab2(sch_1):sgpio_pch_ssata_load_r") )
				( member ( electricalNetRef "@crescent_city_bb_fab1_lib.crescent_city_bb_fab1(sch_1):sgpio_pch_ssata_clock") )
				( member ( electricalNetRef "@crescent_city_bb_fab1_lib.crescent_city_bb_fab1(sch_1):sgpio_pch_ssata_dout0") )
				( member ( electricalNetRef "@crescent_city_bb_fab1_lib.crescent_city_bb_fab1(sch_1):sgpio_pch_ssata_load") )
				( objectStatus "SNCLS_SGPIO_SSATA" )
			)
			( netClass "@crescent_city_bb_fab1_lib.crescent_city_bb_fab1(sch_1):\CLS_FAN\"
				( memberType ( signal ) )
				( objectFlag fObjectElectrical )
				( member ( signalRef "@baseboard_fab2_lib.baseboard_fab2(sch_1):fan_tach0") )
				( member ( signalRef "@baseboard_fab2_lib.baseboard_fab2(sch_1):fan_tach0_cpu0_d1") )
				( member ( signalRef "@baseboard_fab2_lib.baseboard_fab2(sch_1):fan_tach0_cpu0_d2") )
				( member ( signalRef "@baseboard_fab2_lib.baseboard_fab2(sch_1):fan_tach2_cpu1_d1") )
				( member ( signalRef "@baseboard_fab2_lib.baseboard_fab2(sch_1):fan_tach2_cpu1_d2") )
				( member ( electricalNetRef "@crescent_city_bb_fab1_lib.crescent_city_bb_fab1(sch_1):fan_tach3_r") )
				( member ( electricalNetRef "@crescent_city_bb_fab1_lib.crescent_city_bb_fab1(sch_1):fan_tach2") )
				( member ( electricalNetRef "@crescent_city_bb_fab1_lib.crescent_city_bb_fab1(sch_1):fan_tach1") )
				( member ( electricalNetRef "@crescent_city_bb_fab1_lib.crescent_city_bb_fab1(sch_1):fan_pwm_out_sys0_r") )
				( member ( electricalNetRef "@crescent_city_bb_fab1_lib.crescent_city_bb_fab1(sch_1):fan_pwm_out_sys1_r") )
				( objectStatus "CLS_FAN" )
			)
			( netClass "@crescent_city_bb_fab1_lib.crescent_city_bb_fab1(sch_1):\CLS_TP\"
				( memberType ( signal ) )
				( objectFlag fObjectElectrical )
				( member ( signalRef "@baseboard_fab2_lib.baseboard_fab2(sch_1):tp_clk_100m_nsscc1_dn") )
				( member ( signalRef "@baseboard_fab2_lib.baseboard_fab2(sch_1):tp_clk_100m_nsscc1_dp") )
				( member ( signalRef "@baseboard_fab2_lib.baseboard_fab2(sch_1):tp_clk_100m_r_dn") )
				( member ( signalRef "@baseboard_fab2_lib.baseboard_fab2(sch_1):tp_clk_100m_r_dp") )
				( member ( signalRef "@baseboard_fab2_lib.baseboard_fab2(sch_1):tp_clk_100m_src12_dn") )
				( member ( signalRef "@baseboard_fab2_lib.baseboard_fab2(sch_1):tp_clk_100m_src12_dp") )
				( member ( signalRef "@baseboard_fab2_lib.baseboard_fab2(sch_1):tp_clk_100m_src13_dn") )
				( member ( signalRef "@baseboard_fab2_lib.baseboard_fab2(sch_1):tp_clk_100m_src13_dp") )
				( member ( signalRef "@baseboard_fab2_lib.baseboard_fab2(sch_1):tp_cpu0_rsvd_247") )
				( member ( signalRef "@baseboard_fab2_lib.baseboard_fab2(sch_1):tp_cpu0_rsvd_248") )
				( member ( signalRef "@baseboard_fab2_lib.baseboard_fab2(sch_1):tp_cpu0_rsvd_249") )
				( member ( signalRef "@baseboard_fab2_lib.baseboard_fab2(sch_1):tp_cpu0_rsvd_250") )
				( member ( signalRef "@baseboard_fab2_lib.baseboard_fab2(sch_1):tp_cpu0_rsvd_251") )
				( member ( signalRef "@baseboard_fab2_lib.baseboard_fab2(sch_1):tp_cpu0_rsvd_252") )
				( member ( signalRef "@baseboard_fab2_lib.baseboard_fab2(sch_1):tp_cpu0_rsvd_253") )
				( member ( signalRef "@baseboard_fab2_lib.baseboard_fab2(sch_1):tp_cpu0_rsvd_254") )
				( member ( signalRef "@baseboard_fab2_lib.baseboard_fab2(sch_1):tp_cpu0_rsvd_255") )
				( member ( signalRef "@baseboard_fab2_lib.baseboard_fab2(sch_1):tp_cpu0_rsvd_256") )
				( member ( signalRef "@baseboard_fab2_lib.baseboard_fab2(sch_1):tp_cpu0_rsvd_258") )
				( member ( signalRef "@baseboard_fab2_lib.baseboard_fab2(sch_1):tp_bios_recover_boot") )
				( member ( signalRef "@baseboard_fab2_lib.baseboard_fab2(sch_1):tp_cd_hfi1_cpu1_int_n") )
				( member ( signalRef "@baseboard_fab2_lib.baseboard_fab2(sch_1):tp_cd_hfi1_cpu1_i2cdat") )
				( member ( signalRef "@baseboard_fab2_lib.baseboard_fab2(sch_1):tp_cd_hfi1_cpu1_i2clk") )
				( member ( signalRef "@baseboard_fab2_lib.baseboard_fab2(sch_1):tp_cd_hfi1_cpu1_led_n") )
				( member ( signalRef "@baseboard_fab2_lib.baseboard_fab2(sch_1):tp_cd_hfi1_cpu1_modprst_n") )
				( member ( signalRef "@baseboard_fab2_lib.baseboard_fab2(sch_1):tp_cd_hfi1_cpu1_reset_n") )
				( member ( signalRef "@baseboard_fab2_lib.baseboard_fab2(sch_1):tp_ch_a_dimm_a0_rfu_0") )
				( member ( signalRef "@baseboard_fab2_lib.baseboard_fab2(sch_1):tp_ch_a_dimm_a0_rfu_1") )
				( member ( signalRef "@baseboard_fab2_lib.baseboard_fab2(sch_1):tp_ch_a_dimm_a0_rfu_2") )
				( member ( signalRef "@baseboard_fab2_lib.baseboard_fab2(sch_1):tp_ch_a_dimm_a1_rfu_0") )
				( member ( signalRef "@baseboard_fab2_lib.baseboard_fab2(sch_1):tp_ch_a_dimm_a1_rfu_1") )
				( member ( signalRef "@baseboard_fab2_lib.baseboard_fab2(sch_1):tp_ch_a_dimm_a1_rfu_2") )
				( member ( signalRef "@baseboard_fab2_lib.baseboard_fab2(sch_1):tp_ch_b_dimm_b0_rfu_0") )
				( member ( signalRef "@baseboard_fab2_lib.baseboard_fab2(sch_1):tp_ch_b_dimm_b0_rfu_1") )
				( member ( signalRef "@baseboard_fab2_lib.baseboard_fab2(sch_1):tp_ch_b_dimm_b0_rfu_2") )
				( member ( signalRef "@baseboard_fab2_lib.baseboard_fab2(sch_1):tp_ch_b_dimm_b1_rfu_0") )
				( member ( signalRef "@baseboard_fab2_lib.baseboard_fab2(sch_1):tp_ch_b_dimm_b1_rfu_1") )
				( member ( signalRef "@baseboard_fab2_lib.baseboard_fab2(sch_1):tp_ch_b_dimm_b1_rfu_2") )
				( member ( signalRef "@baseboard_fab2_lib.baseboard_fab2(sch_1):tp_ch_c_dimm_c0_rfu_0") )
				( member ( signalRef "@baseboard_fab2_lib.baseboard_fab2(sch_1):tp_ch_c_dimm_c0_rfu_1") )
				( member ( signalRef "@baseboard_fab2_lib.baseboard_fab2(sch_1):tp_ch_c_dimm_c0_rfu_2") )
				( member ( signalRef "@baseboard_fab2_lib.baseboard_fab2(sch_1):tp_ch_c_dimm_c1_rfu_0") )
				( member ( signalRef "@baseboard_fab2_lib.baseboard_fab2(sch_1):tp_ch_c_dimm_c1_rfu_1") )
				( member ( signalRef "@baseboard_fab2_lib.baseboard_fab2(sch_1):tp_ch_c_dimm_c1_rfu_2") )
				( member ( signalRef "@baseboard_fab2_lib.baseboard_fab2(sch_1):tp_ch_d_dimm_d0_rfu_0") )
				( member ( signalRef "@baseboard_fab2_lib.baseboard_fab2(sch_1):tp_ch_d_dimm_d0_rfu_1") )
				( member ( signalRef "@baseboard_fab2_lib.baseboard_fab2(sch_1):tp_ch_d_dimm_d0_rfu_2") )
				( member ( signalRef "@baseboard_fab2_lib.baseboard_fab2(sch_1):tp_ch_d_dimm_d1_rfu_0") )
				( member ( signalRef "@baseboard_fab2_lib.baseboard_fab2(sch_1):tp_ch_d_dimm_d1_rfu_1") )
				( member ( signalRef "@baseboard_fab2_lib.baseboard_fab2(sch_1):tp_ch_d_dimm_d1_rfu_2") )
				( member ( signalRef "@baseboard_fab2_lib.baseboard_fab2(sch_1):tp_ch_e_dimm_e0_rfu_0") )
				( member ( signalRef "@baseboard_fab2_lib.baseboard_fab2(sch_1):tp_ch_e_dimm_e0_rfu_1") )
				( member ( signalRef "@baseboard_fab2_lib.baseboard_fab2(sch_1):tp_ch_e_dimm_e0_rfu_2") )
				( member ( signalRef "@baseboard_fab2_lib.baseboard_fab2(sch_1):tp_ch_e_dimm_e1_rfu_0") )
				( member ( signalRef "@baseboard_fab2_lib.baseboard_fab2(sch_1):tp_ch_e_dimm_e1_rfu_1") )
				( member ( signalRef "@baseboard_fab2_lib.baseboard_fab2(sch_1):tp_ch_e_dimm_e1_rfu_2") )
				( member ( signalRef "@baseboard_fab2_lib.baseboard_fab2(sch_1):tp_ch_f_dimm_f0_rfu_0") )
				( member ( signalRef "@baseboard_fab2_lib.baseboard_fab2(sch_1):tp_ch_f_dimm_f0_rfu_1") )
				( member ( signalRef "@baseboard_fab2_lib.baseboard_fab2(sch_1):tp_ch_f_dimm_f0_rfu_2") )
				( member ( signalRef "@baseboard_fab2_lib.baseboard_fab2(sch_1):tp_ch_f_dimm_f1_rfu_0") )
				( member ( signalRef "@baseboard_fab2_lib.baseboard_fab2(sch_1):tp_ch_f_dimm_f1_rfu_1") )
				( member ( signalRef "@baseboard_fab2_lib.baseboard_fab2(sch_1):tp_ch_f_dimm_f1_rfu_2") )
				( member ( signalRef "@baseboard_fab2_lib.baseboard_fab2(sch_1):tp_ch_g_dimm_g0_rfu_0") )
				( member ( signalRef "@baseboard_fab2_lib.baseboard_fab2(sch_1):tp_ch_g_dimm_g0_rfu_1") )
				( member ( signalRef "@baseboard_fab2_lib.baseboard_fab2(sch_1):tp_ch_g_dimm_g0_rfu_2") )
				( member ( signalRef "@baseboard_fab2_lib.baseboard_fab2(sch_1):tp_ch_g_dimm0_rfu_0") )
				( member ( signalRef "@baseboard_fab2_lib.baseboard_fab2(sch_1):tp_ch_g_dimm0_rfu_1") )
				( member ( signalRef "@baseboard_fab2_lib.baseboard_fab2(sch_1):tp_ch_g_dimm0_rfu_2") )
				( member ( signalRef "@baseboard_fab2_lib.baseboard_fab2(sch_1):tp_ch_h_dimm_h0_rfu_0") )
				( member ( signalRef "@baseboard_fab2_lib.baseboard_fab2(sch_1):tp_ch_h_dimm_h0_rfu_1") )
				( member ( signalRef "@baseboard_fab2_lib.baseboard_fab2(sch_1):tp_ch_h_dimm_h0_rfu_2") )
				( member ( signalRef "@baseboard_fab2_lib.baseboard_fab2(sch_1):tp_ch_h_dimm0_rfu_0") )
				( member ( signalRef "@baseboard_fab2_lib.baseboard_fab2(sch_1):tp_ch_h_dimm0_rfu_1") )
				( member ( signalRef "@baseboard_fab2_lib.baseboard_fab2(sch_1):tp_ch_h_dimm0_rfu_2") )
				( member ( signalRef "@baseboard_fab2_lib.baseboard_fab2(sch_1):tp_ch_j_dimm_j0_rfu_0") )
				( member ( signalRef "@baseboard_fab2_lib.baseboard_fab2(sch_1):tp_ch_j_dimm_j0_rfu_1") )
				( member ( signalRef "@baseboard_fab2_lib.baseboard_fab2(sch_1):tp_ch_j_dimm_j0_rfu_2") )
				( member ( signalRef "@baseboard_fab2_lib.baseboard_fab2(sch_1):tp_ch_j_dimm_j1_rfu_0") )
				( member ( signalRef "@baseboard_fab2_lib.baseboard_fab2(sch_1):tp_ch_j_dimm_j1_rfu_1") )
				( member ( signalRef "@baseboard_fab2_lib.baseboard_fab2(sch_1):tp_ch_j_dimm_j1_rfu_2") )
				( member ( signalRef "@baseboard_fab2_lib.baseboard_fab2(sch_1):tp_ch_k_dimm_k0_rfu_0") )
				( member ( signalRef "@baseboard_fab2_lib.baseboard_fab2(sch_1):tp_ch_k_dimm_k0_rfu_1") )
				( member ( signalRef "@baseboard_fab2_lib.baseboard_fab2(sch_1):tp_ch_k_dimm_k0_rfu_2") )
				( member ( signalRef "@baseboard_fab2_lib.baseboard_fab2(sch_1):tp_ch_k_dimm0_rfu_0") )
				( member ( signalRef "@baseboard_fab2_lib.baseboard_fab2(sch_1):tp_ch_k_dimm0_rfu_1") )
				( member ( signalRef "@baseboard_fab2_lib.baseboard_fab2(sch_1):tp_ch_k_dimm0_rfu_2") )
				( member ( signalRef "@baseboard_fab2_lib.baseboard_fab2(sch_1):tp_ch_l_dimm_l0_rfu_0") )
				( member ( signalRef "@baseboard_fab2_lib.baseboard_fab2(sch_1):tp_ch_l_dimm_l0_rfu_1") )
				( member ( signalRef "@baseboard_fab2_lib.baseboard_fab2(sch_1):tp_ch_l_dimm_l0_rfu_2") )
				( member ( signalRef "@baseboard_fab2_lib.baseboard_fab2(sch_1):tp_ch_l_dimm0_rfu_0") )
				( member ( signalRef "@baseboard_fab2_lib.baseboard_fab2(sch_1):tp_ch_l_dimm0_rfu_1") )
				( member ( signalRef "@baseboard_fab2_lib.baseboard_fab2(sch_1):tp_ch_l_dimm0_rfu_2") )
				( member ( signalRef "@baseboard_fab2_lib.baseboard_fab2(sch_1):tp_ch_m_dimm_m0_rfu_0") )
				( member ( signalRef "@baseboard_fab2_lib.baseboard_fab2(sch_1):tp_ch_m_dimm_m0_rfu_1") )
				( member ( signalRef "@baseboard_fab2_lib.baseboard_fab2(sch_1):tp_ch_m_dimm_m0_rfu_2") )
				( member ( signalRef "@baseboard_fab2_lib.baseboard_fab2(sch_1):tp_ch_m_dimm_m1_rfu_0") )
				( member ( signalRef "@baseboard_fab2_lib.baseboard_fab2(sch_1):tp_ch_m_dimm_m1_rfu_1") )
				( member ( signalRef "@baseboard_fab2_lib.baseboard_fab2(sch_1):tp_ch_m_dimm_m1_rfu_2") )
				( member ( signalRef "@baseboard_fab2_lib.baseboard_fab2(sch_1):tp_clk_24m_pmsync2") )
				( member ( signalRef "@baseboard_fab2_lib.baseboard_fab2(sch_1):tp_clk_96m_ckmng_n") )
				( member ( signalRef "@baseboard_fab2_lib.baseboard_fab2(sch_1):tp_clk_96m_ckmng_p") )
				( member ( signalRef "@baseboard_fab2_lib.baseboard_fab2(sch_1):tp_cpu0_upi2_rsvd_cw14") )
				( member ( signalRef "@baseboard_fab2_lib.baseboard_fab2(sch_1):tp_cpu0_upi2_rsvd_cw16") )
				( member ( signalRef "@baseboard_fab2_lib.baseboard_fab2(sch_1):tp_cpu0_upi2_rsvd_da16") )
				( member ( signalRef "@baseboard_fab2_lib.baseboard_fab2(sch_1):tp_cpu0_upi2_rsvd_db15") )
				( member ( signalRef "@baseboard_fab2_lib.baseboard_fab2(sch_1):tp_cpu0_upi2_rsvd_dc16") )
				( member ( signalRef "@baseboard_fab2_lib.baseboard_fab2(sch_1):tp_clk_125m") )
				( member ( signalRef "@baseboard_fab2_lib.baseboard_fab2(sch_1):tp_clk_125m_bmca") )
				( member ( signalRef "@baseboard_fab2_lib.baseboard_fab2(sch_1):tp_clk5_50m_ckmng") )
				( member ( signalRef "@baseboard_fab2_lib.baseboard_fab2(sch_1):tp_cpld1_pr9c") )
				( member ( signalRef "@baseboard_fab2_lib.baseboard_fab2(sch_1):tp_cpld1_pr9d") )
				( member ( signalRef "@baseboard_fab2_lib.baseboard_fab2(sch_1):tp_cpld1_pr7c") )
				( member ( signalRef "@baseboard_fab2_lib.baseboard_fab2(sch_1):tp_cpld1_pr9a") )
				( member ( signalRef "@baseboard_fab2_lib.baseboard_fab2(sch_1):tp_cpld1_pr7d") )
				( member ( signalRef "@baseboard_fab2_lib.baseboard_fab2(sch_1):tp_cpld1_pr7a_pclkt1_0") )
				( member ( signalRef "@baseboard_fab2_lib.baseboard_fab2(sch_1):tp_cpld1_pr7b_pclkc1_0") )
				( member ( signalRef "@baseboard_fab2_lib.baseboard_fab2(sch_1):tp_cpld1_pt20d_programn") )
				( member ( signalRef "@baseboard_fab2_lib.baseboard_fab2(sch_1):tp_cpld1_pt24c_initn") )
				( member ( signalRef "@baseboard_fab2_lib.baseboard_fab2(sch_1):tp_cpld1_pt24d_done") )
				( member ( signalRef "@baseboard_fab2_lib.baseboard_fab2(sch_1):tp_cpu_pch_trigger_in") )
				( member ( signalRef "@baseboard_fab2_lib.baseboard_fab2(sch_1):tp_cpu_pch_trigger_out") )
				( member ( signalRef "@baseboard_fab2_lib.baseboard_fab2(sch_1):tp_cpu0_pe_hp_scl") )
				( member ( signalRef "@baseboard_fab2_lib.baseboard_fab2(sch_1):tp_cpu0_pe_hp_sda") )
				( member ( signalRef "@baseboard_fab2_lib.baseboard_fab2(sch_1):tp_cpu0_procdis_g_n") )
				( member ( signalRef "@baseboard_fab2_lib.baseboard_fab2(sch_1):tp_cpu0_test_6") )
				( member ( signalRef "@baseboard_fab2_lib.baseboard_fab2(sch_1):tp_cpu0_rsvd_184") )
				( member ( signalRef "@baseboard_fab2_lib.baseboard_fab2(sch_1):tp_cpu0_rsvd_186") )
				( member ( signalRef "@baseboard_fab2_lib.baseboard_fab2(sch_1):tp_cpu0_rsvd_189") )
				( member ( signalRef "@baseboard_fab2_lib.baseboard_fab2(sch_1):tp_cpu0_rsvd_190") )
				( member ( signalRef "@baseboard_fab2_lib.baseboard_fab2(sch_1):tp_cpu0_rsvd_194") )
				( member ( signalRef "@baseboard_fab2_lib.baseboard_fab2(sch_1):tp_cpu0_rsvd_198") )
				( member ( signalRef "@baseboard_fab2_lib.baseboard_fab2(sch_1):tp_cpu0_rsvd_199") )
				( member ( signalRef "@baseboard_fab2_lib.baseboard_fab2(sch_1):tp_cpu0_rsvd_204") )
				( member ( signalRef "@baseboard_fab2_lib.baseboard_fab2(sch_1):tp_cpu0_rsvd_205") )
				( member ( signalRef "@baseboard_fab2_lib.baseboard_fab2(sch_1):tp_cpu0_rsvd_208") )
				( member ( signalRef "@baseboard_fab2_lib.baseboard_fab2(sch_1):tp_cpu0_rsvd_210") )
				( member ( signalRef "@baseboard_fab2_lib.baseboard_fab2(sch_1):tp_cpu0_rsvd_211") )
				( member ( signalRef "@baseboard_fab2_lib.baseboard_fab2(sch_1):tp_cpu0_rsvd_212") )
				( member ( signalRef "@baseboard_fab2_lib.baseboard_fab2(sch_1):tp_cpu0_rsvd_214") )
				( member ( signalRef "@baseboard_fab2_lib.baseboard_fab2(sch_1):tp_cpu0_rsvd_216") )
				( member ( signalRef "@baseboard_fab2_lib.baseboard_fab2(sch_1):tp_cpu0_rsvd_217") )
				( member ( signalRef "@baseboard_fab2_lib.baseboard_fab2(sch_1):tp_cpu0_rsvd_218") )
				( member ( signalRef "@baseboard_fab2_lib.baseboard_fab2(sch_1):tp_cpu0_rsvd_219") )
				( member ( signalRef "@baseboard_fab2_lib.baseboard_fab2(sch_1):tp_cpu0_rsvd_222") )
				( member ( signalRef "@baseboard_fab2_lib.baseboard_fab2(sch_1):tp_cpu0_rsvd_223") )
				( member ( signalRef "@baseboard_fab2_lib.baseboard_fab2(sch_1):tp_cpu0_rsvd_224") )
				( member ( signalRef "@baseboard_fab2_lib.baseboard_fab2(sch_1):tp_cpu0_rsvd_225") )
				( member ( signalRef "@baseboard_fab2_lib.baseboard_fab2(sch_1):tp_cpu0_rsvd_226") )
				( member ( signalRef "@baseboard_fab2_lib.baseboard_fab2(sch_1):tp_cpu0_rsvd_227") )
				( member ( signalRef "@baseboard_fab2_lib.baseboard_fab2(sch_1):tp_cpu0_rsvd_228") )
				( member ( signalRef "@baseboard_fab2_lib.baseboard_fab2(sch_1):tp_cpu0_rsvd_229") )
				( member ( signalRef "@baseboard_fab2_lib.baseboard_fab2(sch_1):tp_cpu0_rsvd_230") )
				( member ( signalRef "@baseboard_fab2_lib.baseboard_fab2(sch_1):tp_cpu0_rsvd_231") )
				( member ( signalRef "@baseboard_fab2_lib.baseboard_fab2(sch_1):tp_cpu0_rsvd_232") )
				( member ( signalRef "@baseboard_fab2_lib.baseboard_fab2(sch_1):tp_cpu0_rsvd_233") )
				( member ( signalRef "@baseboard_fab2_lib.baseboard_fab2(sch_1):tp_cpu0_rsvd_234") )
				( member ( signalRef "@baseboard_fab2_lib.baseboard_fab2(sch_1):tp_cpu0_rsvd_235") )
				( member ( signalRef "@baseboard_fab2_lib.baseboard_fab2(sch_1):tp_cpu0_rsvd_236") )
				( member ( signalRef "@baseboard_fab2_lib.baseboard_fab2(sch_1):tp_cpu0_rsvd_237") )
				( member ( signalRef "@baseboard_fab2_lib.baseboard_fab2(sch_1):tp_cpu0_rsvd_238") )
				( member ( signalRef "@baseboard_fab2_lib.baseboard_fab2(sch_1):tp_cpu0_rsvd_239") )
				( member ( signalRef "@baseboard_fab2_lib.baseboard_fab2(sch_1):tp_cpu0_rsvd_240") )
				( member ( signalRef "@baseboard_fab2_lib.baseboard_fab2(sch_1):tp_cpu0_rsvd_241") )
				( member ( signalRef "@baseboard_fab2_lib.baseboard_fab2(sch_1):tp_cpu0_rsvd_242") )
				( member ( signalRef "@baseboard_fab2_lib.baseboard_fab2(sch_1):tp_cpu0_rsvd_243") )
				( member ( signalRef "@baseboard_fab2_lib.baseboard_fab2(sch_1):tp_cpu0_rsvd_244") )
				( member ( signalRef "@baseboard_fab2_lib.baseboard_fab2(sch_1):tp_cpu0_rsvd_245") )
				( member ( signalRef "@baseboard_fab2_lib.baseboard_fab2(sch_1):tp_cpu0_rsvd_246") )
				( member ( signalRef "@baseboard_fab2_lib.baseboard_fab2(sch_1):tp_cpu1_rsvd_223") )
				( member ( signalRef "@baseboard_fab2_lib.baseboard_fab2(sch_1):tp_cpu1_rsvd_224") )
				( member ( signalRef "@baseboard_fab2_lib.baseboard_fab2(sch_1):tp_cpu1_rsvd_225") )
				( member ( signalRef "@baseboard_fab2_lib.baseboard_fab2(sch_1):tp_cpu1_rsvd_226") )
				( member ( signalRef "@baseboard_fab2_lib.baseboard_fab2(sch_1):tp_cpu1_rsvd_227") )
				( member ( signalRef "@baseboard_fab2_lib.baseboard_fab2(sch_1):tp_cpu1_rsvd_228") )
				( member ( signalRef "@baseboard_fab2_lib.baseboard_fab2(sch_1):tp_cpu1_rsvd_229") )
				( member ( signalRef "@baseboard_fab2_lib.baseboard_fab2(sch_1):tp_cpu1_rsvd_230") )
				( member ( signalRef "@baseboard_fab2_lib.baseboard_fab2(sch_1):tp_cpu1_rsvd_231") )
				( member ( signalRef "@baseboard_fab2_lib.baseboard_fab2(sch_1):tp_cpu1_rsvd_232") )
				( member ( signalRef "@baseboard_fab2_lib.baseboard_fab2(sch_1):tp_cpu1_rsvd_233") )
				( member ( signalRef "@baseboard_fab2_lib.baseboard_fab2(sch_1):tp_cpu1_rsvd_234") )
				( member ( signalRef "@baseboard_fab2_lib.baseboard_fab2(sch_1):tp_cpu0_rsvd_259") )
				( member ( signalRef "@baseboard_fab2_lib.baseboard_fab2(sch_1):tp_cpu0_rsvd_260") )
				( member ( signalRef "@baseboard_fab2_lib.baseboard_fab2(sch_1):tp_cpu0_rsvd_261") )
				( member ( signalRef "@baseboard_fab2_lib.baseboard_fab2(sch_1):tp_cpu0_rsvd_262") )
				( member ( signalRef "@baseboard_fab2_lib.baseboard_fab2(sch_1):tp_cpu0_rsvd_263") )
				( member ( signalRef "@baseboard_fab2_lib.baseboard_fab2(sch_1):tp_cpu0_rsvd_264") )
				( member ( signalRef "@baseboard_fab2_lib.baseboard_fab2(sch_1):tp_cpu0_rsvd_265") )
				( member ( signalRef "@baseboard_fab2_lib.baseboard_fab2(sch_1):tp_cpu0_rsvd_266") )
				( member ( signalRef "@baseboard_fab2_lib.baseboard_fab2(sch_1):tp_cpu0_rsvd_267") )
				( member ( signalRef "@baseboard_fab2_lib.baseboard_fab2(sch_1):tp_cpu0_rsvd_268") )
				( member ( signalRef "@baseboard_fab2_lib.baseboard_fab2(sch_1):tp_cpu0_rsvd_269") )
				( member ( signalRef "@baseboard_fab2_lib.baseboard_fab2(sch_1):tp_cpu0_rsvd_270") )
				( member ( signalRef "@baseboard_fab2_lib.baseboard_fab2(sch_1):tp_cpu0_rsvd_271") )
				( member ( signalRef "@baseboard_fab2_lib.baseboard_fab2(sch_1):tp_cpu0_rsvd_272") )
				( member ( signalRef "@baseboard_fab2_lib.baseboard_fab2(sch_1):tp_cpu0_rsvd_273") )
				( member ( signalRef "@baseboard_fab2_lib.baseboard_fab2(sch_1):tp_cpu0_rsvd_274") )
				( member ( signalRef "@baseboard_fab2_lib.baseboard_fab2(sch_1):tp_cpu0_rsvd_276") )
				( member ( signalRef "@baseboard_fab2_lib.baseboard_fab2(sch_1):tp_cpu0_rsvd_277") )
				( member ( signalRef "@baseboard_fab2_lib.baseboard_fab2(sch_1):tp_cpu0_rsvd_278") )
				( member ( signalRef "@baseboard_fab2_lib.baseboard_fab2(sch_1):tp_cpu0_rsvd_279") )
				( member ( signalRef "@baseboard_fab2_lib.baseboard_fab2(sch_1):tp_cpu0_rsvd_280") )
				( member ( signalRef "@baseboard_fab2_lib.baseboard_fab2(sch_1):tp_cpu0_rsvd_281") )
				( member ( signalRef "@baseboard_fab2_lib.baseboard_fab2(sch_1):tp_cpu0_rsvd_284") )
				( member ( signalRef "@baseboard_fab2_lib.baseboard_fab2(sch_1):tp_cpu0_rsvd_285") )
				( member ( signalRef "@baseboard_fab2_lib.baseboard_fab2(sch_1):tp_cpu0_rsvd_286") )
				( member ( signalRef "@baseboard_fab2_lib.baseboard_fab2(sch_1):tp_cpu0_rsvd_288") )
				( member ( signalRef "@baseboard_fab2_lib.baseboard_fab2(sch_1):tp_cpu0_rsvd_289") )
				( member ( signalRef "@baseboard_fab2_lib.baseboard_fab2(sch_1):tp_cpu0_rsvd_290") )
				( member ( signalRef "@baseboard_fab2_lib.baseboard_fab2(sch_1):tp_cpu0_rsvd_291") )
				( member ( signalRef "@baseboard_fab2_lib.baseboard_fab2(sch_1):tp_cpu0_rsvd_292") )
				( member ( signalRef "@baseboard_fab2_lib.baseboard_fab2(sch_1):tp_cpu0_rsvd_293") )
				( member ( signalRef "@baseboard_fab2_lib.baseboard_fab2(sch_1):tp_cpu0_rsvd_300") )
				( member ( signalRef "@baseboard_fab2_lib.baseboard_fab2(sch_1):tp_cpu0_socket_id_2") )
				( member ( signalRef "@baseboard_fab2_lib.baseboard_fab2(sch_1):tp_cpu0_rsvd_test_5") )
				( member ( signalRef "@baseboard_fab2_lib.baseboard_fab2(sch_1):tp_cpu0_upi2_rsvd_ca12") )
				( member ( signalRef "@baseboard_fab2_lib.baseboard_fab2(sch_1):tp_cpu0_upi2_rsvd_cb11") )
				( member ( signalRef "@baseboard_fab2_lib.baseboard_fab2(sch_1):tp_cpu0_upi2_rsvd_cc10") )
				( member ( signalRef "@baseboard_fab2_lib.baseboard_fab2(sch_1):tp_cpu0_upi2_rsvd_cc12") )
				( member ( signalRef "@baseboard_fab2_lib.baseboard_fab2(sch_1):tp_cpu0_upi2_rsvd_cd11") )
				( member ( signalRef "@baseboard_fab2_lib.baseboard_fab2(sch_1):tp_cpu0_upi2_rsvd_ce12") )
				( member ( signalRef "@baseboard_fab2_lib.baseboard_fab2(sch_1):tp_cpu0_upi2_rsvd_cf11") )
				( member ( signalRef "@baseboard_fab2_lib.baseboard_fab2(sch_1):tp_cpu0_upi2_rsvd_cf13") )
				( member ( signalRef "@baseboard_fab2_lib.baseboard_fab2(sch_1):tp_cpu0_upi2_rsvd_cg12") )
				( member ( signalRef "@baseboard_fab2_lib.baseboard_fab2(sch_1):tp_cpu0_upi2_rsvd_ch11") )
				( member ( signalRef "@baseboard_fab2_lib.baseboard_fab2(sch_1):tp_cpu0_upi2_rsvd_ch13") )
				( member ( signalRef "@baseboard_fab2_lib.baseboard_fab2(sch_1):tp_cpu0_upi2_rsvd_cj14") )
				( member ( signalRef "@baseboard_fab2_lib.baseboard_fab2(sch_1):tp_cpu0_upi2_rsvd_ck13") )
				( member ( signalRef "@baseboard_fab2_lib.baseboard_fab2(sch_1):tp_cpu0_upi2_rsvd_cm13") )
				( member ( signalRef "@baseboard_fab2_lib.baseboard_fab2(sch_1):tp_cpu0_upi2_rsvd_cr14") )
				( member ( signalRef "@baseboard_fab2_lib.baseboard_fab2(sch_1):tp_cpu0_upi2_rsvd_cu14") )
				( member ( signalRef "@baseboard_fab2_lib.baseboard_fab2(sch_1):tp_cpu0_upi2_rsvd_cv13") )
				( member ( signalRef "@baseboard_fab2_lib.baseboard_fab2(sch_1):tp_cpu1_upi2_rsvd_cg12") )
				( member ( signalRef "@baseboard_fab2_lib.baseboard_fab2(sch_1):tp_cpu1_upi2_rsvd_ch11") )
				( member ( signalRef "@baseboard_fab2_lib.baseboard_fab2(sch_1):tp_cpu1_upi2_rsvd_ch13") )
				( member ( signalRef "@baseboard_fab2_lib.baseboard_fab2(sch_1):tp_cpu1_upi2_rsvd_cj14") )
				( member ( signalRef "@baseboard_fab2_lib.baseboard_fab2(sch_1):tp_cpu1_upi2_rsvd_ck13") )
				( member ( signalRef "@baseboard_fab2_lib.baseboard_fab2(sch_1):tp_cpu1_upi2_rsvd_cm13") )
				( member ( signalRef "@baseboard_fab2_lib.baseboard_fab2(sch_1):tp_cpu0_upi2_rsvd_dd15") )
				( member ( signalRef "@baseboard_fab2_lib.baseboard_fab2(sch_1):tp_cpu0_upi2_rsvd_dd17") )
				( member ( signalRef "@baseboard_fab2_lib.baseboard_fab2(sch_1):tp_cpu0_upi2_rsvd_de16") )
				( member ( signalRef "@baseboard_fab2_lib.baseboard_fab2(sch_1):tp_cpu0_upi2_rsvd_df15") )
				( member ( signalRef "@baseboard_fab2_lib.baseboard_fab2(sch_1):tp_cpu0_upi2_rsvd_df17") )
				( member ( signalRef "@baseboard_fab2_lib.baseboard_fab2(sch_1):tp_cpu0_upi2_rsvd_dg18") )
				( member ( signalRef "@baseboard_fab2_lib.baseboard_fab2(sch_1):tp_cpu0_upi2_rsvd_dg20") )
				( member ( signalRef "@baseboard_fab2_lib.baseboard_fab2(sch_1):tp_cpu0_upi2_rsvd_dh17") )
				( member ( signalRef "@baseboard_fab2_lib.baseboard_fab2(sch_1):tp_cpu0_upi2_rsvd_dh19") )
				( member ( signalRef "@baseboard_fab2_lib.baseboard_fab2(sch_1):tp_cpu0_upi2_rsvd_dj18") )
				( member ( signalRef "@baseboard_fab2_lib.baseboard_fab2(sch_1):tp_cpu0_upi2_rsvd_dj20") )
				( member ( signalRef "@baseboard_fab2_lib.baseboard_fab2(sch_1):tp_cpu0_upi2_rsvd_dk17") )
				( member ( signalRef "@baseboard_fab2_lib.baseboard_fab2(sch_1):tp_cpu0_upi2_rsvd_dk19") )
				( member ( signalRef "@baseboard_fab2_lib.baseboard_fab2(sch_1):tp_cpu0_upi2_rsvd_dl20") )
				( member ( signalRef "@baseboard_fab2_lib.baseboard_fab2(sch_1):tp_cpu0_upi2_rsvd_dm21") )
				( member ( signalRef "@baseboard_fab2_lib.baseboard_fab2(sch_1):tp_cpu0_upi2_rsvd_dn20") )
				( member ( signalRef "@baseboard_fab2_lib.baseboard_fab2(sch_1):tp_cpu0_upi2_rsvd_dp21") )
				( member ( signalRef "@baseboard_fab2_lib.baseboard_fab2(sch_1):tp_cpu0_upi2_rsvd_dt21") )
				( member ( signalRef "@baseboard_fab2_lib.baseboard_fab2(sch_1):tp_cpu1_dmi_rx_dn0") )
				( member ( signalRef "@baseboard_fab2_lib.baseboard_fab2(sch_1):tp_cpu1_dmi_rx_dn1") )
				( member ( signalRef "@baseboard_fab2_lib.baseboard_fab2(sch_1):tp_cpu1_dmi_rx_dn2") )
				( member ( signalRef "@baseboard_fab2_lib.baseboard_fab2(sch_1):tp_cpu1_dmi_rx_dn3") )
				( member ( signalRef "@baseboard_fab2_lib.baseboard_fab2(sch_1):tp_cpu1_dmi_rx_dp0") )
				( member ( signalRef "@baseboard_fab2_lib.baseboard_fab2(sch_1):tp_cpu1_dmi_rx_dp1") )
				( member ( signalRef "@baseboard_fab2_lib.baseboard_fab2(sch_1):tp_cpu1_dmi_rx_dp2") )
				( member ( signalRef "@baseboard_fab2_lib.baseboard_fab2(sch_1):tp_cpu1_dmi_rx_dp3") )
				( member ( signalRef "@baseboard_fab2_lib.baseboard_fab2(sch_1):tp_cpu1_dmi_tx_dn0") )
				( member ( signalRef "@baseboard_fab2_lib.baseboard_fab2(sch_1):tp_cpu1_dmi_tx_dn1") )
				( member ( signalRef "@baseboard_fab2_lib.baseboard_fab2(sch_1):tp_cpu1_dmi_tx_dn2") )
				( member ( signalRef "@baseboard_fab2_lib.baseboard_fab2(sch_1):tp_cpu1_dmi_tx_dn3") )
				( member ( signalRef "@baseboard_fab2_lib.baseboard_fab2(sch_1):tp_cpu1_dmi_tx_dp0") )
				( member ( signalRef "@baseboard_fab2_lib.baseboard_fab2(sch_1):tp_cpu1_dmi_tx_dp1") )
				( member ( signalRef "@baseboard_fab2_lib.baseboard_fab2(sch_1):tp_cpu1_dmi_tx_dp2") )
				( member ( signalRef "@baseboard_fab2_lib.baseboard_fab2(sch_1):tp_cpu1_dmi_tx_dp3") )
				( member ( signalRef "@baseboard_fab2_lib.baseboard_fab2(sch_1):tp_cpu1_nmi") )
				( member ( signalRef "@baseboard_fab2_lib.baseboard_fab2(sch_1):tp_cpu1_proc_dis_g_n") )
				( member ( signalRef "@baseboard_fab2_lib.baseboard_fab2(sch_1):tp_cpu1_test_6") )
				( member ( signalRef "@baseboard_fab2_lib.baseboard_fab2(sch_1):tp_cpu1_rsvd_174") )
				( member ( signalRef "@baseboard_fab2_lib.baseboard_fab2(sch_1):tp_cpu1_rsvd_176") )
				( member ( signalRef "@baseboard_fab2_lib.baseboard_fab2(sch_1):tp_cpu1_rsvd_177") )
				( member ( signalRef "@baseboard_fab2_lib.baseboard_fab2(sch_1):tp_cpu1_rsvd_178") )
				( member ( signalRef "@baseboard_fab2_lib.baseboard_fab2(sch_1):tp_cpu1_rsvd_179") )
				( member ( signalRef "@baseboard_fab2_lib.baseboard_fab2(sch_1):tp_cpu1_rsvd_180") )
				( member ( signalRef "@baseboard_fab2_lib.baseboard_fab2(sch_1):tp_cpu1_rsvd_181") )
				( member ( signalRef "@baseboard_fab2_lib.baseboard_fab2(sch_1):tp_cpu1_rsvd_182") )
				( member ( signalRef "@baseboard_fab2_lib.baseboard_fab2(sch_1):tp_cpu1_rsvd_183") )
				( member ( signalRef "@baseboard_fab2_lib.baseboard_fab2(sch_1):tp_cpu1_rsvd_184") )
				( member ( signalRef "@baseboard_fab2_lib.baseboard_fab2(sch_1):tp_cpu1_rsvd_186") )
				( member ( signalRef "@baseboard_fab2_lib.baseboard_fab2(sch_1):tp_cpu1_rsvd_189") )
				( member ( signalRef "@baseboard_fab2_lib.baseboard_fab2(sch_1):tp_cpu1_rsvd_190") )
				( member ( signalRef "@baseboard_fab2_lib.baseboard_fab2(sch_1):tp_cpu1_rsvd_204") )
				( member ( signalRef "@baseboard_fab2_lib.baseboard_fab2(sch_1):tp_cpu1_rsvd_205") )
				( member ( signalRef "@baseboard_fab2_lib.baseboard_fab2(sch_1):tp_cpu1_rsvd_208") )
				( member ( signalRef "@baseboard_fab2_lib.baseboard_fab2(sch_1):tp_cpu1_rsvd_210") )
				( member ( signalRef "@baseboard_fab2_lib.baseboard_fab2(sch_1):tp_cpu1_rsvd_211") )
				( member ( signalRef "@baseboard_fab2_lib.baseboard_fab2(sch_1):tp_cpu1_rsvd_212") )
				( member ( signalRef "@baseboard_fab2_lib.baseboard_fab2(sch_1):tp_cpu1_rsvd_214") )
				( member ( signalRef "@baseboard_fab2_lib.baseboard_fab2(sch_1):tp_cpu1_rsvd_216") )
				( member ( signalRef "@baseboard_fab2_lib.baseboard_fab2(sch_1):tp_cpu1_rsvd_217") )
				( member ( signalRef "@baseboard_fab2_lib.baseboard_fab2(sch_1):tp_cpu1_rsvd_218") )
				( member ( signalRef "@baseboard_fab2_lib.baseboard_fab2(sch_1):tp_cpu1_rsvd_219") )
				( member ( signalRef "@baseboard_fab2_lib.baseboard_fab2(sch_1):tp_cpu1_rsvd_222") )
				( member ( signalRef "@baseboard_fab2_lib.baseboard_fab2(sch_1):tp_ioe4") )
				( member ( signalRef "@baseboard_fab2_lib.baseboard_fab2(sch_1):tp_iof4") )
				( member ( signalRef "@baseboard_fab2_lib.baseboard_fab2(sch_1):tp_iog3") )
				( member ( signalRef "@baseboard_fab2_lib.baseboard_fab2(sch_1):tp_ioh3") )
				( member ( signalRef "@baseboard_fab2_lib.baseboard_fab2(sch_1):tp_ioh4") )
				( member ( signalRef "@baseboard_fab2_lib.baseboard_fab2(sch_1):tp_ioi4") )
				( member ( signalRef "@baseboard_fab2_lib.baseboard_fab2(sch_1):tp_cpld1_pt16b") )
				( member ( signalRef "@baseboard_fab2_lib.baseboard_fab2(sch_1):tp_k4b1g16_bmc_nc0") )
				( member ( signalRef "@baseboard_fab2_lib.baseboard_fab2(sch_1):tp_k4b1g16_bmc_nc1") )
				( member ( signalRef "@baseboard_fab2_lib.baseboard_fab2(sch_1):tp_k4b1g16_bmc_nc2") )
				( member ( signalRef "@baseboard_fab2_lib.baseboard_fab2(sch_1):tp_cpu1_rsvd_235") )
				( member ( signalRef "@baseboard_fab2_lib.baseboard_fab2(sch_1):tp_cpu1_rsvd_236") )
				( member ( signalRef "@baseboard_fab2_lib.baseboard_fab2(sch_1):tp_cpu1_rsvd_237") )
				( member ( signalRef "@baseboard_fab2_lib.baseboard_fab2(sch_1):tp_cpu1_rsvd_238") )
				( member ( signalRef "@baseboard_fab2_lib.baseboard_fab2(sch_1):tp_cpu1_rsvd_239") )
				( member ( signalRef "@baseboard_fab2_lib.baseboard_fab2(sch_1):tp_cpu1_rsvd_240") )
				( member ( signalRef "@baseboard_fab2_lib.baseboard_fab2(sch_1):tp_cpu1_rsvd_241") )
				( member ( signalRef "@baseboard_fab2_lib.baseboard_fab2(sch_1):tp_cpu1_rsvd_242") )
				( member ( signalRef "@baseboard_fab2_lib.baseboard_fab2(sch_1):tp_cpu1_rsvd_243") )
				( member ( signalRef "@baseboard_fab2_lib.baseboard_fab2(sch_1):tp_cpu1_rsvd_244") )
				( member ( signalRef "@baseboard_fab2_lib.baseboard_fab2(sch_1):tp_cpu1_rsvd_245") )
				( member ( signalRef "@baseboard_fab2_lib.baseboard_fab2(sch_1):tp_cpu1_rsvd_246") )
				( member ( signalRef "@baseboard_fab2_lib.baseboard_fab2(sch_1):tp_cpu1_rsvd_247") )
				( member ( signalRef "@baseboard_fab2_lib.baseboard_fab2(sch_1):tp_cpu1_rsvd_248") )
				( member ( signalRef "@baseboard_fab2_lib.baseboard_fab2(sch_1):tp_cpu1_rsvd_249") )
				( member ( signalRef "@baseboard_fab2_lib.baseboard_fab2(sch_1):tp_cpu1_rsvd_250") )
				( member ( signalRef "@baseboard_fab2_lib.baseboard_fab2(sch_1):tp_cpu1_rsvd_251") )
				( member ( signalRef "@baseboard_fab2_lib.baseboard_fab2(sch_1):tp_cpu1_rsvd_252") )
				( member ( signalRef "@baseboard_fab2_lib.baseboard_fab2(sch_1):tp_cpu1_rsvd_253") )
				( member ( signalRef "@baseboard_fab2_lib.baseboard_fab2(sch_1):tp_cpu1_rsvd_254") )
				( member ( signalRef "@baseboard_fab2_lib.baseboard_fab2(sch_1):tp_cpu1_rsvd_255") )
				( member ( signalRef "@baseboard_fab2_lib.baseboard_fab2(sch_1):tp_cpu1_rsvd_256") )
				( member ( signalRef "@baseboard_fab2_lib.baseboard_fab2(sch_1):tp_cpu1_rsvd_258") )
				( member ( signalRef "@baseboard_fab2_lib.baseboard_fab2(sch_1):tp_cpu1_rsvd_259") )
				( member ( signalRef "@baseboard_fab2_lib.baseboard_fab2(sch_1):tp_cpu1_rsvd_260") )
				( member ( signalRef "@baseboard_fab2_lib.baseboard_fab2(sch_1):tp_cpu1_rsvd_261") )
				( member ( signalRef "@baseboard_fab2_lib.baseboard_fab2(sch_1):tp_cpu1_rsvd_262") )
				( member ( signalRef "@baseboard_fab2_lib.baseboard_fab2(sch_1):tp_cpu1_rsvd_263") )
				( member ( signalRef "@baseboard_fab2_lib.baseboard_fab2(sch_1):tp_cpu1_rsvd_264") )
				( member ( signalRef "@baseboard_fab2_lib.baseboard_fab2(sch_1):tp_cpu1_rsvd_265") )
				( member ( signalRef "@baseboard_fab2_lib.baseboard_fab2(sch_1):tp_cpu1_rsvd_266") )
				( member ( signalRef "@baseboard_fab2_lib.baseboard_fab2(sch_1):tp_cpu1_rsvd_267") )
				( member ( signalRef "@baseboard_fab2_lib.baseboard_fab2(sch_1):tp_cpu1_rsvd_268") )
				( member ( signalRef "@baseboard_fab2_lib.baseboard_fab2(sch_1):tp_cpu1_rsvd_269") )
				( member ( signalRef "@baseboard_fab2_lib.baseboard_fab2(sch_1):tp_cpu1_rsvd_270") )
				( member ( signalRef "@baseboard_fab2_lib.baseboard_fab2(sch_1):tp_cpu1_rsvd_271") )
				( member ( signalRef "@baseboard_fab2_lib.baseboard_fab2(sch_1):tp_cpu1_rsvd_272") )
				( member ( signalRef "@baseboard_fab2_lib.baseboard_fab2(sch_1):tp_cpu1_rsvd_273") )
				( member ( signalRef "@baseboard_fab2_lib.baseboard_fab2(sch_1):tp_cpu1_rsvd_274") )
				( member ( signalRef "@baseboard_fab2_lib.baseboard_fab2(sch_1):tp_cpu1_rsvd_276") )
				( member ( signalRef "@baseboard_fab2_lib.baseboard_fab2(sch_1):tp_cpu1_rsvd_277") )
				( member ( signalRef "@baseboard_fab2_lib.baseboard_fab2(sch_1):tp_cpu1_rsvd_278") )
				( member ( signalRef "@baseboard_fab2_lib.baseboard_fab2(sch_1):tp_cpu1_rsvd_279") )
				( member ( signalRef "@baseboard_fab2_lib.baseboard_fab2(sch_1):tp_cpu1_rsvd_280") )
				( member ( signalRef "@baseboard_fab2_lib.baseboard_fab2(sch_1):tp_cpu1_rsvd_281") )
				( member ( signalRef "@baseboard_fab2_lib.baseboard_fab2(sch_1):tp_cpu1_rsvd_284") )
				( member ( signalRef "@baseboard_fab2_lib.baseboard_fab2(sch_1):tp_cpu1_rsvd_285") )
				( member ( signalRef "@baseboard_fab2_lib.baseboard_fab2(sch_1):tp_cpu1_rsvd_286") )
				( member ( signalRef "@baseboard_fab2_lib.baseboard_fab2(sch_1):tp_cpu1_rsvd_288") )
				( member ( signalRef "@baseboard_fab2_lib.baseboard_fab2(sch_1):tp_cpu1_rsvd_289") )
				( member ( signalRef "@baseboard_fab2_lib.baseboard_fab2(sch_1):tp_cpu1_rsvd_290") )
				( member ( signalRef "@baseboard_fab2_lib.baseboard_fab2(sch_1):tp_cpu1_rsvd_291") )
				( member ( signalRef "@baseboard_fab2_lib.baseboard_fab2(sch_1):tp_cpu1_rsvd_292") )
				( member ( signalRef "@baseboard_fab2_lib.baseboard_fab2(sch_1):tp_cpu1_rsvd_293") )
				( member ( signalRef "@baseboard_fab2_lib.baseboard_fab2(sch_1):tp_cpu1_rsvd_300") )
				( member ( signalRef "@baseboard_fab2_lib.baseboard_fab2(sch_1):fm_cpu1_sm_wp") )
				( member ( signalRef "@baseboard_fab2_lib.baseboard_fab2(sch_1):tp_cpu1_socket_id_2") )
				( member ( signalRef "@baseboard_fab2_lib.baseboard_fab2(sch_1):tp_cpu1_rsvd_test_5") )
				( member ( signalRef "@baseboard_fab2_lib.baseboard_fab2(sch_1):tp_cpu1_upi2_rsvd_ca12") )
				( member ( signalRef "@baseboard_fab2_lib.baseboard_fab2(sch_1):tp_cpu1_upi2_rsvd_cb11") )
				( member ( signalRef "@baseboard_fab2_lib.baseboard_fab2(sch_1):tp_cpu1_upi2_rsvd_cc10") )
				( member ( signalRef "@baseboard_fab2_lib.baseboard_fab2(sch_1):tp_cpu1_upi2_rsvd_cc12") )
				( member ( signalRef "@baseboard_fab2_lib.baseboard_fab2(sch_1):tp_cpu1_upi2_rsvd_cd11") )
				( member ( signalRef "@baseboard_fab2_lib.baseboard_fab2(sch_1):tp_cpu1_upi2_rsvd_ce12") )
				( member ( signalRef "@baseboard_fab2_lib.baseboard_fab2(sch_1):tp_cpu1_upi2_rsvd_cf11") )
				( member ( signalRef "@baseboard_fab2_lib.baseboard_fab2(sch_1):tp_cpu1_upi2_rsvd_cf13") )
				( member ( signalRef "@baseboard_fab2_lib.baseboard_fab2(sch_1):tp_pch_rsvd28") )
				( member ( signalRef "@baseboard_fab2_lib.baseboard_fab2(sch_1):tp_pch_rsvd29") )
				( member ( signalRef "@baseboard_fab2_lib.baseboard_fab2(sch_1):tp_pch_rsvd30") )
				( member ( signalRef "@baseboard_fab2_lib.baseboard_fab2(sch_1):tp_pch_rsvd31") )
				( member ( signalRef "@baseboard_fab2_lib.baseboard_fab2(sch_1):tp_pch_rsvd32") )
				( member ( signalRef "@baseboard_fab2_lib.baseboard_fab2(sch_1):tp_pch_rsvd33") )
				( member ( signalRef "@baseboard_fab2_lib.baseboard_fab2(sch_1):tp_pch_rsvd34") )
				( member ( signalRef "@baseboard_fab2_lib.baseboard_fab2(sch_1):tp_pch_rsvd35") )
				( member ( signalRef "@baseboard_fab2_lib.baseboard_fab2(sch_1):tp_pch_rsvd36") )
				( member ( signalRef "@baseboard_fab2_lib.baseboard_fab2(sch_1):tp_pch_rsvd37") )
				( member ( signalRef "@baseboard_fab2_lib.baseboard_fab2(sch_1):tp_pch_rsvd38") )
				( member ( signalRef "@baseboard_fab2_lib.baseboard_fab2(sch_1):tp_pch_rsvd41") )
				( member ( signalRef "@baseboard_fab2_lib.baseboard_fab2(sch_1):tp_cpu1_upi2_rsvd_cr14") )
				( member ( signalRef "@baseboard_fab2_lib.baseboard_fab2(sch_1):tp_cpu1_upi2_rsvd_cu14") )
				( member ( signalRef "@baseboard_fab2_lib.baseboard_fab2(sch_1):tp_cpu1_upi2_rsvd_cv13") )
				( member ( signalRef "@baseboard_fab2_lib.baseboard_fab2(sch_1):tp_cpu1_upi2_rsvd_cw14") )
				( member ( signalRef "@baseboard_fab2_lib.baseboard_fab2(sch_1):tp_cpu1_upi2_rsvd_cw16") )
				( member ( signalRef "@baseboard_fab2_lib.baseboard_fab2(sch_1):tp_cpu1_upi2_rsvd_da16") )
				( member ( signalRef "@baseboard_fab2_lib.baseboard_fab2(sch_1):tp_cpu1_upi2_rsvd_db15") )
				( member ( signalRef "@baseboard_fab2_lib.baseboard_fab2(sch_1):tp_cpu1_upi2_rsvd_dc16") )
				( member ( signalRef "@baseboard_fab2_lib.baseboard_fab2(sch_1):tp_cpu1_upi2_rsvd_dd15") )
				( member ( signalRef "@baseboard_fab2_lib.baseboard_fab2(sch_1):tp_cpu1_upi2_rsvd_dd17") )
				( member ( signalRef "@baseboard_fab2_lib.baseboard_fab2(sch_1):tp_cpu1_upi2_rsvd_de16") )
				( member ( signalRef "@baseboard_fab2_lib.baseboard_fab2(sch_1):tp_cpu1_upi2_rsvd_df15") )
				( member ( signalRef "@baseboard_fab2_lib.baseboard_fab2(sch_1):tp_cpu1_upi2_rsvd_df17") )
				( member ( signalRef "@baseboard_fab2_lib.baseboard_fab2(sch_1):tp_cpu1_upi2_rsvd_dg18") )
				( member ( signalRef "@baseboard_fab2_lib.baseboard_fab2(sch_1):tp_cpu1_upi2_rsvd_dg20") )
				( member ( signalRef "@baseboard_fab2_lib.baseboard_fab2(sch_1):tp_cpu1_upi2_rsvd_dh17") )
				( member ( signalRef "@baseboard_fab2_lib.baseboard_fab2(sch_1):tp_cpu1_upi2_rsvd_dh19") )
				( member ( signalRef "@baseboard_fab2_lib.baseboard_fab2(sch_1):tp_cpu1_upi2_rsvd_dj18") )
				( member ( signalRef "@baseboard_fab2_lib.baseboard_fab2(sch_1):tp_cpu1_upi2_rsvd_dj20") )
				( member ( signalRef "@baseboard_fab2_lib.baseboard_fab2(sch_1):tp_cpu1_upi2_rsvd_dk17") )
				( member ( signalRef "@baseboard_fab2_lib.baseboard_fab2(sch_1):tp_cpu1_upi2_rsvd_dk19") )
				( member ( signalRef "@baseboard_fab2_lib.baseboard_fab2(sch_1):tp_cpu1_upi2_rsvd_dl20") )
				( member ( signalRef "@baseboard_fab2_lib.baseboard_fab2(sch_1):tp_cpu1_upi2_rsvd_dm21") )
				( member ( signalRef "@baseboard_fab2_lib.baseboard_fab2(sch_1):tp_cpu1_upi2_rsvd_dn20") )
				( member ( signalRef "@baseboard_fab2_lib.baseboard_fab2(sch_1):tp_cpu1_upi2_rsvd_dp21") )
				( member ( signalRef "@baseboard_fab2_lib.baseboard_fab2(sch_1):tp_cpu1_upi2_rsvd_dt21") )
				( member ( signalRef "@baseboard_fab2_lib.baseboard_fab2(sch_1):tp_cpld1_pl2b_l_gpllc_in") )
				( member ( signalRef "@baseboard_fab2_lib.baseboard_fab2(sch_1):tp_cpld1_pb8a_mclk_cclk") )
				( member ( signalRef "@baseboard_fab2_lib.baseboard_fab2(sch_1):tp_cpld1_pb5a_csspin") )
				( member ( signalRef "@baseboard_fab2_lib.baseboard_fab2(sch_1):tp_cpld1_pb8b_so_spiso") )
				( member ( signalRef "@baseboard_fab2_lib.baseboard_fab2(sch_1):tp_cpld1_pt20b") )
				( member ( signalRef "@baseboard_fab2_lib.baseboard_fab2(sch_1):tp_cpld1_pt20a") )
				( member ( signalRef "@baseboard_fab2_lib.baseboard_fab2(sch_1):tp_cpld1_pt22c") )
				( member ( signalRef "@baseboard_fab2_lib.baseboard_fab2(sch_1):tp_fm_qat_cbl_prsnt0_r_n") )
				( member ( signalRef "@baseboard_fab2_lib.baseboard_fab2(sch_1):tp_fm_qat_cbl_prsnt1_n_r") )
				( member ( signalRef "@baseboard_fab2_lib.baseboard_fab2(sch_1):tp_fm_qat_cbl_prsnt2_n") )
				( member ( signalRef "@baseboard_fab2_lib.baseboard_fab2(sch_1):tp_cpld1_pl1a_l_gpllt_fb") )
				( member ( signalRef "@baseboard_fab2_lib.baseboard_fab2(sch_1):tp_gpiom5_nrts2_vpib7") )
				( member ( signalRef "@baseboard_fab2_lib.baseboard_fab2(sch_1):tp_hfi_io_conn0_rsvd_17") )
				( member ( signalRef "@baseboard_fab2_lib.baseboard_fab2(sch_1):tp_hsc_alert2_n") )
				( member ( signalRef "@baseboard_fab2_lib.baseboard_fab2(sch_1):tp_hsc_mclk") )
				( member ( signalRef "@baseboard_fab2_lib.baseboard_fab2(sch_1):tp_hsc_mdat") )
				( member ( signalRef "@baseboard_fab2_lib.baseboard_fab2(sch_1):tp_hsc_spissn") )
				( member ( signalRef "@baseboard_fab2_lib.baseboard_fab2(sch_1):tp_ie_debug_mode") )
				( member ( signalRef "@baseboard_fab2_lib.baseboard_fab2(sch_1):tp_fm_wake_n") )
				( member ( signalRef "@baseboard_fab2_lib.baseboard_fab2(sch_1):tp_pvddq_abc_mp1") )
				( member ( signalRef "@baseboard_fab2_lib.baseboard_fab2(sch_1):tp_pvddq_abc_ph3_imon") )
				( member ( signalRef "@baseboard_fab2_lib.baseboard_fab2(sch_1):tp_pvddq_abc_ph3_imon_ref") )
				( member ( signalRef "@baseboard_fab2_lib.baseboard_fab2(sch_1):tp_pvddq_abc_pinalrt_n") )
				( member ( signalRef "@baseboard_fab2_lib.baseboard_fab2(sch_1):tp_pvddq_abc_pwm3") )
				( member ( signalRef "@baseboard_fab2_lib.baseboard_fab2(sch_1):tp_pvddq_abc_reset_n") )
				( member ( signalRef "@baseboard_fab2_lib.baseboard_fab2(sch_1):tp_pvddq_def_bpwm1") )
				( member ( signalRef "@baseboard_fab2_lib.baseboard_fab2(sch_1):tp_k4b1g16_bmc_nc3") )
				( member ( signalRef "@baseboard_fab2_lib.baseboard_fab2(sch_1):tp_k4b1g16_bmc_nc4") )
				( member ( signalRef "@baseboard_fab2_lib.baseboard_fab2(sch_1):tp_cpld1_pb16b_pclkc2_1") )
				( member ( signalRef "@baseboard_fab2_lib.baseboard_fab2(sch_1):tp_pch_gpp_j21") )
				( member ( signalRef "@baseboard_fab2_lib.baseboard_fab2(sch_1):tp_pch_gpp_j23") )
				( member ( signalRef "@baseboard_fab2_lib.baseboard_fab2(sch_1):tp_cpld1_pl1b_l_gpllc_fb") )
				( member ( signalRef "@baseboard_fab2_lib.baseboard_fab2(sch_1):tp_cpld1_pb11b_pclkc2_0") )
				( member ( signalRef "@baseboard_fab2_lib.baseboard_fab2(sch_1):tp_me_rcvr_boot") )
				( member ( signalRef "@baseboard_fab2_lib.baseboard_fab2(sch_1):tp_nmi_cpu0") )
				( member ( signalRef "@baseboard_fab2_lib.baseboard_fab2(sch_1):tp_password_clear") )
				( member ( signalRef "@baseboard_fab2_lib.baseboard_fab2(sch_1):tp_pch_dispa_bclk") )
				( member ( signalRef "@baseboard_fab2_lib.baseboard_fab2(sch_1):tp_pch_dispa_sdi") )
				( member ( signalRef "@baseboard_fab2_lib.baseboard_fab2(sch_1):tp_pch_dispa_sdo") )
				( member ( signalRef "@baseboard_fab2_lib.baseboard_fab2(sch_1):tp_pch_hda_bclk") )
				( member ( signalRef "@baseboard_fab2_lib.baseboard_fab2(sch_1):tp_pch_hda_sdi_0") )
				( member ( signalRef "@baseboard_fab2_lib.baseboard_fab2(sch_1):tp_pch_hda_sdi_1") )
				( member ( signalRef "@baseboard_fab2_lib.baseboard_fab2(sch_1):tp_pch_hda_sync") )
				( member ( signalRef "@baseboard_fab2_lib.baseboard_fab2(sch_1):tp_pch_hsa_rst_n") )
				( member ( signalRef "@baseboard_fab2_lib.baseboard_fab2(sch_1):tp_pch_rsvd0") )
				( member ( signalRef "@baseboard_fab2_lib.baseboard_fab2(sch_1):tp_pch_rsvd1") )
				( member ( signalRef "@baseboard_fab2_lib.baseboard_fab2(sch_1):tp_pch_rsvd2") )
				( member ( signalRef "@baseboard_fab2_lib.baseboard_fab2(sch_1):tp_pch_rsvd3") )
				( member ( signalRef "@baseboard_fab2_lib.baseboard_fab2(sch_1):tp_pch_rsvd4") )
				( member ( signalRef "@baseboard_fab2_lib.baseboard_fab2(sch_1):tp_pch_rsvd5") )
				( member ( signalRef "@baseboard_fab2_lib.baseboard_fab2(sch_1):tp_pch_rsvd6") )
				( member ( signalRef "@baseboard_fab2_lib.baseboard_fab2(sch_1):tp_pch_rsvd7") )
				( member ( signalRef "@baseboard_fab2_lib.baseboard_fab2(sch_1):tp_pch_rsvd8") )
				( member ( signalRef "@baseboard_fab2_lib.baseboard_fab2(sch_1):tp_pch_rsvd9") )
				( member ( signalRef "@baseboard_fab2_lib.baseboard_fab2(sch_1):tp_pch_rsvd12") )
				( member ( signalRef "@baseboard_fab2_lib.baseboard_fab2(sch_1):tp_pch_rsvd13") )
				( member ( signalRef "@baseboard_fab2_lib.baseboard_fab2(sch_1):tp_pch_rsvd14") )
				( member ( signalRef "@baseboard_fab2_lib.baseboard_fab2(sch_1):tp_pch_rsvd15") )
				( member ( signalRef "@baseboard_fab2_lib.baseboard_fab2(sch_1):tp_pch_rsvd16") )
				( member ( signalRef "@baseboard_fab2_lib.baseboard_fab2(sch_1):tp_pch_rsvd17") )
				( member ( signalRef "@baseboard_fab2_lib.baseboard_fab2(sch_1):tp_pch_rsvd18") )
				( member ( signalRef "@baseboard_fab2_lib.baseboard_fab2(sch_1):tp_pch_rsvd19") )
				( member ( signalRef "@baseboard_fab2_lib.baseboard_fab2(sch_1):tp_pch_rsvd20") )
				( member ( signalRef "@baseboard_fab2_lib.baseboard_fab2(sch_1):tp_pch_rsvd21") )
				( member ( signalRef "@baseboard_fab2_lib.baseboard_fab2(sch_1):tp_pch_rsvd22") )
				( member ( signalRef "@baseboard_fab2_lib.baseboard_fab2(sch_1):tp_pch_rsvd23") )
				( member ( signalRef "@baseboard_fab2_lib.baseboard_fab2(sch_1):tp_pch_rsvd24") )
				( member ( signalRef "@baseboard_fab2_lib.baseboard_fab2(sch_1):tp_pch_rsvd25") )
				( member ( signalRef "@baseboard_fab2_lib.baseboard_fab2(sch_1):tp_pch_rsvd26") )
				( member ( signalRef "@baseboard_fab2_lib.baseboard_fab2(sch_1):tp_pch_rsvd27") )
				( member ( signalRef "@baseboard_fab2_lib.baseboard_fab2(sch_1):tp_p3e_cpu1_pe1_mp_txp(6)") )
				( member ( signalRef "@baseboard_fab2_lib.baseboard_fab2(sch_1):tp_p3e_cpu1_pe1_mp_txp(7)") )
				( member ( signalRef "@baseboard_fab2_lib.baseboard_fab2(sch_1):tp_p3e_cpu1_pe1_rsr3_rxn(8)") )
				( member ( signalRef "@baseboard_fab2_lib.baseboard_fab2(sch_1):tp_p3e_cpu1_pe1_rsr3_rxn(9)") )
				( member ( signalRef "@baseboard_fab2_lib.baseboard_fab2(sch_1):tp_p3e_cpu1_pe1_rsr3_rxn(10)") )
				( member ( signalRef "@baseboard_fab2_lib.baseboard_fab2(sch_1):tp_p3e_cpu1_pe1_rsr3_rxn(11)") )
				( member ( signalRef "@baseboard_fab2_lib.baseboard_fab2(sch_1):tp_p3e_cpu1_pe1_rsr3_rxn(12)") )
				( member ( signalRef "@baseboard_fab2_lib.baseboard_fab2(sch_1):tp_p3e_cpu1_pe1_rsr3_rxn(13)") )
				( member ( signalRef "@baseboard_fab2_lib.baseboard_fab2(sch_1):tp_p3e_cpu1_pe1_rsr3_rxn(14)") )
				( member ( signalRef "@baseboard_fab2_lib.baseboard_fab2(sch_1):tp_p3e_cpu1_pe1_rsr3_rxn(15)") )
				( member ( signalRef "@baseboard_fab2_lib.baseboard_fab2(sch_1):tp_p3e_cpu1_pe1_rsr3_rxp(8)") )
				( member ( signalRef "@baseboard_fab2_lib.baseboard_fab2(sch_1):tp_p3e_cpu1_pe1_rsr3_rxp(9)") )
				( member ( signalRef "@baseboard_fab2_lib.baseboard_fab2(sch_1):tp_pch_rsvd42") )
				( member ( signalRef "@baseboard_fab2_lib.baseboard_fab2(sch_1):tp_pch_rsvd45") )
				( member ( signalRef "@baseboard_fab2_lib.baseboard_fab2(sch_1):tp_pch_rsvd46") )
				( member ( signalRef "@baseboard_fab2_lib.baseboard_fab2(sch_1):tp_pch_rsvd47") )
				( member ( signalRef "@baseboard_fab2_lib.baseboard_fab2(sch_1):tp_pch_rsvd48") )
				( member ( signalRef "@baseboard_fab2_lib.baseboard_fab2(sch_1):tp_pch_rsvd49") )
				( member ( signalRef "@baseboard_fab2_lib.baseboard_fab2(sch_1):tp_pch_rsvd50") )
				( member ( signalRef "@baseboard_fab2_lib.baseboard_fab2(sch_1):tp_pch_rsvd51") )
				( member ( signalRef "@baseboard_fab2_lib.baseboard_fab2(sch_1):tp_pch_rsvd52") )
				( member ( signalRef "@baseboard_fab2_lib.baseboard_fab2(sch_1):tp_pch_rsvd53") )
				( member ( signalRef "@baseboard_fab2_lib.baseboard_fab2(sch_1):tp_pch_rsvd54") )
				( member ( signalRef "@baseboard_fab2_lib.baseboard_fab2(sch_1):tp_pch_rsvd55") )
				( member ( signalRef "@baseboard_fab2_lib.baseboard_fab2(sch_1):tp_pch_rsvd58") )
				( member ( signalRef "@baseboard_fab2_lib.baseboard_fab2(sch_1):tp_pch_rsvd59") )
				( member ( signalRef "@baseboard_fab2_lib.baseboard_fab2(sch_1):tp_pch_rsvd64") )
				( member ( signalRef "@baseboard_fab2_lib.baseboard_fab2(sch_1):tp_pch_rsvd65") )
				( member ( signalRef "@baseboard_fab2_lib.baseboard_fab2(sch_1):tp_cpld1_pr12d") )
				( member ( signalRef "@baseboard_fab2_lib.baseboard_fab2(sch_1):tp_pltrst_cpu_n") )
				( member ( signalRef "@baseboard_fab2_lib.baseboard_fab2(sch_1):tp_pm_sync_gtl") )
				( member ( signalRef "@baseboard_fab2_lib.baseboard_fab2(sch_1):tp_pvccin_cpu0_airef6") )
				( member ( signalRef "@baseboard_fab2_lib.baseboard_fab2(sch_1):tp_pvccin_cpu0_apwm6") )
				( member ( signalRef "@baseboard_fab2_lib.baseboard_fab2(sch_1):tp_pvccin_cpu0_gp1") )
				( member ( signalRef "@baseboard_fab2_lib.baseboard_fab2(sch_1):tp_pvccin_cpu0_reset") )
				( member ( signalRef "@baseboard_fab2_lib.baseboard_fab2(sch_1):tp_pvccin_cpu1_airef6") )
				( member ( signalRef "@baseboard_fab2_lib.baseboard_fab2(sch_1):tp_pvccin_cpu1_apwm6") )
				( member ( signalRef "@baseboard_fab2_lib.baseboard_fab2(sch_1):tp_pvccin_cpu1_gp1") )
				( member ( signalRef "@baseboard_fab2_lib.baseboard_fab2(sch_1):tp_pvccin_cpu1_reset_n") )
				( member ( signalRef "@baseboard_fab2_lib.baseboard_fab2(sch_1):tp_pvccio_cpu0_biref1") )
				( member ( signalRef "@baseboard_fab2_lib.baseboard_fab2(sch_1):tp_pvccio_cpu0_bpwm1") )
				( member ( signalRef "@baseboard_fab2_lib.baseboard_fab2(sch_1):tp_pvccio_cpu0_btsen") )
				( member ( signalRef "@baseboard_fab2_lib.baseboard_fab2(sch_1):tp_pvccio_cpu0_bvref") )
				( member ( signalRef "@baseboard_fab2_lib.baseboard_fab2(sch_1):tp_pvccio_cpu0_bvsen") )
				( member ( signalRef "@baseboard_fab2_lib.baseboard_fab2(sch_1):tp_vr_pvccio_cpu0_mp0") )
				( member ( signalRef "@baseboard_fab2_lib.baseboard_fab2(sch_1):tp_vr_pvccio_cpu0_mp1") )
				( member ( signalRef "@baseboard_fab2_lib.baseboard_fab2(sch_1):tp_pvccio_cpu0_pinalrt_n") )
				( member ( signalRef "@baseboard_fab2_lib.baseboard_fab2(sch_1):tp_pvccio_cpu0_reset_n") )
				( member ( signalRef "@baseboard_fab2_lib.baseboard_fab2(sch_1):tp_pvccio_cpu1_biref1") )
				( member ( signalRef "@baseboard_fab2_lib.baseboard_fab2(sch_1):tp_pvccio_cpu1_bpwm1") )
				( member ( signalRef "@baseboard_fab2_lib.baseboard_fab2(sch_1):tp_pvccio_cpu1_btsen") )
				( member ( signalRef "@baseboard_fab2_lib.baseboard_fab2(sch_1):tp_pvccio_cpu1_bvref") )
				( member ( signalRef "@baseboard_fab2_lib.baseboard_fab2(sch_1):tp_pvccio_cpu1_bvsen") )
				( member ( signalRef "@baseboard_fab2_lib.baseboard_fab2(sch_1):tp_vr_pvccio_cpu1_mp0") )
				( member ( signalRef "@baseboard_fab2_lib.baseboard_fab2(sch_1):tp_vr_pvccio_cpu1_mp1") )
				( member ( signalRef "@baseboard_fab2_lib.baseboard_fab2(sch_1):tp_pvccio_cpu1_pinalrt_n") )
				( member ( signalRef "@baseboard_fab2_lib.baseboard_fab2(sch_1):tp_pvccio_cpu1_reset_n") )
				( member ( signalRef "@baseboard_fab2_lib.baseboard_fab2(sch_1):tp_pvddq_abc_bpwm1") )
				( member ( signalRef "@baseboard_fab2_lib.baseboard_fab2(sch_1):tp_pvddq_abc_bref1") )
				( member ( signalRef "@baseboard_fab2_lib.baseboard_fab2(sch_1):tp_pvddq_abc_btsen") )
				( member ( signalRef "@baseboard_fab2_lib.baseboard_fab2(sch_1):tp_pvddq_abc_bvref") )
				( member ( signalRef "@baseboard_fab2_lib.baseboard_fab2(sch_1):tp_pvddq_abc_bvsen") )
				( member ( signalRef "@baseboard_fab2_lib.baseboard_fab2(sch_1):tp_cpld1_pt13a") )
				( member ( signalRef "@baseboard_fab2_lib.baseboard_fab2(sch_1):tp_cpld1_pt11b") )
				( member ( signalRef "@baseboard_fab2_lib.baseboard_fab2(sch_1):tp_cpld1_pt11a") )
				( member ( signalRef "@baseboard_fab2_lib.baseboard_fab2(sch_1):tp_rst_rtcrst_n") )
				( member ( signalRef "@baseboard_fab2_lib.baseboard_fab2(sch_1):tp_rsvd_b1") )
				( member ( signalRef "@baseboard_fab2_lib.baseboard_fab2(sch_1):tp_sgpio_sata_clock1_r") )
				( member ( signalRef "@baseboard_fab2_lib.baseboard_fab2(sch_1):tp_sgpio_sata_data1_r") )
				( member ( signalRef "@baseboard_fab2_lib.baseboard_fab2(sch_1):tp_pvddq_def_bref1") )
				( member ( signalRef "@baseboard_fab2_lib.baseboard_fab2(sch_1):tp_pvddq_def_btsen") )
				( member ( signalRef "@baseboard_fab2_lib.baseboard_fab2(sch_1):tp_pvddq_def_bvref") )
				( member ( signalRef "@baseboard_fab2_lib.baseboard_fab2(sch_1):tp_pvddq_def_bvsen") )
				( member ( signalRef "@baseboard_fab2_lib.baseboard_fab2(sch_1):tp_pvddq_def_mp1") )
				( member ( signalRef "@baseboard_fab2_lib.baseboard_fab2(sch_1):tp_pvddq_def_ph3_imon") )
				( member ( signalRef "@baseboard_fab2_lib.baseboard_fab2(sch_1):tp_pvddq_def_ph3_imon_ref") )
				( member ( signalRef "@baseboard_fab2_lib.baseboard_fab2(sch_1):tp_pvddq_def_pinalrt_n") )
				( member ( signalRef "@baseboard_fab2_lib.baseboard_fab2(sch_1):tp_pvddq_def_pwm3") )
				( member ( signalRef "@baseboard_fab2_lib.baseboard_fab2(sch_1):tp_pvddq_def_reset_n") )
				( member ( signalRef "@baseboard_fab2_lib.baseboard_fab2(sch_1):tp_pvddq_ghj_bpwm1") )
				( member ( signalRef "@baseboard_fab2_lib.baseboard_fab2(sch_1):tp_pvddq_ghj_bref1") )
				( member ( signalRef "@baseboard_fab2_lib.baseboard_fab2(sch_1):tp_pvddq_ghj_btsen") )
				( member ( signalRef "@baseboard_fab2_lib.baseboard_fab2(sch_1):tp_pvddq_ghj_bvref") )
				( member ( signalRef "@baseboard_fab2_lib.baseboard_fab2(sch_1):tp_pvddq_ghj_bvsen") )
				( member ( signalRef "@baseboard_fab2_lib.baseboard_fab2(sch_1):tp_pvddq_ghj_mp1") )
				( member ( signalRef "@baseboard_fab2_lib.baseboard_fab2(sch_1):tp_pvddq_ghj_pwm3") )
				( member ( signalRef "@baseboard_fab2_lib.baseboard_fab2(sch_1):tp_pvddq_ghj_reset_n") )
				( member ( signalRef "@baseboard_fab2_lib.baseboard_fab2(sch_1):tp_pvddq_klm_bpwm1") )
				( member ( signalRef "@baseboard_fab2_lib.baseboard_fab2(sch_1):tp_pvddq_klm_bref1") )
				( member ( signalRef "@baseboard_fab2_lib.baseboard_fab2(sch_1):tp_pvddq_klm_btsen") )
				( member ( signalRef "@baseboard_fab2_lib.baseboard_fab2(sch_1):tp_pvddq_klm_bvref") )
				( member ( signalRef "@baseboard_fab2_lib.baseboard_fab2(sch_1):tp_pvddq_klm_bvsen") )
				( member ( signalRef "@baseboard_fab2_lib.baseboard_fab2(sch_1):tp_pvddq_klm_reset_n") )
				( member ( signalRef "@baseboard_fab2_lib.baseboard_fab2(sch_1):tp_pvnn_pch_pinalrt_n") )
				( member ( signalRef "@baseboard_fab2_lib.baseboard_fab2(sch_1):tp_pvnn_pch_reset_n") )
				( member ( signalRef "@baseboard_fab2_lib.baseboard_fab2(sch_1):tp_pvnn_pch_svid_alert") )
				( member ( signalRef "@baseboard_fab2_lib.baseboard_fab2(sch_1):tp_pvnn_pch_vclk") )
				( member ( signalRef "@baseboard_fab2_lib.baseboard_fab2(sch_1):tp_pvnn_pch_vdio") )
				( member ( signalRef "@baseboard_fab2_lib.baseboard_fab2(sch_1):tp_cpld1_pt22d") )
				( member ( signalRef "@baseboard_fab2_lib.baseboard_fab2(sch_1):tp_p3e_cpu1_pe1_mp_rxn(0)") )
				( member ( signalRef "@baseboard_fab2_lib.baseboard_fab2(sch_1):tp_p3e_cpu1_pe1_mp_rxn(1)") )
				( member ( signalRef "@baseboard_fab2_lib.baseboard_fab2(sch_1):tp_p3e_cpu1_pe1_mp_rxn(2)") )
				( member ( signalRef "@baseboard_fab2_lib.baseboard_fab2(sch_1):tp_p3e_cpu1_pe1_mp_rxn(3)") )
				( member ( signalRef "@baseboard_fab2_lib.baseboard_fab2(sch_1):tp_p3e_cpu1_pe1_mp_rxn(4)") )
				( member ( signalRef "@baseboard_fab2_lib.baseboard_fab2(sch_1):tp_p3e_cpu1_pe1_mp_rxn(5)") )
				( member ( signalRef "@baseboard_fab2_lib.baseboard_fab2(sch_1):tp_p3e_cpu1_pe1_mp_rxn(6)") )
				( member ( signalRef "@baseboard_fab2_lib.baseboard_fab2(sch_1):tp_p3e_cpu1_pe1_mp_rxn(7)") )
				( member ( signalRef "@baseboard_fab2_lib.baseboard_fab2(sch_1):tp_p3e_cpu1_pe1_mp_rxp(0)") )
				( member ( signalRef "@baseboard_fab2_lib.baseboard_fab2(sch_1):tp_p3e_cpu1_pe1_mp_rxp(1)") )
				( member ( signalRef "@baseboard_fab2_lib.baseboard_fab2(sch_1):tp_p3e_cpu1_pe1_mp_rxp(2)") )
				( member ( signalRef "@baseboard_fab2_lib.baseboard_fab2(sch_1):tp_p3e_cpu1_pe1_mp_rxp(3)") )
				( member ( signalRef "@baseboard_fab2_lib.baseboard_fab2(sch_1):tp_p3e_cpu1_pe1_mp_rxp(4)") )
				( member ( signalRef "@baseboard_fab2_lib.baseboard_fab2(sch_1):tp_p3e_cpu1_pe1_mp_rxp(5)") )
				( member ( signalRef "@baseboard_fab2_lib.baseboard_fab2(sch_1):tp_p3e_cpu1_pe1_mp_rxp(6)") )
				( member ( signalRef "@baseboard_fab2_lib.baseboard_fab2(sch_1):tp_p3e_cpu1_pe1_mp_rxp(7)") )
				( member ( signalRef "@baseboard_fab2_lib.baseboard_fab2(sch_1):tp_p3e_cpu1_pe1_mp_txn(0)") )
				( member ( signalRef "@baseboard_fab2_lib.baseboard_fab2(sch_1):tp_p3e_cpu1_pe1_mp_txn(1)") )
				( member ( signalRef "@baseboard_fab2_lib.baseboard_fab2(sch_1):tp_p3e_cpu1_pe1_mp_txn(2)") )
				( member ( signalRef "@baseboard_fab2_lib.baseboard_fab2(sch_1):tp_p3e_cpu1_pe1_mp_txn(3)") )
				( member ( signalRef "@baseboard_fab2_lib.baseboard_fab2(sch_1):tp_p3e_cpu1_pe1_mp_txn(4)") )
				( member ( signalRef "@baseboard_fab2_lib.baseboard_fab2(sch_1):tp_p3e_cpu1_pe1_mp_txn(5)") )
				( member ( signalRef "@baseboard_fab2_lib.baseboard_fab2(sch_1):tp_p3e_cpu1_pe1_mp_txn(6)") )
				( member ( signalRef "@baseboard_fab2_lib.baseboard_fab2(sch_1):tp_p3e_cpu1_pe1_mp_txn(7)") )
				( member ( signalRef "@baseboard_fab2_lib.baseboard_fab2(sch_1):tp_p3e_cpu1_pe1_mp_txp(0)") )
				( member ( signalRef "@baseboard_fab2_lib.baseboard_fab2(sch_1):tp_p3e_cpu1_pe1_mp_txp(1)") )
				( member ( signalRef "@baseboard_fab2_lib.baseboard_fab2(sch_1):tp_p3e_cpu1_pe1_mp_txp(2)") )
				( member ( signalRef "@baseboard_fab2_lib.baseboard_fab2(sch_1):tp_p3e_cpu1_pe1_mp_txp(3)") )
				( member ( signalRef "@baseboard_fab2_lib.baseboard_fab2(sch_1):tp_p3e_cpu1_pe1_mp_txp(4)") )
				( member ( signalRef "@baseboard_fab2_lib.baseboard_fab2(sch_1):tp_p3e_cpu1_pe1_mp_txp(5)") )
				( member ( signalRef "@baseboard_fab2_lib.baseboard_fab2(sch_1):tp_xdp_cpu_obsfn_c0") )
				( member ( signalRef "@baseboard_fab2_lib.baseboard_fab2(sch_1):tp_xdp_cpu0_obsdata_a0_mbp2_n") )
				( member ( signalRef "@baseboard_fab2_lib.baseboard_fab2(sch_1):tp_p3e_cpu1_pe1_rsr3_rxp(10)") )
				( member ( signalRef "@baseboard_fab2_lib.baseboard_fab2(sch_1):tp_p3e_cpu1_pe1_rsr3_rxp(11)") )
				( member ( signalRef "@baseboard_fab2_lib.baseboard_fab2(sch_1):tp_p3e_cpu1_pe1_rsr3_rxp(12)") )
				( member ( signalRef "@baseboard_fab2_lib.baseboard_fab2(sch_1):tp_p3e_cpu1_pe1_rsr3_rxp(13)") )
				( member ( signalRef "@baseboard_fab2_lib.baseboard_fab2(sch_1):tp_p3e_cpu1_pe1_rsr3_rxp(14)") )
				( member ( signalRef "@baseboard_fab2_lib.baseboard_fab2(sch_1):tp_p3e_cpu1_pe1_rsr3_rxp(15)") )
				( member ( signalRef "@baseboard_fab2_lib.baseboard_fab2(sch_1):tp_p3e_cpu1_pe1_rsr3_txn(8)") )
				( member ( signalRef "@baseboard_fab2_lib.baseboard_fab2(sch_1):tp_p3e_cpu1_pe1_rsr3_txn(9)") )
				( member ( signalRef "@baseboard_fab2_lib.baseboard_fab2(sch_1):tp_p3e_cpu1_pe1_rsr3_txn(10)") )
				( member ( signalRef "@baseboard_fab2_lib.baseboard_fab2(sch_1):tp_p3e_cpu1_pe1_rsr3_txn(11)") )
				( member ( signalRef "@baseboard_fab2_lib.baseboard_fab2(sch_1):tp_p3e_cpu1_pe1_rsr3_txn(12)") )
				( member ( signalRef "@baseboard_fab2_lib.baseboard_fab2(sch_1):tp_p3e_cpu1_pe1_rsr3_txn(13)") )
				( member ( signalRef "@baseboard_fab2_lib.baseboard_fab2(sch_1):tp_p3e_cpu1_pe1_rsr3_txn(14)") )
				( member ( signalRef "@baseboard_fab2_lib.baseboard_fab2(sch_1):tp_p3e_cpu1_pe1_rsr3_txn(15)") )
				( member ( signalRef "@baseboard_fab2_lib.baseboard_fab2(sch_1):tp_p3e_cpu1_pe1_rsr3_txp(8)") )
				( member ( signalRef "@baseboard_fab2_lib.baseboard_fab2(sch_1):tp_p3e_cpu1_pe1_rsr3_txp(9)") )
				( member ( signalRef "@baseboard_fab2_lib.baseboard_fab2(sch_1):tp_p3e_cpu1_pe1_rsr3_txp(10)") )
				( member ( signalRef "@baseboard_fab2_lib.baseboard_fab2(sch_1):tp_p3e_cpu1_pe1_rsr3_txp(11)") )
				( member ( signalRef "@baseboard_fab2_lib.baseboard_fab2(sch_1):tp_p3e_cpu1_pe1_rsr3_txp(12)") )
				( member ( signalRef "@baseboard_fab2_lib.baseboard_fab2(sch_1):tp_p3e_cpu1_pe1_rsr3_txp(13)") )
				( member ( signalRef "@baseboard_fab2_lib.baseboard_fab2(sch_1):tp_p3e_cpu1_pe1_rsr3_txp(14)") )
				( member ( signalRef "@baseboard_fab2_lib.baseboard_fab2(sch_1):tp_p3e_cpu1_pe1_rsr3_txp(15)") )
				( member ( signalRef "@baseboard_fab2_lib.baseboard_fab2(sch_1):tp_p3e_cpu1_pe2_rsr_rxn(0)") )
				( member ( signalRef "@baseboard_fab2_lib.baseboard_fab2(sch_1):tp_p3e_cpu1_pe2_rsr_rxn(1)") )
				( member ( signalRef "@baseboard_fab2_lib.baseboard_fab2(sch_1):tp_p3e_cpu1_pe2_rsr_rxn(2)") )
				( member ( signalRef "@baseboard_fab2_lib.baseboard_fab2(sch_1):tp_p3e_cpu1_pe2_rsr_rxn(3)") )
				( member ( signalRef "@baseboard_fab2_lib.baseboard_fab2(sch_1):tp_p3e_cpu1_pe2_rsr_rxn(4)") )
				( member ( signalRef "@baseboard_fab2_lib.baseboard_fab2(sch_1):tp_p3e_cpu1_pe2_rsr_rxn(5)") )
				( member ( signalRef "@baseboard_fab2_lib.baseboard_fab2(sch_1):tp_p3e_cpu1_pe2_rsr_rxn(6)") )
				( member ( signalRef "@baseboard_fab2_lib.baseboard_fab2(sch_1):tp_p3e_cpu1_pe2_rsr_rxn(7)") )
				( member ( signalRef "@baseboard_fab2_lib.baseboard_fab2(sch_1):tp_p3e_cpu1_pe2_rsr_rxn(8)") )
				( member ( signalRef "@baseboard_fab2_lib.baseboard_fab2(sch_1):tp_p3e_cpu1_pe2_rsr_rxn(9)") )
				( member ( signalRef "@baseboard_fab2_lib.baseboard_fab2(sch_1):tp_p3e_cpu1_pe2_rsr_rxn(10)") )
				( member ( signalRef "@baseboard_fab2_lib.baseboard_fab2(sch_1):tp_p3e_cpu1_pe2_rsr_rxn(11)") )
				( member ( signalRef "@baseboard_fab2_lib.baseboard_fab2(sch_1):tp_p3e_cpu1_pe2_rsr_rxn(12)") )
				( member ( signalRef "@baseboard_fab2_lib.baseboard_fab2(sch_1):tp_p3e_cpu1_pe2_rsr_rxn(13)") )
				( member ( signalRef "@baseboard_fab2_lib.baseboard_fab2(sch_1):tp_p3e_cpu1_pe2_rsr_rxn(14)") )
				( member ( signalRef "@baseboard_fab2_lib.baseboard_fab2(sch_1):tp_p3e_cpu1_pe2_rsr_rxn(15)") )
				( member ( signalRef "@baseboard_fab2_lib.baseboard_fab2(sch_1):tp_p3e_cpu1_pe2_rsr_rxp(0)") )
				( member ( signalRef "@baseboard_fab2_lib.baseboard_fab2(sch_1):tp_p3e_cpu1_pe2_rsr_rxp(1)") )
				( member ( signalRef "@baseboard_fab2_lib.baseboard_fab2(sch_1):tp_p3e_cpu1_pe2_rsr_rxp(2)") )
				( member ( signalRef "@baseboard_fab2_lib.baseboard_fab2(sch_1):tp_p3e_cpu1_pe2_rsr_rxp(3)") )
				( member ( signalRef "@baseboard_fab2_lib.baseboard_fab2(sch_1):tp_p3e_cpu1_pe2_rsr_rxp(4)") )
				( member ( signalRef "@baseboard_fab2_lib.baseboard_fab2(sch_1):tp_p3e_cpu1_pe2_rsr_rxp(5)") )
				( member ( signalRef "@baseboard_fab2_lib.baseboard_fab2(sch_1):tp_p3e_cpu1_pe2_rsr_rxp(6)") )
				( member ( signalRef "@baseboard_fab2_lib.baseboard_fab2(sch_1):tp_p3e_cpu1_pe2_rsr_rxp(7)") )
				( member ( signalRef "@baseboard_fab2_lib.baseboard_fab2(sch_1):tp_p3e_cpu1_pe2_rsr_rxp(8)") )
				( member ( signalRef "@baseboard_fab2_lib.baseboard_fab2(sch_1):tp_p3e_cpu1_pe2_rsr_rxp(9)") )
				( member ( signalRef "@baseboard_fab2_lib.baseboard_fab2(sch_1):tp_p3e_cpu1_pe2_rsr_rxp(10)") )
				( member ( signalRef "@baseboard_fab2_lib.baseboard_fab2(sch_1):tp_p3e_cpu1_pe2_rsr_rxp(11)") )
				( member ( signalRef "@baseboard_fab2_lib.baseboard_fab2(sch_1):tp_p3e_cpu1_pe2_rsr_rxp(12)") )
				( member ( signalRef "@baseboard_fab2_lib.baseboard_fab2(sch_1):tp_p3e_cpu1_pe2_rsr_rxp(13)") )
				( member ( signalRef "@baseboard_fab2_lib.baseboard_fab2(sch_1):tp_p3e_cpu1_pe2_rsr_rxp(14)") )
				( member ( signalRef "@baseboard_fab2_lib.baseboard_fab2(sch_1):tp_p3e_cpu1_pe2_rsr_rxp(15)") )
				( member ( signalRef "@baseboard_fab2_lib.baseboard_fab2(sch_1):tp_p3e_cpu1_pe2_rsr_txn(0)") )
				( member ( signalRef "@baseboard_fab2_lib.baseboard_fab2(sch_1):tp_p3e_cpu1_pe2_rsr_txn(1)") )
				( member ( signalRef "@baseboard_fab2_lib.baseboard_fab2(sch_1):tp_p3e_cpu1_pe2_rsr_txn(2)") )
				( member ( signalRef "@baseboard_fab2_lib.baseboard_fab2(sch_1):tp_p3e_cpu1_pe2_rsr_txn(3)") )
				( member ( signalRef "@baseboard_fab2_lib.baseboard_fab2(sch_1):tp_p3e_cpu1_pe2_rsr_txn(4)") )
				( member ( signalRef "@baseboard_fab2_lib.baseboard_fab2(sch_1):tp_p3e_cpu1_pe2_rsr_txn(5)") )
				( member ( signalRef "@baseboard_fab2_lib.baseboard_fab2(sch_1):tp_p3e_cpu1_pe2_rsr_txn(6)") )
				( member ( signalRef "@baseboard_fab2_lib.baseboard_fab2(sch_1):tp_p3e_cpu1_pe2_rsr_txn(7)") )
				( member ( signalRef "@baseboard_fab2_lib.baseboard_fab2(sch_1):tp_p3e_cpu1_pe2_rsr_txn(8)") )
				( member ( signalRef "@baseboard_fab2_lib.baseboard_fab2(sch_1):tp_p3e_cpu1_pe2_rsr_txn(9)") )
				( member ( signalRef "@baseboard_fab2_lib.baseboard_fab2(sch_1):tp_p3e_cpu1_pe2_rsr_txn(10)") )
				( member ( signalRef "@baseboard_fab2_lib.baseboard_fab2(sch_1):tp_p3e_cpu1_pe2_rsr_txn(11)") )
				( member ( signalRef "@baseboard_fab2_lib.baseboard_fab2(sch_1):tp_p3e_cpu1_pe2_rsr_txn(12)") )
				( member ( signalRef "@baseboard_fab2_lib.baseboard_fab2(sch_1):tp_p3e_cpu1_pe2_rsr_txn(13)") )
				( member ( signalRef "@baseboard_fab2_lib.baseboard_fab2(sch_1):tp_p3e_cpu1_pe2_rsr_txn(14)") )
				( member ( signalRef "@baseboard_fab2_lib.baseboard_fab2(sch_1):tp_p3e_cpu1_pe2_rsr_txn(15)") )
				( member ( signalRef "@baseboard_fab2_lib.baseboard_fab2(sch_1):tp_p3e_cpu1_pe2_rsr_txp(0)") )
				( member ( signalRef "@baseboard_fab2_lib.baseboard_fab2(sch_1):tp_p3e_cpu1_pe2_rsr_txp(1)") )
				( member ( signalRef "@baseboard_fab2_lib.baseboard_fab2(sch_1):tp_p3e_cpu1_pe2_rsr_txp(2)") )
				( member ( signalRef "@baseboard_fab2_lib.baseboard_fab2(sch_1):tp_p3e_cpu1_pe2_rsr_txp(3)") )
				( member ( signalRef "@baseboard_fab2_lib.baseboard_fab2(sch_1):tp_p3e_cpu1_pe2_rsr_txp(4)") )
				( member ( signalRef "@baseboard_fab2_lib.baseboard_fab2(sch_1):tp_p3e_cpu1_pe2_rsr_txp(5)") )
				( member ( signalRef "@baseboard_fab2_lib.baseboard_fab2(sch_1):tp_p3e_cpu1_pe2_rsr_txp(6)") )
				( member ( signalRef "@baseboard_fab2_lib.baseboard_fab2(sch_1):tp_p3e_cpu1_pe2_rsr_txp(7)") )
				( member ( signalRef "@baseboard_fab2_lib.baseboard_fab2(sch_1):tp_p3e_cpu1_pe2_rsr_txp(8)") )
				( member ( signalRef "@baseboard_fab2_lib.baseboard_fab2(sch_1):tp_p3e_cpu1_pe2_rsr_txp(9)") )
				( member ( signalRef "@baseboard_fab2_lib.baseboard_fab2(sch_1):tp_p3e_cpu1_pe2_rsr_txp(10)") )
				( member ( signalRef "@baseboard_fab2_lib.baseboard_fab2(sch_1):tp_p3e_cpu1_pe2_rsr_txp(11)") )
				( member ( signalRef "@baseboard_fab2_lib.baseboard_fab2(sch_1):tp_p3e_cpu1_pe2_rsr_txp(12)") )
				( member ( signalRef "@baseboard_fab2_lib.baseboard_fab2(sch_1):tp_p3e_cpu1_pe2_rsr_txp(13)") )
				( member ( signalRef "@baseboard_fab2_lib.baseboard_fab2(sch_1):tp_p3e_cpu1_pe2_rsr_txp(14)") )
				( member ( signalRef "@baseboard_fab2_lib.baseboard_fab2(sch_1):tp_p3e_cpu1_pe2_rsr_txp(15)") )
				( member ( signalRef "@baseboard_fab2_lib.baseboard_fab2(sch_1):tp_cpld1_pt17b_pclkc0_1") )
				( member ( signalRef "@baseboard_fab2_lib.baseboard_fab2(sch_1):tp_xdp_cpu0_obsdata_a1_mbp3_n") )
				( member ( signalRef "@baseboard_fab2_lib.baseboard_fab2(sch_1):tp_xdp_cpu0_obsdata_a2_mbp4_n") )
				( member ( signalRef "@baseboard_fab2_lib.baseboard_fab2(sch_1):tp_xdp_cpu0_obsdata_a3_mbp5_n") )
				( member ( signalRef "@baseboard_fab2_lib.baseboard_fab2(sch_1):tp_xdp_cpu1_obsdata_b0_mbp2_n") )
				( member ( signalRef "@baseboard_fab2_lib.baseboard_fab2(sch_1):tp_xdp_cpu1_obsdata_b1_mbp3_n") )
				( member ( signalRef "@baseboard_fab2_lib.baseboard_fab2(sch_1):tp_xdp_cpu1_obsdata_b2_mbp4_n") )
				( member ( signalRef "@baseboard_fab2_lib.baseboard_fab2(sch_1):tp_xdp_cpu1_obsdata_b3_mbp5_n") )
				( member ( signalRef "@baseboard_fab2_lib.baseboard_fab2(sch_1):tp_10gbe_kr0_mon_dn") )
				( member ( signalRef "@baseboard_fab2_lib.baseboard_fab2(sch_1):tp_10gbe_kr0_mon_dp") )
				( member ( signalRef "@baseboard_fab2_lib.baseboard_fab2(sch_1):tp_10gbe_kr1_mon_dn") )
				( member ( signalRef "@baseboard_fab2_lib.baseboard_fab2(sch_1):tp_10gbe_kr1_mon_dp") )
				( member ( signalRef "@baseboard_fab2_lib.baseboard_fab2(sch_1):tp_33p_33m_smbadr") )
				( member ( signalRef "@baseboard_fab2_lib.baseboard_fab2(sch_1):tp_sgpio_sata_load1_r") )
				( member ( signalRef "@baseboard_fab2_lib.baseboard_fab2(sch_1):tp_slp_lan_n") )
				( member ( signalRef "@baseboard_fab2_lib.baseboard_fab2(sch_1):tp_smb_ddr_abc_en") )
				( member ( signalRef "@baseboard_fab2_lib.baseboard_fab2(sch_1):tp_smb_ddr_def_en") )
				( member ( signalRef "@baseboard_fab2_lib.baseboard_fab2(sch_1):tp_smb_ddr_ghj_en") )
				( member ( signalRef "@baseboard_fab2_lib.baseboard_fab2(sch_1):tp_smb_ddr_klm_en") )
				( member ( signalRef "@baseboard_fab2_lib.baseboard_fab2(sch_1):tp_smb_pehpcpu1_en") )
				( member ( signalRef "@baseboard_fab2_lib.baseboard_fab2(sch_1):fm_cpu0_sm_wp") )
				( member ( signalRef "@baseboard_fab2_lib.baseboard_fab2(sch_1):tp_spi_bmc_bt_d2") )
				( member ( signalRef "@baseboard_fab2_lib.baseboard_fab2(sch_1):tp_spi_pch_cs1_r1_n") )
				( member ( signalRef "@baseboard_fab2_lib.baseboard_fab2(sch_1):tp_spi_0_0") )
				( member ( signalRef "@baseboard_fab2_lib.baseboard_fab2(sch_1):tp_spi_0_1") )
				( member ( signalRef "@baseboard_fab2_lib.baseboard_fab2(sch_1):tp_spi_0_2") )
				( member ( signalRef "@baseboard_fab2_lib.baseboard_fab2(sch_1):tp_spi_0_3") )
				( member ( signalRef "@baseboard_fab2_lib.baseboard_fab2(sch_1):tp_spi_0_4") )
				( member ( signalRef "@baseboard_fab2_lib.baseboard_fab2(sch_1):tp_spi_0_5") )
				( member ( signalRef "@baseboard_fab2_lib.baseboard_fab2(sch_1):tp_spi_0_6") )
				( member ( signalRef "@baseboard_fab2_lib.baseboard_fab2(sch_1):tp_spi_1_0") )
				( member ( signalRef "@baseboard_fab2_lib.baseboard_fab2(sch_1):tp_spi_1_1") )
				( member ( signalRef "@baseboard_fab2_lib.baseboard_fab2(sch_1):tp_spi_1_2") )
				( member ( signalRef "@baseboard_fab2_lib.baseboard_fab2(sch_1):tp_spi_1_3") )
				( member ( signalRef "@baseboard_fab2_lib.baseboard_fab2(sch_1):tp_spi_1_4") )
				( member ( signalRef "@baseboard_fab2_lib.baseboard_fab2(sch_1):tp_spi_1_5") )
				( member ( signalRef "@baseboard_fab2_lib.baseboard_fab2(sch_1):tp_spi_1_6") )
				( member ( signalRef "@baseboard_fab2_lib.baseboard_fab2(sch_1):tp_spi_2_6") )
				( member ( signalRef "@baseboard_fab2_lib.baseboard_fab2(sch_1):tp_spi_2_5") )
				( member ( signalRef "@baseboard_fab2_lib.baseboard_fab2(sch_1):tp_spi_2_4") )
				( member ( signalRef "@baseboard_fab2_lib.baseboard_fab2(sch_1):tp_spi_2_3") )
				( member ( signalRef "@baseboard_fab2_lib.baseboard_fab2(sch_1):tp_spi_2_2") )
				( member ( signalRef "@baseboard_fab2_lib.baseboard_fab2(sch_1):tp_spi_2_1") )
				( member ( signalRef "@baseboard_fab2_lib.baseboard_fab2(sch_1):tp_spi_2_0") )
				( member ( signalRef "@baseboard_fab2_lib.baseboard_fab2(sch_1):tp_usb2_p8_dn") )
				( member ( signalRef "@baseboard_fab2_lib.baseboard_fab2(sch_1):tp_usb2_p8_dp") )
				( member ( signalRef "@baseboard_fab2_lib.baseboard_fab2(sch_1):tp_usb2_p9_dn") )
				( member ( signalRef "@baseboard_fab2_lib.baseboard_fab2(sch_1):tp_usb2_p9_dp") )
				( member ( signalRef "@baseboard_fab2_lib.baseboard_fab2(sch_1):tp_usb2_p02_dn") )
				( member ( signalRef "@baseboard_fab2_lib.baseboard_fab2(sch_1):tp_usb2_p02_dp") )
				( member ( signalRef "@baseboard_fab2_lib.baseboard_fab2(sch_1):tp_usb2_p03_dn") )
				( member ( signalRef "@baseboard_fab2_lib.baseboard_fab2(sch_1):tp_usb2_p03_dp") )
				( member ( signalRef "@baseboard_fab2_lib.baseboard_fab2(sch_1):tp_usb2_p06_dn") )
				( member ( signalRef "@baseboard_fab2_lib.baseboard_fab2(sch_1):tp_usb2_p06_dp") )
				( member ( signalRef "@baseboard_fab2_lib.baseboard_fab2(sch_1):tp_usb2_p07_dn") )
				( member ( signalRef "@baseboard_fab2_lib.baseboard_fab2(sch_1):tp_usb2_p07_dp") )
				( member ( signalRef "@baseboard_fab2_lib.baseboard_fab2(sch_1):tp_usb2_p10_dn") )
				( member ( signalRef "@baseboard_fab2_lib.baseboard_fab2(sch_1):tp_usb2_p10_dp") )
				( member ( signalRef "@baseboard_fab2_lib.baseboard_fab2(sch_1):tp_usb2_p11_dn") )
				( member ( signalRef "@baseboard_fab2_lib.baseboard_fab2(sch_1):tp_usb2_p11_dp") )
				( member ( signalRef "@baseboard_fab2_lib.baseboard_fab2(sch_1):tp_usb2_p12_dn") )
				( member ( signalRef "@baseboard_fab2_lib.baseboard_fab2(sch_1):tp_usb2_p12_dp") )
				( member ( signalRef "@baseboard_fab2_lib.baseboard_fab2(sch_1):tp_usb2_p13_dn") )
				( member ( signalRef "@baseboard_fab2_lib.baseboard_fab2(sch_1):tp_usb2_p13_dp") )
				( member ( signalRef "@baseboard_fab2_lib.baseboard_fab2(sch_1):tp_usb2_p14_dn") )
				( member ( signalRef "@baseboard_fab2_lib.baseboard_fab2(sch_1):tp_usb2_p14_dp") )
				( member ( signalRef "@baseboard_fab2_lib.baseboard_fab2(sch_1):tp_usb3_p04_rxn") )
				( member ( signalRef "@baseboard_fab2_lib.baseboard_fab2(sch_1):tp_usb3_p04_rxp") )
				( member ( signalRef "@baseboard_fab2_lib.baseboard_fab2(sch_1):tp_usb3_p04_txn") )
				( member ( signalRef "@baseboard_fab2_lib.baseboard_fab2(sch_1):tp_usb3_p04_txp") )
				( member ( signalRef "@baseboard_fab2_lib.baseboard_fab2(sch_1):tp_vr_pvccio_cpu0_aiinsen") )
				( member ( signalRef "@baseboard_fab2_lib.baseboard_fab2(sch_1):tp_vr_pvccio_cpu1_aiinsen") )
				( member ( signalRef "@baseboard_fab2_lib.baseboard_fab2(sch_1):tp_vr_pvnn_pch_aiinsen") )
				( objectStatus "CLS_TP" )
			)
			( netClass "@crescent_city_bb_fab1_lib.crescent_city_bb_fab1(sch_1):\CLS_PUPD\"
				( memberType ( signal ) )
				( attribute "PROPAGATION_DELAY_PATH_TYPE" "AD:AR"
					( Origin gBackEnd )
				)
				( attribute "PROPAGATION_DELAY_MAX" "2000.00 MIL"
					( Units "uMaxMinProp" "ns" 1.000000)
					( Origin gBackEnd )
				)
				( objectFlag fObjectElectrical )
				( member ( signalRef "@baseboard_fab2_lib.baseboard_fab2(sch_1):pu_pi7c9x1172_i2c_spi_n") )
				( member ( signalRef "@baseboard_fab2_lib.baseboard_fab2(sch_1):pu_rst_perst_bit0") )
				( member ( signalRef "@baseboard_fab2_lib.baseboard_fab2(sch_1):pu_rst_perst_bit1") )
				( member ( signalRef "@baseboard_fab2_lib.baseboard_fab2(sch_1):pu_spi_bmc_bt_hold_n") )
				( member ( signalRef "@baseboard_fab2_lib.baseboard_fab2(sch_1):pu_spi_bmc_bt_wp_n") )
				( member ( signalRef "@baseboard_fab2_lib.baseboard_fab2(sch_1):pu_spi_flash_reset_2_n") )
				( member ( signalRef "@baseboard_fab2_lib.baseboard_fab2(sch_1):pu_spi0_rst") )
				( member ( signalRef "@baseboard_fab2_lib.baseboard_fab2(sch_1):pu_spi1_rst") )
				( member ( signalRef "@baseboard_fab2_lib.baseboard_fab2(sch_1):pu_sprv_lan_pwr_good") )
				( member ( signalRef "@baseboard_fab2_lib.baseboard_fab2(sch_1):pu_thermtrip_force_n") )
				( member ( signalRef "@baseboard_fab2_lib.baseboard_fab2(sch_1):pu_tmp421_1_a1") )
				( member ( signalRef "@baseboard_fab2_lib.baseboard_fab2(sch_1):pu_tmp421_2_a0") )
				( member ( signalRef "@baseboard_fab2_lib.baseboard_fab2(sch_1):pu_tri_state_en") )
				( member ( signalRef "@baseboard_fab2_lib.baseboard_fab2(sch_1):pu_vr_pvccin_cpu0_imon") )
				( member ( signalRef "@baseboard_fab2_lib.baseboard_fab2(sch_1):pu_vr_pvccio_cpu0_fault1") )
				( member ( signalRef "@baseboard_fab2_lib.baseboard_fab2(sch_1):pu_vr_pvccio_cpu1_fault1") )
				( member ( signalRef "@baseboard_fab2_lib.baseboard_fab2(sch_1):pu_vr_pvddq_abc_fault1") )
				( member ( signalRef "@baseboard_fab2_lib.baseboard_fab2(sch_1):pu_vr_pvddq_def_fault1") )
				( member ( signalRef "@baseboard_fab2_lib.baseboard_fab2(sch_1):pu_vr_pvddq_ghj_fault1") )
				( member ( signalRef "@baseboard_fab2_lib.baseboard_fab2(sch_1):pu_vr_pvddq_klm_fault1") )
				( member ( signalRef "@baseboard_fab2_lib.baseboard_fab2(sch_1):pu_vr_pvnn_pch_fault1") )
				( member ( signalRef "@baseboard_fab2_lib.baseboard_fab2(sch_1):pd_adcrext") )
				( member ( signalRef "@baseboard_fab2_lib.baseboard_fab2(sch_1):pd_ckmng_oe") )
				( member ( signalRef "@baseboard_fab2_lib.baseboard_fab2(sch_1):pd_cpu0_bist_enable") )
				( member ( signalRef "@baseboard_fab2_lib.baseboard_fab2(sch_1):pd_cpu0_dmimode_override") )
				( member ( signalRef "@baseboard_fab2_lib.baseboard_fab2(sch_1):pd_cpu0_ksfc_dis") )
				( member ( signalRef "@baseboard_fab2_lib.baseboard_fab2(sch_1):pd_cpu0_txt_plten") )
				( member ( signalRef "@baseboard_fab2_lib.baseboard_fab2(sch_1):pd_cpu1_bist_enable") )
				( member ( signalRef "@baseboard_fab2_lib.baseboard_fab2(sch_1):pd_cpu1_dmimode_override") )
				( member ( signalRef "@baseboard_fab2_lib.baseboard_fab2(sch_1):pd_cpu1_ksfc_dis") )
				( member ( signalRef "@baseboard_fab2_lib.baseboard_fab2(sch_1):pd_cpu1_txt_plten") )
				( member ( signalRef "@baseboard_fab2_lib.baseboard_fab2(sch_1):pd_dir_2") )
				( member ( signalRef "@baseboard_fab2_lib.baseboard_fab2(sch_1):pd_fru_wp") )
				( member ( signalRef "@baseboard_fab2_lib.baseboard_fab2(sch_1):pd_gtl2014_1_vref") )
				( member ( signalRef "@baseboard_fab2_lib.baseboard_fab2(sch_1):pd_gtl2014_2_vref") )
				( member ( signalRef "@baseboard_fab2_lib.baseboard_fab2(sch_1):pd_gtl2104_dir_0") )
				( member ( signalRef "@baseboard_fab2_lib.baseboard_fab2(sch_1):pd_gtl2104_dir_1") )
				( member ( signalRef "@baseboard_fab2_lib.baseboard_fab2(sch_1):pd_gtl2104_4_dir") )
				( member ( signalRef "@baseboard_fab2_lib.baseboard_fab2(sch_1):pd_hsc_retry_n") )
				( member ( signalRef "@baseboard_fab2_lib.baseboard_fab2(sch_1):pd_ie_debug_mode") )
				( member ( signalRef "@baseboard_fab2_lib.baseboard_fab2(sch_1):pd_me_rcvr_n") )
				( member ( signalRef "@baseboard_fab2_lib.baseboard_fab2(sch_1):a_m_bmc_zq") )
				( member ( signalRef "@baseboard_fab2_lib.baseboard_fab2(sch_1):pd_password_clear") )
				( member ( signalRef "@baseboard_fab2_lib.baseboard_fab2(sch_1):pd_perext") )
				( member ( signalRef "@baseboard_fab2_lib.baseboard_fab2(sch_1):pd_rst_rtcrst_n") )
				( member ( signalRef "@baseboard_fab2_lib.baseboard_fab2(sch_1):pd_sata0_controller_type_r") )
				( member ( signalRef "@baseboard_fab2_lib.baseboard_fab2(sch_1):pd_sata1_controller_type_r") )
				( member ( signalRef "@baseboard_fab2_lib.baseboard_fab2(sch_1):pd_sata2_controller_type") )
				( member ( signalRef "@baseboard_fab2_lib.baseboard_fab2(sch_1):pd_sprv_rset") )
				( member ( signalRef "@baseboard_fab2_lib.baseboard_fab2(sch_1):pd_sp_entest") )
				( member ( signalRef "@baseboard_fab2_lib.baseboard_fab2(sch_1):pd_tmp421_1_a0") )
				( member ( signalRef "@baseboard_fab2_lib.baseboard_fab2(sch_1):pd_tmp421_2_a1") )
				( member ( signalRef "@baseboard_fab2_lib.baseboard_fab2(sch_1):pd_usb_bmc_p1_dn") )
				( member ( signalRef "@baseboard_fab2_lib.baseboard_fab2(sch_1):pd_usb_bmc_p1_dp") )
				( member ( signalRef "@baseboard_fab2_lib.baseboard_fab2(sch_1):pu_adr_timer_hold_off_n") )
				( member ( signalRef "@baseboard_fab2_lib.baseboard_fab2(sch_1):pu_at24c64_a2") )
				( member ( signalRef "@baseboard_fab2_lib.baseboard_fab2(sch_1):pu_bios_recover_boot") )
				( member ( signalRef "@baseboard_fab2_lib.baseboard_fab2(sch_1):pu_bios_usb_recovery") )
				( member ( signalRef "@baseboard_fab2_lib.baseboard_fab2(sch_1):h_cpu0_bmcinit") )
				( member ( signalRef "@baseboard_fab2_lib.baseboard_fab2(sch_1):pu_cpu0_ear_n") )
				( member ( signalRef "@baseboard_fab2_lib.baseboard_fab2(sch_1):pu_cpu0_frmagent") )
				( member ( signalRef "@baseboard_fab2_lib.baseboard_fab2(sch_1):pu_cpu0_legacy_skt") )
				( member ( signalRef "@baseboard_fab2_lib.baseboard_fab2(sch_1):pu_cpu0_safe_mode_boot") )
				( member ( signalRef "@baseboard_fab2_lib.baseboard_fab2(sch_1):pu_cpu0_socket_id_0") )
				( member ( signalRef "@baseboard_fab2_lib.baseboard_fab2(sch_1):pu_cpu0_socket_id_1") )
				( member ( signalRef "@baseboard_fab2_lib.baseboard_fab2(sch_1):pu_cpu0_tsc_sync") )
				( member ( signalRef "@baseboard_fab2_lib.baseboard_fab2(sch_1):pu_cpu0_txt_agent") )
				( member ( signalRef "@baseboard_fab2_lib.baseboard_fab2(sch_1):h_cpu1_bmcinit") )
				( member ( signalRef "@baseboard_fab2_lib.baseboard_fab2(sch_1):pu_cpu1_ear_n") )
				( member ( signalRef "@baseboard_fab2_lib.baseboard_fab2(sch_1):pu_cpu1_frmagent") )
				( member ( signalRef "@baseboard_fab2_lib.baseboard_fab2(sch_1):pu_cpu1_legacy_skt") )
				( member ( signalRef "@baseboard_fab2_lib.baseboard_fab2(sch_1):pu_cpu1_safe_mode_boot") )
				( member ( signalRef "@baseboard_fab2_lib.baseboard_fab2(sch_1):pu_cpu1_socket_id_0") )
				( member ( signalRef "@baseboard_fab2_lib.baseboard_fab2(sch_1):pu_cpu1_socket_id_1") )
				( member ( signalRef "@baseboard_fab2_lib.baseboard_fab2(sch_1):pu_cpu1_tsc_sync") )
				( member ( signalRef "@baseboard_fab2_lib.baseboard_fab2(sch_1):pu_cpu1_txt_agent") )
				( member ( signalRef "@baseboard_fab2_lib.baseboard_fab2(sch_1):pu_datain1_sata_0_r") )
				( member ( signalRef "@baseboard_fab2_lib.baseboard_fab2(sch_1):pu_datain1_sata_1_r") )
				( member ( signalRef "@baseboard_fab2_lib.baseboard_fab2(sch_1):pu_datain1_sata_2") )
				( member ( signalRef "@baseboard_fab2_lib.baseboard_fab2(sch_1):pu_fm_rcin_n") )
				( member ( signalRef "@baseboard_fab2_lib.baseboard_fab2(sch_1):pu_gtl2014_1_dir") )
				( member ( signalRef "@baseboard_fab2_lib.baseboard_fab2(sch_1):pu_gtl2014_2_dir") )
				( member ( signalRef "@baseboard_fab2_lib.baseboard_fab2(sch_1):pu_irq_pch_sci_whea_n") )
				( member ( signalRef "@baseboard_fab2_lib.baseboard_fab2(sch_1):pu_irq_vralert_n") )
				( member ( signalRef "@baseboard_fab2_lib.baseboard_fab2(sch_1):pu_key_conn_pin2_r") )
				( member ( signalRef "@baseboard_fab2_lib.baseboard_fab2(sch_1):pu_lpc_clkrun_n") )
				( member ( signalRef "@baseboard_fab2_lib.baseboard_fab2(sch_1):pu_lpc_pme_n") )
				( member ( signalRef "@baseboard_fab2_lib.baseboard_fab2(sch_1):pu_nv_hold_n") )
				( member ( signalRef "@baseboard_fab2_lib.baseboard_fab2(sch_1):pu_nv_wp_n") )
				( member ( signalRef "@baseboard_fab2_lib.baseboard_fab2(sch_1):pu_pch_tls_enable_strap") )
				( objectStatus "CLS_PUPD" )
			)
			( netClass "@crescent_city_bb_fab1_lib.crescent_city_bb_fab1(sch_1):\CLS_NC\"
				( memberType ( signal ) )
				( attribute "PROPAGATION_DELAY_PATH_TYPE" "AD:AR"
					( Origin gBackEnd )
				)
				( attribute "PROPAGATION_DELAY_MAX" "2000.00 MIL"
					( Units "uMaxMinProp" "ns" 1.000000)
					( Origin gBackEnd )
				)
				( objectFlag fObjectElectrical )
				( member ( signalRef "@baseboard_fab2_lib.baseboard_fab2(sch_1):tp_cpu0_rsvd_101") )
				( member ( signalRef "@baseboard_fab2_lib.baseboard_fab2(sch_1):tp_cpu0_rsvd_105") )
				( member ( signalRef "@baseboard_fab2_lib.baseboard_fab2(sch_1):tp_cpu0_rsvd_106") )
				( member ( signalRef "@baseboard_fab2_lib.baseboard_fab2(sch_1):tp_cpu0_rsvd_108") )
				( member ( signalRef "@baseboard_fab2_lib.baseboard_fab2(sch_1):tp_cpu0_rsvd_111") )
				( member ( signalRef "@baseboard_fab2_lib.baseboard_fab2(sch_1):tp_cpu0_rsvd_113") )
				( member ( signalRef "@baseboard_fab2_lib.baseboard_fab2(sch_1):tp_cpu0_rsvd_114") )
				( member ( signalRef "@baseboard_fab2_lib.baseboard_fab2(sch_1):tp_cpu0_rsvd_117") )
				( member ( signalRef "@baseboard_fab2_lib.baseboard_fab2(sch_1):tp_cpu0_rsvd_119") )
				( member ( signalRef "@baseboard_fab2_lib.baseboard_fab2(sch_1):tp_cpu0_rsvd_121") )
				( member ( signalRef "@baseboard_fab2_lib.baseboard_fab2(sch_1):tp_cpu0_rsvd_123") )
				( member ( signalRef "@baseboard_fab2_lib.baseboard_fab2(sch_1):tp_cpu0_rsvd_124") )
				( member ( signalRef "@baseboard_fab2_lib.baseboard_fab2(sch_1):tp_cpu0_rsvd_144") )
				( member ( signalRef "@baseboard_fab2_lib.baseboard_fab2(sch_1):tp_cpu0_rsvd_145") )
				( member ( signalRef "@baseboard_fab2_lib.baseboard_fab2(sch_1):tp_cpu0_rsvd_146") )
				( member ( signalRef "@baseboard_fab2_lib.baseboard_fab2(sch_1):tp_cpu0_rsvd_147") )
				( member ( signalRef "@baseboard_fab2_lib.baseboard_fab2(sch_1):tp_cpu0_rsvd_148") )
				( member ( signalRef "@baseboard_fab2_lib.baseboard_fab2(sch_1):tp_cpu0_rsvd_149") )
				( member ( signalRef "@baseboard_fab2_lib.baseboard_fab2(sch_1):tp_cpu0_rsvd_150") )
				( member ( signalRef "@baseboard_fab2_lib.baseboard_fab2(sch_1):tp_cpu0_rsvd_151") )
				( member ( signalRef "@baseboard_fab2_lib.baseboard_fab2(sch_1):tp_cpu0_rsvd_152") )
				( member ( signalRef "@baseboard_fab2_lib.baseboard_fab2(sch_1):tp_cpu0_rsvd_154") )
				( member ( signalRef "@baseboard_fab2_lib.baseboard_fab2(sch_1):tp_cpu0_rsvd_155") )
				( member ( signalRef "@baseboard_fab2_lib.baseboard_fab2(sch_1):tp_cpu0_rsvd_156") )
				( member ( signalRef "@baseboard_fab2_lib.baseboard_fab2(sch_1):tp_cpu0_rsvd_157") )
				( member ( signalRef "@baseboard_fab2_lib.baseboard_fab2(sch_1):tp_cpu0_rsvd_158") )
				( member ( signalRef "@baseboard_fab2_lib.baseboard_fab2(sch_1):tp_cpu0_rsvd_159") )
				( member ( signalRef "@baseboard_fab2_lib.baseboard_fab2(sch_1):tp_cpu0_rsvd_160") )
				( member ( signalRef "@baseboard_fab2_lib.baseboard_fab2(sch_1):tp_cpu0_rsvd_161") )
				( member ( signalRef "@baseboard_fab2_lib.baseboard_fab2(sch_1):tp_cpu0_rsvd_162") )
				( member ( signalRef "@baseboard_fab2_lib.baseboard_fab2(sch_1):tp_cpu0_rsvd_163") )
				( member ( signalRef "@baseboard_fab2_lib.baseboard_fab2(sch_1):tp_cpu0_rsvd_164") )
				( member ( signalRef "@baseboard_fab2_lib.baseboard_fab2(sch_1):tp_cpu0_rsvd_166") )
				( member ( signalRef "@baseboard_fab2_lib.baseboard_fab2(sch_1):tp_cpu0_rsvd_167") )
				( member ( signalRef "@baseboard_fab2_lib.baseboard_fab2(sch_1):tp_cpu0_rsvd_168") )
				( member ( signalRef "@baseboard_fab2_lib.baseboard_fab2(sch_1):tp_cpu0_rsvd_169") )
				( member ( signalRef "@baseboard_fab2_lib.baseboard_fab2(sch_1):tp_cpu0_rsvd_170") )
				( member ( signalRef "@baseboard_fab2_lib.baseboard_fab2(sch_1):tp_cpu0_rsvd_171") )
				( member ( signalRef "@baseboard_fab2_lib.baseboard_fab2(sch_1):tp_cpu0_rsvd_172") )
				( member ( signalRef "@baseboard_fab2_lib.baseboard_fab2(sch_1):tp_cpu0_rsvd_173") )
				( member ( signalRef "@baseboard_fab2_lib.baseboard_fab2(sch_1):tp_cpu0_rsvd_174") )
				( member ( signalRef "@baseboard_fab2_lib.baseboard_fab2(sch_1):tp_cpu0_rsvd_175") )
				( member ( signalRef "@baseboard_fab2_lib.baseboard_fab2(sch_1):tp_cpu0_rsvd_176") )
				( member ( signalRef "@baseboard_fab2_lib.baseboard_fab2(sch_1):tp_cpu1_rsvd_95") )
				( member ( signalRef "@baseboard_fab2_lib.baseboard_fab2(sch_1):tp_cpu1_rsvd_97") )
				( member ( signalRef "@baseboard_fab2_lib.baseboard_fab2(sch_1):tp_cpu1_rsvd_99") )
				( member ( signalRef "@baseboard_fab2_lib.baseboard_fab2(sch_1):tp_cpu1_rsvd_100") )
				( member ( signalRef "@baseboard_fab2_lib.baseboard_fab2(sch_1):tp_cpu1_rsvd_101") )
				( member ( signalRef "@baseboard_fab2_lib.baseboard_fab2(sch_1):tp_cpu1_rsvd_105") )
				( member ( signalRef "@baseboard_fab2_lib.baseboard_fab2(sch_1):tp_cpu1_rsvd_106") )
				( member ( signalRef "@baseboard_fab2_lib.baseboard_fab2(sch_1):tp_cpu1_rsvd_108") )
				( member ( signalRef "@baseboard_fab2_lib.baseboard_fab2(sch_1):tp_cpu1_rsvd_111") )
				( member ( signalRef "@baseboard_fab2_lib.baseboard_fab2(sch_1):tp_cpu1_rsvd_113") )
				( member ( signalRef "@baseboard_fab2_lib.baseboard_fab2(sch_1):tp_cpu1_rsvd_114") )
				( member ( signalRef "@baseboard_fab2_lib.baseboard_fab2(sch_1):tp_cpu1_rsvd_117") )
				( member ( signalRef "@baseboard_fab2_lib.baseboard_fab2(sch_1):tp_cpu1_rsvd_119") )
				( member ( signalRef "@baseboard_fab2_lib.baseboard_fab2(sch_1):tp_cpu1_rsvd_121") )
				( member ( signalRef "@baseboard_fab2_lib.baseboard_fab2(sch_1):tp_cpu1_rsvd_123") )
				( member ( signalRef "@baseboard_fab2_lib.baseboard_fab2(sch_1):tp_cpu1_rsvd_124") )
				( member ( signalRef "@baseboard_fab2_lib.baseboard_fab2(sch_1):tp_cpu1_rsvd_144") )
				( member ( signalRef "@baseboard_fab2_lib.baseboard_fab2(sch_1):tp_cpu1_rsvd_145") )
				( member ( signalRef "@baseboard_fab2_lib.baseboard_fab2(sch_1):tp_cpu1_rsvd_146") )
				( member ( signalRef "@baseboard_fab2_lib.baseboard_fab2(sch_1):tp_cpu1_rsvd_147") )
				( member ( signalRef "@baseboard_fab2_lib.baseboard_fab2(sch_1):tp_cpu1_rsvd_148") )
				( member ( signalRef "@baseboard_fab2_lib.baseboard_fab2(sch_1):tp_cpu1_rsvd_149") )
				( member ( signalRef "@baseboard_fab2_lib.baseboard_fab2(sch_1):tp_cpu1_rsvd_150") )
				( member ( signalRef "@baseboard_fab2_lib.baseboard_fab2(sch_1):tp_cpu1_rsvd_151") )
				( member ( signalRef "@baseboard_fab2_lib.baseboard_fab2(sch_1):tp_cpu1_rsvd_152") )
				( member ( signalRef "@baseboard_fab2_lib.baseboard_fab2(sch_1):tp_cpu1_rsvd_154") )
				( member ( signalRef "@baseboard_fab2_lib.baseboard_fab2(sch_1):tp_cpu1_rsvd_155") )
				( member ( signalRef "@baseboard_fab2_lib.baseboard_fab2(sch_1):tp_cpu1_rsvd_156") )
				( member ( signalRef "@baseboard_fab2_lib.baseboard_fab2(sch_1):tp_cpu1_rsvd_157") )
				( member ( signalRef "@baseboard_fab2_lib.baseboard_fab2(sch_1):tp_cpu1_rsvd_158") )
				( member ( signalRef "@baseboard_fab2_lib.baseboard_fab2(sch_1):tp_cpu1_rsvd_159") )
				( member ( signalRef "@baseboard_fab2_lib.baseboard_fab2(sch_1):tp_cpu1_rsvd_160") )
				( member ( signalRef "@baseboard_fab2_lib.baseboard_fab2(sch_1):tp_cpu1_rsvd_161") )
				( member ( signalRef "@baseboard_fab2_lib.baseboard_fab2(sch_1):tp_cpu1_rsvd_162") )
				( member ( signalRef "@baseboard_fab2_lib.baseboard_fab2(sch_1):tp_cpu1_rsvd_163") )
				( member ( signalRef "@baseboard_fab2_lib.baseboard_fab2(sch_1):tp_cpu1_rsvd_164") )
				( member ( signalRef "@baseboard_fab2_lib.baseboard_fab2(sch_1):tp_cpu1_rsvd_166") )
				( member ( signalRef "@baseboard_fab2_lib.baseboard_fab2(sch_1):tp_cpu1_rsvd_167") )
				( member ( signalRef "@baseboard_fab2_lib.baseboard_fab2(sch_1):tp_cpu1_rsvd_168") )
				( member ( signalRef "@baseboard_fab2_lib.baseboard_fab2(sch_1):tp_cpu1_rsvd_169") )
				( member ( signalRef "@baseboard_fab2_lib.baseboard_fab2(sch_1):tp_cpu1_rsvd_170") )
				( member ( signalRef "@baseboard_fab2_lib.baseboard_fab2(sch_1):tp_adc128_vref") )
				( member ( signalRef "@baseboard_fab2_lib.baseboard_fab2(sch_1):nc_clk_156m_cpu0_osc") )
				( member ( signalRef "@baseboard_fab2_lib.baseboard_fab2(sch_1):nc_clk_156m_cpu1_osc") )
				( member ( signalRef "@baseboard_fab2_lib.baseboard_fab2(sch_1):nc_cpld1") )
				( member ( signalRef "@baseboard_fab2_lib.baseboard_fab2(sch_1):tp_cpu0_rsvd_82") )
				( member ( signalRef "@baseboard_fab2_lib.baseboard_fab2(sch_1):tp_cpu0_rsvd_85") )
				( member ( signalRef "@baseboard_fab2_lib.baseboard_fab2(sch_1):tp_cpu0_rsvd_90") )
				( member ( signalRef "@baseboard_fab2_lib.baseboard_fab2(sch_1):tp_cpu0_rsvd_91") )
				( member ( signalRef "@baseboard_fab2_lib.baseboard_fab2(sch_1):tp_cpu0_rsvd_94") )
				( member ( signalRef "@baseboard_fab2_lib.baseboard_fab2(sch_1):tp_cpu0_rsvd_95") )
				( member ( signalRef "@baseboard_fab2_lib.baseboard_fab2(sch_1):tp_cpu0_rsvd_97") )
				( member ( signalRef "@baseboard_fab2_lib.baseboard_fab2(sch_1):tp_cpu0_rsvd_99") )
				( member ( signalRef "@baseboard_fab2_lib.baseboard_fab2(sch_1):tp_cpu0_rsvd_100") )
				( member ( signalRef "@baseboard_fab2_lib.baseboard_fab2(sch_1):tp_fm_cpu1_cd_hfi0_modprst_n") )
				( member ( signalRef "@baseboard_fab2_lib.baseboard_fab2(sch_1):tp_cpld1_pl7d_pclkt4_0") )
				( member ( signalRef "@baseboard_fab2_lib.baseboard_fab2(sch_1):tp_gpio0_dsrb_n") )
				( member ( signalRef "@baseboard_fab2_lib.baseboard_fab2(sch_1):tp_gpio1_dtrb_n") )
				( member ( signalRef "@baseboard_fab2_lib.baseboard_fab2(sch_1):tp_gpio2_cdb_n") )
				( member ( signalRef "@baseboard_fab2_lib.baseboard_fab2(sch_1):tp_gpio3_rib_n") )
				( member ( signalRef "@baseboard_fab2_lib.baseboard_fab2(sch_1):tp_gpio4_dsra_n") )
				( member ( signalRef "@baseboard_fab2_lib.baseboard_fab2(sch_1):tp_gpio5_dtra_n") )
				( member ( signalRef "@baseboard_fab2_lib.baseboard_fab2(sch_1):tp_gpio6_cda_n") )
				( member ( signalRef "@baseboard_fab2_lib.baseboard_fab2(sch_1):tp_gpio7_ria_n") )
				( member ( signalRef "@baseboard_fab2_lib.baseboard_fab2(sch_1):tp_irq_cpu1_cd_hfi0_n") )
				( member ( signalRef "@baseboard_fab2_lib.baseboard_fab2(sch_1):tp_jtag_bmc_rtck") )
				( member ( signalRef "@baseboard_fab2_lib.baseboard_fab2(sch_1):tp_led_cpu1_cd_hfi0_n") )
				( member ( signalRef "@baseboard_fab2_lib.baseboard_fab2(sch_1):tp_led_m2_act_n") )
				( member ( signalRef "@baseboard_fab2_lib.baseboard_fab2(sch_1):tp_m_bmc_ddr3_mioz") )
				( member ( signalRef "@baseboard_fab2_lib.baseboard_fab2(sch_1):tp_m2_devslp") )
				( member ( signalRef "@baseboard_fab2_lib.baseboard_fab2(sch_1):tp_m2_32m_susclk") )
				( member ( signalRef "@baseboard_fab2_lib.baseboard_fab2(sch_1):tp_pi7c9x1172_enir_n") )
				( member ( signalRef "@baseboard_fab2_lib.baseboard_fab2(sch_1):tp_pi7c9x1172_en485_n") )
				( member ( signalRef "@baseboard_fab2_lib.baseboard_fab2(sch_1):tp_pi7c9x1172_rtsa_n") )
				( member ( signalRef "@baseboard_fab2_lib.baseboard_fab2(sch_1):tp_pi7c9x1172_rtsb_n") )
				( member ( signalRef "@baseboard_fab2_lib.baseboard_fab2(sch_1):tp_pi7c9x1172_so") )
				( member ( signalRef "@baseboard_fab2_lib.baseboard_fab2(sch_1):nc_pi7c9x1172_1") )
				( member ( signalRef "@baseboard_fab2_lib.baseboard_fab2(sch_1):nc_pi7c9x1172_8") )
				( member ( signalRef "@baseboard_fab2_lib.baseboard_fab2(sch_1):tp_pvccin_cpu0_ph2_gl_0") )
				( member ( signalRef "@baseboard_fab2_lib.baseboard_fab2(sch_1):tp_pvccin_cpu0_ph3_gl_0") )
				( member ( signalRef "@baseboard_fab2_lib.baseboard_fab2(sch_1):tp_pvccin_cpu0_ph4_gl_0") )
				( member ( signalRef "@baseboard_fab2_lib.baseboard_fab2(sch_1):tp_pvccin_cpu0_ph5_gl_0") )
				( member ( signalRef "@baseboard_fab2_lib.baseboard_fab2(sch_1):tp_pvccinc_cpu1_ph1_gl_0") )
				( member ( signalRef "@baseboard_fab2_lib.baseboard_fab2(sch_1):tp_pvccinc_cpu1_ph2_gl_0") )
				( member ( signalRef "@baseboard_fab2_lib.baseboard_fab2(sch_1):tp_pvccin_cpu1_ph3_gl_0") )
				( member ( signalRef "@baseboard_fab2_lib.baseboard_fab2(sch_1):tp_pvccin_cpu1_ph4_gl_0") )
				( member ( signalRef "@baseboard_fab2_lib.baseboard_fab2(sch_1):tp_pvccin_cpu1_ph5_gl_0") )
				( member ( signalRef "@baseboard_fab2_lib.baseboard_fab2(sch_1):nc_pvccio_cpu0_dnc0") )
				( member ( signalRef "@baseboard_fab2_lib.baseboard_fab2(sch_1):nc_pvccio_cpu0_dnc1") )
				( member ( signalRef "@baseboard_fab2_lib.baseboard_fab2(sch_1):nc_pvccio_cpu0_dnc2") )
				( member ( signalRef "@baseboard_fab2_lib.baseboard_fab2(sch_1):nc_pvccio_cpu0_dnc3") )
				( member ( signalRef "@baseboard_fab2_lib.baseboard_fab2(sch_1):nc_pvccio_cpu0_dnc4") )
				( member ( signalRef "@baseboard_fab2_lib.baseboard_fab2(sch_1):tp_pvccio_cpu0_gl_0") )
				( member ( signalRef "@baseboard_fab2_lib.baseboard_fab2(sch_1):nc_pvccio_cpu1_dnc0") )
				( member ( signalRef "@baseboard_fab2_lib.baseboard_fab2(sch_1):nc_pvccio_cpu1_dnc1") )
				( member ( signalRef "@baseboard_fab2_lib.baseboard_fab2(sch_1):tp_cpu0_rsvd_177") )
				( member ( signalRef "@baseboard_fab2_lib.baseboard_fab2(sch_1):tp_cpu0_rsvd_178") )
				( member ( signalRef "@baseboard_fab2_lib.baseboard_fab2(sch_1):tp_cpu0_rsvd_179") )
				( member ( signalRef "@baseboard_fab2_lib.baseboard_fab2(sch_1):tp_cpu0_rsvd_180") )
				( member ( signalRef "@baseboard_fab2_lib.baseboard_fab2(sch_1):tp_cpu0_rsvd_181") )
				( member ( signalRef "@baseboard_fab2_lib.baseboard_fab2(sch_1):tp_cpu0_rsvd_182") )
				( member ( signalRef "@baseboard_fab2_lib.baseboard_fab2(sch_1):tp_cpu0_rsvd_183") )
				( member ( signalRef "@baseboard_fab2_lib.baseboard_fab2(sch_1):tp_cpu0_test_7") )
				( member ( signalRef "@baseboard_fab2_lib.baseboard_fab2(sch_1):tp_cpu0_test_8") )
				( member ( signalRef "@baseboard_fab2_lib.baseboard_fab2(sch_1):tp_cpu0_test_10") )
				( member ( signalRef "@baseboard_fab2_lib.baseboard_fab2(sch_1):tp_cpu0_test_9") )
				( member ( signalRef "@baseboard_fab2_lib.baseboard_fab2(sch_1):tp_cpu0_rsvd_test_11") )
				( member ( signalRef "@baseboard_fab2_lib.baseboard_fab2(sch_1):tp_cpu1_rsvd_82") )
				( member ( signalRef "@baseboard_fab2_lib.baseboard_fab2(sch_1):tp_cpu1_rsvd_85") )
				( member ( signalRef "@baseboard_fab2_lib.baseboard_fab2(sch_1):tp_cpu1_rsvd_90") )
				( member ( signalRef "@baseboard_fab2_lib.baseboard_fab2(sch_1):tp_cpu1_rsvd_91") )
				( member ( signalRef "@baseboard_fab2_lib.baseboard_fab2(sch_1):tp_cpu1_rsvd_94") )
				( member ( signalRef "@baseboard_fab2_lib.baseboard_fab2(sch_1):nc_pvccio_cpu1_dnc2") )
				( member ( signalRef "@baseboard_fab2_lib.baseboard_fab2(sch_1):nc_pvccio_cpu1_dnc3") )
				( member ( signalRef "@baseboard_fab2_lib.baseboard_fab2(sch_1):nc_pvccio_cpu1_dnc4") )
				( member ( signalRef "@baseboard_fab2_lib.baseboard_fab2(sch_1):tp_pvccio_cpu1_gl_0") )
				( member ( signalRef "@baseboard_fab2_lib.baseboard_fab2(sch_1):nc_pvddq_abc_dnc0") )
				( member ( signalRef "@baseboard_fab2_lib.baseboard_fab2(sch_1):nc_pvddq_abc_dnc1") )
				( member ( signalRef "@baseboard_fab2_lib.baseboard_fab2(sch_1):tp_pvddq_abc_ph1_gl_0") )
				( member ( signalRef "@baseboard_fab2_lib.baseboard_fab2(sch_1):tp_pvddq_abc_ph2_gl_0") )
				( member ( signalRef "@baseboard_fab2_lib.baseboard_fab2(sch_1):nc_pvddq_def_dnc0") )
				( member ( signalRef "@baseboard_fab2_lib.baseboard_fab2(sch_1):nc_pvddq_def_dnc1") )
				( member ( signalRef "@baseboard_fab2_lib.baseboard_fab2(sch_1):tp_pvddq_def_ph1_gl_0") )
				( member ( signalRef "@baseboard_fab2_lib.baseboard_fab2(sch_1):tp_pvddq_def_ph2_gl_0") )
				( member ( signalRef "@baseboard_fab2_lib.baseboard_fab2(sch_1):nc_pvddq_ghj_dnc0") )
				( member ( signalRef "@baseboard_fab2_lib.baseboard_fab2(sch_1):nc_pvddq_ghj_dnc1") )
				( member ( signalRef "@baseboard_fab2_lib.baseboard_fab2(sch_1):tp_pvddq_ghj_ph1_gl_0") )
				( member ( signalRef "@baseboard_fab2_lib.baseboard_fab2(sch_1):tp_pvddq_ghj_ph2_gl_0") )
				( member ( signalRef "@baseboard_fab2_lib.baseboard_fab2(sch_1):tp_pvddq_ghj_ph3_imon") )
				( member ( signalRef "@baseboard_fab2_lib.baseboard_fab2(sch_1):tp_pvddq_ghj_ph3_imon_ref") )
				( member ( signalRef "@baseboard_fab2_lib.baseboard_fab2(sch_1):nc_pvddq_ghj_pinalrt_n") )
				( member ( signalRef "@baseboard_fab2_lib.baseboard_fab2(sch_1):nc_pvddq_klm_dnc0") )
				( member ( signalRef "@baseboard_fab2_lib.baseboard_fab2(sch_1):nc_pvddq_klm_dnc1") )
				( member ( signalRef "@baseboard_fab2_lib.baseboard_fab2(sch_1):nc_pvddq_klm_gp0") )
				( member ( signalRef "@baseboard_fab2_lib.baseboard_fab2(sch_1):nc_pvddq_klm_gp1") )
				( member ( signalRef "@baseboard_fab2_lib.baseboard_fab2(sch_1):tp_pvddq_klm_ph1_gl_0") )
				( member ( signalRef "@baseboard_fab2_lib.baseboard_fab2(sch_1):tp_pvddq_klm_ph2_gl_0") )
				( member ( signalRef "@baseboard_fab2_lib.baseboard_fab2(sch_1):tp_pvddq_klm_ph3_imon") )
				( member ( signalRef "@baseboard_fab2_lib.baseboard_fab2(sch_1):tp_pvddq_klm_ph3_imon_ref") )
				( member ( signalRef "@baseboard_fab2_lib.baseboard_fab2(sch_1):nc_pvddq_klm_pinalrt_n") )
				( member ( signalRef "@baseboard_fab2_lib.baseboard_fab2(sch_1):nc_pvddq_klm_pwm3") )
				( member ( signalRef "@baseboard_fab2_lib.baseboard_fab2(sch_1):nc_pvnn_pch_dnc0") )
				( member ( signalRef "@baseboard_fab2_lib.baseboard_fab2(sch_1):nc_pvnn_pch_dnc1") )
				( member ( signalRef "@baseboard_fab2_lib.baseboard_fab2(sch_1):nc_pvnn_pch_dnc2") )
				( member ( signalRef "@baseboard_fab2_lib.baseboard_fab2(sch_1):nc_pvnn_pch_dnc3") )
				( member ( signalRef "@baseboard_fab2_lib.baseboard_fab2(sch_1):nc_pvnn_pch_dnc4") )
				( member ( signalRef "@baseboard_fab2_lib.baseboard_fab2(sch_1):tp_pvnn_pch_gl_0") )
				( member ( signalRef "@baseboard_fab2_lib.baseboard_fab2(sch_1):tp_pvsa_cpu0_gl_0") )
				( member ( signalRef "@baseboard_fab2_lib.baseboard_fab2(sch_1):tp_pvsa_cpu1_gl_0") )
				( member ( signalRef "@baseboard_fab2_lib.baseboard_fab2(sch_1):tp_p1v05_pch_gl_0") )
				( member ( signalRef "@baseboard_fab2_lib.baseboard_fab2(sch_1):tp_rgmii1txctl_gpiot1") )
				( member ( signalRef "@baseboard_fab2_lib.baseboard_fab2(sch_1):tp_rgmii1txd2_gpiot4") )
				( member ( signalRef "@baseboard_fab2_lib.baseboard_fab2(sch_1):tp_rgmii1txd3_gpiot5") )
				( member ( signalRef "@baseboard_fab2_lib.baseboard_fab2(sch_1):tp_rgmii2txctl_gpiot7") )
				( member ( signalRef "@baseboard_fab2_lib.baseboard_fab2(sch_1):tp_rgmii2txd2_gpiot4") )
				( member ( signalRef "@baseboard_fab2_lib.baseboard_fab2(sch_1):tp_rgmii2txd3_gpiot5") )
				( member ( signalRef "@baseboard_fab2_lib.baseboard_fab2(sch_1):tp_rst_cpu1_cd_hfi0_n") )
				( member ( signalRef "@baseboard_fab2_lib.baseboard_fab2(sch_1):tp_smb_cpu1_cd_hfi0_i2cclk") )
				( member ( signalRef "@baseboard_fab2_lib.baseboard_fab2(sch_1):tp_smb_cpu1_cd_hfi0_i2cdat") )
				( member ( signalRef "@baseboard_fab2_lib.baseboard_fab2(sch_1):tp_spi_pch_bios_clk_r") )
				( member ( signalRef "@baseboard_fab2_lib.baseboard_fab2(sch_1):tp_spi_pch_bios_cs0_r_n") )
				( member ( signalRef "@baseboard_fab2_lib.baseboard_fab2(sch_1):tp_spi_pch_bios_miso_r") )
				( member ( signalRef "@baseboard_fab2_lib.baseboard_fab2(sch_1):tp_spi_pch_bios_mosi_r") )
				( member ( signalRef "@baseboard_fab2_lib.baseboard_fab2(sch_1):tp_spi_switch1_3") )
				( member ( signalRef "@baseboard_fab2_lib.baseboard_fab2(sch_1):tp_spi_switch1_6") )
				( member ( signalRef "@baseboard_fab2_lib.baseboard_fab2(sch_1):tp_spi_switch1_9") )
				( member ( signalRef "@baseboard_fab2_lib.baseboard_fab2(sch_1):tp_spi_switch1_10") )
				( member ( signalRef "@baseboard_fab2_lib.baseboard_fab2(sch_1):tp_spi_switch1_11") )
				( member ( signalRef "@baseboard_fab2_lib.baseboard_fab2(sch_1):tp_spi_switch1_12") )
				( member ( signalRef "@baseboard_fab2_lib.baseboard_fab2(sch_1):tp_spi_switch1_13") )
				( member ( signalRef "@baseboard_fab2_lib.baseboard_fab2(sch_1):tp_spi_switch1_14") )
				( member ( signalRef "@baseboard_fab2_lib.baseboard_fab2(sch_1):nc_sprngvlle_22") )
				( member ( signalRef "@baseboard_fab2_lib.baseboard_fab2(sch_1):tp_sprv_sdp0") )
				( member ( signalRef "@baseboard_fab2_lib.baseboard_fab2(sch_1):tp_sprv_sdp1") )
				( member ( signalRef "@baseboard_fab2_lib.baseboard_fab2(sch_1):tp_sprv_sdp2") )
				( member ( signalRef "@baseboard_fab2_lib.baseboard_fab2(sch_1):tp_sprv_sdp3") )
				( member ( signalRef "@baseboard_fab2_lib.baseboard_fab2(sch_1):tp_usb_esd_ac2") )
				( member ( signalRef "@baseboard_fab2_lib.baseboard_fab2(sch_1):tp_usb_esd_ac3") )
				( member ( signalRef "@baseboard_fab2_lib.baseboard_fab2(sch_1):tp_usb_esd_out2") )
				( member ( signalRef "@baseboard_fab2_lib.baseboard_fab2(sch_1):tp_usb_esd_out3") )
				( member ( signalRef "@baseboard_fab2_lib.baseboard_fab2(sch_1):tp_vgahs_gpioj4") )
				( member ( signalRef "@baseboard_fab2_lib.baseboard_fab2(sch_1):tp_vgavs_gpioj5") )
				( member ( signalRef "@baseboard_fab2_lib.baseboard_fab2(sch_1):tp_cpu1_rsvd_171") )
				( member ( signalRef "@baseboard_fab2_lib.baseboard_fab2(sch_1):tp_cpu1_rsvd_172") )
				( member ( signalRef "@baseboard_fab2_lib.baseboard_fab2(sch_1):tp_cpu1_rsvd_173") )
				( member ( signalRef "@baseboard_fab2_lib.baseboard_fab2(sch_1):tp_cpu1_rsvd_175") )
				( member ( signalRef "@baseboard_fab2_lib.baseboard_fab2(sch_1):tp_cpu1_test_7") )
				( member ( signalRef "@baseboard_fab2_lib.baseboard_fab2(sch_1):tp_cpu1_test_8") )
				( member ( signalRef "@baseboard_fab2_lib.baseboard_fab2(sch_1):tp_cpu1_test_10") )
				( member ( signalRef "@baseboard_fab2_lib.baseboard_fab2(sch_1):tp_cpu1_test_9") )
				( member ( signalRef "@baseboard_fab2_lib.baseboard_fab2(sch_1):tp_cpu1_rsvd_test_11") )
				( member ( signalRef "@baseboard_fab2_lib.baseboard_fab2(sch_1):tp_dacb") )
				( member ( signalRef "@baseboard_fab2_lib.baseboard_fab2(sch_1):tp_dacg") )
				( member ( signalRef "@baseboard_fab2_lib.baseboard_fab2(sch_1):tp_dacr") )
				( member ( signalRef "@baseboard_fab2_lib.baseboard_fab2(sch_1):tp_ddcclk_gpioj6") )
				( member ( signalRef "@baseboard_fab2_lib.baseboard_fab2(sch_1):tp_ddcdat_gpioj7") )
				( objectStatus "CLS_NC" )
			)
			( netClass "@crescent_city_bb_fab1_lib.crescent_city_bb_fab1(sch_1):\CLS-SGPIO\"
				( memberType ( signal ) )
				( objectFlag fObjectElectrical )
				( member ( signalRef "@baseboard_fab2_lib.baseboard_fab2(sch_1):sp1_bmc_host_uart_rx") )
				( member ( signalRef "@baseboard_fab2_lib.baseboard_fab2(sch_1):sp1_bmc_host_uart_tx") )
				( member ( signalRef "@baseboard_fab2_lib.baseboard_fab2(sch_1):uart_bmc_rxd5") )
				( member ( signalRef "@baseboard_fab2_lib.baseboard_fab2(sch_1):uart_bmc_txd5") )
				( member ( electricalNetRef "@crescent_city_bb_fab1_lib.crescent_city_bb_fab1(sch_1):sp2_bmc_cm_uart_tx") )
				( member ( electricalNetRef "@crescent_city_bb_fab1_lib.crescent_city_bb_fab1(sch_1):sp2_bmc_cm_uart_rx") )
				( objectStatus "CLS_SGPIO" )
			)
			( netClass "@crescent_city_bb_fab1_lib.crescent_city_bb_fab1(sch_1):\SNCLS_SGPIO\"
				( memberType ( signal ) )
				( spacingCSetRef "@crescent_city_bb_fab1_lib.crescent_city_bb_fab1(sch_1):\6_MILS\" )
				( objectFlag fObjectSpacing )
				( objectFlag fObjectSameNetSpacing )
				( member ( signalRef "@baseboard_fab2_lib.baseboard_fab2(sch_1):sp1_bmc_host_uart_rx") )
				( member ( signalRef "@baseboard_fab2_lib.baseboard_fab2(sch_1):sp1_bmc_host_uart_tx") )
				( member ( signalRef "@baseboard_fab2_lib.baseboard_fab2(sch_1):uart_bmc_rxd5") )
				( member ( signalRef "@baseboard_fab2_lib.baseboard_fab2(sch_1):uart_bmc_txd5") )
				( member ( signalRef "@baseboard_fab2_lib.baseboard_fab2(sch_1):sp1_host_bridge_uart_rx") )
				( member ( signalRef "@baseboard_fab2_lib.baseboard_fab2(sch_1):sp1_host_bridge_uart_tx") )
				( member ( signalRef "@baseboard_fab2_lib.baseboard_fab2(sch_1):uart_bridge_rxd5") )
				( member ( signalRef "@baseboard_fab2_lib.baseboard_fab2(sch_1):uart_bridge_txd5") )
				( member ( signalRef "@baseboard_fab2_lib.baseboard_fab2(sch_1):spa_mid_dbg_rx") )
				( member ( signalRef "@baseboard_fab2_lib.baseboard_fab2(sch_1):spa_mid_dbg_tx") )
				( member ( signalRef "@baseboard_fab2_lib.baseboard_fab2(sch_1):spa_sin_sw_r") )
				( member ( signalRef "@baseboard_fab2_lib.baseboard_fab2(sch_1):sp2_bmc_cm_uart_rx") )
				( member ( signalRef "@baseboard_fab2_lib.baseboard_fab2(sch_1):sp2_bmc_cm_uart_tx") )
				( member ( signalRef "@baseboard_fab2_lib.baseboard_fab2(sch_1):uart_mux_in_r") )
				( member ( signalRef "@baseboard_fab2_lib.baseboard_fab2(sch_1):uart_mux_out_r") )
				( member ( electricalNetRef "@crescent_city_bb_fab1_lib.crescent_city_bb_fab1(sch_1):sp2_bmc_cm_uart_rx") )
				( member ( electricalNetRef "@crescent_city_bb_fab1_lib.crescent_city_bb_fab1(sch_1):sp2_bmc_cm_uart_tx") )
				( objectStatus "SNCLS_SERIAL_3.3V" )
			)
			( netClass "@crescent_city_bb_fab1_lib.crescent_city_bb_fab1(sch_1):\CLS_SFI\"
				( memberType ( signal ) )
				( electricalCSetRef "@crescent_city_bb_fab1_lib.crescent_city_bb_fab1(sch_1):\SFI\" )
				( attribute "PROPAGATION_DELAY_PATH_TYPE" "AD:AR"
					( Origin gBackEnd )
				)
				( attribute "PROPAGATION_DELAY_MIN" "3000.00 MIL"
					( Units "uMaxMinProp" "ns" 1.000000)
					( Origin gBackEnd )
				)
				( objectFlag fObjectElectrical )
				( objectStatus "CLS_SFI" )
			)
			( netClass "@crescent_city_bb_fab1_lib.crescent_city_bb_fab1(sch_1):\CLS_JTAG\"
				( memberType ( signal ) )
				( objectFlag fObjectElectrical )
				( member ( electricalNetRef "@crescent_city_bb_fab1_lib.crescent_city_bb_fab1(sch_1):jtag_pch_gbe_tms") )
				( member ( electricalNetRef "@crescent_city_bb_fab1_lib.crescent_city_bb_fab1(sch_1):jtag_pch_gbe_clk") )
				( member ( electricalNetRef "@crescent_city_bb_fab1_lib.crescent_city_bb_fab1(sch_1):jtag_pch_gbe_tdi") )
				( member ( electricalNetRef "@crescent_city_bb_fab1_lib.crescent_city_bb_fab1(sch_1):jtag_pch_gbe_tdo") )
				( member ( electricalNetRef "@crescent_city_bb_fab1_lib.crescent_city_bb_fab1(sch_1):jtag_pch_gbe_trst_n") )
				( member ( electricalNetRef "@baseboard_fab2_lib.baseboard_fab2(sch_1):jtag_mcp_cpu1_tdi") )
				( objectStatus "CLS_JTAG" )
			)
			( netClass "@crescent_city_bb_fab1_lib.crescent_city_bb_fab1(sch_1):\CLS_XDP\"
				( memberType ( signal ) )
				( attribute "PROPAGATION_DELAY_PATH_TYPE" "D:R"
					( Origin gBackEnd )
				)
				( attribute "PROPAGATION_DELAY_MAX" "24000.00 MIL"
					( Units "uMaxMinProp" "ns" 1.000000)
					( Origin gBackEnd )
				)
				( objectFlag fObjectElectrical )
				( member ( signalRef "@baseboard_fab2_lib.baseboard_fab2(sch_1):xdp_cpu_mbp0_n") )
				( member ( signalRef "@baseboard_fab2_lib.baseboard_fab2(sch_1):xdp_cpu_mbp1_n") )
				( member ( signalRef "@baseboard_fab2_lib.baseboard_fab2(sch_1):xdp_cpu_pwr_debug_n") )
				( member ( signalRef "@baseboard_fab2_lib.baseboard_fab2(sch_1):xdp_itp_pmode") )
				( member ( signalRef "@baseboard_fab2_lib.baseboard_fab2(sch_1):xdp_pch_tck1") )
				( member ( signalRef "@baseboard_fab2_lib.baseboard_fab2(sch_1):xdp_present_n") )
				( member ( signalRef "@baseboard_fab2_lib.baseboard_fab2(sch_1):xdp_pwrgd_rst_n") )
				( member ( signalRef "@baseboard_fab2_lib.baseboard_fab2(sch_1):xdp_rst_co_n") )
				( member ( signalRef "@baseboard_fab2_lib.baseboard_fab2(sch_1):xdp_syspwrok") )
				( member ( electricalNetRef "@crescent_city_bb_fab1_lib.crescent_city_bb_fab1(sch_1):xdp_cpu1_tdi") )
				( member ( electricalNetRef "@crescent_city_bb_fab1_lib.crescent_city_bb_fab1(sch_1):xdp_cpu_tck0") )
				( member ( electricalNetRef "@crescent_city_bb_fab1_lib.crescent_city_bb_fab1(sch_1):xdp_cpu_trst_n") )
				( member ( electricalNetRef "@crescent_city_bb_fab1_lib.crescent_city_bb_fab1(sch_1):xdp_cpu_tms") )
				( member ( electricalNetRef "@crescent_city_bb_fab1_lib.crescent_city_bb_fab1(sch_1):xdp_cpu_tdi") )
				( member ( electricalNetRef "@crescent_city_bb_fab1_lib.crescent_city_bb_fab1(sch_1):xdp_rsmrst_n") )
				( member ( electricalNetRef "@crescent_city_bb_fab1_lib.crescent_city_bb_fab1(sch_1):xdp_cpu_preq_n") )
				( member ( electricalNetRef "@crescent_city_bb_fab1_lib.crescent_city_bb_fab1(sch_1):xdp_cpu_prdy_n") )
				( member ( electricalNetRef "@crescent_city_bb_fab1_lib.crescent_city_bb_fab1(sch_1):xdp_obsfn_b1_mbp7_n") )
				( member ( electricalNetRef "@crescent_city_bb_fab1_lib.crescent_city_bb_fab1(sch_1):xdp_obsfn_b0_mbp6_n") )
				( objectStatus "CLS_XDP" )
			)
			( netClass "@crescent_city_bb_fab1_lib.crescent_city_bb_fab1(sch_1):\CLS_SMBUS2\"
				( memberType ( signal ) )
				( attribute "PROPAGATION_DELAY_PATH_TYPE" "D:R"
					( Origin gBackEnd )
				)
				( attribute "PROPAGATION_DELAY_MAX" "25100.00 MIL"
					( Units "uMaxMinProp" "ns" 1.000000)
					( Origin gBackEnd )
				)
				( objectFlag fObjectElectrical )
				( member ( signalRef "@baseboard_fab2_lib.baseboard_fab2(sch_1):smb_hfi0_cpu0_lvc2_scl") )
				( member ( signalRef "@baseboard_fab2_lib.baseboard_fab2(sch_1):smb_hfi0_cpu0_lvc2_sda") )
				( member ( signalRef "@baseboard_fab2_lib.baseboard_fab2(sch_1):smb_hfi1_cpu0_lvc2_scl") )
				( member ( signalRef "@baseboard_fab2_lib.baseboard_fab2(sch_1):smb_hfi1_cpu0_lvc2_sda") )
				( member ( electricalNetRef "@crescent_city_bb_fab1_lib.crescent_city_bb_fab1(sch_1):smb_slotx24_bmc_stby_lvc3_scl") )
				( member ( electricalNetRef "@crescent_city_bb_fab1_lib.crescent_city_bb_fab1(sch_1):smb_sensor_pch_stby_lvc3_scl") )
				( member ( electricalNetRef "@crescent_city_bb_fab1_lib.crescent_city_bb_fab1(sch_1):smb_lan_stby_lvc3_sda") )
				( member ( electricalNetRef "@crescent_city_bb_fab1_lib.crescent_city_bb_fab1(sch_1):smb_lan_stby_lvc3_scl") )
				( member ( electricalNetRef "@crescent_city_bb_fab1_lib.crescent_city_bb_fab1(sch_1):smb_3v3sb_hsc_sda_r") )
				( member ( electricalNetRef "@crescent_city_bb_fab1_lib.crescent_city_bb_fab1(sch_1):smb_3v3sb_hsc_scl_r") )
				( member ( electricalNetRef "@crescent_city_bb_fab1_lib.crescent_city_bb_fab1(sch_1):smb_slotx24_bmc_stby_lvc3_sda") )
				( member ( electricalNetRef "@crescent_city_bb_fab1_lib.crescent_city_bb_fab1(sch_1):smb_smlink0_stby_lvc3_sda") )
				( member ( electricalNetRef "@crescent_city_bb_fab1_lib.crescent_city_bb_fab1(sch_1):smb_smlink0_stby_lvc3_scl") )
				( member ( electricalNetRef "@crescent_city_bb_fab1_lib.crescent_city_bb_fab1(sch_1):smb_sensor_bmc_stby_lvc3_sda") )
				( member ( electricalNetRef "@crescent_city_bb_fab1_lib.crescent_city_bb_fab1(sch_1):smb_vr_sda_pvccio_cpu0") )
				( member ( electricalNetRef "@crescent_city_bb_fab1_lib.crescent_city_bb_fab1(sch_1):smb_vr_scl_pvccio_cpu0") )
				( member ( electricalNetRef "@crescent_city_bb_fab1_lib.crescent_city_bb_fab1(sch_1):smb_ddr_klm_vpp_sda") )
				( member ( electricalNetRef "@crescent_city_bb_fab1_lib.crescent_city_bb_fab1(sch_1):smb_ddr_klm_vpp_scl") )
				( member ( electricalNetRef "@crescent_city_bb_fab1_lib.crescent_city_bb_fab1(sch_1):smb_ddr_ghj_vpp_sda") )
				( member ( electricalNetRef "@crescent_city_bb_fab1_lib.crescent_city_bb_fab1(sch_1):smb_ddr_ghj_vpp_scl") )
				( member ( electricalNetRef "@crescent_city_bb_fab1_lib.crescent_city_bb_fab1(sch_1):smb_ddr_def_vpp_sda") )
				( member ( electricalNetRef "@crescent_city_bb_fab1_lib.crescent_city_bb_fab1(sch_1):smb_ddr_def_vpp_scl") )
				( member ( electricalNetRef "@crescent_city_bb_fab1_lib.crescent_city_bb_fab1(sch_1):smb_ddr_abc_vpp_sda") )
				( member ( electricalNetRef "@crescent_city_bb_fab1_lib.crescent_city_bb_fab1(sch_1):smb_ddr_abc_vpp_scl") )
				( objectStatus "CLS_SMBUS2" )
			)
			( netClass "@crescent_city_bb_fab1_lib.crescent_city_bb_fab1(sch_1):\NCLSMB1\"
				( memberType ( signal ) )
				( objectFlag fObjectElectrical )
				( member ( electricalNetRef "@crescent_city_bb_fab1_lib.crescent_city_bb_fab1(sch_1):smb_ddr_klm_sda_g") )
				( member ( electricalNetRef "@crescent_city_bb_fab1_lib.crescent_city_bb_fab1(sch_1):smb_ddr_klm_scl_g") )
				( member ( electricalNetRef "@crescent_city_bb_fab1_lib.crescent_city_bb_fab1(sch_1):smb_ddr_ghj_sda_g") )
				( member ( electricalNetRef "@crescent_city_bb_fab1_lib.crescent_city_bb_fab1(sch_1):smb_ddr_ghj_scl_g") )
				( member ( electricalNetRef "@crescent_city_bb_fab1_lib.crescent_city_bb_fab1(sch_1):smb_ddr_def_sda_g") )
				( member ( electricalNetRef "@crescent_city_bb_fab1_lib.crescent_city_bb_fab1(sch_1):smb_ddr_def_scl_g") )
				( member ( electricalNetRef "@crescent_city_bb_fab1_lib.crescent_city_bb_fab1(sch_1):smb_ddr_abc_sda_g") )
				( member ( electricalNetRef "@crescent_city_bb_fab1_lib.crescent_city_bb_fab1(sch_1):smb_ddr_abc_scl_g") )
				( objectStatus "CLS_SMBUS1" )
			)
			( netClass "@crescent_city_bb_fab1_lib.crescent_city_bb_fab1(sch_1):\CLS_SATA\"
				( memberType ( signal ) )
				( attribute "DIFFP_PHASE_TOL" "5 mil"
					( Units "uPhaseTol" "ns" 1.000000)
					( Origin gBackEnd )
				)
				( attribute "DIFFP_PHASE_MAX_LENGTH" "600.00"
					( Origin gBackEnd )
				)
				( attribute "DIFFP_PHASE_TOL_DYNAMIC" "25 mil"
					( Units "uPhaseTol" "mil" 1.000000)
					( Origin gBackEnd )
				)
				( objectFlag fObjectElectrical )
				( member ( diffPairRef "@crescent_city_bb_fab1_lib.crescent_city_bb_fab1(sch_1):\DP_78\") )
				( member ( diffPairRef "@crescent_city_bb_fab1_lib.crescent_city_bb_fab1(sch_1):\DP_105\") )
				( member ( diffPairRef "@crescent_city_bb_fab1_lib.crescent_city_bb_fab1(sch_1):\DP_106\") )
				( member ( diffPairRef "@crescent_city_bb_fab1_lib.crescent_city_bb_fab1(sch_1):\DP_79\") )
				( member ( diffPairRef "@crescent_city_bb_fab1_lib.crescent_city_bb_fab1(sch_1):\DP_80\") )
				( member ( diffPairRef "@crescent_city_bb_fab1_lib.crescent_city_bb_fab1(sch_1):\DP_81\") )
				( member ( diffPairRef "@crescent_city_bb_fab1_lib.crescent_city_bb_fab1(sch_1):\DP_82\") )
				( member ( diffPairRef "@crescent_city_bb_fab1_lib.crescent_city_bb_fab1(sch_1):\DP_83\") )
				( member ( diffPairRef "@crescent_city_bb_fab1_lib.crescent_city_bb_fab1(sch_1):\DP_84\") )
				( member ( diffPairRef "@crescent_city_bb_fab1_lib.crescent_city_bb_fab1(sch_1):\DP_85\") )
				( member ( diffPairRef "@crescent_city_bb_fab1_lib.crescent_city_bb_fab1(sch_1):\DP_86\") )
				( member ( diffPairRef "@crescent_city_bb_fab1_lib.crescent_city_bb_fab1(sch_1):\DP_87\") )
				( member ( diffPairRef "@crescent_city_bb_fab1_lib.crescent_city_bb_fab1(sch_1):\DP_88\") )
				( member ( diffPairRef "@crescent_city_bb_fab1_lib.crescent_city_bb_fab1(sch_1):\DP_89\") )
				( member ( diffPairRef "@crescent_city_bb_fab1_lib.crescent_city_bb_fab1(sch_1):\DP_90\") )
				( member ( diffPairRef "@crescent_city_bb_fab1_lib.crescent_city_bb_fab1(sch_1):\DP_91\") )
				( member ( diffPairRef "@crescent_city_bb_fab1_lib.crescent_city_bb_fab1(sch_1):\DP_92\") )
				( member ( diffPairRef "@crescent_city_bb_fab1_lib.crescent_city_bb_fab1(sch_1):\DP_93\") )
				( member ( diffPairRef "@crescent_city_bb_fab1_lib.crescent_city_bb_fab1(sch_1):\DP_94\") )
				( member ( diffPairRef "@crescent_city_bb_fab1_lib.crescent_city_bb_fab1(sch_1):\DP_95\") )
				( member ( diffPairRef "@crescent_city_bb_fab1_lib.crescent_city_bb_fab1(sch_1):\DP_96\") )
				( member ( diffPairRef "@crescent_city_bb_fab1_lib.crescent_city_bb_fab1(sch_1):\DP_97\") )
				( member ( diffPairRef "@crescent_city_bb_fab1_lib.crescent_city_bb_fab1(sch_1):\DP_98\") )
				( member ( diffPairRef "@crescent_city_bb_fab1_lib.crescent_city_bb_fab1(sch_1):\DP_99\") )
				( member ( diffPairRef "@crescent_city_bb_fab1_lib.crescent_city_bb_fab1(sch_1):\DP_100\") )
				( member ( diffPairRef "@crescent_city_bb_fab1_lib.crescent_city_bb_fab1(sch_1):\DP_101\") )
				( member ( diffPairRef "@crescent_city_bb_fab1_lib.crescent_city_bb_fab1(sch_1):\DP_102\") )
				( member ( diffPairRef "@crescent_city_bb_fab1_lib.crescent_city_bb_fab1(sch_1):\DP_103\") )
				( member ( diffPairRef "@crescent_city_bb_fab1_lib.crescent_city_bb_fab1(sch_1):\DP_104\") )
				( member ( diffPairRef "@crescent_city_bb_fab1_lib.crescent_city_bb_fab1(sch_1):\P3E_PCH_M2_SATA6G_RX_D\") )
				( member ( diffPairRef "@crescent_city_bb_fab1_lib.crescent_city_bb_fab1(sch_1):\P3E_PCH_M2_SATA6G_TX_D\") )
				( objectStatus "CLS_SATA" )
			)
			( netClass "@crescent_city_bb_fab1_lib.crescent_city_bb_fab1(sch_1):\RMII\"
				( memberType ( signal ) )
				( objectFlag fObjectElectrical )
				( member ( signalRef "@baseboard_fab2_lib.baseboard_fab2(sch_1):rmii_bmc_ocp_crsdv") )
				( member ( signalRef "@baseboard_fab2_lib.baseboard_fab2(sch_1):rmii_bmc_ocp_rxd0") )
				( member ( signalRef "@baseboard_fab2_lib.baseboard_fab2(sch_1):rmii_bmc_ocp_rxd1") )
				( member ( signalRef "@baseboard_fab2_lib.baseboard_fab2(sch_1):rmii_bmc_ocp_rxer") )
				( member ( electricalNetRef "@crescent_city_bb_fab1_lib.crescent_city_bb_fab1(sch_1):rmii_bmc_ocp_txen") )
				( member ( electricalNetRef "@crescent_city_bb_fab1_lib.crescent_city_bb_fab1(sch_1):rmii_bmc_pch_sprngvlle_rxer") )
				( member ( electricalNetRef "@crescent_city_bb_fab1_lib.crescent_city_bb_fab1(sch_1):rmii_bmc_pch_sprngvlle_crsdv") )
				( member ( electricalNetRef "@crescent_city_bb_fab1_lib.crescent_city_bb_fab1(sch_1):rmii_sprngvlle_bmc_pch_rxd1") )
				( member ( electricalNetRef "@crescent_city_bb_fab1_lib.crescent_city_bb_fab1(sch_1):rmii_sprngvlle_bmc_pch_rxd0") )
				( member ( electricalNetRef "@crescent_city_bb_fab1_lib.crescent_city_bb_fab1(sch_1):rmii_bmc_pch_sprngvlle_txen") )
				( member ( electricalNetRef "@crescent_city_bb_fab1_lib.crescent_city_bb_fab1(sch_1):rmii_bmc_pch_sprngvlle_txd1") )
				( member ( electricalNetRef "@crescent_city_bb_fab1_lib.crescent_city_bb_fab1(sch_1):rmii_bmc_pch_sprngvlle_txd0") )
				( member ( electricalNetRef "@crescent_city_bb_fab1_lib.crescent_city_bb_fab1(sch_1):clk_50m_ckmng_ocp") )
				( member ( electricalNetRef "@crescent_city_bb_fab1_lib.crescent_city_bb_fab1(sch_1):clk_50m_ckmng_bmc_1") )
				( member ( electricalNetRef "@crescent_city_bb_fab1_lib.crescent_city_bb_fab1(sch_1):clk_50m_nic") )
				( member ( electricalNetRef "@crescent_city_bb_fab1_lib.crescent_city_bb_fab1(sch_1):rmii_bmc_ocp_txd1") )
				( member ( electricalNetRef "@crescent_city_bb_fab1_lib.crescent_city_bb_fab1(sch_1):rmii_bmc_ocp_txd0") )
				( member ( electricalNetRef "@crescent_city_bb_fab1_lib.crescent_city_bb_fab1(sch_1):clk_50m_ckmng_bmc_2") )
				( member ( electricalNetRef "@crescent_city_bb_fab1_lib.crescent_city_bb_fab1(sch_1):clk_50m_ckmng_sprvlle") )
				( member ( electricalNetRef "@crescent_city_bb_fab1_lib.crescent_city_bb_fab1(sch_1):rmii_pch_sprngvlle_arb_out") )
				( member ( electricalNetRef "@crescent_city_bb_fab1_lib.crescent_city_bb_fab1(sch_1):rmii_pch_sprngvlle_arb_in") )
				( objectStatus "CLS_RMII" )
			)
			( netClass "@crescent_city_bb_fab1_lib.crescent_city_bb_fab1(sch_1):\CLS_USB3\"
				( memberType ( signal ) )
				( objectFlag fObjectElectrical )
				( objectStatus "CLS_USB3" )
			)
			( netClass "@crescent_city_bb_fab1_lib.crescent_city_bb_fab1(sch_1):\CLS_USB2\"
				( memberType ( signal ) )
				( objectFlag fObjectElectrical )
				( member ( diffPairRef "@crescent_city_bb_fab1_lib.crescent_city_bb_fab1(sch_1):\USB2_PCH_BMC_P4_D\") )
				( member ( diffPairRef "@crescent_city_bb_fab1_lib.crescent_city_bb_fab1(sch_1):\USB2_PCH_BMC_P5_D\") )
				( member ( diffPairRef "@crescent_city_bb_fab1_lib.crescent_city_bb_fab1(sch_1):\DP_USB2_P02\") )
				( member ( electricalNetRef "@crescent_city_bb_fab1_lib.crescent_city_bb_fab1(sch_1):usb2_p01_dn") )
				( member ( electricalNetRef "@crescent_city_bb_fab1_lib.crescent_city_bb_fab1(sch_1):usb2_p01_dp") )
				( objectStatus "CLS_USB2" )
			)
			( netClass "@crescent_city_bb_fab1_lib.crescent_city_bb_fab1(sch_1):\CLK_SE\"
				( memberType ( signal ) )
				( objectFlag fObjectElectrical )
				( member ( signalRef "@baseboard_fab2_lib.baseboard_fab2(sch_1):clk_48m_usb_bmc") )
				( member ( electricalNetRef "@crescent_city_bb_fab1_lib.crescent_city_bb_fab1(sch_1):clk_24m_bmc_lpc") )
				( member ( electricalNetRef "@crescent_city_bb_fab1_lib.crescent_city_bb_fab1(sch_1):h_pmsync_clk_24m_cpu0") )
				( member ( electricalNetRef "@crescent_city_bb_fab1_lib.crescent_city_bb_fab1(sch_1):clk_32k_susclk_pld") )
				( member ( electricalNetRef "@crescent_city_bb_fab1_lib.crescent_city_bb_fab1(sch_1):clk_25m_bmc") )
				( member ( electricalNetRef "@crescent_city_bb_fab1_lib.crescent_city_bb_fab1(sch_1):clk_25m_cpld") )
				( objectStatus "CLK_SE" )
			)
			( netClass "@crescent_city_bb_fab1_lib.crescent_city_bb_fab1(sch_1):\CPU_BCLK\"
				( memberType ( signal ) )
				( electricalCSetRef "@crescent_city_bb_fab1_lib.crescent_city_bb_fab1(sch_1):\BCLK\" )
				( objectFlag fObjectElectrical )
				( member ( electricalNetRef "@crescent_city_bb_fab1_lib.crescent_city_bb_fab1(sch_1):clk_100m_cpu1_bclk2_dp") )
				( member ( electricalNetRef "@crescent_city_bb_fab1_lib.crescent_city_bb_fab1(sch_1):clk_100m_cpu1_bclk2_dn") )
				( member ( electricalNetRef "@crescent_city_bb_fab1_lib.crescent_city_bb_fab1(sch_1):clk_100m_cpu1_bclk1_dp") )
				( member ( electricalNetRef "@crescent_city_bb_fab1_lib.crescent_city_bb_fab1(sch_1):clk_100m_cpu1_bclk1_dn") )
				( member ( electricalNetRef "@crescent_city_bb_fab1_lib.crescent_city_bb_fab1(sch_1):clk_100m_cpu1_bclk0_dp") )
				( member ( electricalNetRef "@crescent_city_bb_fab1_lib.crescent_city_bb_fab1(sch_1):clk_100m_cpu1_bclk0_dn") )
				( member ( electricalNetRef "@crescent_city_bb_fab1_lib.crescent_city_bb_fab1(sch_1):clk_100m_cpu0_bclk2_dp") )
				( member ( electricalNetRef "@crescent_city_bb_fab1_lib.crescent_city_bb_fab1(sch_1):clk_100m_cpu0_bclk2_dn") )
				( member ( electricalNetRef "@crescent_city_bb_fab1_lib.crescent_city_bb_fab1(sch_1):clk_100m_cpu0_bclk1_dp") )
				( member ( electricalNetRef "@crescent_city_bb_fab1_lib.crescent_city_bb_fab1(sch_1):clk_100m_cpu0_bclk1_dn") )
				( member ( electricalNetRef "@crescent_city_bb_fab1_lib.crescent_city_bb_fab1(sch_1):clk_100m_cpu0_bclk0_dp") )
				( member ( electricalNetRef "@crescent_city_bb_fab1_lib.crescent_city_bb_fab1(sch_1):clk_100m_cpu0_bclk0_dn") )
				( objectStatus "CPU_BCLK" )
			)
			( netClass "@crescent_city_bb_fab1_lib.crescent_city_bb_fab1(sch_1):\CLS_BMC\"
				( memberType ( signal ) )
				( attribute "MAX_VIA_COUNT" "2"
					( Origin gBackEnd )
				)
				( attribute "PROPAGATION_DELAY_PATH_TYPE" "AD:AR"
					( Origin gBackEnd )
				)
				( attribute "PROPAGATION_DELAY_MAX" "1000.00 MIL"
					( Units "uMaxMinProp" "ns" 1.000000)
					( Origin gBackEnd )
				)
				( objectFlag fObjectElectrical )
				( member ( signalRef "@baseboard_fab2_lib.baseboard_fab2(sch_1):m_bmc_ddr3_dq(0)") )
				( member ( signalRef "@baseboard_fab2_lib.baseboard_fab2(sch_1):m_bmc_ddr3_dq(1)") )
				( member ( signalRef "@baseboard_fab2_lib.baseboard_fab2(sch_1):m_bmc_ddr3_dq(2)") )
				( member ( signalRef "@baseboard_fab2_lib.baseboard_fab2(sch_1):m_bmc_ddr3_dq(3)") )
				( member ( signalRef "@baseboard_fab2_lib.baseboard_fab2(sch_1):m_bmc_ddr3_dq(4)") )
				( member ( signalRef "@baseboard_fab2_lib.baseboard_fab2(sch_1):m_bmc_ddr3_dq(5)") )
				( member ( signalRef "@baseboard_fab2_lib.baseboard_fab2(sch_1):m_bmc_ddr3_dq(6)") )
				( member ( signalRef "@baseboard_fab2_lib.baseboard_fab2(sch_1):m_bmc_ddr3_dq(7)") )
				( member ( signalRef "@baseboard_fab2_lib.baseboard_fab2(sch_1):m_bmc_ddr3_dq(8)") )
				( member ( signalRef "@baseboard_fab2_lib.baseboard_fab2(sch_1):m_bmc_ddr3_dq(9)") )
				( member ( signalRef "@baseboard_fab2_lib.baseboard_fab2(sch_1):m_bmc_ddr3_dq(10)") )
				( member ( signalRef "@baseboard_fab2_lib.baseboard_fab2(sch_1):m_bmc_ddr3_dq(11)") )
				( member ( signalRef "@baseboard_fab2_lib.baseboard_fab2(sch_1):m_bmc_ddr3_dq(12)") )
				( member ( signalRef "@baseboard_fab2_lib.baseboard_fab2(sch_1):m_bmc_ddr3_dq(13)") )
				( member ( signalRef "@baseboard_fab2_lib.baseboard_fab2(sch_1):m_bmc_ddr3_dq(14)") )
				( member ( signalRef "@baseboard_fab2_lib.baseboard_fab2(sch_1):m_bmc_ddr3_dq(15)") )
				( member ( signalRef "@baseboard_fab2_lib.baseboard_fab2(sch_1):m_bmc_ddr3_ma(0)") )
				( member ( signalRef "@baseboard_fab2_lib.baseboard_fab2(sch_1):m_bmc_ddr3_ma(1)") )
				( member ( signalRef "@baseboard_fab2_lib.baseboard_fab2(sch_1):m_bmc_ddr3_ma(2)") )
				( member ( signalRef "@baseboard_fab2_lib.baseboard_fab2(sch_1):m_bmc_ddr3_ma(3)") )
				( member ( signalRef "@baseboard_fab2_lib.baseboard_fab2(sch_1):m_bmc_ddr3_ma(4)") )
				( member ( signalRef "@baseboard_fab2_lib.baseboard_fab2(sch_1):m_bmc_ddr3_ma(5)") )
				( member ( signalRef "@baseboard_fab2_lib.baseboard_fab2(sch_1):m_bmc_ddr3_ma(6)") )
				( member ( signalRef "@baseboard_fab2_lib.baseboard_fab2(sch_1):m_bmc_ddr3_ma(7)") )
				( member ( signalRef "@baseboard_fab2_lib.baseboard_fab2(sch_1):m_bmc_ddr3_ma(8)") )
				( member ( signalRef "@baseboard_fab2_lib.baseboard_fab2(sch_1):m_bmc_ddr3_ma(9)") )
				( member ( signalRef "@baseboard_fab2_lib.baseboard_fab2(sch_1):m_bmc_ddr3_ma(10)") )
				( member ( signalRef "@baseboard_fab2_lib.baseboard_fab2(sch_1):m_bmc_ddr3_ma(11)") )
				( member ( signalRef "@baseboard_fab2_lib.baseboard_fab2(sch_1):m_bmc_ddr3_ma(12)") )
				( member ( signalRef "@baseboard_fab2_lib.baseboard_fab2(sch_1):m_bmc_ddr3_ma(13)") )
				( member ( signalRef "@baseboard_fab2_lib.baseboard_fab2(sch_1):m_bmc_ddr3_ma(14)") )
				( member ( signalRef "@baseboard_fab2_lib.baseboard_fab2(sch_1):m_bmc_ddr3_mck_n") )
				( member ( signalRef "@baseboard_fab2_lib.baseboard_fab2(sch_1):m_bmc_ddr3_mck_p") )
				( member ( signalRef "@baseboard_fab2_lib.baseboard_fab2(sch_1):m_bmc_ddr3_mdm_0") )
				( member ( signalRef "@baseboard_fab2_lib.baseboard_fab2(sch_1):m_bmc_ddr3_mdm_1") )
				( member ( signalRef "@baseboard_fab2_lib.baseboard_fab2(sch_1):m_bmc_ddr3_mba_0") )
				( member ( signalRef "@baseboard_fab2_lib.baseboard_fab2(sch_1):m_bmc_ddr3_mba_1") )
				( member ( signalRef "@baseboard_fab2_lib.baseboard_fab2(sch_1):m_bmc_ddr3_mba_2") )
				( member ( signalRef "@baseboard_fab2_lib.baseboard_fab2(sch_1):m_bmc_ddr3_mcas_n") )
				( member ( signalRef "@baseboard_fab2_lib.baseboard_fab2(sch_1):m_bmc_ddr3_mcke") )
				( member ( signalRef "@baseboard_fab2_lib.baseboard_fab2(sch_1):m_bmc_ddr3_mcs_n") )
				( member ( signalRef "@baseboard_fab2_lib.baseboard_fab2(sch_1):m_bmc_ddr3_modt") )
				( member ( signalRef "@baseboard_fab2_lib.baseboard_fab2(sch_1):m_bmc_ddr3_mras_n") )
				( member ( signalRef "@baseboard_fab2_lib.baseboard_fab2(sch_1):m_bmc_ddr3_mwe_n") )
				( member ( signalRef "@baseboard_fab2_lib.baseboard_fab2(sch_1):m_bmc_ddr3_mdqs_0_dn") )
				( member ( signalRef "@baseboard_fab2_lib.baseboard_fab2(sch_1):m_bmc_ddr3_mdqs_0_dp") )
				( member ( signalRef "@baseboard_fab2_lib.baseboard_fab2(sch_1):m_bmc_ddr3_mdqs_1_dn") )
				( member ( signalRef "@baseboard_fab2_lib.baseboard_fab2(sch_1):m_bmc_ddr3_mdqs_1_dp") )
				( objectStatus "CLS_BMC" )
			)
			( netClass "@crescent_city_bb_fab1_lib.crescent_city_bb_fab1(sch_1):\CLS_SIDEBAND\"
				( memberType ( signal ) )
				( objectFlag fObjectElectrical )
				( member ( signalRef "@baseboard_fab2_lib.baseboard_fab2(sch_1):h_cpu0_fast_wake_lvt3_n") )
				( member ( signalRef "@baseboard_fab2_lib.baseboard_fab2(sch_1):h_cpu0_fivr_fault_g") )
				( member ( signalRef "@baseboard_fab2_lib.baseboard_fab2(sch_1):h_cpu0_memabc_memhot") )
				( member ( signalRef "@baseboard_fab2_lib.baseboard_fab2(sch_1):h_cpu0_memdef_memhot") )
				( member ( signalRef "@baseboard_fab2_lib.baseboard_fab2(sch_1):h_cpu0_thermtrip_g_n") )
				( member ( signalRef "@baseboard_fab2_lib.baseboard_fab2(sch_1):h_cpu1_fivr_fault_g") )
				( member ( signalRef "@baseboard_fab2_lib.baseboard_fab2(sch_1):h_cpu1_memghj_memhot") )
				( member ( signalRef "@baseboard_fab2_lib.baseboard_fab2(sch_1):h_cpu1_memklm_memhot") )
				( member ( signalRef "@baseboard_fab2_lib.baseboard_fab2(sch_1):h_cpu1_thermtrip_g_n") )
				( member ( signalRef "@baseboard_fab2_lib.baseboard_fab2(sch_1):h_cpu0_fast_wake") )
				( member ( signalRef "@baseboard_fab2_lib.baseboard_fab2(sch_1):fm_cpu0_thermtrip_latch_lvt3_n") )
				( member ( signalRef "@baseboard_fab2_lib.baseboard_fab2(sch_1):fm_cpu1_thermtrip_latch_lvt3_n") )
				( member ( electricalNetRef "@crescent_city_bb_fab1_lib.crescent_city_bb_fab1(sch_1):h_cpu_err2_g_r_n") )
				( member ( electricalNetRef "@crescent_city_bb_fab1_lib.crescent_city_bb_fab1(sch_1):h_cpu0_fast_wake_b_n") )
				( member ( electricalNetRef "@crescent_city_bb_fab1_lib.crescent_city_bb_fab1(sch_1):h_pm_sync_gtl_r1") )
				( member ( electricalNetRef "@crescent_city_bb_fab1_lib.crescent_city_bb_fab1(sch_1):h_cpu0_msmi_g_n") )
				( member ( electricalNetRef "@crescent_city_bb_fab1_lib.crescent_city_bb_fab1(sch_1):h_cpu0_caterr_g_n") )
				( member ( electricalNetRef "@baseboard_fab2_lib.baseboard_fab2(sch_1):fm_cpu1_prochot_lvt3_k_n") )
				( member ( electricalNetRef "@baseboard_fab2_lib.baseboard_fab2(sch_1):h_cpu1_memklm_memhot_g_pch_n") )
				( member ( electricalNetRef "@baseboard_fab2_lib.baseboard_fab2(sch_1):h_cpu1_memghj_memhot_g_pch_n") )
				( member ( electricalNetRef "@baseboard_fab2_lib.baseboard_fab2(sch_1):fm_cpu0_prochot_lvt3_k_n") )
				( member ( electricalNetRef "@baseboard_fab2_lib.baseboard_fab2(sch_1):h_cpu0_memdef_memhot_g_pch_n") )
				( member ( electricalNetRef "@baseboard_fab2_lib.baseboard_fab2(sch_1):h_cpu0_memabc_memhot_g_pch_n") )
				( member ( electricalNetRef "@baseboard_fab2_lib.baseboard_fab2(sch_1):fm_cpu_err0_lvt3_k_n") )
				( objectStatus "CLS_SIDEBAND" )
			)
			( netClass "@crescent_city_bb_fab1_lib.crescent_city_bb_fab1(sch_1):\DMI\"
				( memberType ( signal ) )
				( electricalCSetRef "@crescent_city_bb_fab1_lib.crescent_city_bb_fab1(sch_1):\DMI_CPU0_PCH_RX_C_DN_0_\" )
				( objectFlag fObjectElectrical )
				( member ( diffPairRef "@sapphirecity_baseboard_lib.sapphirecity_baseboard(sch_1):\DMI_CPU0_PCH_TX_C_D\(0)") )
				( member ( diffPairRef "@sapphirecity_baseboard_lib.sapphirecity_baseboard(sch_1):\DMI_CPU0_PCH_TX_C_D\(1)") )
				( member ( diffPairRef "@sapphirecity_baseboard_lib.sapphirecity_baseboard(sch_1):\DMI_CPU0_PCH_TX_C_D\(2)") )
				( member ( diffPairRef "@sapphirecity_baseboard_lib.sapphirecity_baseboard(sch_1):\DMI_CPU0_PCH_TX_C_D\(3)") )
				( objectStatus "CLS_DMI" )
			)
			( netClass "@crescent_city_bb_fab1_lib.crescent_city_bb_fab1(sch_1):\SNCLS_SFI_TX\"
				( memberType ( signal ) )
				( spacingCSetRef "@crescent_city_bb_fab1_lib.crescent_city_bb_fab1(sch_1):\15H_US_&_7H_SL\" )
				( objectFlag fObjectSpacing )
				( objectFlag fObjectSameNetSpacing )
				( objectStatus "SNCLS_SFI_TX" )
			)
			( netClass "@crescent_city_bb_fab1_lib.crescent_city_bb_fab1(sch_1):\SNCLS_SFI_RX\"
				( memberType ( signal ) )
				( spacingCSetRef "@crescent_city_bb_fab1_lib.crescent_city_bb_fab1(sch_1):\15H_US_&_7H_SL\" )
				( objectFlag fObjectSpacing )
				( objectFlag fObjectSameNetSpacing )
				( objectStatus "SNCLS_SFI_RX" )
			)
			( netClass "@crescent_city_bb_fab1_lib.crescent_city_bb_fab1(sch_1):\PNCLS_93-OHM_DIFF\"
				( memberType ( signal ) )
				( physicalCSetRef "@sapphirecity_baseboard_lib.sapphirecity_baseboard(sch_1):\95_OHM_DIFF\" )
				( objectFlag fObjectPhysical )
				( objectStatus "PNCLS_93-OHM_DIFF" )
			)
			( netClass "@crescent_city_bb_fab1_lib.crescent_city_bb_fab1(sch_1):\SNCLS_NIC_MDI_7H-6H\"
				( memberType ( signal ) )
				( spacingCSetRef "@baseboard_fab2_lib.baseboard_fab2(sch_1):\NEW_NIC_7H_US_&_6H_SL\" )
				( attribute "LINE_TO_THRUVIA_SPACING" "12.00"
					( Origin gBackEnd )
				)
				( attribute "LINE_TO_SHAPE_SPACING" "14.00"
					( Origin gBackEnd )
				)
				( objectFlag fObjectSpacing )
				( objectFlag fObjectSameNetSpacing )
				( member ( diffPairRef "@crescent_city_bb_fab1_lib.crescent_city_bb_fab1(sch_1):\NIC_MDI_SPRV_RJ45_0_D\") )
				( member ( diffPairRef "@crescent_city_bb_fab1_lib.crescent_city_bb_fab1(sch_1):\NIC_MDI_SPRV_RJ45_1_D\") )
				( member ( diffPairRef "@crescent_city_bb_fab1_lib.crescent_city_bb_fab1(sch_1):\MDI_MNG_RX\") )
				( member ( diffPairRef "@crescent_city_bb_fab1_lib.crescent_city_bb_fab1(sch_1):\MDI_MNG_TX\") )
				( member ( diffPairRef "@crescent_city_bb_fab1_lib.crescent_city_bb_fab1(sch_1):\DP_106\") )
				( member ( diffPairRef "@crescent_city_bb_fab1_lib.crescent_city_bb_fab1(sch_1):\DP_105\") )
				( member ( signalRef "@baseboard_fab2_lib.baseboard_fab2(sch_1):nic_mdi_sprv_rj45_2_r_dn") )
				( member ( signalRef "@baseboard_fab2_lib.baseboard_fab2(sch_1):nic_mdi_sprv_rj45_2_r_dp") )
				( member ( signalRef "@baseboard_fab2_lib.baseboard_fab2(sch_1):nic_mdi_sprv_rj45_3_r_dn") )
				( member ( signalRef "@baseboard_fab2_lib.baseboard_fab2(sch_1):nic_mdi_sprv_rj45_3_r_dp") )
				( member ( signalRef "@baseboard_fab2_lib.baseboard_fab2(sch_1):nic_ser_n_mdi_3_dn") )
				( member ( signalRef "@baseboard_fab2_lib.baseboard_fab2(sch_1):nic_ser_p_mdi_3_dp") )
				( member ( signalRef "@baseboard_fab2_lib.baseboard_fab2(sch_1):nic_set_n_mdi_2_dn") )
				( member ( signalRef "@baseboard_fab2_lib.baseboard_fab2(sch_1):nic_set_p_mdi_2_dp") )
				( objectStatus "SNCLS_NIC_MDI" )
			)
			( netClass "@crescent_city_bb_fab1_lib.crescent_city_bb_fab1(sch_1):\PNCLS_4MIL\"
				( memberType ( signal ) )
				( physicalCSetRef "@crescent_city_bb_fab1_lib.crescent_city_bb_fab1(sch_1):\4_MIL\" )
				( objectFlag fObjectPhysical )
				( member ( signalRef "@baseboard_fab2_lib.baseboard_fab2(sch_1):a_extclkn") )
				( member ( signalRef "@baseboard_fab2_lib.baseboard_fab2(sch_1):a_extclkp") )
				( member ( signalRef "@baseboard_fab2_lib.baseboard_fab2(sch_1):a_usb2_vbus") )
				( member ( signalRef "@baseboard_fab2_lib.baseboard_fab2(sch_1):a_m_bmc_zq") )
				( objectStatus "PNCLS_4MIL" )
			)
			( netClass "@crescent_city_bb_fab1_lib.crescent_city_bb_fab1(sch_1):\P3E_CPU1_PE1_MP_TX\"
				( memberType ( signal ) )
				( spacingCSetRef "@sapphirecity_baseboard_lib.sapphirecity_baseboard(sch_1):\11H_US_AND_5H_SL_VIA+3H_A\" )
				( objectFlag fObjectSpacing )
				( objectFlag fObjectSameNetSpacing )
				( member ( diffPairRef "@crescent_city_bb_fab1_lib.crescent_city_bb_fab1(sch_1):\DP_73\") )
				( member ( diffPairRef "@crescent_city_bb_fab1_lib.crescent_city_bb_fab1(sch_1):\DP_74\") )
				( member ( diffPairRef "@crescent_city_bb_fab1_lib.crescent_city_bb_fab1(sch_1):\DP_75\") )
				( member ( diffPairRef "@crescent_city_bb_fab1_lib.crescent_city_bb_fab1(sch_1):\DP_77\") )
				( member ( signalRef "@baseboard_fab2_lib.baseboard_fab2(sch_1):p3e_pch_m2_tx_c_dn(1)") )
				( member ( signalRef "@baseboard_fab2_lib.baseboard_fab2(sch_1):p3e_pch_m2_tx_c_dn(2)") )
				( member ( signalRef "@baseboard_fab2_lib.baseboard_fab2(sch_1):p3e_pch_m2_tx_c_dn(3)") )
				( member ( signalRef "@baseboard_fab2_lib.baseboard_fab2(sch_1):p3e_pch_m2_tx_c_dp(1)") )
				( member ( signalRef "@baseboard_fab2_lib.baseboard_fab2(sch_1):p3e_pch_m2_tx_c_dp(2)") )
				( member ( signalRef "@baseboard_fab2_lib.baseboard_fab2(sch_1):p3e_pch_m2_tx_c_dp(3)") )
				( member ( signalRef "@baseboard_fab2_lib.baseboard_fab2(sch_1):p3e_pch_m2_tx_dn(1)") )
				( member ( signalRef "@baseboard_fab2_lib.baseboard_fab2(sch_1):p3e_pch_m2_tx_dn(2)") )
				( member ( signalRef "@baseboard_fab2_lib.baseboard_fab2(sch_1):p3e_pch_m2_tx_dn(3)") )
				( member ( signalRef "@baseboard_fab2_lib.baseboard_fab2(sch_1):p3e_pch_m2_tx_dp(1)") )
				( member ( signalRef "@baseboard_fab2_lib.baseboard_fab2(sch_1):p3e_pch_m2_tx_dp(2)") )
				( member ( signalRef "@baseboard_fab2_lib.baseboard_fab2(sch_1):p3e_pch_m2_tx_dp(3)") )
				( objectStatus "SNCLS_P3E_CPU1_PE1_MP_TX" )
			)
			( netClass "@crescent_city_bb_fab1_lib.crescent_city_bb_fab1(sch_1):\P3E_CPU1_PE1_MP_RX\"
				( memberType ( signal ) )
				( spacingCSetRef "@sapphirecity_baseboard_lib.sapphirecity_baseboard(sch_1):\11H_US_AND_5H_SL_VIA+3H_A\" )
				( objectFlag fObjectSpacing )
				( objectFlag fObjectSameNetSpacing )
				( member ( diffPairRef "@crescent_city_bb_fab1_lib.crescent_city_bb_fab1(sch_1):\P3E_PCH_M2_RX_D\(1)") )
				( member ( diffPairRef "@crescent_city_bb_fab1_lib.crescent_city_bb_fab1(sch_1):\P3E_PCH_M2_RX_D\(2)") )
				( member ( diffPairRef "@crescent_city_bb_fab1_lib.crescent_city_bb_fab1(sch_1):\P3E_PCH_M2_RX_D\(3)") )
				( member ( diffPairRef "@crescent_city_bb_fab1_lib.crescent_city_bb_fab1(sch_1):\DP_76\") )
				( member ( signalRef "@baseboard_fab2_lib.baseboard_fab2(sch_1):p3e_pch_m2_rx_dn(1)") )
				( member ( signalRef "@baseboard_fab2_lib.baseboard_fab2(sch_1):p3e_pch_m2_rx_dn(2)") )
				( member ( signalRef "@baseboard_fab2_lib.baseboard_fab2(sch_1):p3e_pch_m2_rx_dn(3)") )
				( member ( signalRef "@baseboard_fab2_lib.baseboard_fab2(sch_1):p3e_pch_m2_rx_dp(1)") )
				( member ( signalRef "@baseboard_fab2_lib.baseboard_fab2(sch_1):p3e_pch_m2_rx_dp(2)") )
				( member ( signalRef "@baseboard_fab2_lib.baseboard_fab2(sch_1):p3e_pch_m2_rx_dp(3)") )
				( objectStatus "SNCLS_P3E_CPU1_PE1_MP_RX" )
			)
			( netClass "@crescent_city_bb_fab1_lib.crescent_city_bb_fab1(sch_1):\WID_10MILS\"
				( memberType ( signal ) )
				( physicalCSetRef "@sapphirecity_baseboard_lib.sapphirecity_baseboard(sch_1):\10_MILS-SE\" )
				( objectFlag fObjectPhysical )
				( member ( signalRef "@baseboard_fab2_lib.baseboard_fab2(sch_1):a_hsc_inap") )
				( member ( signalRef "@baseboard_fab2_lib.baseboard_fab2(sch_1):m_f_cpu_vref") )
				( member ( signalRef "@baseboard_fab2_lib.baseboard_fab2(sch_1):m_f_vref") )
				( member ( signalRef "@baseboard_fab2_lib.baseboard_fab2(sch_1):a_pg_p5v") )
				( member ( signalRef "@baseboard_fab2_lib.baseboard_fab2(sch_1):a_pg_p12v_main") )
				( member ( signalRef "@baseboard_fab2_lib.baseboard_fab2(sch_1):vr_pvccin_cpu1_vd12") )
				( member ( signalRef "@baseboard_fab2_lib.baseboard_fab2(sch_1):vr_pvsa_cpu0_phase_sw") )
				( member ( signalRef "@baseboard_fab2_lib.baseboard_fab2(sch_1):vr_pvsa_cpu1_phase_sw") )
				( member ( signalRef "@baseboard_fab2_lib.baseboard_fab2(sch_1):a_p12v_stby_fph_gate") )
				( member ( signalRef "@baseboard_fab2_lib.baseboard_fab2(sch_1):vr_pvccin_cpu0_pwm1") )
				( member ( signalRef "@baseboard_fab2_lib.baseboard_fab2(sch_1):vr_pvccin_cpu0_pwm2") )
				( member ( signalRef "@baseboard_fab2_lib.baseboard_fab2(sch_1):vr_pvccin_cpu0_pwm3") )
				( member ( signalRef "@baseboard_fab2_lib.baseboard_fab2(sch_1):vr_pvccin_cpu0_pwm4") )
				( member ( signalRef "@baseboard_fab2_lib.baseboard_fab2(sch_1):vr_pvccin_cpu0_pwm5") )
				( member ( signalRef "@baseboard_fab2_lib.baseboard_fab2(sch_1):vr_pvccin_cpu1_pwm1") )
				( member ( signalRef "@baseboard_fab2_lib.baseboard_fab2(sch_1):vr_pvccin_cpu1_pwm2") )
				( member ( signalRef "@baseboard_fab2_lib.baseboard_fab2(sch_1):vr_pvccin_cpu1_pwm3") )
				( member ( signalRef "@baseboard_fab2_lib.baseboard_fab2(sch_1):vr_pvccin_cpu1_pwm4") )
				( member ( signalRef "@baseboard_fab2_lib.baseboard_fab2(sch_1):vr_pvccin_cpu1_pwm5") )
				( member ( signalRef "@baseboard_fab2_lib.baseboard_fab2(sch_1):vr_pvccio_cpu0_pwm1") )
				( member ( signalRef "@baseboard_fab2_lib.baseboard_fab2(sch_1):vr_pvccio_cpu1_pwm1") )
				( member ( signalRef "@baseboard_fab2_lib.baseboard_fab2(sch_1):vr_pvddq_abc_pwm1") )
				( member ( signalRef "@baseboard_fab2_lib.baseboard_fab2(sch_1):vr_pvddq_abc_pwm2") )
				( member ( signalRef "@baseboard_fab2_lib.baseboard_fab2(sch_1):vr_pvddq_def_pwm1") )
				( member ( signalRef "@baseboard_fab2_lib.baseboard_fab2(sch_1):vr_pvddq_def_pwm2") )
				( member ( signalRef "@baseboard_fab2_lib.baseboard_fab2(sch_1):vr_pvddq_ghj_pwm1") )
				( member ( signalRef "@baseboard_fab2_lib.baseboard_fab2(sch_1):vr_pvddq_ghj_pwm2") )
				( member ( signalRef "@baseboard_fab2_lib.baseboard_fab2(sch_1):vr_pvddq_klm_pwm1") )
				( member ( signalRef "@baseboard_fab2_lib.baseboard_fab2(sch_1):vr_pvddq_klm_pwm2") )
				( member ( signalRef "@baseboard_fab2_lib.baseboard_fab2(sch_1):vr_pvnn_pch_pwm1") )
				( member ( signalRef "@baseboard_fab2_lib.baseboard_fab2(sch_1):vr_pvsa_cpu0_pwm") )
				( member ( signalRef "@baseboard_fab2_lib.baseboard_fab2(sch_1):vr_pvsa_cpu1_pwm") )
				( member ( signalRef "@baseboard_fab2_lib.baseboard_fab2(sch_1):vr_p1v05_pch_stby_pwm1") )
				( member ( signalRef "@baseboard_fab2_lib.baseboard_fab2(sch_1):vr_p1v8_pch_stby_fb") )
				( member ( signalRef "@baseboard_fab2_lib.baseboard_fab2(sch_1):vr_p1v26_bmc_stby_fb") )
				( member ( signalRef "@baseboard_fab2_lib.baseboard_fab2(sch_1):vr_p1v538_bmc_stby_fb") )
				( member ( signalRef "@baseboard_fab2_lib.baseboard_fab2(sch_1):a_p3v_bat_r") )
				( member ( signalRef "@baseboard_fab2_lib.baseboard_fab2(sch_1):a_p3v_bat_scaled") )
				( member ( signalRef "@baseboard_fab2_lib.baseboard_fab2(sch_1):a_hsc_uv") )
				( member ( signalRef "@baseboard_fab2_lib.baseboard_fab2(sch_1):a_hsc_ov") )
				( member ( signalRef "@baseboard_fab2_lib.baseboard_fab2(sch_1):a_adm1085_cext") )
				( member ( signalRef "@baseboard_fab2_lib.baseboard_fab2(sch_1):a_cbot") )
				( member ( signalRef "@baseboard_fab2_lib.baseboard_fab2(sch_1):a_ctop") )
				( member ( signalRef "@baseboard_fab2_lib.baseboard_fab2(sch_1):a_cpu0_upi2_rbias") )
				( member ( signalRef "@baseboard_fab2_lib.baseboard_fab2(sch_1):a_cpu0_upi01_rbias") )
				( member ( signalRef "@baseboard_fab2_lib.baseboard_fab2(sch_1):a_cpu0_mcp01_rbias") )
				( member ( signalRef "@baseboard_fab2_lib.baseboard_fab2(sch_1):a_cpu0_pe3_rbias") )
				( member ( signalRef "@baseboard_fab2_lib.baseboard_fab2(sch_1):a_cpu0_pe012_rbias") )
				( member ( signalRef "@baseboard_fab2_lib.baseboard_fab2(sch_1):a_cpu1_upi2_rbias") )
				( member ( signalRef "@baseboard_fab2_lib.baseboard_fab2(sch_1):a_cpu1_upi01_rbias") )
				( member ( signalRef "@baseboard_fab2_lib.baseboard_fab2(sch_1):a_cpu1_mcp01_rbias") )
				( member ( signalRef "@baseboard_fab2_lib.baseboard_fab2(sch_1):a_cpu1_pe3_rbias") )
				( member ( signalRef "@baseboard_fab2_lib.baseboard_fab2(sch_1):a_cpu1_pe012_rbias") )
				( member ( signalRef "@baseboard_fab2_lib.baseboard_fab2(sch_1):a_dacrset") )
				( member ( signalRef "@baseboard_fab2_lib.baseboard_fab2(sch_1):a_1p8_3p3_rcomp") )
				( member ( signalRef "@baseboard_fab2_lib.baseboard_fab2(sch_1):a_rcomp_3p3") )
				( member ( signalRef "@baseboard_fab2_lib.baseboard_fab2(sch_1):a_hsc_iset") )
				( member ( signalRef "@baseboard_fab2_lib.baseboard_fab2(sch_1):a_hsc_iset_s") )
				( member ( signalRef "@baseboard_fab2_lib.baseboard_fab2(sch_1):a_hsc_iset_s2") )
				( member ( signalRef "@baseboard_fab2_lib.baseboard_fab2(sch_1):a_hsc_istart") )
				( member ( signalRef "@baseboard_fab2_lib.baseboard_fab2(sch_1):a_hsc_pset") )
				( member ( signalRef "@baseboard_fab2_lib.baseboard_fab2(sch_1):a_kr0_rbias") )
				( member ( signalRef "@baseboard_fab2_lib.baseboard_fab2(sch_1):a_kr1_rbias") )
				( member ( signalRef "@baseboard_fab2_lib.baseboard_fab2(sch_1):a_pch_xclk_biasref") )
				( member ( signalRef "@baseboard_fab2_lib.baseboard_fab2(sch_1):a_pcieup_rcomp_n") )
				( member ( signalRef "@baseboard_fab2_lib.baseboard_fab2(sch_1):a_pcieup_rcomp_p") )
				( member ( signalRef "@baseboard_fab2_lib.baseboard_fab2(sch_1):a_pcie_rcomp_n") )
				( member ( signalRef "@baseboard_fab2_lib.baseboard_fab2(sch_1):a_pcie_rcomp_p") )
				( member ( signalRef "@baseboard_fab2_lib.baseboard_fab2(sch_1):a_pvccrtc_ext_cap") )
				( member ( signalRef "@baseboard_fab2_lib.baseboard_fab2(sch_1):a_usb2vres") )
				( member ( signalRef "@baseboard_fab2_lib.baseboard_fab2(sch_1):a_usb2_comp") )
				( member ( signalRef "@baseboard_fab2_lib.baseboard_fab2(sch_1):a_hsc_vcap") )
				( member ( signalRef "@baseboard_fab2_lib.baseboard_fab2(sch_1):m_a_cpu_vref") )
				( member ( signalRef "@baseboard_fab2_lib.baseboard_fab2(sch_1):a_cpu0_abc_rcomp0") )
				( member ( signalRef "@baseboard_fab2_lib.baseboard_fab2(sch_1):a_cpu0_abc_rcomp1") )
				( member ( signalRef "@baseboard_fab2_lib.baseboard_fab2(sch_1):a_cpu0_abc_rcomp2") )
				( member ( signalRef "@baseboard_fab2_lib.baseboard_fab2(sch_1):a_cpu0_def_rcomp0") )
				( member ( signalRef "@baseboard_fab2_lib.baseboard_fab2(sch_1):a_cpu0_def_rcomp1") )
				( member ( signalRef "@baseboard_fab2_lib.baseboard_fab2(sch_1):a_cpu0_def_rcomp2") )
				( member ( signalRef "@baseboard_fab2_lib.baseboard_fab2(sch_1):a_cpu1_ghj_rcomp0") )
				( member ( signalRef "@baseboard_fab2_lib.baseboard_fab2(sch_1):a_cpu1_ghj_rcomp1") )
				( member ( signalRef "@baseboard_fab2_lib.baseboard_fab2(sch_1):a_cpu1_ghj_rcomp2") )
				( member ( signalRef "@baseboard_fab2_lib.baseboard_fab2(sch_1):a_cpu1_klm_rcomp0") )
				( member ( signalRef "@baseboard_fab2_lib.baseboard_fab2(sch_1):a_cpu1_klm_rcomp1") )
				( member ( signalRef "@baseboard_fab2_lib.baseboard_fab2(sch_1):a_cpu1_klm_rcomp2") )
				( member ( signalRef "@baseboard_fab2_lib.baseboard_fab2(sch_1):a_hsc_c") )
				( member ( signalRef "@baseboard_fab2_lib.baseboard_fab2(sch_1):a_hsc_csout") )
				( member ( signalRef "@baseboard_fab2_lib.baseboard_fab2(sch_1):a_hsc_high") )
				( member ( signalRef "@baseboard_fab2_lib.baseboard_fab2(sch_1):a_hsc_high_en") )
				( member ( signalRef "@baseboard_fab2_lib.baseboard_fab2(sch_1):a_hsc_low") )
				( member ( signalRef "@baseboard_fab2_lib.baseboard_fab2(sch_1):a_hsc_low_gate") )
				( member ( signalRef "@baseboard_fab2_lib.baseboard_fab2(sch_1):a_hsc_ocp_sel") )
				( member ( signalRef "@baseboard_fab2_lib.baseboard_fab2(sch_1):a_hsc_pwgin") )
				( member ( signalRef "@baseboard_fab2_lib.baseboard_fab2(sch_1):a_hsc_gate1_r") )
				( member ( signalRef "@baseboard_fab2_lib.baseboard_fab2(sch_1):a_hsc_gate2_r") )
				( member ( signalRef "@baseboard_fab2_lib.baseboard_fab2(sch_1):a_hsc_gate3_r") )
				( member ( signalRef "@baseboard_fab2_lib.baseboard_fab2(sch_1):a_hsc_low_en") )
				( member ( signalRef "@baseboard_fab2_lib.baseboard_fab2(sch_1):a_hsc_timer") )
				( member ( signalRef "@baseboard_fab2_lib.baseboard_fab2(sch_1):a_hsc_timer_r") )
				( member ( signalRef "@baseboard_fab2_lib.baseboard_fab2(sch_1):a_p12v_stby_adr_trigger") )
				( member ( signalRef "@baseboard_fab2_lib.baseboard_fab2(sch_1):a_p12v_stby_fp_trigger") )
				( member ( signalRef "@baseboard_fab2_lib.baseboard_fab2(sch_1):a_comp_ckmng") )
				( member ( signalRef "@baseboard_fab2_lib.baseboard_fab2(sch_1):a_pvnn_stby_pch_sensor") )
				( member ( signalRef "@baseboard_fab2_lib.baseboard_fab2(sch_1):a_p1v05_stby_pch_sensor") )
				( member ( signalRef "@baseboard_fab2_lib.baseboard_fab2(sch_1):a_p3v3_scaled") )
				( member ( signalRef "@baseboard_fab2_lib.baseboard_fab2(sch_1):a_p3v3_stby_scaled") )
				( member ( signalRef "@baseboard_fab2_lib.baseboard_fab2(sch_1):a_p5v_scaled") )
				( member ( signalRef "@baseboard_fab2_lib.baseboard_fab2(sch_1):a_p5v_stby_scaled") )
				( member ( signalRef "@baseboard_fab2_lib.baseboard_fab2(sch_1):a_p12v_stby_scaled") )
				( member ( signalRef "@baseboard_fab2_lib.baseboard_fab2(sch_1):a_hsc_vout") )
				( member ( signalRef "@baseboard_fab2_lib.baseboard_fab2(sch_1):m_a_vref") )
				( member ( signalRef "@baseboard_fab2_lib.baseboard_fab2(sch_1):m_b_cpu_vref") )
				( member ( signalRef "@baseboard_fab2_lib.baseboard_fab2(sch_1):m_b_vref") )
				( member ( signalRef "@baseboard_fab2_lib.baseboard_fab2(sch_1):m_c_cpu_vref") )
				( member ( signalRef "@baseboard_fab2_lib.baseboard_fab2(sch_1):m_c_vref") )
				( member ( signalRef "@baseboard_fab2_lib.baseboard_fab2(sch_1):p3v3_stby_bmc_adcvrefp") )
				( member ( signalRef "@baseboard_fab2_lib.baseboard_fab2(sch_1):m_d_cpu_vref") )
				( member ( signalRef "@baseboard_fab2_lib.baseboard_fab2(sch_1):m_d_vref") )
				( member ( signalRef "@baseboard_fab2_lib.baseboard_fab2(sch_1):m_e_cpu_vref") )
				( member ( signalRef "@baseboard_fab2_lib.baseboard_fab2(sch_1):m_e_vref") )
				( member ( signalRef "@baseboard_fab2_lib.baseboard_fab2(sch_1):p3v3_stby_bmc_adcvrefn") )
				( member ( signalRef "@baseboard_fab2_lib.baseboard_fab2(sch_1):m_g_cpu_vref") )
				( member ( signalRef "@baseboard_fab2_lib.baseboard_fab2(sch_1):m_g_vref") )
				( member ( signalRef "@baseboard_fab2_lib.baseboard_fab2(sch_1):m_h_cpu_vref") )
				( member ( signalRef "@baseboard_fab2_lib.baseboard_fab2(sch_1):m_h_vref") )
				( member ( signalRef "@baseboard_fab2_lib.baseboard_fab2(sch_1):m_j_cpu_vref") )
				( member ( signalRef "@baseboard_fab2_lib.baseboard_fab2(sch_1):m_j_vref") )
				( member ( signalRef "@baseboard_fab2_lib.baseboard_fab2(sch_1):p0v7_gtl2104_5_vref") )
				( member ( signalRef "@baseboard_fab2_lib.baseboard_fab2(sch_1):m_k_cpu_vref") )
				( member ( signalRef "@baseboard_fab2_lib.baseboard_fab2(sch_1):m_k_vref") )
				( member ( signalRef "@baseboard_fab2_lib.baseboard_fab2(sch_1):m_l_cpu_vref") )
				( member ( signalRef "@baseboard_fab2_lib.baseboard_fab2(sch_1):m_l_vref") )
				( member ( signalRef "@baseboard_fab2_lib.baseboard_fab2(sch_1):m_m_cpu_vref") )
				( member ( signalRef "@baseboard_fab2_lib.baseboard_fab2(sch_1):m_m_vref") )
				( member ( signalRef "@baseboard_fab2_lib.baseboard_fab2(sch_1):a_hsc_hsn") )
				( member ( signalRef "@baseboard_fab2_lib.baseboard_fab2(sch_1):a_hsc_hsp") )
				( member ( signalRef "@baseboard_fab2_lib.baseboard_fab2(sch_1):a_hsc_mon") )
				( member ( signalRef "@baseboard_fab2_lib.baseboard_fab2(sch_1):a_hsc_mop") )
				( member ( signalRef "@baseboard_fab2_lib.baseboard_fab2(sch_1):vr_pvccin_cpu0_avinsen") )
				( member ( signalRef "@baseboard_fab2_lib.baseboard_fab2(sch_1):vr_pvccin_cpu0_vdd") )
				( member ( signalRef "@baseboard_fab2_lib.baseboard_fab2(sch_1):vr_pvccin_cpu0_ph1_vcin") )
				( member ( signalRef "@baseboard_fab2_lib.baseboard_fab2(sch_1):vr_pvccin_cpu1_avinsen") )
				( member ( signalRef "@baseboard_fab2_lib.baseboard_fab2(sch_1):pu_vr_pvccin_cpu1_imon") )
				( member ( signalRef "@baseboard_fab2_lib.baseboard_fab2(sch_1):vr_pvccin_cpu1_ph1_vcin") )
				( member ( signalRef "@baseboard_fab2_lib.baseboard_fab2(sch_1):vr_fb_pvpp_klm") )
				( member ( signalRef "@baseboard_fab2_lib.baseboard_fab2(sch_1):vr_fb_pvpp_ghj") )
				( member ( signalRef "@baseboard_fab2_lib.baseboard_fab2(sch_1):vr_fb_pvpp_def") )
				( member ( signalRef "@baseboard_fab2_lib.baseboard_fab2(sch_1):vr_pvccin_cpu0_ph2_vcin") )
				( member ( signalRef "@baseboard_fab2_lib.baseboard_fab2(sch_1):vr_comp_rc_pvpp_klm") )
				( member ( signalRef "@baseboard_fab2_lib.baseboard_fab2(sch_1):vr_comp_rc_pvpp_ghj") )
				( member ( signalRef "@baseboard_fab2_lib.baseboard_fab2(sch_1):vr_pvccin_cpu0_ph3_vcin") )
				( member ( signalRef "@baseboard_fab2_lib.baseboard_fab2(sch_1):vr_comp_rc_pvpp_def") )
				( member ( signalRef "@baseboard_fab2_lib.baseboard_fab2(sch_1):vr_comp_pvpp_klm_3") )
				( member ( signalRef "@baseboard_fab2_lib.baseboard_fab2(sch_1):vr_pvccin_cpu0_ph4_vcin") )
				( member ( signalRef "@baseboard_fab2_lib.baseboard_fab2(sch_1):vr_comp_pvpp_klm") )
				( member ( signalRef "@baseboard_fab2_lib.baseboard_fab2(sch_1):vr_comp_pvpp_ghj_3") )
				( member ( signalRef "@baseboard_fab2_lib.baseboard_fab2(sch_1):vr_pvccin_cpu0_ph5_vcin") )
				( member ( signalRef "@baseboard_fab2_lib.baseboard_fab2(sch_1):vr_pvccin_cpu0_vd12") )
				( member ( signalRef "@baseboard_fab2_lib.baseboard_fab2(sch_1):vr_comp_pvpp_ghj") )
				( member ( signalRef "@baseboard_fab2_lib.baseboard_fab2(sch_1):vr_comp_pvpp_def_3") )
				( member ( signalRef "@baseboard_fab2_lib.baseboard_fab2(sch_1):vr_comp_pvpp_def") )
				( member ( signalRef "@baseboard_fab2_lib.baseboard_fab2(sch_1):vr_pvccin_cpu1_ph2_vcin") )
				( member ( signalRef "@baseboard_fab2_lib.baseboard_fab2(sch_1):vr_fb_pvpp_abc") )
				( member ( signalRef "@baseboard_fab2_lib.baseboard_fab2(sch_1):vr_comp_rc_pvpp_abc") )
				( member ( signalRef "@baseboard_fab2_lib.baseboard_fab2(sch_1):vr_pvccin_cpu1_ph3_vcin") )
				( member ( signalRef "@baseboard_fab2_lib.baseboard_fab2(sch_1):vr_comp_pvpp_abc_3") )
				( member ( signalRef "@baseboard_fab2_lib.baseboard_fab2(sch_1):vr_comp_pvpp_abc") )
				( member ( signalRef "@baseboard_fab2_lib.baseboard_fab2(sch_1):vr_pvccin_cpu1_ph4_vcin") )
				( member ( signalRef "@baseboard_fab2_lib.baseboard_fab2(sch_1):vr_pvccin_cpu1_ph5_vcin") )
				( member ( signalRef "@baseboard_fab2_lib.baseboard_fab2(sch_1):p0v7_gtl2104_vref_1") )
				( member ( signalRef "@baseboard_fab2_lib.baseboard_fab2(sch_1):p0v7_gtl2104_vref_0") )
				( member ( signalRef "@baseboard_fab2_lib.baseboard_fab2(sch_1):vr_pvccio_cpu0_avsp") )
				( member ( signalRef "@baseboard_fab2_lib.baseboard_fab2(sch_1):a_hsc_gate") )
				( member ( signalRef "@baseboard_fab2_lib.baseboard_fab2(sch_1):a_hsc_temp") )
				( member ( electricalNetRef "@crescent_city_bb_fab1_lib.crescent_city_bb_fab1(sch_1):a_cbot") )
				( member ( electricalNetRef "@crescent_city_bb_fab1_lib.crescent_city_bb_fab1(sch_1):a_hsc_csout") )
				( member ( electricalNetRef "@crescent_city_bb_fab1_lib.crescent_city_bb_fab1(sch_1):a_hsc_gate1_r") )
				( member ( electricalNetRef "@crescent_city_bb_fab1_lib.crescent_city_bb_fab1(sch_1):a_hsc_hsn") )
				( member ( electricalNetRef "@crescent_city_bb_fab1_lib.crescent_city_bb_fab1(sch_1):a_hsc_hsp") )
				( member ( electricalNetRef "@crescent_city_bb_fab1_lib.crescent_city_bb_fab1(sch_1):a_hsc_timer") )
				( member ( electricalNetRef "@crescent_city_bb_fab1_lib.crescent_city_bb_fab1(sch_1):m_a_cpu_vref") )
				( member ( electricalNetRef "@crescent_city_bb_fab1_lib.crescent_city_bb_fab1(sch_1):m_b_cpu_vref") )
				( member ( electricalNetRef "@crescent_city_bb_fab1_lib.crescent_city_bb_fab1(sch_1):m_c_cpu_vref") )
				( member ( electricalNetRef "@crescent_city_bb_fab1_lib.crescent_city_bb_fab1(sch_1):m_d_cpu_vref") )
				( member ( electricalNetRef "@crescent_city_bb_fab1_lib.crescent_city_bb_fab1(sch_1):m_e_cpu_vref") )
				( member ( electricalNetRef "@crescent_city_bb_fab1_lib.crescent_city_bb_fab1(sch_1):m_f_cpu_vref") )
				( member ( electricalNetRef "@crescent_city_bb_fab1_lib.crescent_city_bb_fab1(sch_1):m_g_cpu_vref") )
				( member ( electricalNetRef "@crescent_city_bb_fab1_lib.crescent_city_bb_fab1(sch_1):m_h_cpu_vref") )
				( member ( electricalNetRef "@crescent_city_bb_fab1_lib.crescent_city_bb_fab1(sch_1):m_j_cpu_vref") )
				( member ( electricalNetRef "@crescent_city_bb_fab1_lib.crescent_city_bb_fab1(sch_1):m_k_cpu_vref") )
				( member ( electricalNetRef "@crescent_city_bb_fab1_lib.crescent_city_bb_fab1(sch_1):m_l_cpu_vref") )
				( member ( electricalNetRef "@crescent_city_bb_fab1_lib.crescent_city_bb_fab1(sch_1):m_m_cpu_vref") )
				( member ( electricalNetRef "@crescent_city_bb_fab1_lib.crescent_city_bb_fab1(sch_1):vr_comp_pvpp_abc") )
				( member ( electricalNetRef "@crescent_city_bb_fab1_lib.crescent_city_bb_fab1(sch_1):vr_comp_pvpp_def") )
				( member ( electricalNetRef "@crescent_city_bb_fab1_lib.crescent_city_bb_fab1(sch_1):vr_comp_pvpp_ghj") )
				( member ( electricalNetRef "@crescent_city_bb_fab1_lib.crescent_city_bb_fab1(sch_1):vr_comp_pvpp_klm") )
				( objectStatus "PNCLS_10MIL" )
			)
			( netClass "@crescent_city_bb_fab1_lib.crescent_city_bb_fab1(sch_1):\SNCLS_SIDEBAND\"
				( memberType ( signal ) )
				( spacingCSetRef "@sapphirecity_baseboard_lib.sapphirecity_baseboard(sch_1):\8MIL_SL_10MIL_MS\" )
				( objectFlag fObjectSpacing )
				( objectFlag fObjectSameNetSpacing )
				( member ( signalRef "@baseboard_fab2_lib.baseboard_fab2(sch_1):h_cpu0_fivr_fault_g") )
				( member ( signalRef "@baseboard_fab2_lib.baseboard_fab2(sch_1):h_cpu0_memabc_memhot") )
				( member ( signalRef "@baseboard_fab2_lib.baseboard_fab2(sch_1):h_cpu0_memabc_memhot_g_n") )
				( member ( signalRef "@baseboard_fab2_lib.baseboard_fab2(sch_1):h_cpu0_memdef_memhot") )
				( member ( signalRef "@baseboard_fab2_lib.baseboard_fab2(sch_1):h_cpu0_memdef_memhot_g_n") )
				( member ( signalRef "@baseboard_fab2_lib.baseboard_fab2(sch_1):h_cpu0_prochot_g_n") )
				( member ( signalRef "@baseboard_fab2_lib.baseboard_fab2(sch_1):h_cpu0_thermtrip_g_n") )
				( member ( signalRef "@baseboard_fab2_lib.baseboard_fab2(sch_1):h_cpu1_fivr_fault_g") )
				( member ( signalRef "@baseboard_fab2_lib.baseboard_fab2(sch_1):h_cpu1_memghj_memhot") )
				( member ( signalRef "@baseboard_fab2_lib.baseboard_fab2(sch_1):h_cpu1_memghj_memhot_g_n") )
				( member ( signalRef "@baseboard_fab2_lib.baseboard_fab2(sch_1):h_cpu1_memklm_memhot") )
				( member ( signalRef "@baseboard_fab2_lib.baseboard_fab2(sch_1):h_cpu1_memklm_memhot_g_n") )
				( member ( signalRef "@baseboard_fab2_lib.baseboard_fab2(sch_1):h_cpu1_prochot_g_n") )
				( member ( signalRef "@baseboard_fab2_lib.baseboard_fab2(sch_1):h_cpu1_thermtrip_g_n") )
				( member ( signalRef "@baseboard_fab2_lib.baseboard_fab2(sch_1):h_cpu0_fast_wake_lvt3_n") )
				( member ( signalRef "@baseboard_fab2_lib.baseboard_fab2(sch_1):peci_pch") )
				( member ( signalRef "@baseboard_fab2_lib.baseboard_fab2(sch_1):h_cpu0_fast_wake") )
				( member ( signalRef "@baseboard_fab2_lib.baseboard_fab2(sch_1):h_cpu_err0_gtl_n") )
				( member ( signalRef "@baseboard_fab2_lib.baseboard_fab2(sch_1):h_cpu_err1_gtl_n") )
				( member ( signalRef "@baseboard_fab2_lib.baseboard_fab2(sch_1):h_cpu0_fast_wake_b_n") )
				( member ( signalRef "@baseboard_fab2_lib.baseboard_fab2(sch_1):h_cpu0_fast_wake_n") )
				( member ( signalRef "@baseboard_fab2_lib.baseboard_fab2(sch_1):h_cpu1_fast_wake_n") )
				( member ( signalRef "@baseboard_fab2_lib.baseboard_fab2(sch_1):peci_bmc") )
				( member ( signalRef "@baseboard_fab2_lib.baseboard_fab2(sch_1):peci_bmc_r") )
				( member ( signalRef "@baseboard_fab2_lib.baseboard_fab2(sch_1):peci_cpu_g") )
				( member ( signalRef "@baseboard_fab2_lib.baseboard_fab2(sch_1):h_cpu_err0_gtl_r_n") )
				( member ( signalRef "@baseboard_fab2_lib.baseboard_fab2(sch_1):h_cpu0_err0_g_n") )
				( member ( signalRef "@baseboard_fab2_lib.baseboard_fab2(sch_1):h_cpu1_err0_g_n") )
				( member ( signalRef "@baseboard_fab2_lib.baseboard_fab2(sch_1):h_cpu_caterr_g_n") )
				( member ( signalRef "@baseboard_fab2_lib.baseboard_fab2(sch_1):h_cpu_err1_gtl_r_n") )
				( member ( signalRef "@baseboard_fab2_lib.baseboard_fab2(sch_1):h_cpu_err2_gtl_n") )
				( member ( signalRef "@baseboard_fab2_lib.baseboard_fab2(sch_1):h_cpu_err2_g_r_n") )
				( member ( signalRef "@baseboard_fab2_lib.baseboard_fab2(sch_1):h_cpu_msmi_g_n") )
				( member ( signalRef "@baseboard_fab2_lib.baseboard_fab2(sch_1):h_cpu0_abc_memhot_lvt3_r_n") )
				( member ( signalRef "@baseboard_fab2_lib.baseboard_fab2(sch_1):h_cpu0_caterr_g_n") )
				( member ( signalRef "@baseboard_fab2_lib.baseboard_fab2(sch_1):h_cpu0_def_memhot_lvt3_r_n") )
				( member ( signalRef "@baseboard_fab2_lib.baseboard_fab2(sch_1):h_cpu0_err1_g_n") )
				( member ( signalRef "@baseboard_fab2_lib.baseboard_fab2(sch_1):h_cpu0_err2_g_n") )
				( member ( signalRef "@baseboard_fab2_lib.baseboard_fab2(sch_1):h_cpu0_memabc_memhot_lvt3_n") )
				( member ( signalRef "@baseboard_fab2_lib.baseboard_fab2(sch_1):h_cpu0_memdef_memhot_lvt3_n") )
				( member ( signalRef "@baseboard_fab2_lib.baseboard_fab2(sch_1):h_cpu0_msmi_g_n") )
				( member ( signalRef "@baseboard_fab2_lib.baseboard_fab2(sch_1):h_cpu1_caterr_g_n") )
				( member ( signalRef "@baseboard_fab2_lib.baseboard_fab2(sch_1):h_cpu1_err1_g_n") )
				( member ( signalRef "@baseboard_fab2_lib.baseboard_fab2(sch_1):h_cpu1_err2_g_n") )
				( member ( signalRef "@baseboard_fab2_lib.baseboard_fab2(sch_1):h_cpu1_ghj_memhot_lvt3_r_n") )
				( member ( signalRef "@baseboard_fab2_lib.baseboard_fab2(sch_1):h_cpu1_klm_memhot_lvt3_r_n") )
				( member ( signalRef "@baseboard_fab2_lib.baseboard_fab2(sch_1):h_cpu1_memghj_memhot_lvt3_n") )
				( member ( signalRef "@baseboard_fab2_lib.baseboard_fab2(sch_1):h_cpu1_memklm_memhot_lvt3_n") )
				( member ( signalRef "@baseboard_fab2_lib.baseboard_fab2(sch_1):h_cpu1_msmi_g_n") )
				( member ( signalRef "@baseboard_fab2_lib.baseboard_fab2(sch_1):h_pm_sync_gtl") )
				( member ( signalRef "@baseboard_fab2_lib.baseboard_fab2(sch_1):h_pm_sync_gtl_r1") )
				( member ( signalRef "@baseboard_fab2_lib.baseboard_fab2(sch_1):h_pm_sync_gtl_r2") )
				( member ( signalRef "@baseboard_fab2_lib.baseboard_fab2(sch_1):h_pm_sync1_gtl_r") )
				( member ( signalRef "@baseboard_fab2_lib.baseboard_fab2(sch_1):h_cpu0_memabc_memhot_g_pch_n") )
				( member ( signalRef "@baseboard_fab2_lib.baseboard_fab2(sch_1):h_cpu0_memdef_memhot_g_pch_n") )
				( member ( signalRef "@baseboard_fab2_lib.baseboard_fab2(sch_1):h_cpu1_memghj_memhot_g_pch_n") )
				( member ( signalRef "@baseboard_fab2_lib.baseboard_fab2(sch_1):h_cpu1_memklm_memhot_g_pch_n") )
				( member ( signalRef "@baseboard_fab2_lib.baseboard_fab2(sch_1):h_cpu0_memabc_memhot_g_r_n") )
				( member ( signalRef "@baseboard_fab2_lib.baseboard_fab2(sch_1):h_cpu0_memabc_memhot_lvt3_bmc_n") )
				( member ( signalRef "@baseboard_fab2_lib.baseboard_fab2(sch_1):h_cpu0_memdef_memhot_g_r_n") )
				( member ( signalRef "@baseboard_fab2_lib.baseboard_fab2(sch_1):h_cpu0_memdef_memhot_lvt3_bmc_n") )
				( member ( signalRef "@baseboard_fab2_lib.baseboard_fab2(sch_1):h_cpu0_prochot_g_r_n") )
				( member ( signalRef "@baseboard_fab2_lib.baseboard_fab2(sch_1):h_cpu1_memghj_memhot_g_r_n") )
				( member ( signalRef "@baseboard_fab2_lib.baseboard_fab2(sch_1):h_cpu1_memghj_memhot_lvt3_bmc_n") )
				( member ( signalRef "@baseboard_fab2_lib.baseboard_fab2(sch_1):h_cpu1_memklm_memhot_g_r_n") )
				( member ( signalRef "@baseboard_fab2_lib.baseboard_fab2(sch_1):h_cpu1_memklm_memhot_lvt3_bmc_n") )
				( member ( signalRef "@baseboard_fab2_lib.baseboard_fab2(sch_1):h_cpu1_prochot_g_r_n") )
				( member ( signalRef "@baseboard_fab2_lib.baseboard_fab2(sch_1):h_cpu_bmcinit_r") )
				( member ( signalRef "@baseboard_fab2_lib.baseboard_fab2(sch_1):h_cpu0_memabc_memhot_pch_n") )
				( member ( signalRef "@baseboard_fab2_lib.baseboard_fab2(sch_1):h_cpu0_memdef_memhot_pch_n") )
				( member ( signalRef "@baseboard_fab2_lib.baseboard_fab2(sch_1):h_cpu1_memghj_memhot_pch_n") )
				( member ( signalRef "@baseboard_fab2_lib.baseboard_fab2(sch_1):h_cpu1_memklm_memhot_pch_n") )
				( member ( electricalNetRef "@crescent_city_bb_fab1_lib.crescent_city_bb_fab1(sch_1):h_cpu_err2_g_r_n") )
				( member ( electricalNetRef "@crescent_city_bb_fab1_lib.crescent_city_bb_fab1(sch_1):h_cpu0_caterr_g_n") )
				( member ( electricalNetRef "@crescent_city_bb_fab1_lib.crescent_city_bb_fab1(sch_1):h_cpu0_fast_wake_b_n") )
				( member ( electricalNetRef "@crescent_city_bb_fab1_lib.crescent_city_bb_fab1(sch_1):h_cpu0_msmi_g_n") )
				( member ( electricalNetRef "@crescent_city_bb_fab1_lib.crescent_city_bb_fab1(sch_1):h_pm_sync_gtl_r1") )
				( member ( electricalNetRef "@crescent_city_bb_fab1_lib.crescent_city_bb_fab1(sch_1):peci_bmc") )
				( member ( electricalNetRef "@baseboard_fab2_lib.baseboard_fab2(sch_1):h_cpu0_memabc_memhot_g_pch_n") )
				( member ( electricalNetRef "@baseboard_fab2_lib.baseboard_fab2(sch_1):h_cpu0_memdef_memhot_g_pch_n") )
				( member ( electricalNetRef "@baseboard_fab2_lib.baseboard_fab2(sch_1):h_cpu1_memghj_memhot_g_pch_n") )
				( member ( electricalNetRef "@baseboard_fab2_lib.baseboard_fab2(sch_1):h_cpu1_memklm_memhot_g_pch_n") )
				( objectStatus "SNCLS_SIDEBAND" )
			)
			( netClass "@crescent_city_bb_fab1_lib.crescent_city_bb_fab1(sch_1):\THERMTRIP_N\"
				( memberType ( signal ) )
				( objectFlag fObjectSpacing )
				( objectFlag fObjectSameNetSpacing )
				( objectStatus "THERMTRIP_N" )
			)
			( netClass "@crescent_city_bb_fab1_lib.crescent_city_bb_fab1(sch_1):\FIVR_FAULT_N\"
				( memberType ( signal ) )
				( objectFlag fObjectSpacing )
				( objectFlag fObjectSameNetSpacing )
				( objectStatus "FIVR_FAULT_N" )
			)
			( netClass "@crescent_city_bb_fab1_lib.crescent_city_bb_fab1(sch_1):\ERROR_N\"
				( memberType ( signal ) )
				( objectFlag fObjectSpacing )
				( objectFlag fObjectSameNetSpacing )
				( objectStatus "ERROR_N" )
			)
			( netClass "@crescent_city_bb_fab1_lib.crescent_city_bb_fab1(sch_1):\PMSYNC\"
				( memberType ( signal ) )
				( objectFlag fObjectSpacing )
				( objectFlag fObjectSameNetSpacing )
				( objectStatus "PMSYNC" )
			)
			( netClass "@crescent_city_bb_fab1_lib.crescent_city_bb_fab1(sch_1):\FAST_WAKE_N\"
				( memberType ( signal ) )
				( objectFlag fObjectSpacing )
				( objectFlag fObjectSameNetSpacing )
				( objectStatus "FAST_WAKE_N" )
			)
			( netClass "@crescent_city_bb_fab1_lib.crescent_city_bb_fab1(sch_1):\CATERR_N\"
				( memberType ( signal ) )
				( objectFlag fObjectSpacing )
				( objectFlag fObjectSameNetSpacing )
				( objectStatus "CATERR_N" )
			)
			( netClass "@crescent_city_bb_fab1_lib.crescent_city_bb_fab1(sch_1):\USB3_TX\"
				( memberType ( signal ) )
				( spacingCSetRef "@crescent_city_bb_fab1_lib.crescent_city_bb_fab1(sch_1):\11H_US_&_7H_SL_VIA+3H_A\" )
				( sameNetSpacingCSetRef "@crescent_city_bb_fab1_lib.crescent_city_bb_fab1(sch_1):\7H_US_AND_5H_SL\" )
				( objectFlag fObjectSpacing )
				( objectFlag fObjectSameNetSpacing )
				( member ( diffPairRef "@crescent_city_bb_fab1_lib.crescent_city_bb_fab1(sch_1):\DP_USB3_P01_TX\") )
				( member ( signalRef "@baseboard_fab2_lib.baseboard_fab2(sch_1):usb3_p01_c_txn") )
				( member ( signalRef "@baseboard_fab2_lib.baseboard_fab2(sch_1):usb3_p01_c_txp") )
				( member ( signalRef "@baseboard_fab2_lib.baseboard_fab2(sch_1):usb3_p01_fb_txn") )
				( member ( signalRef "@baseboard_fab2_lib.baseboard_fab2(sch_1):usb3_p01_fb_txp") )
				( member ( signalRef "@baseboard_fab2_lib.baseboard_fab2(sch_1):usb3_p01_txn") )
				( member ( signalRef "@baseboard_fab2_lib.baseboard_fab2(sch_1):usb3_p01_txp") )
				( objectStatus "SNCLS_USB3_TX" )
			)
			( netClass "@crescent_city_bb_fab1_lib.crescent_city_bb_fab1(sch_1):\PNCLS_15-MIL\"
				( memberType ( signal ) )
				( physicalCSetRef "@sapphirecity_baseboard_lib.sapphirecity_baseboard(sch_1):\15_MILS-SE\" )
				( objectFlag fObjectPhysical )
				( member ( signalRef "@baseboard_fab2_lib.baseboard_fab2(sch_1):m_bmc_ddr3_mvref") )
				( member ( signalRef "@baseboard_fab2_lib.baseboard_fab2(sch_1):vr_pvpp_abc_snub") )
				( member ( signalRef "@baseboard_fab2_lib.baseboard_fab2(sch_1):vr_pvpp_def_snub") )
				( member ( signalRef "@baseboard_fab2_lib.baseboard_fab2(sch_1):vr_pvpp_ghj_snub") )
				( member ( signalRef "@baseboard_fab2_lib.baseboard_fab2(sch_1):vr_pvpp_klm_snub") )
				( member ( signalRef "@baseboard_fab2_lib.baseboard_fab2(sch_1):vr_p3v3_stby_snub") )
				( objectStatus "PNCLS_15MIL" )
			)
			( netClass "@crescent_city_bb_fab1_lib.crescent_city_bb_fab1(sch_1):\PNCL_100OHM_DIFF\"
				( memberType ( signal ) )
				( physicalCSetRef "@baseboard_fab2_lib.baseboard_fab2(sch_1):\100_OHM_DIFF_FAB2\" )
				( objectFlag fObjectPhysical )
				( member ( diffPairRef "@crescent_city_bb_fab1_lib.crescent_city_bb_fab1(sch_1):\DP_V_M_BMC_DDR3_DQS0\") )
				( member ( diffPairRef "@crescent_city_bb_fab1_lib.crescent_city_bb_fab1(sch_1):\DP_V_M_BMC_DDR3_DQS1\") )
				( member ( diffPairRef "@crescent_city_bb_fab1_lib.crescent_city_bb_fab1(sch_1):\M_BMC_DDR3_MCK_\") )
				( member ( diffPairRef "@crescent_city_bb_fab1_lib.crescent_city_bb_fab1(sch_1):\MDI_MNG_RX\") )
				( member ( diffPairRef "@crescent_city_bb_fab1_lib.crescent_city_bb_fab1(sch_1):\MDI_MNG_TX\") )
				( member ( diffPairRef "@crescent_city_bb_fab1_lib.crescent_city_bb_fab1(sch_1):\NIC_MDI_SPRV_RJ45_0_D\") )
				( member ( diffPairRef "@crescent_city_bb_fab1_lib.crescent_city_bb_fab1(sch_1):\NIC_MDI_SPRV_RJ45_1_D\") )
				( member ( diffPairRef "@crescent_city_bb_fab1_lib.crescent_city_bb_fab1(sch_1):\DP_105\") )
				( member ( diffPairRef "@crescent_city_bb_fab1_lib.crescent_city_bb_fab1(sch_1):\DP_106\") )
				( member ( diffPairRef "@baseboard_fab2_lib.baseboard_fab2(sch_1):\DP_KR_P0_OCP_RX\") )
				( member ( diffPairRef "@baseboard_fab2_lib.baseboard_fab2(sch_1):\DP_KR_P1_OCP_RX\") )
				( member ( diffPairRef "@baseboard_fab2_lib.baseboard_fab2(sch_1):\DP_KR_P2_OCP_RX\") )
				( member ( diffPairRef "@baseboard_fab2_lib.baseboard_fab2(sch_1):\DP_KR_P3_OCP_RX\") )
				( member ( diffPairRef "@baseboard_fab2_lib.baseboard_fab2(sch_1):\DP_KR_P0_OCP_TX\") )
				( member ( diffPairRef "@baseboard_fab2_lib.baseboard_fab2(sch_1):\DP_KR_P1_OCP_TX\") )
				( member ( diffPairRef "@baseboard_fab2_lib.baseboard_fab2(sch_1):\DP_KR_P2_OCP_TX\") )
				( member ( diffPairRef "@baseboard_fab2_lib.baseboard_fab2(sch_1):\DP_KR_P3_OCP_TX\") )
				( member ( signalRef "@baseboard_fab2_lib.baseboard_fab2(sch_1):nic_mdi_sprv_rj45_2_r_dn") )
				( member ( signalRef "@baseboard_fab2_lib.baseboard_fab2(sch_1):nic_mdi_sprv_rj45_2_r_dp") )
				( member ( signalRef "@baseboard_fab2_lib.baseboard_fab2(sch_1):nic_mdi_sprv_rj45_3_r_dn") )
				( member ( signalRef "@baseboard_fab2_lib.baseboard_fab2(sch_1):nic_mdi_sprv_rj45_3_r_dp") )
				( member ( signalRef "@baseboard_fab2_lib.baseboard_fab2(sch_1):nic_ser_n_mdi_3_dn") )
				( member ( signalRef "@baseboard_fab2_lib.baseboard_fab2(sch_1):nic_ser_p_mdi_3_dp") )
				( member ( signalRef "@baseboard_fab2_lib.baseboard_fab2(sch_1):nic_set_n_mdi_2_dn") )
				( member ( signalRef "@baseboard_fab2_lib.baseboard_fab2(sch_1):nic_set_p_mdi_2_dp") )
				( member ( signalRef "@baseboard_fab2_lib.baseboard_fab2(sch_1):l1_z100_ms") )
				( member ( signalRef "@baseboard_fab2_lib.baseboard_fab2(sch_1):l14_z100_ms") )
				( objectStatus "PNCLS_100-OHM_DIFF" )
			)
			( netClass "@crescent_city_bb_fab1_lib.crescent_city_bb_fab1(sch_1):\PNCLS_20MIL\"
				( memberType ( signal ) )
				( physicalCSetRef "@crescent_city_bb_fab1_lib.crescent_city_bb_fab1(sch_1):\20MIL_W\" )
				( attribute "DIFFP_PRIMARY_GAP" "0.00"
					( Origin gBackEnd )
				)
				( attribute "DIFFP_COUPLED_PLUS" "0.10"
					( Origin gBackEnd )
				)
				( attribute "DIFFP_COUPLED_MINUS" "0.10"
					( Origin gBackEnd )
				)
				( attribute "DIFFP_MIN_SPACE" "0.00"
					( Origin gBackEnd )
				)
				( attribute "MIN_LINE_WIDTH" "20.00"
					( Origin gBackEnd )
				)
				( attribute "MAX_LINE_WIDTH" "50.00"
					( Origin gBackEnd )
				)
				( attribute "DIFFP_NECK_GAP" "0.00"
					( Origin gBackEnd )
				)
				( attribute "MIN_NECK_WIDTH" "8.00"
					( Origin gBackEnd )
				)
				( attribute "MAXIMUM_NECK_LENGTH" "250.00"
					( Origin gBackEnd )
				)
				( objectFlag fObjectPhysical )
				( member ( signalRef "@baseboard_fab2_lib.baseboard_fab2(sch_1):vr_pvddq_klm_ph2_phase") )
				( member ( signalRef "@baseboard_fab2_lib.baseboard_fab2(sch_1):vr_pvnn_pch_ph1_boot") )
				( member ( signalRef "@baseboard_fab2_lib.baseboard_fab2(sch_1):vr_pvnn_pch_ph1_phase") )
				( member ( signalRef "@baseboard_fab2_lib.baseboard_fab2(sch_1):vr_pvpp_abc_boot") )
				( member ( signalRef "@baseboard_fab2_lib.baseboard_fab2(sch_1):vr_pvpp_abc_boot_r") )
				( member ( signalRef "@baseboard_fab2_lib.baseboard_fab2(sch_1):vr_pvpp_def_boot") )
				( member ( signalRef "@baseboard_fab2_lib.baseboard_fab2(sch_1):vr_pvpp_def_boot_r") )
				( member ( signalRef "@baseboard_fab2_lib.baseboard_fab2(sch_1):vr_pvpp_ghj_boot") )
				( member ( signalRef "@baseboard_fab2_lib.baseboard_fab2(sch_1):vr_pvpp_ghj_boot_r") )
				( member ( signalRef "@baseboard_fab2_lib.baseboard_fab2(sch_1):vr_pvpp_ghj_phase") )
				( member ( signalRef "@baseboard_fab2_lib.baseboard_fab2(sch_1):vr_pvpp_klm_boot") )
				( member ( signalRef "@baseboard_fab2_lib.baseboard_fab2(sch_1):vr_pvpp_klm_boot_r") )
				( member ( signalRef "@baseboard_fab2_lib.baseboard_fab2(sch_1):vr_pvpp_klm_phase") )
				( member ( signalRef "@baseboard_fab2_lib.baseboard_fab2(sch_1):vr_pvsa_cpu0_boot") )
				( member ( signalRef "@baseboard_fab2_lib.baseboard_fab2(sch_1):vr_pvsa_cpu0_phase") )
				( member ( signalRef "@baseboard_fab2_lib.baseboard_fab2(sch_1):vr_pvsa_cpu1_boot") )
				( member ( signalRef "@baseboard_fab2_lib.baseboard_fab2(sch_1):vr_pvpp_abc_phase") )
				( member ( signalRef "@baseboard_fab2_lib.baseboard_fab2(sch_1):vr_pvddq_klm_ph2_boot") )
				( member ( signalRef "@baseboard_fab2_lib.baseboard_fab2(sch_1):vr_pvddq_klm_ph1_phase") )
				( member ( signalRef "@baseboard_fab2_lib.baseboard_fab2(sch_1):vr_pvddq_klm_ph1_boot") )
				( member ( signalRef "@baseboard_fab2_lib.baseboard_fab2(sch_1):vr_pvddq_ghj_ph2_phase") )
				( member ( signalRef "@baseboard_fab2_lib.baseboard_fab2(sch_1):vr_pvddq_ghj_ph2_boot") )
				( member ( signalRef "@baseboard_fab2_lib.baseboard_fab2(sch_1):vr_pvddq_ghj_ph1_phase") )
				( member ( signalRef "@baseboard_fab2_lib.baseboard_fab2(sch_1):vr_pvddq_ghj_ph1_boot") )
				( member ( signalRef "@baseboard_fab2_lib.baseboard_fab2(sch_1):vr_pvddq_def_ph2_phase") )
				( member ( signalRef "@baseboard_fab2_lib.baseboard_fab2(sch_1):vr_pvddq_def_ph2_boot") )
				( member ( signalRef "@baseboard_fab2_lib.baseboard_fab2(sch_1):vr_pvddq_def_ph1_phase") )
				( member ( signalRef "@baseboard_fab2_lib.baseboard_fab2(sch_1):vr_pvddq_def_ph1_boot") )
				( member ( signalRef "@baseboard_fab2_lib.baseboard_fab2(sch_1):vr_pvccin_cpu1_ph5_phase") )
				( member ( signalRef "@baseboard_fab2_lib.baseboard_fab2(sch_1):vr_pvccin_cpu1_ph5_boot") )
				( member ( signalRef "@baseboard_fab2_lib.baseboard_fab2(sch_1):vr_pvccin_cpu1_ph4_phase") )
				( member ( signalRef "@baseboard_fab2_lib.baseboard_fab2(sch_1):vr_pvccin_cpu1_ph4_boot") )
				( member ( signalRef "@baseboard_fab2_lib.baseboard_fab2(sch_1):vr_pvccin_cpu1_ph3_phase") )
				( member ( signalRef "@baseboard_fab2_lib.baseboard_fab2(sch_1):vr_pvccin_cpu1_ph3_boot") )
				( member ( signalRef "@baseboard_fab2_lib.baseboard_fab2(sch_1):vr_pvccin_cpu1_ph2_phase") )
				( member ( signalRef "@baseboard_fab2_lib.baseboard_fab2(sch_1):vr_pvccin_cpu1_ph2_boot") )
				( member ( signalRef "@baseboard_fab2_lib.baseboard_fab2(sch_1):vr_pvccin_cpu1_ph1_phase") )
				( member ( signalRef "@baseboard_fab2_lib.baseboard_fab2(sch_1):vr_pvccin_cpu1_ph1_boot") )
				( member ( signalRef "@baseboard_fab2_lib.baseboard_fab2(sch_1):vr_pvccin_cpu1_phase5") )
				( member ( signalRef "@baseboard_fab2_lib.baseboard_fab2(sch_1):vr_pvsa_cpu1_phase") )
				( member ( signalRef "@baseboard_fab2_lib.baseboard_fab2(sch_1):vr_p1v05_pch_stby_ph1_boot") )
				( member ( signalRef "@baseboard_fab2_lib.baseboard_fab2(sch_1):vr_p1v05_pch_stby_ph1_phase") )
				( member ( signalRef "@baseboard_fab2_lib.baseboard_fab2(sch_1):vr_p3v3_stby_boot") )
				( member ( signalRef "@baseboard_fab2_lib.baseboard_fab2(sch_1):vr_p3v3_stby_boot_r") )
				( member ( signalRef "@baseboard_fab2_lib.baseboard_fab2(sch_1):vr_p3v3_stby_phase") )
				( member ( signalRef "@baseboard_fab2_lib.baseboard_fab2(sch_1):vr_p5v_stby_boot") )
				( member ( signalRef "@baseboard_fab2_lib.baseboard_fab2(sch_1):vr_p5v_stby_phase") )
				( member ( signalRef "@baseboard_fab2_lib.baseboard_fab2(sch_1):vr_p5v_stby_comp") )
				( member ( signalRef "@baseboard_fab2_lib.baseboard_fab2(sch_1):vr_p5v_stby_rc_comp") )
				( member ( signalRef "@baseboard_fab2_lib.baseboard_fab2(sch_1):vr_pvpp_def_phase") )
				( member ( signalRef "@baseboard_fab2_lib.baseboard_fab2(sch_1):vr_p3v3_stby_ugate") )
				( member ( signalRef "@baseboard_fab2_lib.baseboard_fab2(sch_1):vr_p3v3_stby_lgate") )
				( member ( signalRef "@baseboard_fab2_lib.baseboard_fab2(sch_1):vr_fet_sw_p5v_stby_pvin") )
				( member ( signalRef "@baseboard_fab2_lib.baseboard_fab2(sch_1):vr_fet_sw_p12v_pvccin_cpu0_r") )
				( member ( signalRef "@baseboard_fab2_lib.baseboard_fab2(sch_1):vr_fet_sw_p12v_pvccin_cpu1_r") )
				( member ( signalRef "@baseboard_fab2_lib.baseboard_fab2(sch_1):vr_fet_sw_p12v_stby_pvccin_cpu0") )
				( member ( signalRef "@baseboard_fab2_lib.baseboard_fab2(sch_1):vr_fet_sw_p12v_stby_pvccin_cpu1") )
				( member ( signalRef "@baseboard_fab2_lib.baseboard_fab2(sch_1):vr_fet_sw_p12v_stby_pvccio_cpu0") )
				( member ( signalRef "@baseboard_fab2_lib.baseboard_fab2(sch_1):vr_fet_sw_p12v_stby_pvddq_abc") )
				( member ( signalRef "@baseboard_fab2_lib.baseboard_fab2(sch_1):vr_fet_sw_p12v_stby_pvddq_def") )
				( member ( signalRef "@baseboard_fab2_lib.baseboard_fab2(sch_1):vr_fet_sw_p12v_stby_pvddq_ghj") )
				( member ( signalRef "@baseboard_fab2_lib.baseboard_fab2(sch_1):vr_fet_sw_p12v_stby_pvddq_klm") )
				( member ( signalRef "@baseboard_fab2_lib.baseboard_fab2(sch_1):vr_fet_sw_p12v_stby_pvpp_abc") )
				( member ( signalRef "@baseboard_fab2_lib.baseboard_fab2(sch_1):vr_fet_sw_p12v_stby_pvpp_def") )
				( member ( signalRef "@baseboard_fab2_lib.baseboard_fab2(sch_1):vr_fet_sw_p12v_stby_pvpp_ghj") )
				( member ( signalRef "@baseboard_fab2_lib.baseboard_fab2(sch_1):vr_fet_sw_p12v_stby_pvpp_klm") )
				( member ( signalRef "@baseboard_fab2_lib.baseboard_fab2(sch_1):vr_fet_sw_p12v_stby_p3v3_stby") )
				( member ( signalRef "@baseboard_fab2_lib.baseboard_fab2(sch_1):vr_pvnn_pch_ph1_phase_sw") )
				( member ( signalRef "@baseboard_fab2_lib.baseboard_fab2(sch_1):vr_p1v05_pch_stby_ph1_phase_sw") )
				( member ( signalRef "@baseboard_fab2_lib.baseboard_fab2(sch_1):vr_pvccio_cpu0_ph1_boot") )
				( member ( signalRef "@baseboard_fab2_lib.baseboard_fab2(sch_1):vr_pvccio_cpu0_ph1_phase") )
				( member ( signalRef "@baseboard_fab2_lib.baseboard_fab2(sch_1):vr_pvccio_cpu1_ph1_boot") )
				( member ( signalRef "@baseboard_fab2_lib.baseboard_fab2(sch_1):vr_pvccio_cpu1_ph1_phase") )
				( member ( signalRef "@baseboard_fab2_lib.baseboard_fab2(sch_1):vr_pvddq_abc_ph1_boot") )
				( member ( signalRef "@baseboard_fab2_lib.baseboard_fab2(sch_1):vr_pvddq_abc_ph1_phase") )
				( member ( signalRef "@baseboard_fab2_lib.baseboard_fab2(sch_1):vr_pvddq_abc_ph2_boot") )
				( member ( signalRef "@baseboard_fab2_lib.baseboard_fab2(sch_1):vr_pvddq_abc_ph2_phase") )
				( member ( signalRef "@baseboard_fab2_lib.baseboard_fab2(sch_1):vr_pvccin_cpu0_phase1") )
				( member ( signalRef "@baseboard_fab2_lib.baseboard_fab2(sch_1):vr_pvccin_cpu0_phase2") )
				( member ( signalRef "@baseboard_fab2_lib.baseboard_fab2(sch_1):vr_pvccin_cpu0_phase3") )
				( member ( signalRef "@baseboard_fab2_lib.baseboard_fab2(sch_1):vr_pvccin_cpu0_phase4") )
				( member ( signalRef "@baseboard_fab2_lib.baseboard_fab2(sch_1):vr_pvccin_cpu0_phase5") )
				( member ( signalRef "@baseboard_fab2_lib.baseboard_fab2(sch_1):vr_pvccin_cpu0_ph1_boot") )
				( member ( signalRef "@baseboard_fab2_lib.baseboard_fab2(sch_1):vr_pvccin_cpu0_ph1_phase") )
				( member ( signalRef "@baseboard_fab2_lib.baseboard_fab2(sch_1):vr_pvccin_cpu0_ph2_boot") )
				( member ( signalRef "@baseboard_fab2_lib.baseboard_fab2(sch_1):vr_pvccin_cpu0_ph2_phase") )
				( member ( signalRef "@baseboard_fab2_lib.baseboard_fab2(sch_1):vr_pvccin_cpu0_ph3_boot") )
				( member ( signalRef "@baseboard_fab2_lib.baseboard_fab2(sch_1):vr_pvccin_cpu0_ph3_phase") )
				( member ( signalRef "@baseboard_fab2_lib.baseboard_fab2(sch_1):vr_pvccin_cpu0_ph4_boot") )
				( member ( signalRef "@baseboard_fab2_lib.baseboard_fab2(sch_1):vr_pvccin_cpu0_ph4_phase") )
				( member ( signalRef "@baseboard_fab2_lib.baseboard_fab2(sch_1):vr_pvccin_cpu0_ph5_boot") )
				( member ( signalRef "@baseboard_fab2_lib.baseboard_fab2(sch_1):vr_pvccin_cpu0_ph5_phase") )
				( member ( signalRef "@baseboard_fab2_lib.baseboard_fab2(sch_1):vr_pvccin_cpu1_phase1") )
				( member ( signalRef "@baseboard_fab2_lib.baseboard_fab2(sch_1):vr_pvccin_cpu1_phase2") )
				( member ( signalRef "@baseboard_fab2_lib.baseboard_fab2(sch_1):vr_pvccin_cpu1_phase3") )
				( member ( signalRef "@baseboard_fab2_lib.baseboard_fab2(sch_1):vr_pvccin_cpu1_phase4") )
				( member ( electricalNetRef "@crescent_city_bb_fab1_lib.crescent_city_bb_fab1(sch_1):vr_p5v_stby_boot") )
				( member ( electricalNetRef "@crescent_city_bb_fab1_lib.crescent_city_bb_fab1(sch_1):vr_p5v_stby_rc_comp") )
				( member ( electricalNetRef "@crescent_city_bb_fab1_lib.crescent_city_bb_fab1(sch_1):vr_pvccio_cpu1_ph1_boot") )
				( member ( electricalNetRef "@crescent_city_bb_fab1_lib.crescent_city_bb_fab1(sch_1):vr_pvddq_abc_ph1_boot") )
				( member ( electricalNetRef "@crescent_city_bb_fab1_lib.crescent_city_bb_fab1(sch_1):vr_pvddq_abc_ph2_boot") )
				( member ( electricalNetRef "@crescent_city_bb_fab1_lib.crescent_city_bb_fab1(sch_1):vr_pvddq_def_ph1_boot") )
				( member ( electricalNetRef "@crescent_city_bb_fab1_lib.crescent_city_bb_fab1(sch_1):vr_pvddq_def_ph2_boot") )
				( member ( electricalNetRef "@crescent_city_bb_fab1_lib.crescent_city_bb_fab1(sch_1):vr_pvddq_ghj_ph1_boot") )
				( member ( electricalNetRef "@crescent_city_bb_fab1_lib.crescent_city_bb_fab1(sch_1):vr_pvddq_ghj_ph2_boot") )
				( member ( electricalNetRef "@crescent_city_bb_fab1_lib.crescent_city_bb_fab1(sch_1):vr_pvddq_klm_ph1_boot") )
				( member ( electricalNetRef "@crescent_city_bb_fab1_lib.crescent_city_bb_fab1(sch_1):vr_pvddq_klm_ph2_boot") )
				( member ( electricalNetRef "@crescent_city_bb_fab1_lib.crescent_city_bb_fab1(sch_1):vr_pvnn_pch_ph1_boot") )
				( member ( electricalNetRef "@crescent_city_bb_fab1_lib.crescent_city_bb_fab1(sch_1):vr_pvpp_abc_boot") )
				( member ( electricalNetRef "@crescent_city_bb_fab1_lib.crescent_city_bb_fab1(sch_1):vr_pvpp_def_boot") )
				( member ( electricalNetRef "@crescent_city_bb_fab1_lib.crescent_city_bb_fab1(sch_1):vr_pvpp_ghj_boot") )
				( member ( electricalNetRef "@crescent_city_bb_fab1_lib.crescent_city_bb_fab1(sch_1):vr_pvpp_klm_boot") )
				( member ( electricalNetRef "@crescent_city_bb_fab1_lib.crescent_city_bb_fab1(sch_1):vr_p1v05_pch_stby_ph1_boot") )
				( member ( electricalNetRef "@crescent_city_bb_fab1_lib.crescent_city_bb_fab1(sch_1):vr_p3v3_stby_boot") )
				( objectStatus "PNCLS_20MIL" )
			)
			( netClass "@crescent_city_bb_fab1_lib.crescent_city_bb_fab1(sch_1):\CLS_KTI_CPU1_CPU0_P1P1\"
				( memberType ( signal ) )
				( objectFlag fObjectElectrical )
				( member ( netGroupRef "@crescent_city_bb_fab1_lib.crescent_city_bb_fab1(sch_1):\NG_KTI_CPU1_CPU0_P1P1_0-1\") )
				( member ( netGroupRef "@crescent_city_bb_fab1_lib.crescent_city_bb_fab1(sch_1):\NG_KTI_CPU1_CPU0_P1P1_2-3\") )
				( member ( netGroupRef "@crescent_city_bb_fab1_lib.crescent_city_bb_fab1(sch_1):\NG_KTI_CPU1_CPU0_P1P1_4-5\") )
				( member ( netGroupRef "@crescent_city_bb_fab1_lib.crescent_city_bb_fab1(sch_1):\NG_KTI_CPU1_CPU0_P1P1_6-7\") )
				( member ( netGroupRef "@crescent_city_bb_fab1_lib.crescent_city_bb_fab1(sch_1):\NG_KTI_CPU1_CPU0_P1P1_8-9\") )
				( member ( netGroupRef "@crescent_city_bb_fab1_lib.crescent_city_bb_fab1(sch_1):\NG_KTI_CPU1_CPU0_P1P1_10-11\") )
				( member ( netGroupRef "@crescent_city_bb_fab1_lib.crescent_city_bb_fab1(sch_1):\NG_KTI_CPU1_CPU0_P1P1_12-13\") )
				( member ( netGroupRef "@crescent_city_bb_fab1_lib.crescent_city_bb_fab1(sch_1):\NG_KTI_CPU1_CPU0_P1P1_14-15\") )
				( member ( netGroupRef "@crescent_city_bb_fab1_lib.crescent_city_bb_fab1(sch_1):\NG_KTI_CPU1_CPU0_P1P1_16-17\") )
				( member ( netGroupRef "@crescent_city_bb_fab1_lib.crescent_city_bb_fab1(sch_1):\NG_KTI_CPU1_CPU0_P1P1_18-19\") )
				( objectStatus "CLS_KTI_CPU1_CPU0_P1P1" )
			)
			( netClass "@crescent_city_bb_fab1_lib.crescent_city_bb_fab1(sch_1):\CLS_KTI_CPU1_CPU0_P0P0\"
				( memberType ( signal ) )
				( objectFlag fObjectElectrical )
				( member ( netGroupRef "@crescent_city_bb_fab1_lib.crescent_city_bb_fab1(sch_1):\NG_KTI_CPU1_CPU0_P0P0_0-1\") )
				( member ( netGroupRef "@crescent_city_bb_fab1_lib.crescent_city_bb_fab1(sch_1):\NG_KTI_CPU1_CPU0_P0P0_2-3\") )
				( member ( netGroupRef "@crescent_city_bb_fab1_lib.crescent_city_bb_fab1(sch_1):\NG_KTI_CPU1_CPU0_P0P0_4-5\") )
				( member ( netGroupRef "@crescent_city_bb_fab1_lib.crescent_city_bb_fab1(sch_1):\NG_KTI_CPU1_CPU0_P0P0_6-7\") )
				( member ( netGroupRef "@crescent_city_bb_fab1_lib.crescent_city_bb_fab1(sch_1):\NG_KTI_CPU1_CPU0_P0P0_8-9\") )
				( member ( netGroupRef "@crescent_city_bb_fab1_lib.crescent_city_bb_fab1(sch_1):\NG_KTI_CPU1_CPU0_P0P0_10-11\") )
				( member ( netGroupRef "@crescent_city_bb_fab1_lib.crescent_city_bb_fab1(sch_1):\NG_KTI_CPU1_CPU0_P0P0_12-13\") )
				( member ( netGroupRef "@crescent_city_bb_fab1_lib.crescent_city_bb_fab1(sch_1):\NG_KTI_CPU1_CPU0_P0P0_14-15\") )
				( member ( netGroupRef "@crescent_city_bb_fab1_lib.crescent_city_bb_fab1(sch_1):\NG_KTI_CPU1_CPU0_P0P0_16-17\") )
				( member ( netGroupRef "@crescent_city_bb_fab1_lib.crescent_city_bb_fab1(sch_1):\NG_KTI_CPU1_CPU0_P0P0_18-19\") )
				( objectStatus "CLS_KTI_CPU1_CPU0_P0P0" )
			)
			( netClass "@crescent_city_bb_fab1_lib.crescent_city_bb_fab1(sch_1):\CLS_KTI_CPU0_CPU1_P1P1\"
				( memberType ( signal ) )
				( objectFlag fObjectElectrical )
				( member ( netGroupRef "@crescent_city_bb_fab1_lib.crescent_city_bb_fab1(sch_1):\NG_KTI_CPU0_CPU1_P1P1_0-1\") )
				( member ( netGroupRef "@crescent_city_bb_fab1_lib.crescent_city_bb_fab1(sch_1):\NG_KTI_CPU0_CPU1_P1P1_2-3\") )
				( member ( netGroupRef "@crescent_city_bb_fab1_lib.crescent_city_bb_fab1(sch_1):\NG_KTI_CPU0_CPU1_P1P1_4-5\") )
				( member ( netGroupRef "@crescent_city_bb_fab1_lib.crescent_city_bb_fab1(sch_1):\NG_KTI_CPU0_CPU1_P1P1_6-7\") )
				( member ( netGroupRef "@crescent_city_bb_fab1_lib.crescent_city_bb_fab1(sch_1):\NG_KTI_CPU0_CPU1_P1P1_8-9\") )
				( member ( netGroupRef "@crescent_city_bb_fab1_lib.crescent_city_bb_fab1(sch_1):\NG_KTI_CPU0_CPU1_P1P1_10-11\") )
				( member ( netGroupRef "@crescent_city_bb_fab1_lib.crescent_city_bb_fab1(sch_1):\NG_KTI_CPU0_CPU1_P1P1_12-13\") )
				( member ( netGroupRef "@crescent_city_bb_fab1_lib.crescent_city_bb_fab1(sch_1):\NG_KTI_CPU0_CPU1_P1P1_14-15\") )
				( member ( netGroupRef "@crescent_city_bb_fab1_lib.crescent_city_bb_fab1(sch_1):\NG_KTI_CPU0_CPU1_P1P1_16-17\") )
				( member ( netGroupRef "@crescent_city_bb_fab1_lib.crescent_city_bb_fab1(sch_1):\NG_KTI_CPU0_CPU1_P1P1_18-19\") )
				( objectStatus "CLS_KTI_CPU0_CPU1_P1P1" )
			)
			( netClass "@crescent_city_bb_fab1_lib.crescent_city_bb_fab1(sch_1):\CLS_KTI_CPU0_CPU1_P0P0\"
				( memberType ( signal ) )
				( objectFlag fObjectElectrical )
				( member ( netGroupRef "@crescent_city_bb_fab1_lib.crescent_city_bb_fab1(sch_1):\NG_KTI_CPU0_CPU1_P0P0_0-1\") )
				( member ( netGroupRef "@crescent_city_bb_fab1_lib.crescent_city_bb_fab1(sch_1):\NG_KTI_CPU0_CPU1_P0P0_2-3\") )
				( member ( netGroupRef "@crescent_city_bb_fab1_lib.crescent_city_bb_fab1(sch_1):\NG_KTI_CPU0_CPU1_P0P0_4-5\") )
				( member ( netGroupRef "@crescent_city_bb_fab1_lib.crescent_city_bb_fab1(sch_1):\NG_KTI_CPU0_CPU1_P0P0_6-7\") )
				( member ( netGroupRef "@crescent_city_bb_fab1_lib.crescent_city_bb_fab1(sch_1):\NG_KTI_CPU0_CPU1_P0P0_8-9\") )
				( member ( netGroupRef "@crescent_city_bb_fab1_lib.crescent_city_bb_fab1(sch_1):\NG_KTI_CPU0_CPU1_P0P0_10-11\") )
				( member ( netGroupRef "@crescent_city_bb_fab1_lib.crescent_city_bb_fab1(sch_1):\NG_KTI_CPU0_CPU1_P0P0_12-13\") )
				( member ( netGroupRef "@crescent_city_bb_fab1_lib.crescent_city_bb_fab1(sch_1):\NG_KTI_CPU0_CPU1_P0P0_14-15\") )
				( member ( netGroupRef "@crescent_city_bb_fab1_lib.crescent_city_bb_fab1(sch_1):\NG_KTI_CPU0_CPU1_P0P0_16-17\") )
				( member ( netGroupRef "@crescent_city_bb_fab1_lib.crescent_city_bb_fab1(sch_1):\NG_KTI_CPU0_CPU1_P0P0_18-19\") )
				( objectStatus "CLS_KTI_CPU0_CPU1_P0P0" )
			)
			( netClass "@crescent_city_bb_fab1_lib.crescent_city_bb_fab1(sch_1):\CLS_DDR_M_CAC-CLKS\"
				( memberType ( signal ) )
				( objectFlag fObjectElectrical )
				( member ( netGroupRef "@crescent_city_bb_fab1_lib.crescent_city_bb_fab1(sch_1):\NG_DDR_M_DLL_1\") )
				( member ( netGroupRef "@crescent_city_bb_fab1_lib.crescent_city_bb_fab1(sch_1):\NG_DDR_M_DLL_2\") )
				( member ( netGroupRef "@crescent_city_bb_fab1_lib.crescent_city_bb_fab1(sch_1):\NG_DDR_M_DLL_3\") )
				( member ( netGroupRef "@crescent_city_bb_fab1_lib.crescent_city_bb_fab1(sch_1):\NG_DDR_M_DLL_4\") )
				( member ( netGroupRef "@crescent_city_bb_fab1_lib.crescent_city_bb_fab1(sch_1):\NG_DDR_M_DLL_5\") )
				( member ( netGroupRef "@crescent_city_bb_fab1_lib.crescent_city_bb_fab1(sch_1):\NG_DDR_M_DLL_6\") )
				( member ( netGroupRef "@crescent_city_bb_fab1_lib.crescent_city_bb_fab1(sch_1):\NG_DDR_M_DLL_7\") )
				( member ( netGroupRef "@crescent_city_bb_fab1_lib.crescent_city_bb_fab1(sch_1):\NG_DDR_M_DLL_8\") )
				( member ( netGroupRef "@crescent_city_bb_fab1_lib.crescent_city_bb_fab1(sch_1):\NG_DDR_M_DLL_9\") )
				( member ( netGroupRef "@crescent_city_bb_fab1_lib.crescent_city_bb_fab1(sch_1):\NG_DDR_M_DLL_10\") )
				( member ( netGroupRef "@crescent_city_bb_fab1_lib.crescent_city_bb_fab1(sch_1):\NG_DDR_M_DLL_11\") )
				( member ( netGroupRef "@crescent_city_bb_fab1_lib.crescent_city_bb_fab1(sch_1):\NG_DDR_M_DLL_12\") )
				( member ( netGroupRef "@crescent_city_bb_fab1_lib.crescent_city_bb_fab1(sch_1):\NG_DDR_M_DLL_13\") )
				( member ( netGroupRef "@crescent_city_bb_fab1_lib.crescent_city_bb_fab1(sch_1):\NG_DDR_M_DLL_14\") )
				( member ( netGroupRef "@crescent_city_bb_fab1_lib.crescent_city_bb_fab1(sch_1):\NG_DDR_M_DLL_15\") )
				( member ( netGroupRef "@crescent_city_bb_fab1_lib.crescent_city_bb_fab1(sch_1):\NG_DDR_M_DLL_16\") )
				( member ( netGroupRef "@crescent_city_bb_fab1_lib.crescent_city_bb_fab1(sch_1):\NG_DDR_M_DLL_17\") )
				( member ( netGroupRef "@crescent_city_bb_fab1_lib.crescent_city_bb_fab1(sch_1):\NG_DDR_M_DLL_18\") )
				( member ( netGroupRef "@crescent_city_bb_fab1_lib.crescent_city_bb_fab1(sch_1):\NG_DDR_M_DLL_19\") )
				( member ( netGroupRef "@crescent_city_bb_fab1_lib.crescent_city_bb_fab1(sch_1):\NG_DDR_M_DLL_20\") )
				( member ( netGroupRef "@crescent_city_bb_fab1_lib.crescent_city_bb_fab1(sch_1):\NG_DDR_M_DLL_21\") )
				( member ( netGroupRef "@crescent_city_bb_fab1_lib.crescent_city_bb_fab1(sch_1):\NG_DDR_M_DLL_22\") )
				( member ( netGroupRef "@crescent_city_bb_fab1_lib.crescent_city_bb_fab1(sch_1):\NG_DDR_M_DLL_23\") )
				( member ( netGroupRef "@crescent_city_bb_fab1_lib.crescent_city_bb_fab1(sch_1):\NG_DDR_M_DLL_24\") )
				( member ( diffPairRef "@sapphirecity_baseboard_lib.sapphirecity_baseboard(sch_1):\M_M_CLK_D\(0)") )
				( member ( diffPairRef "@sapphirecity_baseboard_lib.sapphirecity_baseboard(sch_1):\M_D_CLK_D\(3)") )
				( objectStatus "CLS_DDR_M_CAC-CLKS" )
			)
			( netClass "@crescent_city_bb_fab1_lib.crescent_city_bb_fab1(sch_1):\CLS_DDR_L_CAC-CLKS\"
				( memberType ( signal ) )
				( objectFlag fObjectElectrical )
				( member ( netGroupRef "@crescent_city_bb_fab1_lib.crescent_city_bb_fab1(sch_1):\NG_DDR_L_DLL_1\") )
				( member ( netGroupRef "@crescent_city_bb_fab1_lib.crescent_city_bb_fab1(sch_1):\NG_DDR_L_DLL_2\") )
				( member ( netGroupRef "@crescent_city_bb_fab1_lib.crescent_city_bb_fab1(sch_1):\NG_DDR_L_DLL_3\") )
				( member ( netGroupRef "@crescent_city_bb_fab1_lib.crescent_city_bb_fab1(sch_1):\NG_DDR_L_DLL_4\") )
				( member ( netGroupRef "@crescent_city_bb_fab1_lib.crescent_city_bb_fab1(sch_1):\NG_DDR_L_DLL_5\") )
				( member ( netGroupRef "@crescent_city_bb_fab1_lib.crescent_city_bb_fab1(sch_1):\NG_DDR_L_DLL_6\") )
				( member ( netGroupRef "@crescent_city_bb_fab1_lib.crescent_city_bb_fab1(sch_1):\NG_DDR_L_DLL_7\") )
				( member ( netGroupRef "@crescent_city_bb_fab1_lib.crescent_city_bb_fab1(sch_1):\NG_DDR_L_DLL_8\") )
				( member ( netGroupRef "@crescent_city_bb_fab1_lib.crescent_city_bb_fab1(sch_1):\NG_DDR_L_DLL_9\") )
				( member ( netGroupRef "@crescent_city_bb_fab1_lib.crescent_city_bb_fab1(sch_1):\NG_DDR_L_DLL_10\") )
				( member ( netGroupRef "@crescent_city_bb_fab1_lib.crescent_city_bb_fab1(sch_1):\NG_DDR_L_DLL_11\") )
				( member ( netGroupRef "@crescent_city_bb_fab1_lib.crescent_city_bb_fab1(sch_1):\NG_DDR_L_DLL_12\") )
				( member ( netGroupRef "@crescent_city_bb_fab1_lib.crescent_city_bb_fab1(sch_1):\NG_DDR_L_DLL_13\") )
				( member ( netGroupRef "@crescent_city_bb_fab1_lib.crescent_city_bb_fab1(sch_1):\NG_DDR_L_DLL_14\") )
				( member ( netGroupRef "@crescent_city_bb_fab1_lib.crescent_city_bb_fab1(sch_1):\NG_DDR_L_DLL_15\") )
				( member ( netGroupRef "@crescent_city_bb_fab1_lib.crescent_city_bb_fab1(sch_1):\NG_DDR_L_DLL_16\") )
				( member ( netGroupRef "@crescent_city_bb_fab1_lib.crescent_city_bb_fab1(sch_1):\NG_DDR_L_DLL_17\") )
				( member ( netGroupRef "@crescent_city_bb_fab1_lib.crescent_city_bb_fab1(sch_1):\NG_DDR_L_DLL_18\") )
				( member ( netGroupRef "@crescent_city_bb_fab1_lib.crescent_city_bb_fab1(sch_1):\NG_DDR_L_DLL_19\") )
				( member ( netGroupRef "@crescent_city_bb_fab1_lib.crescent_city_bb_fab1(sch_1):\NG_DDR_L_DLL_20\") )
				( member ( netGroupRef "@crescent_city_bb_fab1_lib.crescent_city_bb_fab1(sch_1):\NG_DDR_L_DLL_21\") )
				( member ( netGroupRef "@crescent_city_bb_fab1_lib.crescent_city_bb_fab1(sch_1):\NG_DDR_L_DLL_22\") )
				( member ( netGroupRef "@crescent_city_bb_fab1_lib.crescent_city_bb_fab1(sch_1):\NG_DDR_L_DLL_23\") )
				( member ( netGroupRef "@crescent_city_bb_fab1_lib.crescent_city_bb_fab1(sch_1):\NG_DDR_L_DLL_24\") )
				( member ( diffPairRef "@sapphirecity_baseboard_lib.sapphirecity_baseboard(sch_1):\M_L_CLK_D\(0)") )
				( member ( diffPairRef "@sapphirecity_baseboard_lib.sapphirecity_baseboard(sch_1):\M_E_CLK_D\(3)") )
				( objectStatus "CLS_DDR_L_CAC-CLKS" )
			)
			( netClass "@crescent_city_bb_fab1_lib.crescent_city_bb_fab1(sch_1):\CLS_DDR_K_CAC-CLKS\"
				( memberType ( signal ) )
				( objectFlag fObjectElectrical )
				( member ( netGroupRef "@crescent_city_bb_fab1_lib.crescent_city_bb_fab1(sch_1):\NG_DDR_K_DLL_1\") )
				( member ( netGroupRef "@crescent_city_bb_fab1_lib.crescent_city_bb_fab1(sch_1):\NG_DDR_K_DLL_2\") )
				( member ( netGroupRef "@crescent_city_bb_fab1_lib.crescent_city_bb_fab1(sch_1):\NG_DDR_K_DLL_3\") )
				( member ( netGroupRef "@crescent_city_bb_fab1_lib.crescent_city_bb_fab1(sch_1):\NG_DDR_K_DLL_4\") )
				( member ( netGroupRef "@crescent_city_bb_fab1_lib.crescent_city_bb_fab1(sch_1):\NG_DDR_K_DLL_5\") )
				( member ( netGroupRef "@crescent_city_bb_fab1_lib.crescent_city_bb_fab1(sch_1):\NG_DDR_K_DLL_6\") )
				( member ( netGroupRef "@crescent_city_bb_fab1_lib.crescent_city_bb_fab1(sch_1):\NG_DDR_K_DLL_7\") )
				( member ( netGroupRef "@crescent_city_bb_fab1_lib.crescent_city_bb_fab1(sch_1):\NG_DDR_K_DLL_8\") )
				( member ( netGroupRef "@crescent_city_bb_fab1_lib.crescent_city_bb_fab1(sch_1):\NG_DDR_K_DLL_9\") )
				( member ( netGroupRef "@crescent_city_bb_fab1_lib.crescent_city_bb_fab1(sch_1):\NG_DDR_K_DLL_10\") )
				( member ( netGroupRef "@crescent_city_bb_fab1_lib.crescent_city_bb_fab1(sch_1):\NG_DDR_K_DLL_11\") )
				( member ( netGroupRef "@crescent_city_bb_fab1_lib.crescent_city_bb_fab1(sch_1):\NG_DDR_K_DLL_12\") )
				( member ( netGroupRef "@crescent_city_bb_fab1_lib.crescent_city_bb_fab1(sch_1):\NG_DDR_K_DLL_13\") )
				( member ( netGroupRef "@crescent_city_bb_fab1_lib.crescent_city_bb_fab1(sch_1):\NG_DDR_K_DLL_14\") )
				( member ( netGroupRef "@crescent_city_bb_fab1_lib.crescent_city_bb_fab1(sch_1):\NG_DDR_K_DLL_15\") )
				( member ( netGroupRef "@crescent_city_bb_fab1_lib.crescent_city_bb_fab1(sch_1):\NG_DDR_K_DLL_16\") )
				( member ( netGroupRef "@crescent_city_bb_fab1_lib.crescent_city_bb_fab1(sch_1):\NG_DDR_K_DLL_17\") )
				( member ( netGroupRef "@crescent_city_bb_fab1_lib.crescent_city_bb_fab1(sch_1):\NG_DDR_K_DLL_18\") )
				( member ( netGroupRef "@crescent_city_bb_fab1_lib.crescent_city_bb_fab1(sch_1):\NG_DDR_K_DLL_19\") )
				( member ( netGroupRef "@crescent_city_bb_fab1_lib.crescent_city_bb_fab1(sch_1):\NG_DDR_K_DLL_20\") )
				( member ( netGroupRef "@crescent_city_bb_fab1_lib.crescent_city_bb_fab1(sch_1):\NG_DDR_K_DLL_21\") )
				( member ( netGroupRef "@crescent_city_bb_fab1_lib.crescent_city_bb_fab1(sch_1):\NG_DDR_K_DLL_22\") )
				( member ( netGroupRef "@crescent_city_bb_fab1_lib.crescent_city_bb_fab1(sch_1):\NG_DDR_K_DLL_23\") )
				( member ( netGroupRef "@crescent_city_bb_fab1_lib.crescent_city_bb_fab1(sch_1):\NG_DDR_K_DLL_24\") )
				( member ( diffPairRef "@sapphirecity_baseboard_lib.sapphirecity_baseboard(sch_1):\M_K_CLK_D\(0)") )
				( member ( diffPairRef "@crescent_city_bb_fab1_lib.crescent_city_bb_fab1(sch_1):\DP_M_K_CLK\(1)") )
				( objectStatus "CLS_DDR_K_CAC-CLKS" )
			)
			( netClass "@crescent_city_bb_fab1_lib.crescent_city_bb_fab1(sch_1):\CLS_DDR_J_CAC-CLKS\"
				( memberType ( signal ) )
				( objectFlag fObjectElectrical )
				( member ( netGroupRef "@crescent_city_bb_fab1_lib.crescent_city_bb_fab1(sch_1):\NG_DDR_J_DLL_1\") )
				( member ( netGroupRef "@crescent_city_bb_fab1_lib.crescent_city_bb_fab1(sch_1):\NG_DDR_J_DLL_2\") )
				( member ( netGroupRef "@crescent_city_bb_fab1_lib.crescent_city_bb_fab1(sch_1):\NG_DDR_J_DLL_3\") )
				( member ( netGroupRef "@crescent_city_bb_fab1_lib.crescent_city_bb_fab1(sch_1):\NG_DDR_J_DLL_4\") )
				( member ( netGroupRef "@crescent_city_bb_fab1_lib.crescent_city_bb_fab1(sch_1):\NG_DDR_J_DLL_5\") )
				( member ( netGroupRef "@crescent_city_bb_fab1_lib.crescent_city_bb_fab1(sch_1):\NG_DDR_J_DLL_6\") )
				( member ( netGroupRef "@crescent_city_bb_fab1_lib.crescent_city_bb_fab1(sch_1):\NG_DDR_J_DLL_7\") )
				( member ( netGroupRef "@crescent_city_bb_fab1_lib.crescent_city_bb_fab1(sch_1):\NG_DDR_J_DLL_8\") )
				( member ( netGroupRef "@crescent_city_bb_fab1_lib.crescent_city_bb_fab1(sch_1):\NG_DDR_J_DLL_9\") )
				( member ( netGroupRef "@crescent_city_bb_fab1_lib.crescent_city_bb_fab1(sch_1):\NG_DDR_J_DLL_10\") )
				( member ( netGroupRef "@crescent_city_bb_fab1_lib.crescent_city_bb_fab1(sch_1):\NG_DDR_J_DLL_11\") )
				( member ( netGroupRef "@crescent_city_bb_fab1_lib.crescent_city_bb_fab1(sch_1):\NG_DDR_J_DLL_12\") )
				( member ( netGroupRef "@crescent_city_bb_fab1_lib.crescent_city_bb_fab1(sch_1):\NG_DDR_J_DLL_13\") )
				( member ( netGroupRef "@crescent_city_bb_fab1_lib.crescent_city_bb_fab1(sch_1):\NG_DDR_J_DLL_14\") )
				( member ( netGroupRef "@crescent_city_bb_fab1_lib.crescent_city_bb_fab1(sch_1):\NG_DDR_J_DLL_15\") )
				( member ( netGroupRef "@crescent_city_bb_fab1_lib.crescent_city_bb_fab1(sch_1):\NG_DDR_J_DLL_16\") )
				( member ( netGroupRef "@crescent_city_bb_fab1_lib.crescent_city_bb_fab1(sch_1):\NG_DDR_J_DLL_17\") )
				( member ( netGroupRef "@crescent_city_bb_fab1_lib.crescent_city_bb_fab1(sch_1):\NG_DDR_J_DLL_18\") )
				( member ( netGroupRef "@crescent_city_bb_fab1_lib.crescent_city_bb_fab1(sch_1):\NG_DDR_J_DLL_19\") )
				( member ( netGroupRef "@crescent_city_bb_fab1_lib.crescent_city_bb_fab1(sch_1):\NG_DDR_J_DLL_20\") )
				( member ( netGroupRef "@crescent_city_bb_fab1_lib.crescent_city_bb_fab1(sch_1):\NG_DDR_J_DLL_21\") )
				( member ( netGroupRef "@crescent_city_bb_fab1_lib.crescent_city_bb_fab1(sch_1):\NG_DDR_J_DLL_22\") )
				( member ( netGroupRef "@crescent_city_bb_fab1_lib.crescent_city_bb_fab1(sch_1):\NG_DDR_J_DLL_23\") )
				( member ( netGroupRef "@crescent_city_bb_fab1_lib.crescent_city_bb_fab1(sch_1):\NG_DDR_J_DLL_24\") )
				( member ( diffPairRef "@sapphirecity_baseboard_lib.sapphirecity_baseboard(sch_1):\M_J_CLK_D\(0)") )
				( member ( diffPairRef "@crescent_city_bb_fab1_lib.crescent_city_bb_fab1(sch_1):\DP_M_J_CLK\(1)") )
				( objectStatus "CLS_DDR_J_CAC-CLKS" )
			)
			( netClass "@crescent_city_bb_fab1_lib.crescent_city_bb_fab1(sch_1):\CLS_DDR_H_CAC-CLKS\"
				( memberType ( signal ) )
				( objectFlag fObjectElectrical )
				( member ( netGroupRef "@crescent_city_bb_fab1_lib.crescent_city_bb_fab1(sch_1):\NG_DDR_H_DLL_1\") )
				( member ( netGroupRef "@crescent_city_bb_fab1_lib.crescent_city_bb_fab1(sch_1):\NG_DDR_H_DLL_2\") )
				( member ( netGroupRef "@crescent_city_bb_fab1_lib.crescent_city_bb_fab1(sch_1):\NG_DDR_H_DLL_3\") )
				( member ( netGroupRef "@crescent_city_bb_fab1_lib.crescent_city_bb_fab1(sch_1):\NG_DDR_H_DLL_4\") )
				( member ( netGroupRef "@crescent_city_bb_fab1_lib.crescent_city_bb_fab1(sch_1):\NG_DDR_H_DLL_5\") )
				( member ( netGroupRef "@crescent_city_bb_fab1_lib.crescent_city_bb_fab1(sch_1):\NG_DDR_H_DLL_6\") )
				( member ( netGroupRef "@crescent_city_bb_fab1_lib.crescent_city_bb_fab1(sch_1):\NG_DDR_H_DLL_7\") )
				( member ( netGroupRef "@crescent_city_bb_fab1_lib.crescent_city_bb_fab1(sch_1):\NG_DDR_H_DLL_8\") )
				( member ( netGroupRef "@crescent_city_bb_fab1_lib.crescent_city_bb_fab1(sch_1):\NG_DDR_H_DLL_9\") )
				( member ( netGroupRef "@crescent_city_bb_fab1_lib.crescent_city_bb_fab1(sch_1):\NG_DDR_H_DLL_10\") )
				( member ( netGroupRef "@crescent_city_bb_fab1_lib.crescent_city_bb_fab1(sch_1):\NG_DDR_H_DLL_11\") )
				( member ( netGroupRef "@crescent_city_bb_fab1_lib.crescent_city_bb_fab1(sch_1):\NG_DDR_H_DLL_12\") )
				( member ( netGroupRef "@crescent_city_bb_fab1_lib.crescent_city_bb_fab1(sch_1):\NG_DDR_H_DLL_13\") )
				( member ( netGroupRef "@crescent_city_bb_fab1_lib.crescent_city_bb_fab1(sch_1):\NG_DDR_H_DLL_14\") )
				( member ( netGroupRef "@crescent_city_bb_fab1_lib.crescent_city_bb_fab1(sch_1):\NG_DDR_H_DLL_15\") )
				( member ( netGroupRef "@crescent_city_bb_fab1_lib.crescent_city_bb_fab1(sch_1):\NG_DDR_H_DLL_16\") )
				( member ( netGroupRef "@crescent_city_bb_fab1_lib.crescent_city_bb_fab1(sch_1):\NG_DDR_H_DLL_17\") )
				( member ( netGroupRef "@crescent_city_bb_fab1_lib.crescent_city_bb_fab1(sch_1):\NG_DDR_H_DLL_18\") )
				( member ( netGroupRef "@crescent_city_bb_fab1_lib.crescent_city_bb_fab1(sch_1):\NG_DDR_H_DLL_19\") )
				( member ( netGroupRef "@crescent_city_bb_fab1_lib.crescent_city_bb_fab1(sch_1):\NG_DDR_H_DLL_20\") )
				( member ( netGroupRef "@crescent_city_bb_fab1_lib.crescent_city_bb_fab1(sch_1):\NG_DDR_H_DLL_21\") )
				( member ( netGroupRef "@crescent_city_bb_fab1_lib.crescent_city_bb_fab1(sch_1):\NG_DDR_H_DLL_22\") )
				( member ( netGroupRef "@crescent_city_bb_fab1_lib.crescent_city_bb_fab1(sch_1):\NG_DDR_H_DLL_23\") )
				( member ( netGroupRef "@crescent_city_bb_fab1_lib.crescent_city_bb_fab1(sch_1):\NG_DDR_H_DLL_24\") )
				( member ( diffPairRef "@sapphirecity_baseboard_lib.sapphirecity_baseboard(sch_1):\M_H_CLK_D\(0)") )
				( member ( diffPairRef "@sapphirecity_baseboard_lib.sapphirecity_baseboard(sch_1):\M_B_CLK_D\(1)") )
				( objectStatus "CLS_DDR_H_CAC-CLKS" )
			)
			( netClass "@crescent_city_bb_fab1_lib.crescent_city_bb_fab1(sch_1):\CLS_DDR_G_CAC-CLKS\"
				( memberType ( signal ) )
				( objectFlag fObjectElectrical )
				( member ( netGroupRef "@crescent_city_bb_fab1_lib.crescent_city_bb_fab1(sch_1):\NG_DDR_G_DLL_1\") )
				( member ( netGroupRef "@crescent_city_bb_fab1_lib.crescent_city_bb_fab1(sch_1):\NG_DDR_G_DLL_2\") )
				( member ( netGroupRef "@crescent_city_bb_fab1_lib.crescent_city_bb_fab1(sch_1):\NG_DDR_G_DLL_3\") )
				( member ( netGroupRef "@crescent_city_bb_fab1_lib.crescent_city_bb_fab1(sch_1):\NG_DDR_G_DLL_4\") )
				( member ( netGroupRef "@crescent_city_bb_fab1_lib.crescent_city_bb_fab1(sch_1):\NG_DDR_G_DLL_5\") )
				( member ( netGroupRef "@crescent_city_bb_fab1_lib.crescent_city_bb_fab1(sch_1):\NG_DDR_G_DLL_6\") )
				( member ( netGroupRef "@crescent_city_bb_fab1_lib.crescent_city_bb_fab1(sch_1):\NG_DDR_G_DLL_7\") )
				( member ( netGroupRef "@crescent_city_bb_fab1_lib.crescent_city_bb_fab1(sch_1):\NG_DDR_G_DLL_8\") )
				( member ( netGroupRef "@crescent_city_bb_fab1_lib.crescent_city_bb_fab1(sch_1):\NG_DDR_G_DLL_9\") )
				( member ( netGroupRef "@crescent_city_bb_fab1_lib.crescent_city_bb_fab1(sch_1):\NG_DDR_G_DLL_10\") )
				( member ( netGroupRef "@crescent_city_bb_fab1_lib.crescent_city_bb_fab1(sch_1):\NG_DDR_G_DLL_11\") )
				( member ( netGroupRef "@crescent_city_bb_fab1_lib.crescent_city_bb_fab1(sch_1):\NG_DDR_G_DLL_12\") )
				( member ( netGroupRef "@crescent_city_bb_fab1_lib.crescent_city_bb_fab1(sch_1):\NG_DDR_G_DLL_13\") )
				( member ( netGroupRef "@crescent_city_bb_fab1_lib.crescent_city_bb_fab1(sch_1):\NG_DDR_G_DLL_14\") )
				( member ( netGroupRef "@crescent_city_bb_fab1_lib.crescent_city_bb_fab1(sch_1):\NG_DDR_G_DLL_15\") )
				( member ( netGroupRef "@crescent_city_bb_fab1_lib.crescent_city_bb_fab1(sch_1):\NG_DDR_G_DLL_16\") )
				( member ( netGroupRef "@crescent_city_bb_fab1_lib.crescent_city_bb_fab1(sch_1):\NG_DDR_G_DLL_17\") )
				( member ( netGroupRef "@crescent_city_bb_fab1_lib.crescent_city_bb_fab1(sch_1):\NG_DDR_G_DLL_18\") )
				( member ( netGroupRef "@crescent_city_bb_fab1_lib.crescent_city_bb_fab1(sch_1):\NG_DDR_G_DLL_19\") )
				( member ( netGroupRef "@crescent_city_bb_fab1_lib.crescent_city_bb_fab1(sch_1):\NG_DDR_G_DLL_20\") )
				( member ( netGroupRef "@crescent_city_bb_fab1_lib.crescent_city_bb_fab1(sch_1):\NG_DDR_G_DLL_21\") )
				( member ( netGroupRef "@crescent_city_bb_fab1_lib.crescent_city_bb_fab1(sch_1):\NG_DDR_G_DLL_22\") )
				( member ( netGroupRef "@crescent_city_bb_fab1_lib.crescent_city_bb_fab1(sch_1):\NG_DDR_G_DLL_23\") )
				( member ( netGroupRef "@crescent_city_bb_fab1_lib.crescent_city_bb_fab1(sch_1):\NG_DDR_G_DLL_24\") )
				( member ( diffPairRef "@sapphirecity_baseboard_lib.sapphirecity_baseboard(sch_1):\M_G_CLK_D\(0)") )
				( member ( diffPairRef "@crescent_city_bb_fab1_lib.crescent_city_bb_fab1(sch_1):\DP_M_G_CLK\(1)") )
				( objectStatus "CLS_DDR_G_CAC-CLKS" )
			)
			( netClass "@crescent_city_bb_fab1_lib.crescent_city_bb_fab1(sch_1):\CLS_DDR_F_CAC-CLKS\"
				( memberType ( signal ) )
				( objectFlag fObjectElectrical )
				( member ( netGroupRef "@crescent_city_bb_fab1_lib.crescent_city_bb_fab1(sch_1):\NG_DDR_F_DLL_1\") )
				( member ( netGroupRef "@crescent_city_bb_fab1_lib.crescent_city_bb_fab1(sch_1):\NG_DDR_F_DLL_2\") )
				( member ( netGroupRef "@crescent_city_bb_fab1_lib.crescent_city_bb_fab1(sch_1):\NG_DDR_F_DLL_3\") )
				( member ( netGroupRef "@crescent_city_bb_fab1_lib.crescent_city_bb_fab1(sch_1):\NG_DDR_F_DLL_4\") )
				( member ( netGroupRef "@crescent_city_bb_fab1_lib.crescent_city_bb_fab1(sch_1):\NG_DDR_F_DLL_5\") )
				( member ( netGroupRef "@crescent_city_bb_fab1_lib.crescent_city_bb_fab1(sch_1):\NG_DDR_F_DLL_6\") )
				( member ( netGroupRef "@crescent_city_bb_fab1_lib.crescent_city_bb_fab1(sch_1):\NG_DDR_F_DLL_7\") )
				( member ( netGroupRef "@crescent_city_bb_fab1_lib.crescent_city_bb_fab1(sch_1):\NG_DDR_F_DLL_8\") )
				( member ( netGroupRef "@crescent_city_bb_fab1_lib.crescent_city_bb_fab1(sch_1):\NG_DDR_F_DLL_9\") )
				( member ( netGroupRef "@crescent_city_bb_fab1_lib.crescent_city_bb_fab1(sch_1):\NG_DDR_F_DLL_10\") )
				( member ( netGroupRef "@crescent_city_bb_fab1_lib.crescent_city_bb_fab1(sch_1):\NG_DDR_F_DLL_11\") )
				( member ( netGroupRef "@crescent_city_bb_fab1_lib.crescent_city_bb_fab1(sch_1):\NG_DDR_F_DLL_12\") )
				( member ( netGroupRef "@crescent_city_bb_fab1_lib.crescent_city_bb_fab1(sch_1):\NG_DDR_F_DLL_13\") )
				( member ( netGroupRef "@crescent_city_bb_fab1_lib.crescent_city_bb_fab1(sch_1):\NG_DDR_F_DLL_14\") )
				( member ( netGroupRef "@crescent_city_bb_fab1_lib.crescent_city_bb_fab1(sch_1):\NG_DDR_F_DLL_15\") )
				( member ( netGroupRef "@crescent_city_bb_fab1_lib.crescent_city_bb_fab1(sch_1):\NG_DDR_F_DLL_16\") )
				( member ( netGroupRef "@crescent_city_bb_fab1_lib.crescent_city_bb_fab1(sch_1):\NG_DDR_F_DLL_17\") )
				( member ( netGroupRef "@crescent_city_bb_fab1_lib.crescent_city_bb_fab1(sch_1):\NG_DDR_F_DLL_18\") )
				( member ( netGroupRef "@crescent_city_bb_fab1_lib.crescent_city_bb_fab1(sch_1):\NG_DDR_F_DLL_19\") )
				( member ( netGroupRef "@crescent_city_bb_fab1_lib.crescent_city_bb_fab1(sch_1):\NG_DDR_F_DLL_20\") )
				( member ( netGroupRef "@crescent_city_bb_fab1_lib.crescent_city_bb_fab1(sch_1):\NG_DDR_F_DLL_21\") )
				( member ( netGroupRef "@crescent_city_bb_fab1_lib.crescent_city_bb_fab1(sch_1):\NG_DDR_F_DLL_22\") )
				( member ( netGroupRef "@crescent_city_bb_fab1_lib.crescent_city_bb_fab1(sch_1):\NG_DDR_F_DLL_23\") )
				( member ( netGroupRef "@crescent_city_bb_fab1_lib.crescent_city_bb_fab1(sch_1):\NG_DDR_F_DLL_24\") )
				( member ( diffPairRef "@sapphirecity_baseboard_lib.sapphirecity_baseboard(sch_1):\M_F_CLK_D\(0)") )
				( member ( diffPairRef "@sapphirecity_baseboard_lib.sapphirecity_baseboard(sch_1):\M_K_CLK_D\(3)") )
				( objectStatus "CLS_DDR_F_CAC-CLKS" )
			)
			( netClass "@crescent_city_bb_fab1_lib.crescent_city_bb_fab1(sch_1):\CLS_DDR_E_CAC-CLKS\"
				( memberType ( signal ) )
				( objectFlag fObjectElectrical )
				( member ( netGroupRef "@crescent_city_bb_fab1_lib.crescent_city_bb_fab1(sch_1):\NG_DDR_E_DLL_1\") )
				( member ( netGroupRef "@crescent_city_bb_fab1_lib.crescent_city_bb_fab1(sch_1):\NG_DDR_E_DLL_2\") )
				( member ( netGroupRef "@crescent_city_bb_fab1_lib.crescent_city_bb_fab1(sch_1):\NG_DDR_E_DLL_3\") )
				( member ( netGroupRef "@crescent_city_bb_fab1_lib.crescent_city_bb_fab1(sch_1):\NG_DDR_E_DLL_4\") )
				( member ( netGroupRef "@crescent_city_bb_fab1_lib.crescent_city_bb_fab1(sch_1):\NG_DDR_E_DLL_5\") )
				( member ( netGroupRef "@crescent_city_bb_fab1_lib.crescent_city_bb_fab1(sch_1):\NG_DDR_E_DLL_6\") )
				( member ( netGroupRef "@crescent_city_bb_fab1_lib.crescent_city_bb_fab1(sch_1):\NG_DDR_E_DLL_7\") )
				( member ( netGroupRef "@crescent_city_bb_fab1_lib.crescent_city_bb_fab1(sch_1):\NG_DDR_E_DLL_8\") )
				( member ( netGroupRef "@crescent_city_bb_fab1_lib.crescent_city_bb_fab1(sch_1):\NG_DDR_E_DLL_9\") )
				( member ( netGroupRef "@crescent_city_bb_fab1_lib.crescent_city_bb_fab1(sch_1):\NG_DDR_E_DLL_10\") )
				( member ( netGroupRef "@crescent_city_bb_fab1_lib.crescent_city_bb_fab1(sch_1):\NG_DDR_E_DLL_11\") )
				( member ( netGroupRef "@crescent_city_bb_fab1_lib.crescent_city_bb_fab1(sch_1):\NG_DDR_E_DLL_12\") )
				( member ( netGroupRef "@crescent_city_bb_fab1_lib.crescent_city_bb_fab1(sch_1):\NG_DDR_E_DLL_13\") )
				( member ( netGroupRef "@crescent_city_bb_fab1_lib.crescent_city_bb_fab1(sch_1):\NG_DDR_E_DLL_14\") )
				( member ( netGroupRef "@crescent_city_bb_fab1_lib.crescent_city_bb_fab1(sch_1):\NG_DDR_E_DLL_15\") )
				( member ( netGroupRef "@crescent_city_bb_fab1_lib.crescent_city_bb_fab1(sch_1):\NG_DDR_E_DLL_16\") )
				( member ( netGroupRef "@crescent_city_bb_fab1_lib.crescent_city_bb_fab1(sch_1):\NG_DDR_E_DLL_17\") )
				( member ( netGroupRef "@crescent_city_bb_fab1_lib.crescent_city_bb_fab1(sch_1):\NG_DDR_E_DLL_18\") )
				( member ( netGroupRef "@crescent_city_bb_fab1_lib.crescent_city_bb_fab1(sch_1):\NG_DDR_E_DLL_19\") )
				( member ( netGroupRef "@crescent_city_bb_fab1_lib.crescent_city_bb_fab1(sch_1):\NG_DDR_E_DLL_20\") )
				( member ( netGroupRef "@crescent_city_bb_fab1_lib.crescent_city_bb_fab1(sch_1):\NG_DDR_E_DLL_21\") )
				( member ( netGroupRef "@crescent_city_bb_fab1_lib.crescent_city_bb_fab1(sch_1):\NG_DDR_E_DLL_22\") )
				( member ( netGroupRef "@crescent_city_bb_fab1_lib.crescent_city_bb_fab1(sch_1):\NG_DDR_E_DLL_23\") )
				( member ( netGroupRef "@crescent_city_bb_fab1_lib.crescent_city_bb_fab1(sch_1):\NG_DDR_E_DLL_24\") )
				( member ( diffPairRef "@sapphirecity_baseboard_lib.sapphirecity_baseboard(sch_1):\M_E_CLK_D\(0)") )
				( member ( diffPairRef "@sapphirecity_baseboard_lib.sapphirecity_baseboard(sch_1):\M_L_CLK_D\(3)") )
				( objectStatus "CLS_DDR_E_CAC-CLKS" )
			)
			( netClass "@crescent_city_bb_fab1_lib.crescent_city_bb_fab1(sch_1):\CLS_DDR_D_CAC-CLKS\"
				( memberType ( signal ) )
				( objectFlag fObjectElectrical )
				( member ( netGroupRef "@crescent_city_bb_fab1_lib.crescent_city_bb_fab1(sch_1):\NG_DDR_D_DLL_1\") )
				( member ( netGroupRef "@crescent_city_bb_fab1_lib.crescent_city_bb_fab1(sch_1):\NG_DDR_D_DLL_2\") )
				( member ( netGroupRef "@crescent_city_bb_fab1_lib.crescent_city_bb_fab1(sch_1):\NG_DDR_D_DLL_3\") )
				( member ( netGroupRef "@crescent_city_bb_fab1_lib.crescent_city_bb_fab1(sch_1):\NG_DDR_D_DLL_4\") )
				( member ( netGroupRef "@crescent_city_bb_fab1_lib.crescent_city_bb_fab1(sch_1):\NG_DDR_D_DLL_5\") )
				( member ( netGroupRef "@crescent_city_bb_fab1_lib.crescent_city_bb_fab1(sch_1):\NG_DDR_D_DLL_6\") )
				( member ( netGroupRef "@crescent_city_bb_fab1_lib.crescent_city_bb_fab1(sch_1):\NG_DDR_D_DLL_7\") )
				( member ( netGroupRef "@crescent_city_bb_fab1_lib.crescent_city_bb_fab1(sch_1):\NG_DDR_D_DLL_8\") )
				( member ( netGroupRef "@crescent_city_bb_fab1_lib.crescent_city_bb_fab1(sch_1):\NG_DDR_D_DLL_9\") )
				( member ( netGroupRef "@crescent_city_bb_fab1_lib.crescent_city_bb_fab1(sch_1):\NG_DDR_D_DLL_10\") )
				( member ( netGroupRef "@crescent_city_bb_fab1_lib.crescent_city_bb_fab1(sch_1):\NG_DDR_D_DLL_11\") )
				( member ( netGroupRef "@crescent_city_bb_fab1_lib.crescent_city_bb_fab1(sch_1):\NG_DDR_D_DLL_12\") )
				( member ( netGroupRef "@crescent_city_bb_fab1_lib.crescent_city_bb_fab1(sch_1):\NG_DDR_D_DLL_13\") )
				( member ( netGroupRef "@crescent_city_bb_fab1_lib.crescent_city_bb_fab1(sch_1):\NG_DDR_D_DLL_14\") )
				( member ( netGroupRef "@crescent_city_bb_fab1_lib.crescent_city_bb_fab1(sch_1):\NG_DDR_D_DLL_15\") )
				( member ( netGroupRef "@crescent_city_bb_fab1_lib.crescent_city_bb_fab1(sch_1):\NG_DDR_D_DLL_16\") )
				( member ( netGroupRef "@crescent_city_bb_fab1_lib.crescent_city_bb_fab1(sch_1):\NG_DDR_D_DLL_17\") )
				( member ( netGroupRef "@crescent_city_bb_fab1_lib.crescent_city_bb_fab1(sch_1):\NG_DDR_D_DLL_18\") )
				( member ( netGroupRef "@crescent_city_bb_fab1_lib.crescent_city_bb_fab1(sch_1):\NG_DDR_D_DLL_19\") )
				( member ( netGroupRef "@crescent_city_bb_fab1_lib.crescent_city_bb_fab1(sch_1):\NG_DDR_D_DLL_20\") )
				( member ( netGroupRef "@crescent_city_bb_fab1_lib.crescent_city_bb_fab1(sch_1):\NG_DDR_D_DLL_21\") )
				( member ( netGroupRef "@crescent_city_bb_fab1_lib.crescent_city_bb_fab1(sch_1):\NG_DDR_D_DLL_22\") )
				( member ( netGroupRef "@crescent_city_bb_fab1_lib.crescent_city_bb_fab1(sch_1):\NG_DDR_D_DLL_23\") )
				( member ( netGroupRef "@crescent_city_bb_fab1_lib.crescent_city_bb_fab1(sch_1):\NG_DDR_D_DLL_24\") )
				( member ( diffPairRef "@sapphirecity_baseboard_lib.sapphirecity_baseboard(sch_1):\M_D_CLK_D\(0)") )
				( member ( diffPairRef "@sapphirecity_baseboard_lib.sapphirecity_baseboard(sch_1):\DP_M_D_CLK_D1\") )
				( objectStatus "CLS_DDR_D_CAC-CLKS" )
			)
			( netClass "@crescent_city_bb_fab1_lib.crescent_city_bb_fab1(sch_1):\CLS_DDR_C_CAC-CLKS\"
				( memberType ( signal ) )
				( objectFlag fObjectElectrical )
				( member ( netGroupRef "@crescent_city_bb_fab1_lib.crescent_city_bb_fab1(sch_1):\NG_DDR_C_DLL_1\") )
				( member ( netGroupRef "@crescent_city_bb_fab1_lib.crescent_city_bb_fab1(sch_1):\NG_DDR_C_DLL_2\") )
				( member ( netGroupRef "@crescent_city_bb_fab1_lib.crescent_city_bb_fab1(sch_1):\NG_DDR_C_DLL_3\") )
				( member ( netGroupRef "@crescent_city_bb_fab1_lib.crescent_city_bb_fab1(sch_1):\NG_DDR_C_DLL_4\") )
				( member ( netGroupRef "@crescent_city_bb_fab1_lib.crescent_city_bb_fab1(sch_1):\NG_DDR_C_DLL_5\") )
				( member ( netGroupRef "@crescent_city_bb_fab1_lib.crescent_city_bb_fab1(sch_1):\NG_DDR_C_DLL_6\") )
				( member ( netGroupRef "@crescent_city_bb_fab1_lib.crescent_city_bb_fab1(sch_1):\NG_DDR_C_DLL_7\") )
				( member ( netGroupRef "@crescent_city_bb_fab1_lib.crescent_city_bb_fab1(sch_1):\NG_DDR_C_DLL_8\") )
				( member ( netGroupRef "@crescent_city_bb_fab1_lib.crescent_city_bb_fab1(sch_1):\NG_DDR_C_DLL_9\") )
				( member ( netGroupRef "@crescent_city_bb_fab1_lib.crescent_city_bb_fab1(sch_1):\NG_DDR_C_DLL_10\") )
				( member ( netGroupRef "@crescent_city_bb_fab1_lib.crescent_city_bb_fab1(sch_1):\NG_DDR_C_DLL_11\") )
				( member ( netGroupRef "@crescent_city_bb_fab1_lib.crescent_city_bb_fab1(sch_1):\NG_DDR_C_DLL_12\") )
				( member ( netGroupRef "@crescent_city_bb_fab1_lib.crescent_city_bb_fab1(sch_1):\NG_DDR_C_DLL_13\") )
				( member ( netGroupRef "@crescent_city_bb_fab1_lib.crescent_city_bb_fab1(sch_1):\NG_DDR_C_DLL_14\") )
				( member ( netGroupRef "@crescent_city_bb_fab1_lib.crescent_city_bb_fab1(sch_1):\NG_DDR_C_DLL_15\") )
				( member ( netGroupRef "@crescent_city_bb_fab1_lib.crescent_city_bb_fab1(sch_1):\NG_DDR_C_DLL_16\") )
				( member ( netGroupRef "@crescent_city_bb_fab1_lib.crescent_city_bb_fab1(sch_1):\NG_DDR_C_DLL_17\") )
				( member ( netGroupRef "@crescent_city_bb_fab1_lib.crescent_city_bb_fab1(sch_1):\NG_DDR_C_DLL_18\") )
				( member ( netGroupRef "@crescent_city_bb_fab1_lib.crescent_city_bb_fab1(sch_1):\NG_DDR_C_DLL_19\") )
				( member ( netGroupRef "@crescent_city_bb_fab1_lib.crescent_city_bb_fab1(sch_1):\NG_DDR_C_DLL_20\") )
				( member ( netGroupRef "@crescent_city_bb_fab1_lib.crescent_city_bb_fab1(sch_1):\NG_DDR_C_DLL_21\") )
				( member ( netGroupRef "@crescent_city_bb_fab1_lib.crescent_city_bb_fab1(sch_1):\NG_DDR_C_DLL_22\") )
				( member ( netGroupRef "@crescent_city_bb_fab1_lib.crescent_city_bb_fab1(sch_1):\NG_DDR_C_DLL_23\") )
				( member ( netGroupRef "@crescent_city_bb_fab1_lib.crescent_city_bb_fab1(sch_1):\NG_DDR_C_DLL_24\") )
				( member ( diffPairRef "@sapphirecity_baseboard_lib.sapphirecity_baseboard(sch_1):\M_C_CLK_D\(0)") )
				( member ( diffPairRef "@sapphirecity_baseboard_lib.sapphirecity_baseboard(sch_1):\M_G_CLK_D\(1)") )
				( objectStatus "CLS_DDR_C_CAC-CLKS" )
			)
			( netClass "@crescent_city_bb_fab1_lib.crescent_city_bb_fab1(sch_1):\CLS_DDR_B_CAC-CLKS\"
				( memberType ( signal ) )
				( objectFlag fObjectElectrical )
				( member ( netGroupRef "@crescent_city_bb_fab1_lib.crescent_city_bb_fab1(sch_1):\NG_DDR_B_DLL_1\") )
				( member ( netGroupRef "@crescent_city_bb_fab1_lib.crescent_city_bb_fab1(sch_1):\NG_DDR_B_DLL_2\") )
				( member ( netGroupRef "@crescent_city_bb_fab1_lib.crescent_city_bb_fab1(sch_1):\NG_DDR_B_DLL_3\") )
				( member ( netGroupRef "@crescent_city_bb_fab1_lib.crescent_city_bb_fab1(sch_1):\NG_DDR_B_DLL_4\") )
				( member ( netGroupRef "@crescent_city_bb_fab1_lib.crescent_city_bb_fab1(sch_1):\NG_DDR_B_DLL_5\") )
				( member ( netGroupRef "@crescent_city_bb_fab1_lib.crescent_city_bb_fab1(sch_1):\NG_DDR_B_DLL_6\") )
				( member ( netGroupRef "@crescent_city_bb_fab1_lib.crescent_city_bb_fab1(sch_1):\NG_DDR_B_DLL_7\") )
				( member ( netGroupRef "@crescent_city_bb_fab1_lib.crescent_city_bb_fab1(sch_1):\NG_DDR_B_DLL_8\") )
				( member ( netGroupRef "@crescent_city_bb_fab1_lib.crescent_city_bb_fab1(sch_1):\NG_DDR_B_DLL_9\") )
				( member ( netGroupRef "@crescent_city_bb_fab1_lib.crescent_city_bb_fab1(sch_1):\NG_DDR_B_DLL_10\") )
				( member ( netGroupRef "@crescent_city_bb_fab1_lib.crescent_city_bb_fab1(sch_1):\NG_DDR_B_DLL_11\") )
				( member ( netGroupRef "@crescent_city_bb_fab1_lib.crescent_city_bb_fab1(sch_1):\NG_DDR_B_DLL_12\") )
				( member ( netGroupRef "@crescent_city_bb_fab1_lib.crescent_city_bb_fab1(sch_1):\NG_DDR_B_DLL_13\") )
				( member ( netGroupRef "@crescent_city_bb_fab1_lib.crescent_city_bb_fab1(sch_1):\NG_DDR_B_DLL_14\") )
				( member ( netGroupRef "@crescent_city_bb_fab1_lib.crescent_city_bb_fab1(sch_1):\NG_DDR_B_DLL_15\") )
				( member ( netGroupRef "@crescent_city_bb_fab1_lib.crescent_city_bb_fab1(sch_1):\NG_DDR_B_DLL_16\") )
				( member ( netGroupRef "@crescent_city_bb_fab1_lib.crescent_city_bb_fab1(sch_1):\NG_DDR_B_DLL_17\") )
				( member ( netGroupRef "@crescent_city_bb_fab1_lib.crescent_city_bb_fab1(sch_1):\NG_DDR_B_DLL_18\") )
				( member ( netGroupRef "@crescent_city_bb_fab1_lib.crescent_city_bb_fab1(sch_1):\NG_DDR_B_DLL_19\") )
				( member ( netGroupRef "@crescent_city_bb_fab1_lib.crescent_city_bb_fab1(sch_1):\NG_DDR_B_DLL_20\") )
				( member ( netGroupRef "@crescent_city_bb_fab1_lib.crescent_city_bb_fab1(sch_1):\NG_DDR_B_DLL_21\") )
				( member ( netGroupRef "@crescent_city_bb_fab1_lib.crescent_city_bb_fab1(sch_1):\NG_DDR_B_DLL_22\") )
				( member ( netGroupRef "@crescent_city_bb_fab1_lib.crescent_city_bb_fab1(sch_1):\NG_DDR_B_DLL_23\") )
				( member ( netGroupRef "@crescent_city_bb_fab1_lib.crescent_city_bb_fab1(sch_1):\NG_DDR_B_DLL_24\") )
				( member ( diffPairRef "@sapphirecity_baseboard_lib.sapphirecity_baseboard(sch_1):\M_B_CLK_D\(0)") )
				( member ( diffPairRef "@sapphirecity_baseboard_lib.sapphirecity_baseboard(sch_1):\M_H_CLK_D\(1)") )
				( objectStatus "CLS_DDR_B_CAC-CLKS" )
			)
			( netClass "@crescent_city_bb_fab1_lib.crescent_city_bb_fab1(sch_1):\CLS_DDR_A_CMD-CLK\"
				( memberType ( signal ) )
				( objectFlag fObjectElectrical )
				( member ( netGroupRef "@crescent_city_bb_fab1_lib.crescent_city_bb_fab1(sch_1):\DDR_A_DLL_1\") )
				( member ( netGroupRef "@crescent_city_bb_fab1_lib.crescent_city_bb_fab1(sch_1):\NG_DDR_A_DLL_2\") )
				( member ( netGroupRef "@crescent_city_bb_fab1_lib.crescent_city_bb_fab1(sch_1):\NG_DDR_A_DLL_3\") )
				( member ( netGroupRef "@crescent_city_bb_fab1_lib.crescent_city_bb_fab1(sch_1):\NG_DDR_A_DLL_4\") )
				( member ( netGroupRef "@crescent_city_bb_fab1_lib.crescent_city_bb_fab1(sch_1):\NG_DDR_A_DLL_5\") )
				( member ( netGroupRef "@crescent_city_bb_fab1_lib.crescent_city_bb_fab1(sch_1):\NG_DDR_A_DLL_6\") )
				( member ( netGroupRef "@crescent_city_bb_fab1_lib.crescent_city_bb_fab1(sch_1):\NG_DDR_A_DLL_7\") )
				( member ( netGroupRef "@crescent_city_bb_fab1_lib.crescent_city_bb_fab1(sch_1):\NG_DDR_A_DLL_8\") )
				( member ( netGroupRef "@crescent_city_bb_fab1_lib.crescent_city_bb_fab1(sch_1):\NG_DDR_A_DLL_9\") )
				( member ( netGroupRef "@crescent_city_bb_fab1_lib.crescent_city_bb_fab1(sch_1):\NG_DDR_A_DLL_10\") )
				( member ( netGroupRef "@crescent_city_bb_fab1_lib.crescent_city_bb_fab1(sch_1):\NG_DDR_A_DLL_11\") )
				( member ( netGroupRef "@crescent_city_bb_fab1_lib.crescent_city_bb_fab1(sch_1):\NG_DDR_A_DLL_12\") )
				( member ( netGroupRef "@crescent_city_bb_fab1_lib.crescent_city_bb_fab1(sch_1):\NG_DDR_A_DLL_13\") )
				( member ( netGroupRef "@crescent_city_bb_fab1_lib.crescent_city_bb_fab1(sch_1):\NG_DDR_A_DLL_14\") )
				( member ( netGroupRef "@crescent_city_bb_fab1_lib.crescent_city_bb_fab1(sch_1):\NG_DDR_A_DLL_15\") )
				( member ( netGroupRef "@crescent_city_bb_fab1_lib.crescent_city_bb_fab1(sch_1):\NG_DDR_A_DLL_16\") )
				( member ( netGroupRef "@crescent_city_bb_fab1_lib.crescent_city_bb_fab1(sch_1):\NG_DDR_A_DLL_17\") )
				( member ( netGroupRef "@crescent_city_bb_fab1_lib.crescent_city_bb_fab1(sch_1):\NG_DDR_A_DLL_18\") )
				( member ( netGroupRef "@crescent_city_bb_fab1_lib.crescent_city_bb_fab1(sch_1):\NG_DDR_A_DLL_19\") )
				( member ( netGroupRef "@crescent_city_bb_fab1_lib.crescent_city_bb_fab1(sch_1):\NG_DDR_A_DLL_20\") )
				( member ( netGroupRef "@crescent_city_bb_fab1_lib.crescent_city_bb_fab1(sch_1):\NG_DDR_A_DLL_21\") )
				( member ( netGroupRef "@crescent_city_bb_fab1_lib.crescent_city_bb_fab1(sch_1):\NG_DDR_A_DLL_22\") )
				( member ( netGroupRef "@crescent_city_bb_fab1_lib.crescent_city_bb_fab1(sch_1):\NG_DDR_A_DLL_23\") )
				( member ( netGroupRef "@crescent_city_bb_fab1_lib.crescent_city_bb_fab1(sch_1):\NG_DDR_A_DLL_24\") )
				( member ( diffPairRef "@sapphirecity_baseboard_lib.sapphirecity_baseboard(sch_1):\M_A_CLK_D\(0)") )
				( member ( diffPairRef "@sapphirecity_baseboard_lib.sapphirecity_baseboard(sch_1):\M_A_CLK_D\(1)") )
				( objectStatus "CLS_DDR_A_CAC-CLKS" )
			)
			( netClass "@crescent_city_bb_fab1_lib.crescent_city_bb_fab1(sch_1):\PNCLS_VSENSE\"
				( memberType ( signal ) )
				( physicalCSetRef "@baseboard_fab2_lib.baseboard_fab2(sch_1):\5-5-5_DIFF\" )
				( objectFlag fObjectPhysical )
				( member ( diffPairRef "@crescent_city_bb_fab1_lib.crescent_city_bb_fab1(sch_1):\DP_VSENSE_PVDDQ_ABC\") )
				( member ( diffPairRef "@crescent_city_bb_fab1_lib.crescent_city_bb_fab1(sch_1):\DP_VSENSE_PVDDQ_DEF\") )
				( member ( diffPairRef "@crescent_city_bb_fab1_lib.crescent_city_bb_fab1(sch_1):\DP_VSENSE_PVDDQ_GHI\") )
				( member ( diffPairRef "@crescent_city_bb_fab1_lib.crescent_city_bb_fab1(sch_1):\DP_VSENSE_P1V0_CPU0_R\") )
				( member ( diffPairRef "@crescent_city_bb_fab1_lib.crescent_city_bb_fab1(sch_1):\DP_VSENSE_P1V0_CPU1_R\") )
				( member ( diffPairRef "@baseboard_fab2_lib.baseboard_fab2(sch_1):\DP_VSENSE_PVSA_CPU1_CPU1_SKT\") )
				( member ( diffPairRef "@baseboard_fab2_lib.baseboard_fab2(sch_1):\DP_VSENSE_PVNN_PCH_STBY_AVS\") )
				( member ( diffPairRef "@crescent_city_bb_fab1_lib.crescent_city_bb_fab1(sch_1):\VSENSE_PVSA_CPU0\") )
				( member ( diffPairRef "@baseboard_fab2_lib.baseboard_fab2(sch_1):\DP_VSENSE_PVCCMCP_CPU1_SKT\") )
				( member ( diffPairRef "@baseboard_fab2_lib.baseboard_fab2(sch_1):\DP_VSENSE_PVCCMCP_CPU0_SKT\") )
				( member ( diffPairRef "@baseboard_fab2_lib.baseboard_fab2(sch_1):\DP_VSENSE_PVCCIO_CPU1_SKT\") )
				( member ( diffPairRef "@baseboard_fab2_lib.baseboard_fab2(sch_1):\DP_VSENSE_PVCCIN_CPU1\") )
				( member ( diffPairRef "@crescent_city_bb_fab1_lib.crescent_city_bb_fab1(sch_1):\VSENSE_P1V05_PCH_STBY\") )
				( member ( diffPairRef "@crescent_city_bb_fab1_lib.crescent_city_bb_fab1(sch_1):\DP_VSENSE_PVDDQ_KLM\") )
				( member ( diffPairRef "@baseboard_fab2_lib.baseboard_fab2(sch_1):\DP_VSENSE_PVCCIO_CPU0_AVS\") )
				( member ( diffPairRef "@baseboard_fab2_lib.baseboard_fab2(sch_1):\DP_ISENSE_PVCCIN_CPU1_PH1\") )
				( member ( diffPairRef "@baseboard_fab2_lib.baseboard_fab2(sch_1):\DP_ISENSE_PVCCIN_CPU1_PH2\") )
				( member ( diffPairRef "@baseboard_fab2_lib.baseboard_fab2(sch_1):\DP_ISENSE_PVCCIN_CPU1_PH3\") )
				( member ( diffPairRef "@baseboard_fab2_lib.baseboard_fab2(sch_1):\DP_ISENSE_PVCCIN_CPU1_PH4\") )
				( member ( diffPairRef "@baseboard_fab2_lib.baseboard_fab2(sch_1):\DP_ISENSE_PVCCIN_CPU1_PH5\") )
				( member ( diffPairRef "@baseboard_fab2_lib.baseboard_fab2(sch_1):\DP_ISENSE_PVSA_CPU1_PH\") )
				( member ( diffPairRef "@baseboard_fab2_lib.baseboard_fab2(sch_1):\DIFFPAIR17\") )
				( member ( diffPairRef "@baseboard_fab2_lib.baseboard_fab2(sch_1):\DIFFPAIR16\") )
				( member ( diffPairRef "@baseboard_fab2_lib.baseboard_fab2(sch_1):\DIFFPAIR15\") )
				( member ( diffPairRef "@baseboard_fab2_lib.baseboard_fab2(sch_1):\DIFFPAIR14\") )
				( member ( diffPairRef "@baseboard_fab2_lib.baseboard_fab2(sch_1):\DIFFPAIR13\") )
				( member ( diffPairRef "@baseboard_fab2_lib.baseboard_fab2(sch_1):\DIFFPAIR12\") )
				( member ( diffPairRef "@baseboard_fab2_lib.baseboard_fab2(sch_1):\DIFFPAIR11\") )
				( member ( diffPairRef "@baseboard_fab2_lib.baseboard_fab2(sch_1):\DIFFPAIR10\") )
				( member ( diffPairRef "@baseboard_fab2_lib.baseboard_fab2(sch_1):\DIFFPAIR9\") )
				( member ( diffPairRef "@baseboard_fab2_lib.baseboard_fab2(sch_1):\DIFFPAIR8\") )
				( member ( diffPairRef "@baseboard_fab2_lib.baseboard_fab2(sch_1):\DP_VSENSE_PVCCIN_CPU0\") )
				( member ( diffPairRef "@baseboard_fab2_lib.baseboard_fab2(sch_1):\DP_VSENSE_PVNN_PCH_STBY\") )
				( member ( diffPairRef "@baseboard_fab2_lib.baseboard_fab2(sch_1):\DP_VSENSE_PVCCIN_CPU0_SKT\") )
				( member ( diffPairRef "@baseboard_fab2_lib.baseboard_fab2(sch_1):\DP_VSENSE_P1V8MCP_CPU0_SKT\") )
				( member ( diffPairRef "@baseboard_fab2_lib.baseboard_fab2(sch_1):\DP_VSENSE_P1V8MCP_CPU1_SKT\") )
				( member ( diffPairRef "@baseboard_fab2_lib.baseboard_fab2(sch_1):\DIFFPAIR0\") )
				( member ( diffPairRef "@baseboard_fab2_lib.baseboard_fab2(sch_1):\DIFFPAIR1\") )
				( member ( diffPairRef "@baseboard_fab2_lib.baseboard_fab2(sch_1):\DIFFPAIR2\") )
				( member ( diffPairRef "@baseboard_fab2_lib.baseboard_fab2(sch_1):\DIFFPAIR3\") )
				( member ( diffPairRef "@baseboard_fab2_lib.baseboard_fab2(sch_1):\DIFFPAIR4\") )
				( member ( diffPairRef "@baseboard_fab2_lib.baseboard_fab2(sch_1):\DIFFPAIR5\") )
				( member ( diffPairRef "@baseboard_fab2_lib.baseboard_fab2(sch_1):\DIFFPAIR6\") )
				( member ( diffPairRef "@baseboard_fab2_lib.baseboard_fab2(sch_1):\DIFFPAIR7\") )
				( member ( signalRef "@baseboard_fab2_lib.baseboard_fab2(sch_1):vsense_pvccin_cpu0_avsp") )
				( member ( signalRef "@baseboard_fab2_lib.baseboard_fab2(sch_1):vsense_pvccin_cpu1_avsp") )
				( member ( signalRef "@baseboard_fab2_lib.baseboard_fab2(sch_1):vsense_pvddq_abc_p") )
				( member ( signalRef "@baseboard_fab2_lib.baseboard_fab2(sch_1):vsense_pvddq_def_p") )
				( member ( signalRef "@baseboard_fab2_lib.baseboard_fab2(sch_1):vsense_pvddq_ghj_p") )
				( member ( signalRef "@baseboard_fab2_lib.baseboard_fab2(sch_1):vsense_pvddq_klm_p") )
				( member ( signalRef "@baseboard_fab2_lib.baseboard_fab2(sch_1):vsense_pvccmcp_cpu0_skt_vrtn") )
				( member ( signalRef "@baseboard_fab2_lib.baseboard_fab2(sch_1):vsense_pvccmcp_cpu0_skt_vsen") )
				( member ( signalRef "@baseboard_fab2_lib.baseboard_fab2(sch_1):vsense_pvccmcp_cpu1_skt_vrtn") )
				( member ( signalRef "@baseboard_fab2_lib.baseboard_fab2(sch_1):vsense_pvccmcp_cpu1_skt_vsen") )
				( member ( signalRef "@baseboard_fab2_lib.baseboard_fab2(sch_1):vsense_pvsa_cpu0_bvsp") )
				( member ( signalRef "@baseboard_fab2_lib.baseboard_fab2(sch_1):vsense_pvsa_cpu0_n") )
				( member ( signalRef "@baseboard_fab2_lib.baseboard_fab2(sch_1):vsense_pvsa_cpu0_p") )
				( member ( signalRef "@baseboard_fab2_lib.baseboard_fab2(sch_1):vsense_pvsa_cpu0_skt_vrtn") )
				( member ( signalRef "@baseboard_fab2_lib.baseboard_fab2(sch_1):vsense_pvsa_cpu0_skt_vsen") )
				( member ( signalRef "@baseboard_fab2_lib.baseboard_fab2(sch_1):vsense_p3v3_stby") )
				( member ( signalRef "@baseboard_fab2_lib.baseboard_fab2(sch_1):vsense_rgnd_p3v3_stby") )
				( member ( signalRef "@baseboard_fab2_lib.baseboard_fab2(sch_1):vsense_vout_p3v3_stby") )
				( member ( signalRef "@baseboard_fab2_lib.baseboard_fab2(sch_1):vsense_p1v05_pch_stby_avsn") )
				( member ( signalRef "@baseboard_fab2_lib.baseboard_fab2(sch_1):vsense_p1v05_pch_stby_avsp") )
				( member ( signalRef "@baseboard_fab2_lib.baseboard_fab2(sch_1):vsense_pvnn_pch_stby_avsn") )
				( member ( signalRef "@baseboard_fab2_lib.baseboard_fab2(sch_1):vsense_pvnn_pch_stby_avsp") )
				( member ( signalRef "@baseboard_fab2_lib.baseboard_fab2(sch_1):vr_p1v05_pch_stby_avsp") )
				( member ( signalRef "@baseboard_fab2_lib.baseboard_fab2(sch_1):vsense_pvccin_cpu0_n") )
				( member ( signalRef "@baseboard_fab2_lib.baseboard_fab2(sch_1):vsense_pvccin_cpu0_p") )
				( member ( signalRef "@baseboard_fab2_lib.baseboard_fab2(sch_1):vsense_pvccin_cpu0_skt_vrtn") )
				( member ( signalRef "@baseboard_fab2_lib.baseboard_fab2(sch_1):vsense_pvccin_cpu0_skt_vsen") )
				( member ( signalRef "@baseboard_fab2_lib.baseboard_fab2(sch_1):vsense_pvccin_cpu1_n") )
				( member ( signalRef "@baseboard_fab2_lib.baseboard_fab2(sch_1):vsense_pvccin_cpu1_p") )
				( member ( signalRef "@baseboard_fab2_lib.baseboard_fab2(sch_1):vsense_pvccin_cpu1_skt_vrtn") )
				( member ( signalRef "@baseboard_fab2_lib.baseboard_fab2(sch_1):vsense_pvccin_cpu1_skt_vsen") )
				( member ( signalRef "@baseboard_fab2_lib.baseboard_fab2(sch_1):vsense_pvccio_cpu0_avsn") )
				( member ( signalRef "@baseboard_fab2_lib.baseboard_fab2(sch_1):vsense_pvccio_cpu0_avsp") )
				( member ( signalRef "@baseboard_fab2_lib.baseboard_fab2(sch_1):vsense_pvccio_cpu0_skt_vrtn") )
				( member ( signalRef "@baseboard_fab2_lib.baseboard_fab2(sch_1):vsense_pvccio_cpu0_skt_vsen") )
				( member ( signalRef "@baseboard_fab2_lib.baseboard_fab2(sch_1):vsense_pvccio_cpu1_avsn") )
				( member ( signalRef "@baseboard_fab2_lib.baseboard_fab2(sch_1):vsense_pvccio_cpu1_avsp") )
				( member ( signalRef "@baseboard_fab2_lib.baseboard_fab2(sch_1):vsense_pvccio_cpu1_skt_vrtn") )
				( member ( signalRef "@baseboard_fab2_lib.baseboard_fab2(sch_1):vsense_pvccio_cpu1_skt_vsen") )
				( member ( signalRef "@baseboard_fab2_lib.baseboard_fab2(sch_1):vr_pvddq_klm_avsp") )
				( member ( signalRef "@baseboard_fab2_lib.baseboard_fab2(sch_1):isense_pvddq_ghj_ph2_imon") )
				( member ( signalRef "@baseboard_fab2_lib.baseboard_fab2(sch_1):isense_pvccin_cpu0_ph1_imon") )
				( member ( signalRef "@baseboard_fab2_lib.baseboard_fab2(sch_1):isense_pvccin_cpu0_ph2_imon") )
				( member ( signalRef "@baseboard_fab2_lib.baseboard_fab2(sch_1):isense_pvccin_cpu0_ph3_imon") )
				( member ( signalRef "@baseboard_fab2_lib.baseboard_fab2(sch_1):isense_pvccin_cpu0_ph4_imon") )
				( member ( signalRef "@baseboard_fab2_lib.baseboard_fab2(sch_1):isense_pvccin_cpu0_ph5_imon") )
				( member ( signalRef "@baseboard_fab2_lib.baseboard_fab2(sch_1):isense_pvccio_cpu0_ph1_imon") )
				( member ( signalRef "@baseboard_fab2_lib.baseboard_fab2(sch_1):isense_pvnn_pch_ph1_imon") )
				( member ( signalRef "@baseboard_fab2_lib.baseboard_fab2(sch_1):isense_pvsa_cpu0_imon") )
				( member ( signalRef "@baseboard_fab2_lib.baseboard_fab2(sch_1):isense_p1v05_pch_stby_ph1_imon") )
				( objectStatus "PNCLS_SENSE_DIFF_5MIL" )
			)
			( netClass "@crescent_city_bb_fab1_lib.crescent_city_bb_fab1(sch_1):\40-OHM-MS_&_38-OHM-SL_SE\"
				( memberType ( signal ) )
				( physicalCSetRef "@sapphirecity_baseboard_lib.sapphirecity_baseboard(sch_1):\40_OHM_US_AND_38_OHM_SL\" )
				( objectFlag fObjectPhysical )
				( member ( signalRef "@baseboard_fab2_lib.baseboard_fab2(sch_1):m_f_ecc(0)") )
				( member ( signalRef "@baseboard_fab2_lib.baseboard_fab2(sch_1):m_f_ecc(1)") )
				( member ( signalRef "@baseboard_fab2_lib.baseboard_fab2(sch_1):m_f_ecc(2)") )
				( member ( signalRef "@baseboard_fab2_lib.baseboard_fab2(sch_1):m_f_ecc(3)") )
				( member ( signalRef "@baseboard_fab2_lib.baseboard_fab2(sch_1):m_f_ecc(4)") )
				( member ( signalRef "@baseboard_fab2_lib.baseboard_fab2(sch_1):m_f_ecc(5)") )
				( member ( signalRef "@baseboard_fab2_lib.baseboard_fab2(sch_1):m_f_ecc(6)") )
				( member ( signalRef "@baseboard_fab2_lib.baseboard_fab2(sch_1):m_f_ecc(7)") )
				( member ( signalRef "@baseboard_fab2_lib.baseboard_fab2(sch_1):m_g_ecc(0)") )
				( member ( signalRef "@baseboard_fab2_lib.baseboard_fab2(sch_1):m_g_ecc(1)") )
				( member ( signalRef "@baseboard_fab2_lib.baseboard_fab2(sch_1):m_g_ecc(2)") )
				( member ( signalRef "@baseboard_fab2_lib.baseboard_fab2(sch_1):m_g_ecc(3)") )
				( member ( signalRef "@baseboard_fab2_lib.baseboard_fab2(sch_1):m_g_ecc(4)") )
				( member ( signalRef "@baseboard_fab2_lib.baseboard_fab2(sch_1):m_g_ecc(5)") )
				( member ( signalRef "@baseboard_fab2_lib.baseboard_fab2(sch_1):m_g_ecc(6)") )
				( member ( signalRef "@baseboard_fab2_lib.baseboard_fab2(sch_1):m_g_ecc(7)") )
				( member ( signalRef "@baseboard_fab2_lib.baseboard_fab2(sch_1):m_h_ecc(0)") )
				( member ( signalRef "@baseboard_fab2_lib.baseboard_fab2(sch_1):m_h_ecc(1)") )
				( member ( signalRef "@baseboard_fab2_lib.baseboard_fab2(sch_1):m_h_ecc(2)") )
				( member ( signalRef "@baseboard_fab2_lib.baseboard_fab2(sch_1):m_h_ecc(3)") )
				( member ( signalRef "@baseboard_fab2_lib.baseboard_fab2(sch_1):m_h_ecc(4)") )
				( member ( signalRef "@baseboard_fab2_lib.baseboard_fab2(sch_1):m_h_ecc(5)") )
				( member ( signalRef "@baseboard_fab2_lib.baseboard_fab2(sch_1):m_h_ecc(6)") )
				( member ( signalRef "@baseboard_fab2_lib.baseboard_fab2(sch_1):m_h_ecc(7)") )
				( member ( signalRef "@baseboard_fab2_lib.baseboard_fab2(sch_1):m_j_ecc(0)") )
				( member ( signalRef "@baseboard_fab2_lib.baseboard_fab2(sch_1):m_j_ecc(1)") )
				( member ( signalRef "@baseboard_fab2_lib.baseboard_fab2(sch_1):m_j_ecc(2)") )
				( member ( signalRef "@baseboard_fab2_lib.baseboard_fab2(sch_1):m_j_ecc(3)") )
				( member ( signalRef "@baseboard_fab2_lib.baseboard_fab2(sch_1):m_j_ecc(4)") )
				( member ( signalRef "@baseboard_fab2_lib.baseboard_fab2(sch_1):m_j_ecc(5)") )
				( member ( signalRef "@baseboard_fab2_lib.baseboard_fab2(sch_1):m_j_ecc(6)") )
				( member ( signalRef "@baseboard_fab2_lib.baseboard_fab2(sch_1):m_j_ecc(7)") )
				( member ( signalRef "@baseboard_fab2_lib.baseboard_fab2(sch_1):m_k_ecc(0)") )
				( member ( signalRef "@baseboard_fab2_lib.baseboard_fab2(sch_1):m_k_ecc(1)") )
				( member ( signalRef "@baseboard_fab2_lib.baseboard_fab2(sch_1):m_k_ecc(2)") )
				( member ( signalRef "@baseboard_fab2_lib.baseboard_fab2(sch_1):m_k_ecc(3)") )
				( member ( signalRef "@baseboard_fab2_lib.baseboard_fab2(sch_1):m_k_ecc(4)") )
				( member ( signalRef "@baseboard_fab2_lib.baseboard_fab2(sch_1):m_k_ecc(5)") )
				( member ( signalRef "@baseboard_fab2_lib.baseboard_fab2(sch_1):m_k_ecc(6)") )
				( member ( signalRef "@baseboard_fab2_lib.baseboard_fab2(sch_1):m_k_ecc(7)") )
				( member ( signalRef "@baseboard_fab2_lib.baseboard_fab2(sch_1):m_l_ecc(0)") )
				( member ( signalRef "@baseboard_fab2_lib.baseboard_fab2(sch_1):m_l_ecc(1)") )
				( member ( signalRef "@baseboard_fab2_lib.baseboard_fab2(sch_1):m_l_ecc(2)") )
				( member ( signalRef "@baseboard_fab2_lib.baseboard_fab2(sch_1):m_l_ecc(3)") )
				( member ( signalRef "@baseboard_fab2_lib.baseboard_fab2(sch_1):m_l_ecc(4)") )
				( member ( signalRef "@baseboard_fab2_lib.baseboard_fab2(sch_1):m_l_ecc(5)") )
				( member ( signalRef "@baseboard_fab2_lib.baseboard_fab2(sch_1):m_l_ecc(6)") )
				( member ( signalRef "@baseboard_fab2_lib.baseboard_fab2(sch_1):m_l_ecc(7)") )
				( member ( signalRef "@baseboard_fab2_lib.baseboard_fab2(sch_1):m_m_ecc(0)") )
				( member ( signalRef "@baseboard_fab2_lib.baseboard_fab2(sch_1):m_m_ecc(1)") )
				( member ( signalRef "@baseboard_fab2_lib.baseboard_fab2(sch_1):m_m_ecc(2)") )
				( member ( signalRef "@baseboard_fab2_lib.baseboard_fab2(sch_1):m_m_ecc(3)") )
				( member ( signalRef "@baseboard_fab2_lib.baseboard_fab2(sch_1):m_m_ecc(4)") )
				( member ( signalRef "@baseboard_fab2_lib.baseboard_fab2(sch_1):m_m_ecc(5)") )
				( member ( signalRef "@baseboard_fab2_lib.baseboard_fab2(sch_1):m_m_ecc(6)") )
				( member ( signalRef "@baseboard_fab2_lib.baseboard_fab2(sch_1):m_m_ecc(7)") )
				( member ( signalRef "@baseboard_fab2_lib.baseboard_fab2(sch_1):m_a_c(2)") )
				( member ( signalRef "@baseboard_fab2_lib.baseboard_fab2(sch_1):m_f_dq(9)") )
				( member ( signalRef "@baseboard_fab2_lib.baseboard_fab2(sch_1):m_f_dq(10)") )
				( member ( signalRef "@baseboard_fab2_lib.baseboard_fab2(sch_1):m_f_dq(11)") )
				( member ( signalRef "@baseboard_fab2_lib.baseboard_fab2(sch_1):m_f_dq(12)") )
				( member ( signalRef "@baseboard_fab2_lib.baseboard_fab2(sch_1):m_f_dq(13)") )
				( member ( signalRef "@baseboard_fab2_lib.baseboard_fab2(sch_1):m_f_dq(14)") )
				( member ( signalRef "@baseboard_fab2_lib.baseboard_fab2(sch_1):m_f_dq(15)") )
				( member ( signalRef "@baseboard_fab2_lib.baseboard_fab2(sch_1):m_f_dq(16)") )
				( member ( signalRef "@baseboard_fab2_lib.baseboard_fab2(sch_1):m_f_dq(17)") )
				( member ( signalRef "@baseboard_fab2_lib.baseboard_fab2(sch_1):m_f_dq(18)") )
				( member ( signalRef "@baseboard_fab2_lib.baseboard_fab2(sch_1):m_f_dq(19)") )
				( member ( signalRef "@baseboard_fab2_lib.baseboard_fab2(sch_1):m_f_dq(20)") )
				( member ( signalRef "@baseboard_fab2_lib.baseboard_fab2(sch_1):m_f_dq(21)") )
				( member ( signalRef "@baseboard_fab2_lib.baseboard_fab2(sch_1):m_f_dq(22)") )
				( member ( signalRef "@baseboard_fab2_lib.baseboard_fab2(sch_1):m_f_dq(23)") )
				( member ( signalRef "@baseboard_fab2_lib.baseboard_fab2(sch_1):m_f_dq(24)") )
				( member ( signalRef "@baseboard_fab2_lib.baseboard_fab2(sch_1):m_f_dq(25)") )
				( member ( signalRef "@baseboard_fab2_lib.baseboard_fab2(sch_1):m_f_dq(26)") )
				( member ( signalRef "@baseboard_fab2_lib.baseboard_fab2(sch_1):m_f_dq(27)") )
				( member ( signalRef "@baseboard_fab2_lib.baseboard_fab2(sch_1):m_f_dq(28)") )
				( member ( signalRef "@baseboard_fab2_lib.baseboard_fab2(sch_1):m_f_dq(29)") )
				( member ( signalRef "@baseboard_fab2_lib.baseboard_fab2(sch_1):m_f_dq(30)") )
				( member ( signalRef "@baseboard_fab2_lib.baseboard_fab2(sch_1):m_f_dq(31)") )
				( member ( signalRef "@baseboard_fab2_lib.baseboard_fab2(sch_1):m_f_dq(32)") )
				( member ( signalRef "@baseboard_fab2_lib.baseboard_fab2(sch_1):m_f_dq(33)") )
				( member ( signalRef "@baseboard_fab2_lib.baseboard_fab2(sch_1):m_f_dq(34)") )
				( member ( signalRef "@baseboard_fab2_lib.baseboard_fab2(sch_1):m_f_dq(35)") )
				( member ( signalRef "@baseboard_fab2_lib.baseboard_fab2(sch_1):m_f_dq(36)") )
				( member ( signalRef "@baseboard_fab2_lib.baseboard_fab2(sch_1):m_f_dq(37)") )
				( member ( signalRef "@baseboard_fab2_lib.baseboard_fab2(sch_1):m_f_dq(38)") )
				( member ( signalRef "@baseboard_fab2_lib.baseboard_fab2(sch_1):m_f_dq(39)") )
				( member ( signalRef "@baseboard_fab2_lib.baseboard_fab2(sch_1):m_f_dq(40)") )
				( member ( signalRef "@baseboard_fab2_lib.baseboard_fab2(sch_1):m_f_dq(41)") )
				( member ( signalRef "@baseboard_fab2_lib.baseboard_fab2(sch_1):m_f_dq(42)") )
				( member ( signalRef "@baseboard_fab2_lib.baseboard_fab2(sch_1):m_f_dq(43)") )
				( member ( signalRef "@baseboard_fab2_lib.baseboard_fab2(sch_1):m_f_dq(44)") )
				( member ( signalRef "@baseboard_fab2_lib.baseboard_fab2(sch_1):m_f_dq(45)") )
				( member ( signalRef "@baseboard_fab2_lib.baseboard_fab2(sch_1):m_f_dq(46)") )
				( member ( signalRef "@baseboard_fab2_lib.baseboard_fab2(sch_1):m_f_dq(47)") )
				( member ( signalRef "@baseboard_fab2_lib.baseboard_fab2(sch_1):m_f_dq(48)") )
				( member ( signalRef "@baseboard_fab2_lib.baseboard_fab2(sch_1):m_f_dq(49)") )
				( member ( signalRef "@baseboard_fab2_lib.baseboard_fab2(sch_1):m_f_dq(50)") )
				( member ( signalRef "@baseboard_fab2_lib.baseboard_fab2(sch_1):m_f_dq(51)") )
				( member ( signalRef "@baseboard_fab2_lib.baseboard_fab2(sch_1):m_f_dq(52)") )
				( member ( signalRef "@baseboard_fab2_lib.baseboard_fab2(sch_1):m_f_dq(53)") )
				( member ( signalRef "@baseboard_fab2_lib.baseboard_fab2(sch_1):m_f_dq(54)") )
				( member ( signalRef "@baseboard_fab2_lib.baseboard_fab2(sch_1):m_f_dq(55)") )
				( member ( signalRef "@baseboard_fab2_lib.baseboard_fab2(sch_1):m_f_dq(56)") )
				( member ( signalRef "@baseboard_fab2_lib.baseboard_fab2(sch_1):m_f_dq(57)") )
				( member ( signalRef "@baseboard_fab2_lib.baseboard_fab2(sch_1):m_f_dq(58)") )
				( member ( signalRef "@baseboard_fab2_lib.baseboard_fab2(sch_1):m_f_dq(59)") )
				( member ( signalRef "@baseboard_fab2_lib.baseboard_fab2(sch_1):m_f_dq(60)") )
				( member ( signalRef "@baseboard_fab2_lib.baseboard_fab2(sch_1):m_f_dq(61)") )
				( member ( signalRef "@baseboard_fab2_lib.baseboard_fab2(sch_1):m_f_dq(62)") )
				( member ( signalRef "@baseboard_fab2_lib.baseboard_fab2(sch_1):m_f_dq(63)") )
				( member ( signalRef "@baseboard_fab2_lib.baseboard_fab2(sch_1):m_g_dq(10)") )
				( member ( signalRef "@baseboard_fab2_lib.baseboard_fab2(sch_1):m_h_dq(13)") )
				( member ( signalRef "@baseboard_fab2_lib.baseboard_fab2(sch_1):m_h_dq(14)") )
				( member ( signalRef "@baseboard_fab2_lib.baseboard_fab2(sch_1):m_h_dq(15)") )
				( member ( signalRef "@baseboard_fab2_lib.baseboard_fab2(sch_1):m_h_dq(16)") )
				( member ( signalRef "@baseboard_fab2_lib.baseboard_fab2(sch_1):m_a_ecc(0)") )
				( member ( signalRef "@baseboard_fab2_lib.baseboard_fab2(sch_1):m_a_ecc(1)") )
				( member ( signalRef "@baseboard_fab2_lib.baseboard_fab2(sch_1):m_a_ecc(2)") )
				( member ( signalRef "@baseboard_fab2_lib.baseboard_fab2(sch_1):m_a_ecc(3)") )
				( member ( signalRef "@baseboard_fab2_lib.baseboard_fab2(sch_1):m_a_ecc(4)") )
				( member ( signalRef "@baseboard_fab2_lib.baseboard_fab2(sch_1):m_a_ecc(5)") )
				( member ( signalRef "@baseboard_fab2_lib.baseboard_fab2(sch_1):m_a_ecc(6)") )
				( member ( signalRef "@baseboard_fab2_lib.baseboard_fab2(sch_1):m_a_ecc(7)") )
				( member ( signalRef "@baseboard_fab2_lib.baseboard_fab2(sch_1):m_b_ecc(0)") )
				( member ( signalRef "@baseboard_fab2_lib.baseboard_fab2(sch_1):m_b_ecc(1)") )
				( member ( signalRef "@baseboard_fab2_lib.baseboard_fab2(sch_1):m_b_ecc(2)") )
				( member ( signalRef "@baseboard_fab2_lib.baseboard_fab2(sch_1):m_b_ecc(3)") )
				( member ( signalRef "@baseboard_fab2_lib.baseboard_fab2(sch_1):m_b_ecc(4)") )
				( member ( signalRef "@baseboard_fab2_lib.baseboard_fab2(sch_1):m_b_ecc(5)") )
				( member ( signalRef "@baseboard_fab2_lib.baseboard_fab2(sch_1):m_b_ecc(6)") )
				( member ( signalRef "@baseboard_fab2_lib.baseboard_fab2(sch_1):m_b_ecc(7)") )
				( member ( signalRef "@baseboard_fab2_lib.baseboard_fab2(sch_1):m_c_ecc(0)") )
				( member ( signalRef "@baseboard_fab2_lib.baseboard_fab2(sch_1):m_c_ecc(1)") )
				( member ( signalRef "@baseboard_fab2_lib.baseboard_fab2(sch_1):m_c_ecc(2)") )
				( member ( signalRef "@baseboard_fab2_lib.baseboard_fab2(sch_1):m_c_ecc(3)") )
				( member ( signalRef "@baseboard_fab2_lib.baseboard_fab2(sch_1):m_c_ecc(4)") )
				( member ( signalRef "@baseboard_fab2_lib.baseboard_fab2(sch_1):m_c_ecc(5)") )
				( member ( signalRef "@baseboard_fab2_lib.baseboard_fab2(sch_1):m_c_ecc(6)") )
				( member ( signalRef "@baseboard_fab2_lib.baseboard_fab2(sch_1):m_c_ecc(7)") )
				( member ( signalRef "@baseboard_fab2_lib.baseboard_fab2(sch_1):m_d_ecc(0)") )
				( member ( signalRef "@baseboard_fab2_lib.baseboard_fab2(sch_1):m_d_ecc(1)") )
				( member ( signalRef "@baseboard_fab2_lib.baseboard_fab2(sch_1):m_d_ecc(2)") )
				( member ( signalRef "@baseboard_fab2_lib.baseboard_fab2(sch_1):m_d_ecc(3)") )
				( member ( signalRef "@baseboard_fab2_lib.baseboard_fab2(sch_1):m_d_ecc(4)") )
				( member ( signalRef "@baseboard_fab2_lib.baseboard_fab2(sch_1):m_d_ecc(5)") )
				( member ( signalRef "@baseboard_fab2_lib.baseboard_fab2(sch_1):m_d_ecc(6)") )
				( member ( signalRef "@baseboard_fab2_lib.baseboard_fab2(sch_1):m_d_ecc(7)") )
				( member ( signalRef "@baseboard_fab2_lib.baseboard_fab2(sch_1):m_e_ecc(0)") )
				( member ( signalRef "@baseboard_fab2_lib.baseboard_fab2(sch_1):m_e_ecc(1)") )
				( member ( signalRef "@baseboard_fab2_lib.baseboard_fab2(sch_1):m_e_ecc(2)") )
				( member ( signalRef "@baseboard_fab2_lib.baseboard_fab2(sch_1):m_e_ecc(3)") )
				( member ( signalRef "@baseboard_fab2_lib.baseboard_fab2(sch_1):m_e_ecc(4)") )
				( member ( signalRef "@baseboard_fab2_lib.baseboard_fab2(sch_1):m_e_ecc(5)") )
				( member ( signalRef "@baseboard_fab2_lib.baseboard_fab2(sch_1):m_e_ecc(6)") )
				( member ( signalRef "@baseboard_fab2_lib.baseboard_fab2(sch_1):m_e_ecc(7)") )
				( member ( signalRef "@baseboard_fab2_lib.baseboard_fab2(sch_1):m_d_dq(37)") )
				( member ( signalRef "@baseboard_fab2_lib.baseboard_fab2(sch_1):m_d_dq(38)") )
				( member ( signalRef "@baseboard_fab2_lib.baseboard_fab2(sch_1):m_d_dq(39)") )
				( member ( signalRef "@baseboard_fab2_lib.baseboard_fab2(sch_1):m_d_dq(40)") )
				( member ( signalRef "@baseboard_fab2_lib.baseboard_fab2(sch_1):m_d_dq(41)") )
				( member ( signalRef "@baseboard_fab2_lib.baseboard_fab2(sch_1):m_d_dq(42)") )
				( member ( signalRef "@baseboard_fab2_lib.baseboard_fab2(sch_1):m_d_dq(43)") )
				( member ( signalRef "@baseboard_fab2_lib.baseboard_fab2(sch_1):m_d_dq(44)") )
				( member ( signalRef "@baseboard_fab2_lib.baseboard_fab2(sch_1):m_d_dq(45)") )
				( member ( signalRef "@baseboard_fab2_lib.baseboard_fab2(sch_1):m_d_dq(46)") )
				( member ( signalRef "@baseboard_fab2_lib.baseboard_fab2(sch_1):m_d_dq(47)") )
				( member ( signalRef "@baseboard_fab2_lib.baseboard_fab2(sch_1):m_d_dq(48)") )
				( member ( signalRef "@baseboard_fab2_lib.baseboard_fab2(sch_1):m_d_dq(49)") )
				( member ( signalRef "@baseboard_fab2_lib.baseboard_fab2(sch_1):m_d_dq(50)") )
				( member ( signalRef "@baseboard_fab2_lib.baseboard_fab2(sch_1):m_d_dq(51)") )
				( member ( signalRef "@baseboard_fab2_lib.baseboard_fab2(sch_1):m_d_dq(52)") )
				( member ( signalRef "@baseboard_fab2_lib.baseboard_fab2(sch_1):m_d_dq(53)") )
				( member ( signalRef "@baseboard_fab2_lib.baseboard_fab2(sch_1):m_d_dq(54)") )
				( member ( signalRef "@baseboard_fab2_lib.baseboard_fab2(sch_1):m_d_dq(55)") )
				( member ( signalRef "@baseboard_fab2_lib.baseboard_fab2(sch_1):m_d_dq(56)") )
				( member ( signalRef "@baseboard_fab2_lib.baseboard_fab2(sch_1):m_d_dq(57)") )
				( member ( signalRef "@baseboard_fab2_lib.baseboard_fab2(sch_1):m_d_dq(58)") )
				( member ( signalRef "@baseboard_fab2_lib.baseboard_fab2(sch_1):m_d_dq(59)") )
				( member ( signalRef "@baseboard_fab2_lib.baseboard_fab2(sch_1):m_d_dq(60)") )
				( member ( signalRef "@baseboard_fab2_lib.baseboard_fab2(sch_1):m_d_dq(61)") )
				( member ( signalRef "@baseboard_fab2_lib.baseboard_fab2(sch_1):m_d_dq(62)") )
				( member ( signalRef "@baseboard_fab2_lib.baseboard_fab2(sch_1):m_d_dq(63)") )
				( member ( signalRef "@baseboard_fab2_lib.baseboard_fab2(sch_1):m_e_dq(0)") )
				( member ( signalRef "@baseboard_fab2_lib.baseboard_fab2(sch_1):m_e_dq(1)") )
				( member ( signalRef "@baseboard_fab2_lib.baseboard_fab2(sch_1):m_e_dq(2)") )
				( member ( signalRef "@baseboard_fab2_lib.baseboard_fab2(sch_1):m_e_dq(3)") )
				( member ( signalRef "@baseboard_fab2_lib.baseboard_fab2(sch_1):m_e_dq(4)") )
				( member ( signalRef "@baseboard_fab2_lib.baseboard_fab2(sch_1):m_e_dq(5)") )
				( member ( signalRef "@baseboard_fab2_lib.baseboard_fab2(sch_1):m_e_dq(6)") )
				( member ( signalRef "@baseboard_fab2_lib.baseboard_fab2(sch_1):m_e_dq(7)") )
				( member ( signalRef "@baseboard_fab2_lib.baseboard_fab2(sch_1):m_e_dq(8)") )
				( member ( signalRef "@baseboard_fab2_lib.baseboard_fab2(sch_1):m_e_dq(9)") )
				( member ( signalRef "@baseboard_fab2_lib.baseboard_fab2(sch_1):m_e_dq(10)") )
				( member ( signalRef "@baseboard_fab2_lib.baseboard_fab2(sch_1):m_e_dq(11)") )
				( member ( signalRef "@baseboard_fab2_lib.baseboard_fab2(sch_1):m_e_dq(12)") )
				( member ( signalRef "@baseboard_fab2_lib.baseboard_fab2(sch_1):m_e_dq(13)") )
				( member ( signalRef "@baseboard_fab2_lib.baseboard_fab2(sch_1):m_e_dq(14)") )
				( member ( signalRef "@baseboard_fab2_lib.baseboard_fab2(sch_1):m_e_dq(15)") )
				( member ( signalRef "@baseboard_fab2_lib.baseboard_fab2(sch_1):m_e_dq(16)") )
				( member ( signalRef "@baseboard_fab2_lib.baseboard_fab2(sch_1):m_e_dq(17)") )
				( member ( signalRef "@baseboard_fab2_lib.baseboard_fab2(sch_1):m_e_dq(18)") )
				( member ( signalRef "@baseboard_fab2_lib.baseboard_fab2(sch_1):m_e_dq(19)") )
				( member ( signalRef "@baseboard_fab2_lib.baseboard_fab2(sch_1):m_e_dq(20)") )
				( member ( signalRef "@baseboard_fab2_lib.baseboard_fab2(sch_1):m_e_dq(21)") )
				( member ( signalRef "@baseboard_fab2_lib.baseboard_fab2(sch_1):m_e_dq(22)") )
				( member ( signalRef "@baseboard_fab2_lib.baseboard_fab2(sch_1):m_e_dq(23)") )
				( member ( signalRef "@baseboard_fab2_lib.baseboard_fab2(sch_1):m_e_dq(24)") )
				( member ( signalRef "@baseboard_fab2_lib.baseboard_fab2(sch_1):m_e_dq(25)") )
				( member ( signalRef "@baseboard_fab2_lib.baseboard_fab2(sch_1):m_e_dq(26)") )
				( member ( signalRef "@baseboard_fab2_lib.baseboard_fab2(sch_1):m_e_dq(27)") )
				( member ( signalRef "@baseboard_fab2_lib.baseboard_fab2(sch_1):m_e_dq(28)") )
				( member ( signalRef "@baseboard_fab2_lib.baseboard_fab2(sch_1):m_e_dq(29)") )
				( member ( signalRef "@baseboard_fab2_lib.baseboard_fab2(sch_1):m_e_dq(30)") )
				( member ( signalRef "@baseboard_fab2_lib.baseboard_fab2(sch_1):m_e_dq(31)") )
				( member ( signalRef "@baseboard_fab2_lib.baseboard_fab2(sch_1):m_e_dq(32)") )
				( member ( signalRef "@baseboard_fab2_lib.baseboard_fab2(sch_1):m_e_dq(33)") )
				( member ( signalRef "@baseboard_fab2_lib.baseboard_fab2(sch_1):m_e_dq(34)") )
				( member ( signalRef "@baseboard_fab2_lib.baseboard_fab2(sch_1):m_e_dq(35)") )
				( member ( signalRef "@baseboard_fab2_lib.baseboard_fab2(sch_1):m_e_dq(36)") )
				( member ( signalRef "@baseboard_fab2_lib.baseboard_fab2(sch_1):m_e_dq(37)") )
				( member ( signalRef "@baseboard_fab2_lib.baseboard_fab2(sch_1):m_e_dq(38)") )
				( member ( signalRef "@baseboard_fab2_lib.baseboard_fab2(sch_1):m_e_dq(39)") )
				( member ( signalRef "@baseboard_fab2_lib.baseboard_fab2(sch_1):m_e_dq(40)") )
				( member ( signalRef "@baseboard_fab2_lib.baseboard_fab2(sch_1):m_e_dq(41)") )
				( member ( signalRef "@baseboard_fab2_lib.baseboard_fab2(sch_1):m_e_dq(42)") )
				( member ( signalRef "@baseboard_fab2_lib.baseboard_fab2(sch_1):m_e_dq(43)") )
				( member ( signalRef "@baseboard_fab2_lib.baseboard_fab2(sch_1):m_e_dq(44)") )
				( member ( signalRef "@baseboard_fab2_lib.baseboard_fab2(sch_1):m_e_dq(45)") )
				( member ( signalRef "@baseboard_fab2_lib.baseboard_fab2(sch_1):m_e_dq(46)") )
				( member ( signalRef "@baseboard_fab2_lib.baseboard_fab2(sch_1):m_e_dq(47)") )
				( member ( signalRef "@baseboard_fab2_lib.baseboard_fab2(sch_1):m_e_dq(48)") )
				( member ( signalRef "@baseboard_fab2_lib.baseboard_fab2(sch_1):m_e_dq(49)") )
				( member ( signalRef "@baseboard_fab2_lib.baseboard_fab2(sch_1):m_e_dq(50)") )
				( member ( signalRef "@baseboard_fab2_lib.baseboard_fab2(sch_1):m_e_dq(51)") )
				( member ( signalRef "@baseboard_fab2_lib.baseboard_fab2(sch_1):m_e_dq(52)") )
				( member ( signalRef "@baseboard_fab2_lib.baseboard_fab2(sch_1):m_e_dq(53)") )
				( member ( signalRef "@baseboard_fab2_lib.baseboard_fab2(sch_1):m_e_dq(54)") )
				( member ( signalRef "@baseboard_fab2_lib.baseboard_fab2(sch_1):m_e_dq(55)") )
				( member ( signalRef "@baseboard_fab2_lib.baseboard_fab2(sch_1):m_e_dq(56)") )
				( member ( signalRef "@baseboard_fab2_lib.baseboard_fab2(sch_1):m_e_dq(57)") )
				( member ( signalRef "@baseboard_fab2_lib.baseboard_fab2(sch_1):m_e_dq(58)") )
				( member ( signalRef "@baseboard_fab2_lib.baseboard_fab2(sch_1):m_e_dq(59)") )
				( member ( signalRef "@baseboard_fab2_lib.baseboard_fab2(sch_1):m_e_dq(60)") )
				( member ( signalRef "@baseboard_fab2_lib.baseboard_fab2(sch_1):m_e_dq(61)") )
				( member ( signalRef "@baseboard_fab2_lib.baseboard_fab2(sch_1):m_e_dq(62)") )
				( member ( signalRef "@baseboard_fab2_lib.baseboard_fab2(sch_1):m_e_dq(63)") )
				( member ( signalRef "@baseboard_fab2_lib.baseboard_fab2(sch_1):m_f_dq(0)") )
				( member ( signalRef "@baseboard_fab2_lib.baseboard_fab2(sch_1):m_f_dq(1)") )
				( member ( signalRef "@baseboard_fab2_lib.baseboard_fab2(sch_1):m_f_dq(2)") )
				( member ( signalRef "@baseboard_fab2_lib.baseboard_fab2(sch_1):m_f_dq(3)") )
				( member ( signalRef "@baseboard_fab2_lib.baseboard_fab2(sch_1):m_f_dq(4)") )
				( member ( signalRef "@baseboard_fab2_lib.baseboard_fab2(sch_1):m_f_dq(5)") )
				( member ( signalRef "@baseboard_fab2_lib.baseboard_fab2(sch_1):m_f_dq(6)") )
				( member ( signalRef "@baseboard_fab2_lib.baseboard_fab2(sch_1):m_f_dq(7)") )
				( member ( signalRef "@baseboard_fab2_lib.baseboard_fab2(sch_1):m_f_dq(8)") )
				( member ( signalRef "@baseboard_fab2_lib.baseboard_fab2(sch_1):m_c_dq(1)") )
				( member ( signalRef "@baseboard_fab2_lib.baseboard_fab2(sch_1):m_c_dq(2)") )
				( member ( signalRef "@baseboard_fab2_lib.baseboard_fab2(sch_1):m_c_dq(3)") )
				( member ( signalRef "@baseboard_fab2_lib.baseboard_fab2(sch_1):m_c_dq(4)") )
				( member ( signalRef "@baseboard_fab2_lib.baseboard_fab2(sch_1):m_c_dq(5)") )
				( member ( signalRef "@baseboard_fab2_lib.baseboard_fab2(sch_1):m_c_dq(6)") )
				( member ( signalRef "@baseboard_fab2_lib.baseboard_fab2(sch_1):m_c_dq(7)") )
				( member ( signalRef "@baseboard_fab2_lib.baseboard_fab2(sch_1):m_c_dq(8)") )
				( member ( signalRef "@baseboard_fab2_lib.baseboard_fab2(sch_1):m_c_dq(9)") )
				( member ( signalRef "@baseboard_fab2_lib.baseboard_fab2(sch_1):m_c_dq(10)") )
				( member ( signalRef "@baseboard_fab2_lib.baseboard_fab2(sch_1):m_c_dq(11)") )
				( member ( signalRef "@baseboard_fab2_lib.baseboard_fab2(sch_1):m_c_dq(12)") )
				( member ( signalRef "@baseboard_fab2_lib.baseboard_fab2(sch_1):m_c_dq(13)") )
				( member ( signalRef "@baseboard_fab2_lib.baseboard_fab2(sch_1):m_c_dq(14)") )
				( member ( signalRef "@baseboard_fab2_lib.baseboard_fab2(sch_1):m_c_dq(15)") )
				( member ( signalRef "@baseboard_fab2_lib.baseboard_fab2(sch_1):m_c_dq(16)") )
				( member ( signalRef "@baseboard_fab2_lib.baseboard_fab2(sch_1):m_c_dq(17)") )
				( member ( signalRef "@baseboard_fab2_lib.baseboard_fab2(sch_1):m_c_dq(18)") )
				( member ( signalRef "@baseboard_fab2_lib.baseboard_fab2(sch_1):m_c_dq(19)") )
				( member ( signalRef "@baseboard_fab2_lib.baseboard_fab2(sch_1):m_c_dq(20)") )
				( member ( signalRef "@baseboard_fab2_lib.baseboard_fab2(sch_1):m_c_dq(21)") )
				( member ( signalRef "@baseboard_fab2_lib.baseboard_fab2(sch_1):m_c_dq(22)") )
				( member ( signalRef "@baseboard_fab2_lib.baseboard_fab2(sch_1):m_c_dq(23)") )
				( member ( signalRef "@baseboard_fab2_lib.baseboard_fab2(sch_1):m_c_dq(24)") )
				( member ( signalRef "@baseboard_fab2_lib.baseboard_fab2(sch_1):m_c_dq(25)") )
				( member ( signalRef "@baseboard_fab2_lib.baseboard_fab2(sch_1):m_c_dq(26)") )
				( member ( signalRef "@baseboard_fab2_lib.baseboard_fab2(sch_1):m_c_dq(27)") )
				( member ( signalRef "@baseboard_fab2_lib.baseboard_fab2(sch_1):m_c_dq(28)") )
				( member ( signalRef "@baseboard_fab2_lib.baseboard_fab2(sch_1):m_c_dq(29)") )
				( member ( signalRef "@baseboard_fab2_lib.baseboard_fab2(sch_1):m_c_dq(30)") )
				( member ( signalRef "@baseboard_fab2_lib.baseboard_fab2(sch_1):m_c_dq(31)") )
				( member ( signalRef "@baseboard_fab2_lib.baseboard_fab2(sch_1):m_c_dq(32)") )
				( member ( signalRef "@baseboard_fab2_lib.baseboard_fab2(sch_1):m_c_dq(33)") )
				( member ( signalRef "@baseboard_fab2_lib.baseboard_fab2(sch_1):m_c_dq(34)") )
				( member ( signalRef "@baseboard_fab2_lib.baseboard_fab2(sch_1):m_c_dq(35)") )
				( member ( signalRef "@baseboard_fab2_lib.baseboard_fab2(sch_1):m_c_dq(36)") )
				( member ( signalRef "@baseboard_fab2_lib.baseboard_fab2(sch_1):m_c_dq(37)") )
				( member ( signalRef "@baseboard_fab2_lib.baseboard_fab2(sch_1):m_c_dq(38)") )
				( member ( signalRef "@baseboard_fab2_lib.baseboard_fab2(sch_1):m_c_dq(39)") )
				( member ( signalRef "@baseboard_fab2_lib.baseboard_fab2(sch_1):m_c_dq(40)") )
				( member ( signalRef "@baseboard_fab2_lib.baseboard_fab2(sch_1):m_c_dq(41)") )
				( member ( signalRef "@baseboard_fab2_lib.baseboard_fab2(sch_1):m_c_dq(42)") )
				( member ( signalRef "@baseboard_fab2_lib.baseboard_fab2(sch_1):m_c_dq(43)") )
				( member ( signalRef "@baseboard_fab2_lib.baseboard_fab2(sch_1):m_c_dq(44)") )
				( member ( signalRef "@baseboard_fab2_lib.baseboard_fab2(sch_1):m_c_dq(45)") )
				( member ( signalRef "@baseboard_fab2_lib.baseboard_fab2(sch_1):m_c_dq(46)") )
				( member ( signalRef "@baseboard_fab2_lib.baseboard_fab2(sch_1):m_c_dq(47)") )
				( member ( signalRef "@baseboard_fab2_lib.baseboard_fab2(sch_1):m_c_dq(48)") )
				( member ( signalRef "@baseboard_fab2_lib.baseboard_fab2(sch_1):m_c_dq(49)") )
				( member ( signalRef "@baseboard_fab2_lib.baseboard_fab2(sch_1):m_c_dq(50)") )
				( member ( signalRef "@baseboard_fab2_lib.baseboard_fab2(sch_1):m_c_dq(51)") )
				( member ( signalRef "@baseboard_fab2_lib.baseboard_fab2(sch_1):m_c_dq(52)") )
				( member ( signalRef "@baseboard_fab2_lib.baseboard_fab2(sch_1):m_c_dq(53)") )
				( member ( signalRef "@baseboard_fab2_lib.baseboard_fab2(sch_1):m_c_dq(54)") )
				( member ( signalRef "@baseboard_fab2_lib.baseboard_fab2(sch_1):m_c_dq(55)") )
				( member ( signalRef "@baseboard_fab2_lib.baseboard_fab2(sch_1):m_c_dq(56)") )
				( member ( signalRef "@baseboard_fab2_lib.baseboard_fab2(sch_1):m_c_dq(57)") )
				( member ( signalRef "@baseboard_fab2_lib.baseboard_fab2(sch_1):m_c_dq(58)") )
				( member ( signalRef "@baseboard_fab2_lib.baseboard_fab2(sch_1):m_c_dq(59)") )
				( member ( signalRef "@baseboard_fab2_lib.baseboard_fab2(sch_1):m_c_dq(60)") )
				( member ( signalRef "@baseboard_fab2_lib.baseboard_fab2(sch_1):m_c_dq(61)") )
				( member ( signalRef "@baseboard_fab2_lib.baseboard_fab2(sch_1):m_c_dq(62)") )
				( member ( signalRef "@baseboard_fab2_lib.baseboard_fab2(sch_1):m_c_dq(63)") )
				( member ( signalRef "@baseboard_fab2_lib.baseboard_fab2(sch_1):m_d_dq(0)") )
				( member ( signalRef "@baseboard_fab2_lib.baseboard_fab2(sch_1):m_d_dq(1)") )
				( member ( signalRef "@baseboard_fab2_lib.baseboard_fab2(sch_1):m_d_dq(2)") )
				( member ( signalRef "@baseboard_fab2_lib.baseboard_fab2(sch_1):m_d_dq(3)") )
				( member ( signalRef "@baseboard_fab2_lib.baseboard_fab2(sch_1):m_d_dq(4)") )
				( member ( signalRef "@baseboard_fab2_lib.baseboard_fab2(sch_1):m_d_dq(5)") )
				( member ( signalRef "@baseboard_fab2_lib.baseboard_fab2(sch_1):m_d_dq(6)") )
				( member ( signalRef "@baseboard_fab2_lib.baseboard_fab2(sch_1):m_d_dq(7)") )
				( member ( signalRef "@baseboard_fab2_lib.baseboard_fab2(sch_1):m_d_dq(8)") )
				( member ( signalRef "@baseboard_fab2_lib.baseboard_fab2(sch_1):m_d_dq(9)") )
				( member ( signalRef "@baseboard_fab2_lib.baseboard_fab2(sch_1):m_d_dq(10)") )
				( member ( signalRef "@baseboard_fab2_lib.baseboard_fab2(sch_1):m_d_dq(11)") )
				( member ( signalRef "@baseboard_fab2_lib.baseboard_fab2(sch_1):m_d_dq(12)") )
				( member ( signalRef "@baseboard_fab2_lib.baseboard_fab2(sch_1):m_d_dq(13)") )
				( member ( signalRef "@baseboard_fab2_lib.baseboard_fab2(sch_1):m_d_dq(14)") )
				( member ( signalRef "@baseboard_fab2_lib.baseboard_fab2(sch_1):m_d_dq(15)") )
				( member ( signalRef "@baseboard_fab2_lib.baseboard_fab2(sch_1):m_d_dq(16)") )
				( member ( signalRef "@baseboard_fab2_lib.baseboard_fab2(sch_1):m_d_dq(17)") )
				( member ( signalRef "@baseboard_fab2_lib.baseboard_fab2(sch_1):m_d_dq(18)") )
				( member ( signalRef "@baseboard_fab2_lib.baseboard_fab2(sch_1):m_d_dq(19)") )
				( member ( signalRef "@baseboard_fab2_lib.baseboard_fab2(sch_1):m_d_dq(20)") )
				( member ( signalRef "@baseboard_fab2_lib.baseboard_fab2(sch_1):m_d_dq(21)") )
				( member ( signalRef "@baseboard_fab2_lib.baseboard_fab2(sch_1):m_d_dq(22)") )
				( member ( signalRef "@baseboard_fab2_lib.baseboard_fab2(sch_1):m_d_dq(23)") )
				( member ( signalRef "@baseboard_fab2_lib.baseboard_fab2(sch_1):m_d_dq(24)") )
				( member ( signalRef "@baseboard_fab2_lib.baseboard_fab2(sch_1):m_d_dq(25)") )
				( member ( signalRef "@baseboard_fab2_lib.baseboard_fab2(sch_1):m_d_dq(26)") )
				( member ( signalRef "@baseboard_fab2_lib.baseboard_fab2(sch_1):m_d_dq(27)") )
				( member ( signalRef "@baseboard_fab2_lib.baseboard_fab2(sch_1):m_d_dq(28)") )
				( member ( signalRef "@baseboard_fab2_lib.baseboard_fab2(sch_1):m_d_dq(29)") )
				( member ( signalRef "@baseboard_fab2_lib.baseboard_fab2(sch_1):m_d_dq(30)") )
				( member ( signalRef "@baseboard_fab2_lib.baseboard_fab2(sch_1):m_d_dq(31)") )
				( member ( signalRef "@baseboard_fab2_lib.baseboard_fab2(sch_1):m_d_dq(32)") )
				( member ( signalRef "@baseboard_fab2_lib.baseboard_fab2(sch_1):m_d_dq(33)") )
				( member ( signalRef "@baseboard_fab2_lib.baseboard_fab2(sch_1):m_d_dq(34)") )
				( member ( signalRef "@baseboard_fab2_lib.baseboard_fab2(sch_1):m_d_dq(35)") )
				( member ( signalRef "@baseboard_fab2_lib.baseboard_fab2(sch_1):m_d_dq(36)") )
				( member ( signalRef "@baseboard_fab2_lib.baseboard_fab2(sch_1):m_m_dq(29)") )
				( member ( signalRef "@baseboard_fab2_lib.baseboard_fab2(sch_1):m_m_dq(30)") )
				( member ( signalRef "@baseboard_fab2_lib.baseboard_fab2(sch_1):m_m_dq(31)") )
				( member ( signalRef "@baseboard_fab2_lib.baseboard_fab2(sch_1):m_m_dq(32)") )
				( member ( signalRef "@baseboard_fab2_lib.baseboard_fab2(sch_1):m_m_dq(33)") )
				( member ( signalRef "@baseboard_fab2_lib.baseboard_fab2(sch_1):m_m_dq(34)") )
				( member ( signalRef "@baseboard_fab2_lib.baseboard_fab2(sch_1):m_m_dq(35)") )
				( member ( signalRef "@baseboard_fab2_lib.baseboard_fab2(sch_1):m_m_dq(36)") )
				( member ( signalRef "@baseboard_fab2_lib.baseboard_fab2(sch_1):m_m_dq(37)") )
				( member ( signalRef "@baseboard_fab2_lib.baseboard_fab2(sch_1):m_m_dq(38)") )
				( member ( signalRef "@baseboard_fab2_lib.baseboard_fab2(sch_1):m_m_dq(39)") )
				( member ( signalRef "@baseboard_fab2_lib.baseboard_fab2(sch_1):m_m_dq(40)") )
				( member ( signalRef "@baseboard_fab2_lib.baseboard_fab2(sch_1):m_m_dq(41)") )
				( member ( signalRef "@baseboard_fab2_lib.baseboard_fab2(sch_1):m_m_dq(42)") )
				( member ( signalRef "@baseboard_fab2_lib.baseboard_fab2(sch_1):m_m_dq(43)") )
				( member ( signalRef "@baseboard_fab2_lib.baseboard_fab2(sch_1):m_m_dq(44)") )
				( member ( signalRef "@baseboard_fab2_lib.baseboard_fab2(sch_1):m_m_dq(45)") )
				( member ( signalRef "@baseboard_fab2_lib.baseboard_fab2(sch_1):m_m_dq(46)") )
				( member ( signalRef "@baseboard_fab2_lib.baseboard_fab2(sch_1):m_m_dq(47)") )
				( member ( signalRef "@baseboard_fab2_lib.baseboard_fab2(sch_1):m_m_dq(48)") )
				( member ( signalRef "@baseboard_fab2_lib.baseboard_fab2(sch_1):m_m_dq(49)") )
				( member ( signalRef "@baseboard_fab2_lib.baseboard_fab2(sch_1):m_m_dq(50)") )
				( member ( signalRef "@baseboard_fab2_lib.baseboard_fab2(sch_1):m_m_dq(51)") )
				( member ( signalRef "@baseboard_fab2_lib.baseboard_fab2(sch_1):m_m_dq(52)") )
				( member ( signalRef "@baseboard_fab2_lib.baseboard_fab2(sch_1):m_m_dq(53)") )
				( member ( signalRef "@baseboard_fab2_lib.baseboard_fab2(sch_1):m_m_dq(54)") )
				( member ( signalRef "@baseboard_fab2_lib.baseboard_fab2(sch_1):m_m_dq(55)") )
				( member ( signalRef "@baseboard_fab2_lib.baseboard_fab2(sch_1):m_m_dq(56)") )
				( member ( signalRef "@baseboard_fab2_lib.baseboard_fab2(sch_1):m_m_dq(57)") )
				( member ( signalRef "@baseboard_fab2_lib.baseboard_fab2(sch_1):m_m_dq(58)") )
				( member ( signalRef "@baseboard_fab2_lib.baseboard_fab2(sch_1):m_m_dq(59)") )
				( member ( signalRef "@baseboard_fab2_lib.baseboard_fab2(sch_1):m_m_dq(60)") )
				( member ( signalRef "@baseboard_fab2_lib.baseboard_fab2(sch_1):m_m_dq(61)") )
				( member ( signalRef "@baseboard_fab2_lib.baseboard_fab2(sch_1):m_m_dq(62)") )
				( member ( signalRef "@baseboard_fab2_lib.baseboard_fab2(sch_1):m_m_dq(63)") )
				( member ( signalRef "@baseboard_fab2_lib.baseboard_fab2(sch_1):m_b_dq(0)") )
				( member ( signalRef "@baseboard_fab2_lib.baseboard_fab2(sch_1):m_b_dq(1)") )
				( member ( signalRef "@baseboard_fab2_lib.baseboard_fab2(sch_1):m_b_dq(2)") )
				( member ( signalRef "@baseboard_fab2_lib.baseboard_fab2(sch_1):m_b_dq(3)") )
				( member ( signalRef "@baseboard_fab2_lib.baseboard_fab2(sch_1):m_b_dq(4)") )
				( member ( signalRef "@baseboard_fab2_lib.baseboard_fab2(sch_1):m_b_dq(5)") )
				( member ( signalRef "@baseboard_fab2_lib.baseboard_fab2(sch_1):m_b_dq(6)") )
				( member ( signalRef "@baseboard_fab2_lib.baseboard_fab2(sch_1):m_b_dq(7)") )
				( member ( signalRef "@baseboard_fab2_lib.baseboard_fab2(sch_1):m_b_dq(8)") )
				( member ( signalRef "@baseboard_fab2_lib.baseboard_fab2(sch_1):m_b_dq(9)") )
				( member ( signalRef "@baseboard_fab2_lib.baseboard_fab2(sch_1):m_b_dq(10)") )
				( member ( signalRef "@baseboard_fab2_lib.baseboard_fab2(sch_1):m_b_dq(11)") )
				( member ( signalRef "@baseboard_fab2_lib.baseboard_fab2(sch_1):m_b_dq(12)") )
				( member ( signalRef "@baseboard_fab2_lib.baseboard_fab2(sch_1):m_b_dq(13)") )
				( member ( signalRef "@baseboard_fab2_lib.baseboard_fab2(sch_1):m_b_dq(14)") )
				( member ( signalRef "@baseboard_fab2_lib.baseboard_fab2(sch_1):m_b_dq(15)") )
				( member ( signalRef "@baseboard_fab2_lib.baseboard_fab2(sch_1):m_b_dq(16)") )
				( member ( signalRef "@baseboard_fab2_lib.baseboard_fab2(sch_1):m_b_dq(17)") )
				( member ( signalRef "@baseboard_fab2_lib.baseboard_fab2(sch_1):m_b_dq(18)") )
				( member ( signalRef "@baseboard_fab2_lib.baseboard_fab2(sch_1):m_b_dq(19)") )
				( member ( signalRef "@baseboard_fab2_lib.baseboard_fab2(sch_1):m_b_dq(20)") )
				( member ( signalRef "@baseboard_fab2_lib.baseboard_fab2(sch_1):m_b_dq(21)") )
				( member ( signalRef "@baseboard_fab2_lib.baseboard_fab2(sch_1):m_b_dq(22)") )
				( member ( signalRef "@baseboard_fab2_lib.baseboard_fab2(sch_1):m_b_dq(23)") )
				( member ( signalRef "@baseboard_fab2_lib.baseboard_fab2(sch_1):m_b_dq(24)") )
				( member ( signalRef "@baseboard_fab2_lib.baseboard_fab2(sch_1):m_b_dq(25)") )
				( member ( signalRef "@baseboard_fab2_lib.baseboard_fab2(sch_1):m_b_dq(26)") )
				( member ( signalRef "@baseboard_fab2_lib.baseboard_fab2(sch_1):m_b_dq(27)") )
				( member ( signalRef "@baseboard_fab2_lib.baseboard_fab2(sch_1):m_b_dq(28)") )
				( member ( signalRef "@baseboard_fab2_lib.baseboard_fab2(sch_1):m_b_dq(29)") )
				( member ( signalRef "@baseboard_fab2_lib.baseboard_fab2(sch_1):m_b_dq(30)") )
				( member ( signalRef "@baseboard_fab2_lib.baseboard_fab2(sch_1):m_b_dq(31)") )
				( member ( signalRef "@baseboard_fab2_lib.baseboard_fab2(sch_1):m_b_dq(32)") )
				( member ( signalRef "@baseboard_fab2_lib.baseboard_fab2(sch_1):m_b_dq(33)") )
				( member ( signalRef "@baseboard_fab2_lib.baseboard_fab2(sch_1):m_b_dq(34)") )
				( member ( signalRef "@baseboard_fab2_lib.baseboard_fab2(sch_1):m_b_dq(35)") )
				( member ( signalRef "@baseboard_fab2_lib.baseboard_fab2(sch_1):m_b_dq(36)") )
				( member ( signalRef "@baseboard_fab2_lib.baseboard_fab2(sch_1):m_b_dq(37)") )
				( member ( signalRef "@baseboard_fab2_lib.baseboard_fab2(sch_1):m_b_dq(38)") )
				( member ( signalRef "@baseboard_fab2_lib.baseboard_fab2(sch_1):m_b_dq(39)") )
				( member ( signalRef "@baseboard_fab2_lib.baseboard_fab2(sch_1):m_b_dq(40)") )
				( member ( signalRef "@baseboard_fab2_lib.baseboard_fab2(sch_1):m_b_dq(41)") )
				( member ( signalRef "@baseboard_fab2_lib.baseboard_fab2(sch_1):m_b_dq(42)") )
				( member ( signalRef "@baseboard_fab2_lib.baseboard_fab2(sch_1):m_b_dq(43)") )
				( member ( signalRef "@baseboard_fab2_lib.baseboard_fab2(sch_1):m_b_dq(44)") )
				( member ( signalRef "@baseboard_fab2_lib.baseboard_fab2(sch_1):m_b_dq(45)") )
				( member ( signalRef "@baseboard_fab2_lib.baseboard_fab2(sch_1):m_b_dq(46)") )
				( member ( signalRef "@baseboard_fab2_lib.baseboard_fab2(sch_1):m_b_dq(47)") )
				( member ( signalRef "@baseboard_fab2_lib.baseboard_fab2(sch_1):m_b_dq(48)") )
				( member ( signalRef "@baseboard_fab2_lib.baseboard_fab2(sch_1):m_b_dq(49)") )
				( member ( signalRef "@baseboard_fab2_lib.baseboard_fab2(sch_1):m_b_dq(50)") )
				( member ( signalRef "@baseboard_fab2_lib.baseboard_fab2(sch_1):m_b_dq(51)") )
				( member ( signalRef "@baseboard_fab2_lib.baseboard_fab2(sch_1):m_b_dq(52)") )
				( member ( signalRef "@baseboard_fab2_lib.baseboard_fab2(sch_1):m_b_dq(53)") )
				( member ( signalRef "@baseboard_fab2_lib.baseboard_fab2(sch_1):m_b_dq(54)") )
				( member ( signalRef "@baseboard_fab2_lib.baseboard_fab2(sch_1):m_b_dq(55)") )
				( member ( signalRef "@baseboard_fab2_lib.baseboard_fab2(sch_1):m_b_dq(56)") )
				( member ( signalRef "@baseboard_fab2_lib.baseboard_fab2(sch_1):m_b_dq(57)") )
				( member ( signalRef "@baseboard_fab2_lib.baseboard_fab2(sch_1):m_b_dq(58)") )
				( member ( signalRef "@baseboard_fab2_lib.baseboard_fab2(sch_1):m_b_dq(59)") )
				( member ( signalRef "@baseboard_fab2_lib.baseboard_fab2(sch_1):m_b_dq(60)") )
				( member ( signalRef "@baseboard_fab2_lib.baseboard_fab2(sch_1):m_b_dq(61)") )
				( member ( signalRef "@baseboard_fab2_lib.baseboard_fab2(sch_1):m_b_dq(62)") )
				( member ( signalRef "@baseboard_fab2_lib.baseboard_fab2(sch_1):m_b_dq(63)") )
				( member ( signalRef "@baseboard_fab2_lib.baseboard_fab2(sch_1):m_c_dq(0)") )
				( member ( signalRef "@baseboard_fab2_lib.baseboard_fab2(sch_1):m_k_dq(57)") )
				( member ( signalRef "@baseboard_fab2_lib.baseboard_fab2(sch_1):m_k_dq(58)") )
				( member ( signalRef "@baseboard_fab2_lib.baseboard_fab2(sch_1):m_k_dq(59)") )
				( member ( signalRef "@baseboard_fab2_lib.baseboard_fab2(sch_1):m_k_dq(60)") )
				( member ( signalRef "@baseboard_fab2_lib.baseboard_fab2(sch_1):m_k_dq(61)") )
				( member ( signalRef "@baseboard_fab2_lib.baseboard_fab2(sch_1):m_k_dq(62)") )
				( member ( signalRef "@baseboard_fab2_lib.baseboard_fab2(sch_1):m_k_dq(63)") )
				( member ( signalRef "@baseboard_fab2_lib.baseboard_fab2(sch_1):m_l_dq(0)") )
				( member ( signalRef "@baseboard_fab2_lib.baseboard_fab2(sch_1):m_l_dq(1)") )
				( member ( signalRef "@baseboard_fab2_lib.baseboard_fab2(sch_1):m_l_dq(2)") )
				( member ( signalRef "@baseboard_fab2_lib.baseboard_fab2(sch_1):m_l_dq(3)") )
				( member ( signalRef "@baseboard_fab2_lib.baseboard_fab2(sch_1):m_l_dq(4)") )
				( member ( signalRef "@baseboard_fab2_lib.baseboard_fab2(sch_1):m_l_dq(5)") )
				( member ( signalRef "@baseboard_fab2_lib.baseboard_fab2(sch_1):m_l_dq(6)") )
				( member ( signalRef "@baseboard_fab2_lib.baseboard_fab2(sch_1):m_l_dq(7)") )
				( member ( signalRef "@baseboard_fab2_lib.baseboard_fab2(sch_1):m_l_dq(8)") )
				( member ( signalRef "@baseboard_fab2_lib.baseboard_fab2(sch_1):m_l_dq(9)") )
				( member ( signalRef "@baseboard_fab2_lib.baseboard_fab2(sch_1):m_l_dq(10)") )
				( member ( signalRef "@baseboard_fab2_lib.baseboard_fab2(sch_1):m_l_dq(11)") )
				( member ( signalRef "@baseboard_fab2_lib.baseboard_fab2(sch_1):m_l_dq(12)") )
				( member ( signalRef "@baseboard_fab2_lib.baseboard_fab2(sch_1):m_l_dq(13)") )
				( member ( signalRef "@baseboard_fab2_lib.baseboard_fab2(sch_1):m_l_dq(14)") )
				( member ( signalRef "@baseboard_fab2_lib.baseboard_fab2(sch_1):m_l_dq(15)") )
				( member ( signalRef "@baseboard_fab2_lib.baseboard_fab2(sch_1):m_l_dq(16)") )
				( member ( signalRef "@baseboard_fab2_lib.baseboard_fab2(sch_1):m_l_dq(17)") )
				( member ( signalRef "@baseboard_fab2_lib.baseboard_fab2(sch_1):m_l_dq(18)") )
				( member ( signalRef "@baseboard_fab2_lib.baseboard_fab2(sch_1):m_l_dq(19)") )
				( member ( signalRef "@baseboard_fab2_lib.baseboard_fab2(sch_1):m_l_dq(20)") )
				( member ( signalRef "@baseboard_fab2_lib.baseboard_fab2(sch_1):m_l_dq(21)") )
				( member ( signalRef "@baseboard_fab2_lib.baseboard_fab2(sch_1):m_l_dq(22)") )
				( member ( signalRef "@baseboard_fab2_lib.baseboard_fab2(sch_1):m_l_dq(23)") )
				( member ( signalRef "@baseboard_fab2_lib.baseboard_fab2(sch_1):m_l_dq(24)") )
				( member ( signalRef "@baseboard_fab2_lib.baseboard_fab2(sch_1):m_l_dq(25)") )
				( member ( signalRef "@baseboard_fab2_lib.baseboard_fab2(sch_1):m_l_dq(26)") )
				( member ( signalRef "@baseboard_fab2_lib.baseboard_fab2(sch_1):m_l_dq(27)") )
				( member ( signalRef "@baseboard_fab2_lib.baseboard_fab2(sch_1):m_l_dq(28)") )
				( member ( signalRef "@baseboard_fab2_lib.baseboard_fab2(sch_1):m_l_dq(29)") )
				( member ( signalRef "@baseboard_fab2_lib.baseboard_fab2(sch_1):m_l_dq(30)") )
				( member ( signalRef "@baseboard_fab2_lib.baseboard_fab2(sch_1):m_l_dq(31)") )
				( member ( signalRef "@baseboard_fab2_lib.baseboard_fab2(sch_1):m_l_dq(32)") )
				( member ( signalRef "@baseboard_fab2_lib.baseboard_fab2(sch_1):m_l_dq(33)") )
				( member ( signalRef "@baseboard_fab2_lib.baseboard_fab2(sch_1):m_l_dq(34)") )
				( member ( signalRef "@baseboard_fab2_lib.baseboard_fab2(sch_1):m_l_dq(35)") )
				( member ( signalRef "@baseboard_fab2_lib.baseboard_fab2(sch_1):m_l_dq(36)") )
				( member ( signalRef "@baseboard_fab2_lib.baseboard_fab2(sch_1):m_l_dq(37)") )
				( member ( signalRef "@baseboard_fab2_lib.baseboard_fab2(sch_1):m_l_dq(38)") )
				( member ( signalRef "@baseboard_fab2_lib.baseboard_fab2(sch_1):m_l_dq(39)") )
				( member ( signalRef "@baseboard_fab2_lib.baseboard_fab2(sch_1):m_l_dq(40)") )
				( member ( signalRef "@baseboard_fab2_lib.baseboard_fab2(sch_1):m_l_dq(41)") )
				( member ( signalRef "@baseboard_fab2_lib.baseboard_fab2(sch_1):m_l_dq(42)") )
				( member ( signalRef "@baseboard_fab2_lib.baseboard_fab2(sch_1):m_l_dq(43)") )
				( member ( signalRef "@baseboard_fab2_lib.baseboard_fab2(sch_1):m_l_dq(44)") )
				( member ( signalRef "@baseboard_fab2_lib.baseboard_fab2(sch_1):m_l_dq(45)") )
				( member ( signalRef "@baseboard_fab2_lib.baseboard_fab2(sch_1):m_l_dq(46)") )
				( member ( signalRef "@baseboard_fab2_lib.baseboard_fab2(sch_1):m_l_dq(47)") )
				( member ( signalRef "@baseboard_fab2_lib.baseboard_fab2(sch_1):m_l_dq(48)") )
				( member ( signalRef "@baseboard_fab2_lib.baseboard_fab2(sch_1):m_l_dq(49)") )
				( member ( signalRef "@baseboard_fab2_lib.baseboard_fab2(sch_1):m_l_dq(50)") )
				( member ( signalRef "@baseboard_fab2_lib.baseboard_fab2(sch_1):m_l_dq(51)") )
				( member ( signalRef "@baseboard_fab2_lib.baseboard_fab2(sch_1):m_l_dq(52)") )
				( member ( signalRef "@baseboard_fab2_lib.baseboard_fab2(sch_1):m_l_dq(53)") )
				( member ( signalRef "@baseboard_fab2_lib.baseboard_fab2(sch_1):m_l_dq(54)") )
				( member ( signalRef "@baseboard_fab2_lib.baseboard_fab2(sch_1):m_l_dq(55)") )
				( member ( signalRef "@baseboard_fab2_lib.baseboard_fab2(sch_1):m_l_dq(56)") )
				( member ( signalRef "@baseboard_fab2_lib.baseboard_fab2(sch_1):m_l_dq(57)") )
				( member ( signalRef "@baseboard_fab2_lib.baseboard_fab2(sch_1):m_l_dq(58)") )
				( member ( signalRef "@baseboard_fab2_lib.baseboard_fab2(sch_1):m_l_dq(59)") )
				( member ( signalRef "@baseboard_fab2_lib.baseboard_fab2(sch_1):m_l_dq(60)") )
				( member ( signalRef "@baseboard_fab2_lib.baseboard_fab2(sch_1):m_l_dq(61)") )
				( member ( signalRef "@baseboard_fab2_lib.baseboard_fab2(sch_1):m_l_dq(62)") )
				( member ( signalRef "@baseboard_fab2_lib.baseboard_fab2(sch_1):m_l_dq(63)") )
				( member ( signalRef "@baseboard_fab2_lib.baseboard_fab2(sch_1):m_m_dq(0)") )
				( member ( signalRef "@baseboard_fab2_lib.baseboard_fab2(sch_1):m_m_dq(1)") )
				( member ( signalRef "@baseboard_fab2_lib.baseboard_fab2(sch_1):m_m_dq(2)") )
				( member ( signalRef "@baseboard_fab2_lib.baseboard_fab2(sch_1):m_m_dq(3)") )
				( member ( signalRef "@baseboard_fab2_lib.baseboard_fab2(sch_1):m_m_dq(4)") )
				( member ( signalRef "@baseboard_fab2_lib.baseboard_fab2(sch_1):m_m_dq(5)") )
				( member ( signalRef "@baseboard_fab2_lib.baseboard_fab2(sch_1):m_m_dq(6)") )
				( member ( signalRef "@baseboard_fab2_lib.baseboard_fab2(sch_1):m_m_dq(7)") )
				( member ( signalRef "@baseboard_fab2_lib.baseboard_fab2(sch_1):m_m_dq(8)") )
				( member ( signalRef "@baseboard_fab2_lib.baseboard_fab2(sch_1):m_m_dq(9)") )
				( member ( signalRef "@baseboard_fab2_lib.baseboard_fab2(sch_1):m_m_dq(10)") )
				( member ( signalRef "@baseboard_fab2_lib.baseboard_fab2(sch_1):m_m_dq(11)") )
				( member ( signalRef "@baseboard_fab2_lib.baseboard_fab2(sch_1):m_m_dq(12)") )
				( member ( signalRef "@baseboard_fab2_lib.baseboard_fab2(sch_1):m_m_dq(13)") )
				( member ( signalRef "@baseboard_fab2_lib.baseboard_fab2(sch_1):m_m_dq(14)") )
				( member ( signalRef "@baseboard_fab2_lib.baseboard_fab2(sch_1):m_m_dq(15)") )
				( member ( signalRef "@baseboard_fab2_lib.baseboard_fab2(sch_1):m_m_dq(16)") )
				( member ( signalRef "@baseboard_fab2_lib.baseboard_fab2(sch_1):m_m_dq(17)") )
				( member ( signalRef "@baseboard_fab2_lib.baseboard_fab2(sch_1):m_m_dq(18)") )
				( member ( signalRef "@baseboard_fab2_lib.baseboard_fab2(sch_1):m_m_dq(19)") )
				( member ( signalRef "@baseboard_fab2_lib.baseboard_fab2(sch_1):m_m_dq(20)") )
				( member ( signalRef "@baseboard_fab2_lib.baseboard_fab2(sch_1):m_m_dq(21)") )
				( member ( signalRef "@baseboard_fab2_lib.baseboard_fab2(sch_1):m_m_dq(22)") )
				( member ( signalRef "@baseboard_fab2_lib.baseboard_fab2(sch_1):m_m_dq(23)") )
				( member ( signalRef "@baseboard_fab2_lib.baseboard_fab2(sch_1):m_m_dq(24)") )
				( member ( signalRef "@baseboard_fab2_lib.baseboard_fab2(sch_1):m_m_dq(25)") )
				( member ( signalRef "@baseboard_fab2_lib.baseboard_fab2(sch_1):m_m_dq(26)") )
				( member ( signalRef "@baseboard_fab2_lib.baseboard_fab2(sch_1):m_m_dq(27)") )
				( member ( signalRef "@baseboard_fab2_lib.baseboard_fab2(sch_1):m_m_dq(28)") )
				( member ( signalRef "@baseboard_fab2_lib.baseboard_fab2(sch_1):m_j_dq(21)") )
				( member ( signalRef "@baseboard_fab2_lib.baseboard_fab2(sch_1):m_j_dq(22)") )
				( member ( signalRef "@baseboard_fab2_lib.baseboard_fab2(sch_1):m_j_dq(23)") )
				( member ( signalRef "@baseboard_fab2_lib.baseboard_fab2(sch_1):m_j_dq(24)") )
				( member ( signalRef "@baseboard_fab2_lib.baseboard_fab2(sch_1):m_j_dq(25)") )
				( member ( signalRef "@baseboard_fab2_lib.baseboard_fab2(sch_1):m_j_dq(26)") )
				( member ( signalRef "@baseboard_fab2_lib.baseboard_fab2(sch_1):m_j_dq(27)") )
				( member ( signalRef "@baseboard_fab2_lib.baseboard_fab2(sch_1):m_j_dq(28)") )
				( member ( signalRef "@baseboard_fab2_lib.baseboard_fab2(sch_1):m_j_dq(29)") )
				( member ( signalRef "@baseboard_fab2_lib.baseboard_fab2(sch_1):m_j_dq(30)") )
				( member ( signalRef "@baseboard_fab2_lib.baseboard_fab2(sch_1):m_j_dq(31)") )
				( member ( signalRef "@baseboard_fab2_lib.baseboard_fab2(sch_1):m_j_dq(32)") )
				( member ( signalRef "@baseboard_fab2_lib.baseboard_fab2(sch_1):m_j_dq(33)") )
				( member ( signalRef "@baseboard_fab2_lib.baseboard_fab2(sch_1):m_j_dq(34)") )
				( member ( signalRef "@baseboard_fab2_lib.baseboard_fab2(sch_1):m_j_dq(35)") )
				( member ( signalRef "@baseboard_fab2_lib.baseboard_fab2(sch_1):m_j_dq(36)") )
				( member ( signalRef "@baseboard_fab2_lib.baseboard_fab2(sch_1):m_j_dq(37)") )
				( member ( signalRef "@baseboard_fab2_lib.baseboard_fab2(sch_1):m_j_dq(38)") )
				( member ( signalRef "@baseboard_fab2_lib.baseboard_fab2(sch_1):m_j_dq(39)") )
				( member ( signalRef "@baseboard_fab2_lib.baseboard_fab2(sch_1):m_j_dq(40)") )
				( member ( signalRef "@baseboard_fab2_lib.baseboard_fab2(sch_1):m_j_dq(41)") )
				( member ( signalRef "@baseboard_fab2_lib.baseboard_fab2(sch_1):m_j_dq(42)") )
				( member ( signalRef "@baseboard_fab2_lib.baseboard_fab2(sch_1):m_j_dq(43)") )
				( member ( signalRef "@baseboard_fab2_lib.baseboard_fab2(sch_1):m_j_dq(44)") )
				( member ( signalRef "@baseboard_fab2_lib.baseboard_fab2(sch_1):m_j_dq(45)") )
				( member ( signalRef "@baseboard_fab2_lib.baseboard_fab2(sch_1):m_j_dq(46)") )
				( member ( signalRef "@baseboard_fab2_lib.baseboard_fab2(sch_1):m_j_dq(47)") )
				( member ( signalRef "@baseboard_fab2_lib.baseboard_fab2(sch_1):m_j_dq(48)") )
				( member ( signalRef "@baseboard_fab2_lib.baseboard_fab2(sch_1):m_j_dq(49)") )
				( member ( signalRef "@baseboard_fab2_lib.baseboard_fab2(sch_1):m_j_dq(50)") )
				( member ( signalRef "@baseboard_fab2_lib.baseboard_fab2(sch_1):m_j_dq(51)") )
				( member ( signalRef "@baseboard_fab2_lib.baseboard_fab2(sch_1):m_j_dq(52)") )
				( member ( signalRef "@baseboard_fab2_lib.baseboard_fab2(sch_1):m_j_dq(53)") )
				( member ( signalRef "@baseboard_fab2_lib.baseboard_fab2(sch_1):m_j_dq(54)") )
				( member ( signalRef "@baseboard_fab2_lib.baseboard_fab2(sch_1):m_j_dq(55)") )
				( member ( signalRef "@baseboard_fab2_lib.baseboard_fab2(sch_1):m_j_dq(56)") )
				( member ( signalRef "@baseboard_fab2_lib.baseboard_fab2(sch_1):m_j_dq(57)") )
				( member ( signalRef "@baseboard_fab2_lib.baseboard_fab2(sch_1):m_j_dq(58)") )
				( member ( signalRef "@baseboard_fab2_lib.baseboard_fab2(sch_1):m_j_dq(59)") )
				( member ( signalRef "@baseboard_fab2_lib.baseboard_fab2(sch_1):m_j_dq(60)") )
				( member ( signalRef "@baseboard_fab2_lib.baseboard_fab2(sch_1):m_j_dq(61)") )
				( member ( signalRef "@baseboard_fab2_lib.baseboard_fab2(sch_1):m_j_dq(62)") )
				( member ( signalRef "@baseboard_fab2_lib.baseboard_fab2(sch_1):m_j_dq(63)") )
				( member ( signalRef "@baseboard_fab2_lib.baseboard_fab2(sch_1):m_k_dq(0)") )
				( member ( signalRef "@baseboard_fab2_lib.baseboard_fab2(sch_1):m_k_dq(1)") )
				( member ( signalRef "@baseboard_fab2_lib.baseboard_fab2(sch_1):m_k_dq(2)") )
				( member ( signalRef "@baseboard_fab2_lib.baseboard_fab2(sch_1):m_k_dq(3)") )
				( member ( signalRef "@baseboard_fab2_lib.baseboard_fab2(sch_1):m_k_dq(4)") )
				( member ( signalRef "@baseboard_fab2_lib.baseboard_fab2(sch_1):m_k_dq(5)") )
				( member ( signalRef "@baseboard_fab2_lib.baseboard_fab2(sch_1):m_k_dq(6)") )
				( member ( signalRef "@baseboard_fab2_lib.baseboard_fab2(sch_1):m_k_dq(7)") )
				( member ( signalRef "@baseboard_fab2_lib.baseboard_fab2(sch_1):m_k_dq(8)") )
				( member ( signalRef "@baseboard_fab2_lib.baseboard_fab2(sch_1):m_k_dq(9)") )
				( member ( signalRef "@baseboard_fab2_lib.baseboard_fab2(sch_1):m_k_dq(10)") )
				( member ( signalRef "@baseboard_fab2_lib.baseboard_fab2(sch_1):m_k_dq(11)") )
				( member ( signalRef "@baseboard_fab2_lib.baseboard_fab2(sch_1):m_k_dq(12)") )
				( member ( signalRef "@baseboard_fab2_lib.baseboard_fab2(sch_1):m_k_dq(13)") )
				( member ( signalRef "@baseboard_fab2_lib.baseboard_fab2(sch_1):m_k_dq(14)") )
				( member ( signalRef "@baseboard_fab2_lib.baseboard_fab2(sch_1):m_k_dq(15)") )
				( member ( signalRef "@baseboard_fab2_lib.baseboard_fab2(sch_1):m_k_dq(16)") )
				( member ( signalRef "@baseboard_fab2_lib.baseboard_fab2(sch_1):m_k_dq(17)") )
				( member ( signalRef "@baseboard_fab2_lib.baseboard_fab2(sch_1):m_k_dq(18)") )
				( member ( signalRef "@baseboard_fab2_lib.baseboard_fab2(sch_1):m_k_dq(19)") )
				( member ( signalRef "@baseboard_fab2_lib.baseboard_fab2(sch_1):m_k_dq(20)") )
				( member ( signalRef "@baseboard_fab2_lib.baseboard_fab2(sch_1):m_k_dq(21)") )
				( member ( signalRef "@baseboard_fab2_lib.baseboard_fab2(sch_1):m_k_dq(22)") )
				( member ( signalRef "@baseboard_fab2_lib.baseboard_fab2(sch_1):m_k_dq(23)") )
				( member ( signalRef "@baseboard_fab2_lib.baseboard_fab2(sch_1):m_k_dq(24)") )
				( member ( signalRef "@baseboard_fab2_lib.baseboard_fab2(sch_1):m_k_dq(25)") )
				( member ( signalRef "@baseboard_fab2_lib.baseboard_fab2(sch_1):m_k_dq(26)") )
				( member ( signalRef "@baseboard_fab2_lib.baseboard_fab2(sch_1):m_k_dq(27)") )
				( member ( signalRef "@baseboard_fab2_lib.baseboard_fab2(sch_1):m_k_dq(28)") )
				( member ( signalRef "@baseboard_fab2_lib.baseboard_fab2(sch_1):m_k_dq(29)") )
				( member ( signalRef "@baseboard_fab2_lib.baseboard_fab2(sch_1):m_k_dq(30)") )
				( member ( signalRef "@baseboard_fab2_lib.baseboard_fab2(sch_1):m_k_dq(31)") )
				( member ( signalRef "@baseboard_fab2_lib.baseboard_fab2(sch_1):m_k_dq(32)") )
				( member ( signalRef "@baseboard_fab2_lib.baseboard_fab2(sch_1):m_k_dq(33)") )
				( member ( signalRef "@baseboard_fab2_lib.baseboard_fab2(sch_1):m_k_dq(34)") )
				( member ( signalRef "@baseboard_fab2_lib.baseboard_fab2(sch_1):m_k_dq(35)") )
				( member ( signalRef "@baseboard_fab2_lib.baseboard_fab2(sch_1):m_k_dq(36)") )
				( member ( signalRef "@baseboard_fab2_lib.baseboard_fab2(sch_1):m_k_dq(37)") )
				( member ( signalRef "@baseboard_fab2_lib.baseboard_fab2(sch_1):m_k_dq(38)") )
				( member ( signalRef "@baseboard_fab2_lib.baseboard_fab2(sch_1):m_k_dq(39)") )
				( member ( signalRef "@baseboard_fab2_lib.baseboard_fab2(sch_1):m_k_dq(40)") )
				( member ( signalRef "@baseboard_fab2_lib.baseboard_fab2(sch_1):m_k_dq(41)") )
				( member ( signalRef "@baseboard_fab2_lib.baseboard_fab2(sch_1):m_k_dq(42)") )
				( member ( signalRef "@baseboard_fab2_lib.baseboard_fab2(sch_1):m_k_dq(43)") )
				( member ( signalRef "@baseboard_fab2_lib.baseboard_fab2(sch_1):m_k_dq(44)") )
				( member ( signalRef "@baseboard_fab2_lib.baseboard_fab2(sch_1):m_k_dq(45)") )
				( member ( signalRef "@baseboard_fab2_lib.baseboard_fab2(sch_1):m_k_dq(46)") )
				( member ( signalRef "@baseboard_fab2_lib.baseboard_fab2(sch_1):m_k_dq(47)") )
				( member ( signalRef "@baseboard_fab2_lib.baseboard_fab2(sch_1):m_k_dq(48)") )
				( member ( signalRef "@baseboard_fab2_lib.baseboard_fab2(sch_1):m_k_dq(49)") )
				( member ( signalRef "@baseboard_fab2_lib.baseboard_fab2(sch_1):m_k_dq(50)") )
				( member ( signalRef "@baseboard_fab2_lib.baseboard_fab2(sch_1):m_k_dq(51)") )
				( member ( signalRef "@baseboard_fab2_lib.baseboard_fab2(sch_1):m_k_dq(52)") )
				( member ( signalRef "@baseboard_fab2_lib.baseboard_fab2(sch_1):m_k_dq(53)") )
				( member ( signalRef "@baseboard_fab2_lib.baseboard_fab2(sch_1):m_k_dq(54)") )
				( member ( signalRef "@baseboard_fab2_lib.baseboard_fab2(sch_1):m_k_dq(55)") )
				( member ( signalRef "@baseboard_fab2_lib.baseboard_fab2(sch_1):m_k_dq(56)") )
				( member ( signalRef "@baseboard_fab2_lib.baseboard_fab2(sch_1):m_g_dq(45)") )
				( member ( signalRef "@baseboard_fab2_lib.baseboard_fab2(sch_1):m_g_dq(46)") )
				( member ( signalRef "@baseboard_fab2_lib.baseboard_fab2(sch_1):m_g_dq(47)") )
				( member ( signalRef "@baseboard_fab2_lib.baseboard_fab2(sch_1):m_g_dq(48)") )
				( member ( signalRef "@baseboard_fab2_lib.baseboard_fab2(sch_1):m_g_dq(49)") )
				( member ( signalRef "@baseboard_fab2_lib.baseboard_fab2(sch_1):m_g_dq(50)") )
				( member ( signalRef "@baseboard_fab2_lib.baseboard_fab2(sch_1):m_g_dq(51)") )
				( member ( signalRef "@baseboard_fab2_lib.baseboard_fab2(sch_1):m_g_dq(52)") )
				( member ( signalRef "@baseboard_fab2_lib.baseboard_fab2(sch_1):m_g_dq(53)") )
				( member ( signalRef "@baseboard_fab2_lib.baseboard_fab2(sch_1):m_g_dq(54)") )
				( member ( signalRef "@baseboard_fab2_lib.baseboard_fab2(sch_1):m_g_dq(55)") )
				( member ( signalRef "@baseboard_fab2_lib.baseboard_fab2(sch_1):m_g_dq(56)") )
				( member ( signalRef "@baseboard_fab2_lib.baseboard_fab2(sch_1):m_g_dq(57)") )
				( member ( signalRef "@baseboard_fab2_lib.baseboard_fab2(sch_1):m_g_dq(58)") )
				( member ( signalRef "@baseboard_fab2_lib.baseboard_fab2(sch_1):m_g_dq(59)") )
				( member ( signalRef "@baseboard_fab2_lib.baseboard_fab2(sch_1):m_g_dq(60)") )
				( member ( signalRef "@baseboard_fab2_lib.baseboard_fab2(sch_1):m_g_dq(61)") )
				( member ( signalRef "@baseboard_fab2_lib.baseboard_fab2(sch_1):m_g_dq(62)") )
				( member ( signalRef "@baseboard_fab2_lib.baseboard_fab2(sch_1):m_g_dq(63)") )
				( member ( signalRef "@baseboard_fab2_lib.baseboard_fab2(sch_1):m_h_dq(0)") )
				( member ( signalRef "@baseboard_fab2_lib.baseboard_fab2(sch_1):m_h_dq(1)") )
				( member ( signalRef "@baseboard_fab2_lib.baseboard_fab2(sch_1):m_h_dq(2)") )
				( member ( signalRef "@baseboard_fab2_lib.baseboard_fab2(sch_1):m_h_dq(3)") )
				( member ( signalRef "@baseboard_fab2_lib.baseboard_fab2(sch_1):m_h_dq(4)") )
				( member ( signalRef "@baseboard_fab2_lib.baseboard_fab2(sch_1):m_h_dq(5)") )
				( member ( signalRef "@baseboard_fab2_lib.baseboard_fab2(sch_1):m_h_dq(6)") )
				( member ( signalRef "@baseboard_fab2_lib.baseboard_fab2(sch_1):m_h_dq(7)") )
				( member ( signalRef "@baseboard_fab2_lib.baseboard_fab2(sch_1):m_h_dq(8)") )
				( member ( signalRef "@baseboard_fab2_lib.baseboard_fab2(sch_1):m_h_dq(9)") )
				( member ( signalRef "@baseboard_fab2_lib.baseboard_fab2(sch_1):m_h_dq(10)") )
				( member ( signalRef "@baseboard_fab2_lib.baseboard_fab2(sch_1):m_h_dq(11)") )
				( member ( signalRef "@baseboard_fab2_lib.baseboard_fab2(sch_1):m_h_dq(12)") )
				( member ( signalRef "@baseboard_fab2_lib.baseboard_fab2(sch_1):m_h_dq(17)") )
				( member ( signalRef "@baseboard_fab2_lib.baseboard_fab2(sch_1):m_h_dq(18)") )
				( member ( signalRef "@baseboard_fab2_lib.baseboard_fab2(sch_1):m_h_dq(19)") )
				( member ( signalRef "@baseboard_fab2_lib.baseboard_fab2(sch_1):m_h_dq(20)") )
				( member ( signalRef "@baseboard_fab2_lib.baseboard_fab2(sch_1):m_h_dq(21)") )
				( member ( signalRef "@baseboard_fab2_lib.baseboard_fab2(sch_1):m_h_dq(22)") )
				( member ( signalRef "@baseboard_fab2_lib.baseboard_fab2(sch_1):m_h_dq(23)") )
				( member ( signalRef "@baseboard_fab2_lib.baseboard_fab2(sch_1):m_h_dq(24)") )
				( member ( signalRef "@baseboard_fab2_lib.baseboard_fab2(sch_1):m_h_dq(25)") )
				( member ( signalRef "@baseboard_fab2_lib.baseboard_fab2(sch_1):m_h_dq(26)") )
				( member ( signalRef "@baseboard_fab2_lib.baseboard_fab2(sch_1):m_h_dq(27)") )
				( member ( signalRef "@baseboard_fab2_lib.baseboard_fab2(sch_1):m_h_dq(28)") )
				( member ( signalRef "@baseboard_fab2_lib.baseboard_fab2(sch_1):m_h_dq(29)") )
				( member ( signalRef "@baseboard_fab2_lib.baseboard_fab2(sch_1):m_h_dq(30)") )
				( member ( signalRef "@baseboard_fab2_lib.baseboard_fab2(sch_1):m_h_dq(31)") )
				( member ( signalRef "@baseboard_fab2_lib.baseboard_fab2(sch_1):m_h_dq(32)") )
				( member ( signalRef "@baseboard_fab2_lib.baseboard_fab2(sch_1):m_h_dq(33)") )
				( member ( signalRef "@baseboard_fab2_lib.baseboard_fab2(sch_1):m_h_dq(34)") )
				( member ( signalRef "@baseboard_fab2_lib.baseboard_fab2(sch_1):m_h_dq(35)") )
				( member ( signalRef "@baseboard_fab2_lib.baseboard_fab2(sch_1):m_h_dq(36)") )
				( member ( signalRef "@baseboard_fab2_lib.baseboard_fab2(sch_1):m_h_dq(37)") )
				( member ( signalRef "@baseboard_fab2_lib.baseboard_fab2(sch_1):m_h_dq(38)") )
				( member ( signalRef "@baseboard_fab2_lib.baseboard_fab2(sch_1):m_h_dq(39)") )
				( member ( signalRef "@baseboard_fab2_lib.baseboard_fab2(sch_1):m_h_dq(40)") )
				( member ( signalRef "@baseboard_fab2_lib.baseboard_fab2(sch_1):m_h_dq(41)") )
				( member ( signalRef "@baseboard_fab2_lib.baseboard_fab2(sch_1):m_h_dq(42)") )
				( member ( signalRef "@baseboard_fab2_lib.baseboard_fab2(sch_1):m_h_dq(43)") )
				( member ( signalRef "@baseboard_fab2_lib.baseboard_fab2(sch_1):m_h_dq(44)") )
				( member ( signalRef "@baseboard_fab2_lib.baseboard_fab2(sch_1):m_h_dq(45)") )
				( member ( signalRef "@baseboard_fab2_lib.baseboard_fab2(sch_1):m_h_dq(46)") )
				( member ( signalRef "@baseboard_fab2_lib.baseboard_fab2(sch_1):m_h_dq(47)") )
				( member ( signalRef "@baseboard_fab2_lib.baseboard_fab2(sch_1):m_h_dq(48)") )
				( member ( signalRef "@baseboard_fab2_lib.baseboard_fab2(sch_1):m_h_dq(49)") )
				( member ( signalRef "@baseboard_fab2_lib.baseboard_fab2(sch_1):m_h_dq(50)") )
				( member ( signalRef "@baseboard_fab2_lib.baseboard_fab2(sch_1):m_h_dq(51)") )
				( member ( signalRef "@baseboard_fab2_lib.baseboard_fab2(sch_1):m_h_dq(52)") )
				( member ( signalRef "@baseboard_fab2_lib.baseboard_fab2(sch_1):m_h_dq(53)") )
				( member ( signalRef "@baseboard_fab2_lib.baseboard_fab2(sch_1):m_h_dq(54)") )
				( member ( signalRef "@baseboard_fab2_lib.baseboard_fab2(sch_1):m_h_dq(55)") )
				( member ( signalRef "@baseboard_fab2_lib.baseboard_fab2(sch_1):m_h_dq(56)") )
				( member ( signalRef "@baseboard_fab2_lib.baseboard_fab2(sch_1):m_h_dq(57)") )
				( member ( signalRef "@baseboard_fab2_lib.baseboard_fab2(sch_1):m_h_dq(58)") )
				( member ( signalRef "@baseboard_fab2_lib.baseboard_fab2(sch_1):m_h_dq(59)") )
				( member ( signalRef "@baseboard_fab2_lib.baseboard_fab2(sch_1):m_h_dq(60)") )
				( member ( signalRef "@baseboard_fab2_lib.baseboard_fab2(sch_1):m_h_dq(61)") )
				( member ( signalRef "@baseboard_fab2_lib.baseboard_fab2(sch_1):m_h_dq(62)") )
				( member ( signalRef "@baseboard_fab2_lib.baseboard_fab2(sch_1):m_h_dq(63)") )
				( member ( signalRef "@baseboard_fab2_lib.baseboard_fab2(sch_1):m_j_dq(0)") )
				( member ( signalRef "@baseboard_fab2_lib.baseboard_fab2(sch_1):m_j_dq(1)") )
				( member ( signalRef "@baseboard_fab2_lib.baseboard_fab2(sch_1):m_j_dq(2)") )
				( member ( signalRef "@baseboard_fab2_lib.baseboard_fab2(sch_1):m_j_dq(3)") )
				( member ( signalRef "@baseboard_fab2_lib.baseboard_fab2(sch_1):m_j_dq(4)") )
				( member ( signalRef "@baseboard_fab2_lib.baseboard_fab2(sch_1):m_j_dq(5)") )
				( member ( signalRef "@baseboard_fab2_lib.baseboard_fab2(sch_1):m_j_dq(6)") )
				( member ( signalRef "@baseboard_fab2_lib.baseboard_fab2(sch_1):m_j_dq(7)") )
				( member ( signalRef "@baseboard_fab2_lib.baseboard_fab2(sch_1):m_j_dq(8)") )
				( member ( signalRef "@baseboard_fab2_lib.baseboard_fab2(sch_1):m_j_dq(9)") )
				( member ( signalRef "@baseboard_fab2_lib.baseboard_fab2(sch_1):m_j_dq(10)") )
				( member ( signalRef "@baseboard_fab2_lib.baseboard_fab2(sch_1):m_j_dq(11)") )
				( member ( signalRef "@baseboard_fab2_lib.baseboard_fab2(sch_1):m_j_dq(12)") )
				( member ( signalRef "@baseboard_fab2_lib.baseboard_fab2(sch_1):m_j_dq(13)") )
				( member ( signalRef "@baseboard_fab2_lib.baseboard_fab2(sch_1):m_j_dq(14)") )
				( member ( signalRef "@baseboard_fab2_lib.baseboard_fab2(sch_1):m_j_dq(15)") )
				( member ( signalRef "@baseboard_fab2_lib.baseboard_fab2(sch_1):m_j_dq(16)") )
				( member ( signalRef "@baseboard_fab2_lib.baseboard_fab2(sch_1):m_j_dq(17)") )
				( member ( signalRef "@baseboard_fab2_lib.baseboard_fab2(sch_1):m_j_dq(18)") )
				( member ( signalRef "@baseboard_fab2_lib.baseboard_fab2(sch_1):m_j_dq(19)") )
				( member ( signalRef "@baseboard_fab2_lib.baseboard_fab2(sch_1):m_j_dq(20)") )
				( member ( signalRef "@baseboard_fab2_lib.baseboard_fab2(sch_1):m_a_dq(8)") )
				( member ( signalRef "@baseboard_fab2_lib.baseboard_fab2(sch_1):m_a_dq(9)") )
				( member ( signalRef "@baseboard_fab2_lib.baseboard_fab2(sch_1):m_a_dq(10)") )
				( member ( signalRef "@baseboard_fab2_lib.baseboard_fab2(sch_1):m_a_dq(11)") )
				( member ( signalRef "@baseboard_fab2_lib.baseboard_fab2(sch_1):m_a_dq(12)") )
				( member ( signalRef "@baseboard_fab2_lib.baseboard_fab2(sch_1):m_a_dq(13)") )
				( member ( signalRef "@baseboard_fab2_lib.baseboard_fab2(sch_1):m_a_dq(14)") )
				( member ( signalRef "@baseboard_fab2_lib.baseboard_fab2(sch_1):m_a_dq(15)") )
				( member ( signalRef "@baseboard_fab2_lib.baseboard_fab2(sch_1):m_a_dq(16)") )
				( member ( signalRef "@baseboard_fab2_lib.baseboard_fab2(sch_1):m_a_dq(17)") )
				( member ( signalRef "@baseboard_fab2_lib.baseboard_fab2(sch_1):m_a_dq(18)") )
				( member ( signalRef "@baseboard_fab2_lib.baseboard_fab2(sch_1):m_a_dq(19)") )
				( member ( signalRef "@baseboard_fab2_lib.baseboard_fab2(sch_1):m_a_dq(20)") )
				( member ( signalRef "@baseboard_fab2_lib.baseboard_fab2(sch_1):m_a_dq(21)") )
				( member ( signalRef "@baseboard_fab2_lib.baseboard_fab2(sch_1):m_a_dq(22)") )
				( member ( signalRef "@baseboard_fab2_lib.baseboard_fab2(sch_1):m_a_dq(23)") )
				( member ( signalRef "@baseboard_fab2_lib.baseboard_fab2(sch_1):m_a_dq(24)") )
				( member ( signalRef "@baseboard_fab2_lib.baseboard_fab2(sch_1):m_a_dq(25)") )
				( member ( signalRef "@baseboard_fab2_lib.baseboard_fab2(sch_1):m_a_dq(26)") )
				( member ( signalRef "@baseboard_fab2_lib.baseboard_fab2(sch_1):m_a_dq(27)") )
				( member ( signalRef "@baseboard_fab2_lib.baseboard_fab2(sch_1):m_a_dq(28)") )
				( member ( signalRef "@baseboard_fab2_lib.baseboard_fab2(sch_1):m_a_dq(29)") )
				( member ( signalRef "@baseboard_fab2_lib.baseboard_fab2(sch_1):m_a_dq(30)") )
				( member ( signalRef "@baseboard_fab2_lib.baseboard_fab2(sch_1):m_a_dq(31)") )
				( member ( signalRef "@baseboard_fab2_lib.baseboard_fab2(sch_1):m_a_dq(32)") )
				( member ( signalRef "@baseboard_fab2_lib.baseboard_fab2(sch_1):m_a_dq(33)") )
				( member ( signalRef "@baseboard_fab2_lib.baseboard_fab2(sch_1):m_a_dq(34)") )
				( member ( signalRef "@baseboard_fab2_lib.baseboard_fab2(sch_1):m_a_dq(35)") )
				( member ( signalRef "@baseboard_fab2_lib.baseboard_fab2(sch_1):m_a_dq(36)") )
				( member ( signalRef "@baseboard_fab2_lib.baseboard_fab2(sch_1):m_a_dq(37)") )
				( member ( signalRef "@baseboard_fab2_lib.baseboard_fab2(sch_1):m_a_dq(38)") )
				( member ( signalRef "@baseboard_fab2_lib.baseboard_fab2(sch_1):m_a_dq(39)") )
				( member ( signalRef "@baseboard_fab2_lib.baseboard_fab2(sch_1):m_a_dq(40)") )
				( member ( signalRef "@baseboard_fab2_lib.baseboard_fab2(sch_1):m_a_dq(41)") )
				( member ( signalRef "@baseboard_fab2_lib.baseboard_fab2(sch_1):m_a_dq(42)") )
				( member ( signalRef "@baseboard_fab2_lib.baseboard_fab2(sch_1):m_a_dq(43)") )
				( member ( signalRef "@baseboard_fab2_lib.baseboard_fab2(sch_1):m_a_dq(44)") )
				( member ( signalRef "@baseboard_fab2_lib.baseboard_fab2(sch_1):m_a_dq(45)") )
				( member ( signalRef "@baseboard_fab2_lib.baseboard_fab2(sch_1):m_a_dq(46)") )
				( member ( signalRef "@baseboard_fab2_lib.baseboard_fab2(sch_1):m_a_dq(47)") )
				( member ( signalRef "@baseboard_fab2_lib.baseboard_fab2(sch_1):m_a_dq(48)") )
				( member ( signalRef "@baseboard_fab2_lib.baseboard_fab2(sch_1):m_a_dq(49)") )
				( member ( signalRef "@baseboard_fab2_lib.baseboard_fab2(sch_1):m_a_dq(50)") )
				( member ( signalRef "@baseboard_fab2_lib.baseboard_fab2(sch_1):m_a_dq(51)") )
				( member ( signalRef "@baseboard_fab2_lib.baseboard_fab2(sch_1):m_a_dq(52)") )
				( member ( signalRef "@baseboard_fab2_lib.baseboard_fab2(sch_1):m_a_dq(53)") )
				( member ( signalRef "@baseboard_fab2_lib.baseboard_fab2(sch_1):m_a_dq(54)") )
				( member ( signalRef "@baseboard_fab2_lib.baseboard_fab2(sch_1):m_a_dq(55)") )
				( member ( signalRef "@baseboard_fab2_lib.baseboard_fab2(sch_1):m_a_dq(56)") )
				( member ( signalRef "@baseboard_fab2_lib.baseboard_fab2(sch_1):m_a_dq(57)") )
				( member ( signalRef "@baseboard_fab2_lib.baseboard_fab2(sch_1):m_a_dq(58)") )
				( member ( signalRef "@baseboard_fab2_lib.baseboard_fab2(sch_1):m_a_dq(59)") )
				( member ( signalRef "@baseboard_fab2_lib.baseboard_fab2(sch_1):m_a_dq(60)") )
				( member ( signalRef "@baseboard_fab2_lib.baseboard_fab2(sch_1):m_a_dq(61)") )
				( member ( signalRef "@baseboard_fab2_lib.baseboard_fab2(sch_1):m_a_dq(62)") )
				( member ( signalRef "@baseboard_fab2_lib.baseboard_fab2(sch_1):m_a_dq(63)") )
				( member ( signalRef "@baseboard_fab2_lib.baseboard_fab2(sch_1):m_g_dq(0)") )
				( member ( signalRef "@baseboard_fab2_lib.baseboard_fab2(sch_1):m_g_dq(1)") )
				( member ( signalRef "@baseboard_fab2_lib.baseboard_fab2(sch_1):m_g_dq(2)") )
				( member ( signalRef "@baseboard_fab2_lib.baseboard_fab2(sch_1):m_g_dq(3)") )
				( member ( signalRef "@baseboard_fab2_lib.baseboard_fab2(sch_1):m_g_dq(4)") )
				( member ( signalRef "@baseboard_fab2_lib.baseboard_fab2(sch_1):m_g_dq(5)") )
				( member ( signalRef "@baseboard_fab2_lib.baseboard_fab2(sch_1):m_g_dq(6)") )
				( member ( signalRef "@baseboard_fab2_lib.baseboard_fab2(sch_1):m_g_dq(7)") )
				( member ( signalRef "@baseboard_fab2_lib.baseboard_fab2(sch_1):m_g_dq(8)") )
				( member ( signalRef "@baseboard_fab2_lib.baseboard_fab2(sch_1):m_g_dq(9)") )
				( member ( signalRef "@baseboard_fab2_lib.baseboard_fab2(sch_1):m_g_dq(11)") )
				( member ( signalRef "@baseboard_fab2_lib.baseboard_fab2(sch_1):m_g_dq(12)") )
				( member ( signalRef "@baseboard_fab2_lib.baseboard_fab2(sch_1):m_g_dq(13)") )
				( member ( signalRef "@baseboard_fab2_lib.baseboard_fab2(sch_1):m_g_dq(14)") )
				( member ( signalRef "@baseboard_fab2_lib.baseboard_fab2(sch_1):m_g_dq(15)") )
				( member ( signalRef "@baseboard_fab2_lib.baseboard_fab2(sch_1):m_g_dq(16)") )
				( member ( signalRef "@baseboard_fab2_lib.baseboard_fab2(sch_1):m_g_dq(17)") )
				( member ( signalRef "@baseboard_fab2_lib.baseboard_fab2(sch_1):m_g_dq(18)") )
				( member ( signalRef "@baseboard_fab2_lib.baseboard_fab2(sch_1):m_g_dq(19)") )
				( member ( signalRef "@baseboard_fab2_lib.baseboard_fab2(sch_1):m_g_dq(20)") )
				( member ( signalRef "@baseboard_fab2_lib.baseboard_fab2(sch_1):m_g_dq(21)") )
				( member ( signalRef "@baseboard_fab2_lib.baseboard_fab2(sch_1):m_g_dq(22)") )
				( member ( signalRef "@baseboard_fab2_lib.baseboard_fab2(sch_1):m_g_dq(23)") )
				( member ( signalRef "@baseboard_fab2_lib.baseboard_fab2(sch_1):m_g_dq(24)") )
				( member ( signalRef "@baseboard_fab2_lib.baseboard_fab2(sch_1):m_g_dq(25)") )
				( member ( signalRef "@baseboard_fab2_lib.baseboard_fab2(sch_1):m_g_dq(26)") )
				( member ( signalRef "@baseboard_fab2_lib.baseboard_fab2(sch_1):m_g_dq(27)") )
				( member ( signalRef "@baseboard_fab2_lib.baseboard_fab2(sch_1):m_g_dq(28)") )
				( member ( signalRef "@baseboard_fab2_lib.baseboard_fab2(sch_1):m_g_dq(29)") )
				( member ( signalRef "@baseboard_fab2_lib.baseboard_fab2(sch_1):m_g_dq(30)") )
				( member ( signalRef "@baseboard_fab2_lib.baseboard_fab2(sch_1):m_g_dq(31)") )
				( member ( signalRef "@baseboard_fab2_lib.baseboard_fab2(sch_1):m_g_dq(32)") )
				( member ( signalRef "@baseboard_fab2_lib.baseboard_fab2(sch_1):m_g_dq(33)") )
				( member ( signalRef "@baseboard_fab2_lib.baseboard_fab2(sch_1):m_g_dq(34)") )
				( member ( signalRef "@baseboard_fab2_lib.baseboard_fab2(sch_1):m_g_dq(35)") )
				( member ( signalRef "@baseboard_fab2_lib.baseboard_fab2(sch_1):m_g_dq(36)") )
				( member ( signalRef "@baseboard_fab2_lib.baseboard_fab2(sch_1):m_g_dq(37)") )
				( member ( signalRef "@baseboard_fab2_lib.baseboard_fab2(sch_1):m_g_dq(38)") )
				( member ( signalRef "@baseboard_fab2_lib.baseboard_fab2(sch_1):m_g_dq(39)") )
				( member ( signalRef "@baseboard_fab2_lib.baseboard_fab2(sch_1):m_g_dq(40)") )
				( member ( signalRef "@baseboard_fab2_lib.baseboard_fab2(sch_1):m_g_dq(41)") )
				( member ( signalRef "@baseboard_fab2_lib.baseboard_fab2(sch_1):m_g_dq(42)") )
				( member ( signalRef "@baseboard_fab2_lib.baseboard_fab2(sch_1):m_g_dq(43)") )
				( member ( signalRef "@baseboard_fab2_lib.baseboard_fab2(sch_1):m_g_dq(44)") )
				( member ( signalRef "@baseboard_fab2_lib.baseboard_fab2(sch_1):m_m_ma(11)") )
				( member ( signalRef "@baseboard_fab2_lib.baseboard_fab2(sch_1):m_m_ma(12)") )
				( member ( signalRef "@baseboard_fab2_lib.baseboard_fab2(sch_1):m_m_ma(13)") )
				( member ( signalRef "@baseboard_fab2_lib.baseboard_fab2(sch_1):m_m_ma(14)") )
				( member ( signalRef "@baseboard_fab2_lib.baseboard_fab2(sch_1):m_m_ma(15)") )
				( member ( signalRef "@baseboard_fab2_lib.baseboard_fab2(sch_1):m_m_ma(16)") )
				( member ( signalRef "@baseboard_fab2_lib.baseboard_fab2(sch_1):m_m_ma(17)") )
				( member ( signalRef "@baseboard_fab2_lib.baseboard_fab2(sch_1):m_a_cke(0)") )
				( member ( signalRef "@baseboard_fab2_lib.baseboard_fab2(sch_1):m_a_cke(1)") )
				( member ( signalRef "@baseboard_fab2_lib.baseboard_fab2(sch_1):m_a_cke(2)") )
				( member ( signalRef "@baseboard_fab2_lib.baseboard_fab2(sch_1):m_a_cke(3)") )
				( member ( signalRef "@baseboard_fab2_lib.baseboard_fab2(sch_1):m_a_odt(0)") )
				( member ( signalRef "@baseboard_fab2_lib.baseboard_fab2(sch_1):m_a_odt(1)") )
				( member ( signalRef "@baseboard_fab2_lib.baseboard_fab2(sch_1):m_a_odt(2)") )
				( member ( signalRef "@baseboard_fab2_lib.baseboard_fab2(sch_1):m_a_odt(3)") )
				( member ( signalRef "@baseboard_fab2_lib.baseboard_fab2(sch_1):m_b_odt(0)") )
				( member ( signalRef "@baseboard_fab2_lib.baseboard_fab2(sch_1):m_b_odt(1)") )
				( member ( signalRef "@baseboard_fab2_lib.baseboard_fab2(sch_1):m_b_odt(2)") )
				( member ( signalRef "@baseboard_fab2_lib.baseboard_fab2(sch_1):m_b_odt(3)") )
				( member ( signalRef "@baseboard_fab2_lib.baseboard_fab2(sch_1):m_c_odt(0)") )
				( member ( signalRef "@baseboard_fab2_lib.baseboard_fab2(sch_1):m_c_odt(1)") )
				( member ( signalRef "@baseboard_fab2_lib.baseboard_fab2(sch_1):m_c_odt(2)") )
				( member ( signalRef "@baseboard_fab2_lib.baseboard_fab2(sch_1):m_c_odt(3)") )
				( member ( signalRef "@baseboard_fab2_lib.baseboard_fab2(sch_1):m_d_odt(0)") )
				( member ( signalRef "@baseboard_fab2_lib.baseboard_fab2(sch_1):m_d_odt(1)") )
				( member ( signalRef "@baseboard_fab2_lib.baseboard_fab2(sch_1):m_d_odt(2)") )
				( member ( signalRef "@baseboard_fab2_lib.baseboard_fab2(sch_1):m_d_odt(3)") )
				( member ( signalRef "@baseboard_fab2_lib.baseboard_fab2(sch_1):m_e_odt(0)") )
				( member ( signalRef "@baseboard_fab2_lib.baseboard_fab2(sch_1):m_e_odt(1)") )
				( member ( signalRef "@baseboard_fab2_lib.baseboard_fab2(sch_1):m_e_odt(2)") )
				( member ( signalRef "@baseboard_fab2_lib.baseboard_fab2(sch_1):m_e_odt(3)") )
				( member ( signalRef "@baseboard_fab2_lib.baseboard_fab2(sch_1):m_f_odt(0)") )
				( member ( signalRef "@baseboard_fab2_lib.baseboard_fab2(sch_1):m_f_odt(1)") )
				( member ( signalRef "@baseboard_fab2_lib.baseboard_fab2(sch_1):m_f_odt(2)") )
				( member ( signalRef "@baseboard_fab2_lib.baseboard_fab2(sch_1):m_f_odt(3)") )
				( member ( signalRef "@baseboard_fab2_lib.baseboard_fab2(sch_1):m_g_odt(0)") )
				( member ( signalRef "@baseboard_fab2_lib.baseboard_fab2(sch_1):m_g_odt(1)") )
				( member ( signalRef "@baseboard_fab2_lib.baseboard_fab2(sch_1):m_g_odt(2)") )
				( member ( signalRef "@baseboard_fab2_lib.baseboard_fab2(sch_1):m_g_odt(3)") )
				( member ( signalRef "@baseboard_fab2_lib.baseboard_fab2(sch_1):m_h_odt(0)") )
				( member ( signalRef "@baseboard_fab2_lib.baseboard_fab2(sch_1):m_h_odt(1)") )
				( member ( signalRef "@baseboard_fab2_lib.baseboard_fab2(sch_1):m_h_odt(2)") )
				( member ( signalRef "@baseboard_fab2_lib.baseboard_fab2(sch_1):m_h_odt(3)") )
				( member ( signalRef "@baseboard_fab2_lib.baseboard_fab2(sch_1):m_j_odt(0)") )
				( member ( signalRef "@baseboard_fab2_lib.baseboard_fab2(sch_1):m_j_odt(1)") )
				( member ( signalRef "@baseboard_fab2_lib.baseboard_fab2(sch_1):m_j_odt(2)") )
				( member ( signalRef "@baseboard_fab2_lib.baseboard_fab2(sch_1):m_j_odt(3)") )
				( member ( signalRef "@baseboard_fab2_lib.baseboard_fab2(sch_1):m_k_odt(0)") )
				( member ( signalRef "@baseboard_fab2_lib.baseboard_fab2(sch_1):m_k_odt(1)") )
				( member ( signalRef "@baseboard_fab2_lib.baseboard_fab2(sch_1):m_k_odt(2)") )
				( member ( signalRef "@baseboard_fab2_lib.baseboard_fab2(sch_1):m_k_odt(3)") )
				( member ( signalRef "@baseboard_fab2_lib.baseboard_fab2(sch_1):m_l_odt(0)") )
				( member ( signalRef "@baseboard_fab2_lib.baseboard_fab2(sch_1):m_l_odt(1)") )
				( member ( signalRef "@baseboard_fab2_lib.baseboard_fab2(sch_1):m_l_odt(2)") )
				( member ( signalRef "@baseboard_fab2_lib.baseboard_fab2(sch_1):m_l_odt(3)") )
				( member ( signalRef "@baseboard_fab2_lib.baseboard_fab2(sch_1):m_m_odt(0)") )
				( member ( signalRef "@baseboard_fab2_lib.baseboard_fab2(sch_1):m_m_odt(1)") )
				( member ( signalRef "@baseboard_fab2_lib.baseboard_fab2(sch_1):m_m_odt(2)") )
				( member ( signalRef "@baseboard_fab2_lib.baseboard_fab2(sch_1):m_m_odt(3)") )
				( member ( signalRef "@baseboard_fab2_lib.baseboard_fab2(sch_1):m_b_act_n") )
				( member ( signalRef "@baseboard_fab2_lib.baseboard_fab2(sch_1):m_c_act_n") )
				( member ( signalRef "@baseboard_fab2_lib.baseboard_fab2(sch_1):m_d_act_n") )
				( member ( signalRef "@baseboard_fab2_lib.baseboard_fab2(sch_1):m_e_act_n") )
				( member ( signalRef "@baseboard_fab2_lib.baseboard_fab2(sch_1):m_f_act_n") )
				( member ( signalRef "@baseboard_fab2_lib.baseboard_fab2(sch_1):m_g_act_n") )
				( member ( signalRef "@baseboard_fab2_lib.baseboard_fab2(sch_1):m_h_act_n") )
				( member ( signalRef "@baseboard_fab2_lib.baseboard_fab2(sch_1):m_j_act_n") )
				( member ( signalRef "@baseboard_fab2_lib.baseboard_fab2(sch_1):m_k_act_n") )
				( member ( signalRef "@baseboard_fab2_lib.baseboard_fab2(sch_1):m_l_act_n") )
				( member ( signalRef "@baseboard_fab2_lib.baseboard_fab2(sch_1):m_m_act_n") )
				( member ( signalRef "@baseboard_fab2_lib.baseboard_fab2(sch_1):m_b_alert_n") )
				( member ( signalRef "@baseboard_fab2_lib.baseboard_fab2(sch_1):m_c_alert_n") )
				( member ( signalRef "@baseboard_fab2_lib.baseboard_fab2(sch_1):m_d_alert_n") )
				( member ( signalRef "@baseboard_fab2_lib.baseboard_fab2(sch_1):m_e_alert_n") )
				( member ( signalRef "@baseboard_fab2_lib.baseboard_fab2(sch_1):m_f_alert_n") )
				( member ( signalRef "@baseboard_fab2_lib.baseboard_fab2(sch_1):m_g_alert_n") )
				( member ( signalRef "@baseboard_fab2_lib.baseboard_fab2(sch_1):m_h_alert_n") )
				( member ( signalRef "@baseboard_fab2_lib.baseboard_fab2(sch_1):m_j_alert_n") )
				( member ( signalRef "@baseboard_fab2_lib.baseboard_fab2(sch_1):m_k_alert_n") )
				( member ( signalRef "@baseboard_fab2_lib.baseboard_fab2(sch_1):m_l_alert_n") )
				( member ( signalRef "@baseboard_fab2_lib.baseboard_fab2(sch_1):m_m_alert_n") )
				( member ( signalRef "@baseboard_fab2_lib.baseboard_fab2(sch_1):m_b_par") )
				( member ( signalRef "@baseboard_fab2_lib.baseboard_fab2(sch_1):m_c_par") )
				( member ( signalRef "@baseboard_fab2_lib.baseboard_fab2(sch_1):m_d_par") )
				( member ( signalRef "@baseboard_fab2_lib.baseboard_fab2(sch_1):m_e_par") )
				( member ( signalRef "@baseboard_fab2_lib.baseboard_fab2(sch_1):m_f_par") )
				( member ( signalRef "@baseboard_fab2_lib.baseboard_fab2(sch_1):m_g_par") )
				( member ( signalRef "@baseboard_fab2_lib.baseboard_fab2(sch_1):m_h_par") )
				( member ( signalRef "@baseboard_fab2_lib.baseboard_fab2(sch_1):m_j_par") )
				( member ( signalRef "@baseboard_fab2_lib.baseboard_fab2(sch_1):m_k_par") )
				( member ( signalRef "@baseboard_fab2_lib.baseboard_fab2(sch_1):m_l_par") )
				( member ( signalRef "@baseboard_fab2_lib.baseboard_fab2(sch_1):m_m_par") )
				( member ( signalRef "@baseboard_fab2_lib.baseboard_fab2(sch_1):m_a_dq(0)") )
				( member ( signalRef "@baseboard_fab2_lib.baseboard_fab2(sch_1):m_a_dq(1)") )
				( member ( signalRef "@baseboard_fab2_lib.baseboard_fab2(sch_1):m_a_dq(2)") )
				( member ( signalRef "@baseboard_fab2_lib.baseboard_fab2(sch_1):m_a_dq(3)") )
				( member ( signalRef "@baseboard_fab2_lib.baseboard_fab2(sch_1):m_a_dq(4)") )
				( member ( signalRef "@baseboard_fab2_lib.baseboard_fab2(sch_1):m_a_dq(5)") )
				( member ( signalRef "@baseboard_fab2_lib.baseboard_fab2(sch_1):m_a_dq(6)") )
				( member ( signalRef "@baseboard_fab2_lib.baseboard_fab2(sch_1):m_a_dq(7)") )
				( member ( signalRef "@baseboard_fab2_lib.baseboard_fab2(sch_1):m_g_ma(1)") )
				( member ( signalRef "@baseboard_fab2_lib.baseboard_fab2(sch_1):m_g_ma(2)") )
				( member ( signalRef "@baseboard_fab2_lib.baseboard_fab2(sch_1):m_g_ma(3)") )
				( member ( signalRef "@baseboard_fab2_lib.baseboard_fab2(sch_1):m_g_ma(4)") )
				( member ( signalRef "@baseboard_fab2_lib.baseboard_fab2(sch_1):m_g_ma(5)") )
				( member ( signalRef "@baseboard_fab2_lib.baseboard_fab2(sch_1):m_g_ma(6)") )
				( member ( signalRef "@baseboard_fab2_lib.baseboard_fab2(sch_1):m_g_ma(7)") )
				( member ( signalRef "@baseboard_fab2_lib.baseboard_fab2(sch_1):m_g_ma(8)") )
				( member ( signalRef "@baseboard_fab2_lib.baseboard_fab2(sch_1):m_g_ma(9)") )
				( member ( signalRef "@baseboard_fab2_lib.baseboard_fab2(sch_1):m_g_ma(10)") )
				( member ( signalRef "@baseboard_fab2_lib.baseboard_fab2(sch_1):m_g_ma(11)") )
				( member ( signalRef "@baseboard_fab2_lib.baseboard_fab2(sch_1):m_g_ma(12)") )
				( member ( signalRef "@baseboard_fab2_lib.baseboard_fab2(sch_1):m_g_ma(13)") )
				( member ( signalRef "@baseboard_fab2_lib.baseboard_fab2(sch_1):m_g_ma(14)") )
				( member ( signalRef "@baseboard_fab2_lib.baseboard_fab2(sch_1):m_g_ma(15)") )
				( member ( signalRef "@baseboard_fab2_lib.baseboard_fab2(sch_1):m_g_ma(16)") )
				( member ( signalRef "@baseboard_fab2_lib.baseboard_fab2(sch_1):m_g_ma(17)") )
				( member ( signalRef "@baseboard_fab2_lib.baseboard_fab2(sch_1):m_h_ma(0)") )
				( member ( signalRef "@baseboard_fab2_lib.baseboard_fab2(sch_1):m_h_ma(1)") )
				( member ( signalRef "@baseboard_fab2_lib.baseboard_fab2(sch_1):m_h_ma(2)") )
				( member ( signalRef "@baseboard_fab2_lib.baseboard_fab2(sch_1):m_h_ma(3)") )
				( member ( signalRef "@baseboard_fab2_lib.baseboard_fab2(sch_1):m_h_ma(4)") )
				( member ( signalRef "@baseboard_fab2_lib.baseboard_fab2(sch_1):m_h_ma(5)") )
				( member ( signalRef "@baseboard_fab2_lib.baseboard_fab2(sch_1):m_h_ma(6)") )
				( member ( signalRef "@baseboard_fab2_lib.baseboard_fab2(sch_1):m_h_ma(7)") )
				( member ( signalRef "@baseboard_fab2_lib.baseboard_fab2(sch_1):m_h_ma(8)") )
				( member ( signalRef "@baseboard_fab2_lib.baseboard_fab2(sch_1):m_h_ma(9)") )
				( member ( signalRef "@baseboard_fab2_lib.baseboard_fab2(sch_1):m_h_ma(10)") )
				( member ( signalRef "@baseboard_fab2_lib.baseboard_fab2(sch_1):m_h_ma(11)") )
				( member ( signalRef "@baseboard_fab2_lib.baseboard_fab2(sch_1):m_h_ma(12)") )
				( member ( signalRef "@baseboard_fab2_lib.baseboard_fab2(sch_1):m_h_ma(13)") )
				( member ( signalRef "@baseboard_fab2_lib.baseboard_fab2(sch_1):m_h_ma(14)") )
				( member ( signalRef "@baseboard_fab2_lib.baseboard_fab2(sch_1):m_h_ma(15)") )
				( member ( signalRef "@baseboard_fab2_lib.baseboard_fab2(sch_1):m_h_ma(16)") )
				( member ( signalRef "@baseboard_fab2_lib.baseboard_fab2(sch_1):m_h_ma(17)") )
				( member ( signalRef "@baseboard_fab2_lib.baseboard_fab2(sch_1):m_j_ma(0)") )
				( member ( signalRef "@baseboard_fab2_lib.baseboard_fab2(sch_1):m_j_ma(1)") )
				( member ( signalRef "@baseboard_fab2_lib.baseboard_fab2(sch_1):m_j_ma(2)") )
				( member ( signalRef "@baseboard_fab2_lib.baseboard_fab2(sch_1):m_j_ma(3)") )
				( member ( signalRef "@baseboard_fab2_lib.baseboard_fab2(sch_1):m_j_ma(4)") )
				( member ( signalRef "@baseboard_fab2_lib.baseboard_fab2(sch_1):m_j_ma(5)") )
				( member ( signalRef "@baseboard_fab2_lib.baseboard_fab2(sch_1):m_j_ma(6)") )
				( member ( signalRef "@baseboard_fab2_lib.baseboard_fab2(sch_1):m_j_ma(7)") )
				( member ( signalRef "@baseboard_fab2_lib.baseboard_fab2(sch_1):m_j_ma(8)") )
				( member ( signalRef "@baseboard_fab2_lib.baseboard_fab2(sch_1):m_j_ma(9)") )
				( member ( signalRef "@baseboard_fab2_lib.baseboard_fab2(sch_1):m_j_ma(10)") )
				( member ( signalRef "@baseboard_fab2_lib.baseboard_fab2(sch_1):m_j_ma(11)") )
				( member ( signalRef "@baseboard_fab2_lib.baseboard_fab2(sch_1):m_j_ma(12)") )
				( member ( signalRef "@baseboard_fab2_lib.baseboard_fab2(sch_1):m_j_ma(13)") )
				( member ( signalRef "@baseboard_fab2_lib.baseboard_fab2(sch_1):m_j_ma(14)") )
				( member ( signalRef "@baseboard_fab2_lib.baseboard_fab2(sch_1):m_j_ma(15)") )
				( member ( signalRef "@baseboard_fab2_lib.baseboard_fab2(sch_1):m_j_ma(16)") )
				( member ( signalRef "@baseboard_fab2_lib.baseboard_fab2(sch_1):m_j_ma(17)") )
				( member ( signalRef "@baseboard_fab2_lib.baseboard_fab2(sch_1):m_k_ma(0)") )
				( member ( signalRef "@baseboard_fab2_lib.baseboard_fab2(sch_1):m_k_ma(1)") )
				( member ( signalRef "@baseboard_fab2_lib.baseboard_fab2(sch_1):m_k_ma(2)") )
				( member ( signalRef "@baseboard_fab2_lib.baseboard_fab2(sch_1):m_k_ma(3)") )
				( member ( signalRef "@baseboard_fab2_lib.baseboard_fab2(sch_1):m_k_ma(4)") )
				( member ( signalRef "@baseboard_fab2_lib.baseboard_fab2(sch_1):m_k_ma(5)") )
				( member ( signalRef "@baseboard_fab2_lib.baseboard_fab2(sch_1):m_k_ma(6)") )
				( member ( signalRef "@baseboard_fab2_lib.baseboard_fab2(sch_1):m_k_ma(7)") )
				( member ( signalRef "@baseboard_fab2_lib.baseboard_fab2(sch_1):m_k_ma(8)") )
				( member ( signalRef "@baseboard_fab2_lib.baseboard_fab2(sch_1):m_k_ma(9)") )
				( member ( signalRef "@baseboard_fab2_lib.baseboard_fab2(sch_1):m_k_ma(10)") )
				( member ( signalRef "@baseboard_fab2_lib.baseboard_fab2(sch_1):m_k_ma(11)") )
				( member ( signalRef "@baseboard_fab2_lib.baseboard_fab2(sch_1):m_k_ma(12)") )
				( member ( signalRef "@baseboard_fab2_lib.baseboard_fab2(sch_1):m_k_ma(13)") )
				( member ( signalRef "@baseboard_fab2_lib.baseboard_fab2(sch_1):m_k_ma(14)") )
				( member ( signalRef "@baseboard_fab2_lib.baseboard_fab2(sch_1):m_k_ma(15)") )
				( member ( signalRef "@baseboard_fab2_lib.baseboard_fab2(sch_1):m_k_ma(16)") )
				( member ( signalRef "@baseboard_fab2_lib.baseboard_fab2(sch_1):m_k_ma(17)") )
				( member ( signalRef "@baseboard_fab2_lib.baseboard_fab2(sch_1):m_l_ma(0)") )
				( member ( signalRef "@baseboard_fab2_lib.baseboard_fab2(sch_1):m_l_ma(1)") )
				( member ( signalRef "@baseboard_fab2_lib.baseboard_fab2(sch_1):m_l_ma(2)") )
				( member ( signalRef "@baseboard_fab2_lib.baseboard_fab2(sch_1):m_l_ma(3)") )
				( member ( signalRef "@baseboard_fab2_lib.baseboard_fab2(sch_1):m_l_ma(4)") )
				( member ( signalRef "@baseboard_fab2_lib.baseboard_fab2(sch_1):m_l_ma(5)") )
				( member ( signalRef "@baseboard_fab2_lib.baseboard_fab2(sch_1):m_l_ma(6)") )
				( member ( signalRef "@baseboard_fab2_lib.baseboard_fab2(sch_1):m_l_ma(7)") )
				( member ( signalRef "@baseboard_fab2_lib.baseboard_fab2(sch_1):m_l_ma(8)") )
				( member ( signalRef "@baseboard_fab2_lib.baseboard_fab2(sch_1):m_l_ma(9)") )
				( member ( signalRef "@baseboard_fab2_lib.baseboard_fab2(sch_1):m_l_ma(10)") )
				( member ( signalRef "@baseboard_fab2_lib.baseboard_fab2(sch_1):m_l_ma(11)") )
				( member ( signalRef "@baseboard_fab2_lib.baseboard_fab2(sch_1):m_l_ma(12)") )
				( member ( signalRef "@baseboard_fab2_lib.baseboard_fab2(sch_1):m_l_ma(13)") )
				( member ( signalRef "@baseboard_fab2_lib.baseboard_fab2(sch_1):m_l_ma(14)") )
				( member ( signalRef "@baseboard_fab2_lib.baseboard_fab2(sch_1):m_l_ma(15)") )
				( member ( signalRef "@baseboard_fab2_lib.baseboard_fab2(sch_1):m_l_ma(16)") )
				( member ( signalRef "@baseboard_fab2_lib.baseboard_fab2(sch_1):m_l_ma(17)") )
				( member ( signalRef "@baseboard_fab2_lib.baseboard_fab2(sch_1):m_m_ma(0)") )
				( member ( signalRef "@baseboard_fab2_lib.baseboard_fab2(sch_1):m_m_ma(1)") )
				( member ( signalRef "@baseboard_fab2_lib.baseboard_fab2(sch_1):m_m_ma(2)") )
				( member ( signalRef "@baseboard_fab2_lib.baseboard_fab2(sch_1):m_m_ma(3)") )
				( member ( signalRef "@baseboard_fab2_lib.baseboard_fab2(sch_1):m_m_ma(4)") )
				( member ( signalRef "@baseboard_fab2_lib.baseboard_fab2(sch_1):m_m_ma(5)") )
				( member ( signalRef "@baseboard_fab2_lib.baseboard_fab2(sch_1):m_m_ma(6)") )
				( member ( signalRef "@baseboard_fab2_lib.baseboard_fab2(sch_1):m_m_ma(7)") )
				( member ( signalRef "@baseboard_fab2_lib.baseboard_fab2(sch_1):m_m_ma(8)") )
				( member ( signalRef "@baseboard_fab2_lib.baseboard_fab2(sch_1):m_m_ma(9)") )
				( member ( signalRef "@baseboard_fab2_lib.baseboard_fab2(sch_1):m_m_ma(10)") )
				( member ( signalRef "@baseboard_fab2_lib.baseboard_fab2(sch_1):m_a_ma(9)") )
				( member ( signalRef "@baseboard_fab2_lib.baseboard_fab2(sch_1):m_a_ma(10)") )
				( member ( signalRef "@baseboard_fab2_lib.baseboard_fab2(sch_1):m_a_ma(11)") )
				( member ( signalRef "@baseboard_fab2_lib.baseboard_fab2(sch_1):m_a_ma(12)") )
				( member ( signalRef "@baseboard_fab2_lib.baseboard_fab2(sch_1):m_a_ma(13)") )
				( member ( signalRef "@baseboard_fab2_lib.baseboard_fab2(sch_1):m_a_ma(14)") )
				( member ( signalRef "@baseboard_fab2_lib.baseboard_fab2(sch_1):m_a_ma(15)") )
				( member ( signalRef "@baseboard_fab2_lib.baseboard_fab2(sch_1):m_a_ma(16)") )
				( member ( signalRef "@baseboard_fab2_lib.baseboard_fab2(sch_1):m_a_ma(17)") )
				( member ( signalRef "@baseboard_fab2_lib.baseboard_fab2(sch_1):m_b_ma(0)") )
				( member ( signalRef "@baseboard_fab2_lib.baseboard_fab2(sch_1):m_b_ma(1)") )
				( member ( signalRef "@baseboard_fab2_lib.baseboard_fab2(sch_1):m_b_ma(2)") )
				( member ( signalRef "@baseboard_fab2_lib.baseboard_fab2(sch_1):m_b_ma(3)") )
				( member ( signalRef "@baseboard_fab2_lib.baseboard_fab2(sch_1):m_b_ma(4)") )
				( member ( signalRef "@baseboard_fab2_lib.baseboard_fab2(sch_1):m_b_ma(5)") )
				( member ( signalRef "@baseboard_fab2_lib.baseboard_fab2(sch_1):m_b_ma(6)") )
				( member ( signalRef "@baseboard_fab2_lib.baseboard_fab2(sch_1):m_b_ma(7)") )
				( member ( signalRef "@baseboard_fab2_lib.baseboard_fab2(sch_1):m_b_ma(8)") )
				( member ( signalRef "@baseboard_fab2_lib.baseboard_fab2(sch_1):m_b_ma(9)") )
				( member ( signalRef "@baseboard_fab2_lib.baseboard_fab2(sch_1):m_b_ma(10)") )
				( member ( signalRef "@baseboard_fab2_lib.baseboard_fab2(sch_1):m_b_ma(11)") )
				( member ( signalRef "@baseboard_fab2_lib.baseboard_fab2(sch_1):m_b_ma(12)") )
				( member ( signalRef "@baseboard_fab2_lib.baseboard_fab2(sch_1):m_b_ma(13)") )
				( member ( signalRef "@baseboard_fab2_lib.baseboard_fab2(sch_1):m_b_ma(14)") )
				( member ( signalRef "@baseboard_fab2_lib.baseboard_fab2(sch_1):m_b_ma(15)") )
				( member ( signalRef "@baseboard_fab2_lib.baseboard_fab2(sch_1):m_b_ma(16)") )
				( member ( signalRef "@baseboard_fab2_lib.baseboard_fab2(sch_1):m_b_ma(17)") )
				( member ( signalRef "@baseboard_fab2_lib.baseboard_fab2(sch_1):m_c_ma(0)") )
				( member ( signalRef "@baseboard_fab2_lib.baseboard_fab2(sch_1):m_c_ma(1)") )
				( member ( signalRef "@baseboard_fab2_lib.baseboard_fab2(sch_1):m_c_ma(2)") )
				( member ( signalRef "@baseboard_fab2_lib.baseboard_fab2(sch_1):m_c_ma(3)") )
				( member ( signalRef "@baseboard_fab2_lib.baseboard_fab2(sch_1):m_c_ma(4)") )
				( member ( signalRef "@baseboard_fab2_lib.baseboard_fab2(sch_1):m_c_ma(5)") )
				( member ( signalRef "@baseboard_fab2_lib.baseboard_fab2(sch_1):m_c_ma(6)") )
				( member ( signalRef "@baseboard_fab2_lib.baseboard_fab2(sch_1):m_c_ma(7)") )
				( member ( signalRef "@baseboard_fab2_lib.baseboard_fab2(sch_1):m_c_ma(8)") )
				( member ( signalRef "@baseboard_fab2_lib.baseboard_fab2(sch_1):m_c_ma(9)") )
				( member ( signalRef "@baseboard_fab2_lib.baseboard_fab2(sch_1):m_c_ma(10)") )
				( member ( signalRef "@baseboard_fab2_lib.baseboard_fab2(sch_1):m_c_ma(11)") )
				( member ( signalRef "@baseboard_fab2_lib.baseboard_fab2(sch_1):m_c_ma(12)") )
				( member ( signalRef "@baseboard_fab2_lib.baseboard_fab2(sch_1):m_c_ma(13)") )
				( member ( signalRef "@baseboard_fab2_lib.baseboard_fab2(sch_1):m_c_ma(14)") )
				( member ( signalRef "@baseboard_fab2_lib.baseboard_fab2(sch_1):m_c_ma(15)") )
				( member ( signalRef "@baseboard_fab2_lib.baseboard_fab2(sch_1):m_c_ma(16)") )
				( member ( signalRef "@baseboard_fab2_lib.baseboard_fab2(sch_1):m_c_ma(17)") )
				( member ( signalRef "@baseboard_fab2_lib.baseboard_fab2(sch_1):m_d_ma(0)") )
				( member ( signalRef "@baseboard_fab2_lib.baseboard_fab2(sch_1):m_d_ma(1)") )
				( member ( signalRef "@baseboard_fab2_lib.baseboard_fab2(sch_1):m_d_ma(2)") )
				( member ( signalRef "@baseboard_fab2_lib.baseboard_fab2(sch_1):m_d_ma(3)") )
				( member ( signalRef "@baseboard_fab2_lib.baseboard_fab2(sch_1):m_d_ma(4)") )
				( member ( signalRef "@baseboard_fab2_lib.baseboard_fab2(sch_1):m_d_ma(5)") )
				( member ( signalRef "@baseboard_fab2_lib.baseboard_fab2(sch_1):m_d_ma(6)") )
				( member ( signalRef "@baseboard_fab2_lib.baseboard_fab2(sch_1):m_d_ma(7)") )
				( member ( signalRef "@baseboard_fab2_lib.baseboard_fab2(sch_1):m_d_ma(8)") )
				( member ( signalRef "@baseboard_fab2_lib.baseboard_fab2(sch_1):m_d_ma(9)") )
				( member ( signalRef "@baseboard_fab2_lib.baseboard_fab2(sch_1):m_d_ma(10)") )
				( member ( signalRef "@baseboard_fab2_lib.baseboard_fab2(sch_1):m_d_ma(11)") )
				( member ( signalRef "@baseboard_fab2_lib.baseboard_fab2(sch_1):m_d_ma(12)") )
				( member ( signalRef "@baseboard_fab2_lib.baseboard_fab2(sch_1):m_d_ma(13)") )
				( member ( signalRef "@baseboard_fab2_lib.baseboard_fab2(sch_1):m_d_ma(14)") )
				( member ( signalRef "@baseboard_fab2_lib.baseboard_fab2(sch_1):m_d_ma(15)") )
				( member ( signalRef "@baseboard_fab2_lib.baseboard_fab2(sch_1):m_d_ma(16)") )
				( member ( signalRef "@baseboard_fab2_lib.baseboard_fab2(sch_1):m_d_ma(17)") )
				( member ( signalRef "@baseboard_fab2_lib.baseboard_fab2(sch_1):m_e_ma(0)") )
				( member ( signalRef "@baseboard_fab2_lib.baseboard_fab2(sch_1):m_e_ma(1)") )
				( member ( signalRef "@baseboard_fab2_lib.baseboard_fab2(sch_1):m_e_ma(2)") )
				( member ( signalRef "@baseboard_fab2_lib.baseboard_fab2(sch_1):m_e_ma(3)") )
				( member ( signalRef "@baseboard_fab2_lib.baseboard_fab2(sch_1):m_e_ma(4)") )
				( member ( signalRef "@baseboard_fab2_lib.baseboard_fab2(sch_1):m_e_ma(5)") )
				( member ( signalRef "@baseboard_fab2_lib.baseboard_fab2(sch_1):m_e_ma(6)") )
				( member ( signalRef "@baseboard_fab2_lib.baseboard_fab2(sch_1):m_e_ma(7)") )
				( member ( signalRef "@baseboard_fab2_lib.baseboard_fab2(sch_1):m_e_ma(8)") )
				( member ( signalRef "@baseboard_fab2_lib.baseboard_fab2(sch_1):m_e_ma(9)") )
				( member ( signalRef "@baseboard_fab2_lib.baseboard_fab2(sch_1):m_e_ma(10)") )
				( member ( signalRef "@baseboard_fab2_lib.baseboard_fab2(sch_1):m_e_ma(11)") )
				( member ( signalRef "@baseboard_fab2_lib.baseboard_fab2(sch_1):m_e_ma(12)") )
				( member ( signalRef "@baseboard_fab2_lib.baseboard_fab2(sch_1):m_e_ma(13)") )
				( member ( signalRef "@baseboard_fab2_lib.baseboard_fab2(sch_1):m_e_ma(14)") )
				( member ( signalRef "@baseboard_fab2_lib.baseboard_fab2(sch_1):m_e_ma(15)") )
				( member ( signalRef "@baseboard_fab2_lib.baseboard_fab2(sch_1):m_e_ma(16)") )
				( member ( signalRef "@baseboard_fab2_lib.baseboard_fab2(sch_1):m_e_ma(17)") )
				( member ( signalRef "@baseboard_fab2_lib.baseboard_fab2(sch_1):m_f_ma(0)") )
				( member ( signalRef "@baseboard_fab2_lib.baseboard_fab2(sch_1):m_f_ma(1)") )
				( member ( signalRef "@baseboard_fab2_lib.baseboard_fab2(sch_1):m_f_ma(2)") )
				( member ( signalRef "@baseboard_fab2_lib.baseboard_fab2(sch_1):m_f_ma(3)") )
				( member ( signalRef "@baseboard_fab2_lib.baseboard_fab2(sch_1):m_f_ma(4)") )
				( member ( signalRef "@baseboard_fab2_lib.baseboard_fab2(sch_1):m_f_ma(5)") )
				( member ( signalRef "@baseboard_fab2_lib.baseboard_fab2(sch_1):m_f_ma(6)") )
				( member ( signalRef "@baseboard_fab2_lib.baseboard_fab2(sch_1):m_f_ma(7)") )
				( member ( signalRef "@baseboard_fab2_lib.baseboard_fab2(sch_1):m_f_ma(8)") )
				( member ( signalRef "@baseboard_fab2_lib.baseboard_fab2(sch_1):m_f_ma(9)") )
				( member ( signalRef "@baseboard_fab2_lib.baseboard_fab2(sch_1):m_f_ma(10)") )
				( member ( signalRef "@baseboard_fab2_lib.baseboard_fab2(sch_1):m_f_ma(11)") )
				( member ( signalRef "@baseboard_fab2_lib.baseboard_fab2(sch_1):m_f_ma(12)") )
				( member ( signalRef "@baseboard_fab2_lib.baseboard_fab2(sch_1):m_f_ma(13)") )
				( member ( signalRef "@baseboard_fab2_lib.baseboard_fab2(sch_1):m_f_ma(14)") )
				( member ( signalRef "@baseboard_fab2_lib.baseboard_fab2(sch_1):m_f_ma(15)") )
				( member ( signalRef "@baseboard_fab2_lib.baseboard_fab2(sch_1):m_f_ma(16)") )
				( member ( signalRef "@baseboard_fab2_lib.baseboard_fab2(sch_1):m_f_ma(17)") )
				( member ( signalRef "@baseboard_fab2_lib.baseboard_fab2(sch_1):m_g_ma(0)") )
				( member ( signalRef "@baseboard_fab2_lib.baseboard_fab2(sch_1):m_h_cs_n(2)") )
				( member ( signalRef "@baseboard_fab2_lib.baseboard_fab2(sch_1):m_h_cs_n(3)") )
				( member ( signalRef "@baseboard_fab2_lib.baseboard_fab2(sch_1):m_h_cs_n(4)") )
				( member ( signalRef "@baseboard_fab2_lib.baseboard_fab2(sch_1):m_h_cs_n(5)") )
				( member ( signalRef "@baseboard_fab2_lib.baseboard_fab2(sch_1):m_h_cs_n(6)") )
				( member ( signalRef "@baseboard_fab2_lib.baseboard_fab2(sch_1):m_h_cs_n(7)") )
				( member ( signalRef "@baseboard_fab2_lib.baseboard_fab2(sch_1):m_j_cs_n(0)") )
				( member ( signalRef "@baseboard_fab2_lib.baseboard_fab2(sch_1):m_j_cs_n(1)") )
				( member ( signalRef "@baseboard_fab2_lib.baseboard_fab2(sch_1):m_j_cs_n(2)") )
				( member ( signalRef "@baseboard_fab2_lib.baseboard_fab2(sch_1):m_j_cs_n(3)") )
				( member ( signalRef "@baseboard_fab2_lib.baseboard_fab2(sch_1):m_j_cs_n(4)") )
				( member ( signalRef "@baseboard_fab2_lib.baseboard_fab2(sch_1):m_j_cs_n(5)") )
				( member ( signalRef "@baseboard_fab2_lib.baseboard_fab2(sch_1):m_j_cs_n(6)") )
				( member ( signalRef "@baseboard_fab2_lib.baseboard_fab2(sch_1):m_j_cs_n(7)") )
				( member ( signalRef "@baseboard_fab2_lib.baseboard_fab2(sch_1):m_k_cs_n(0)") )
				( member ( signalRef "@baseboard_fab2_lib.baseboard_fab2(sch_1):m_k_cs_n(1)") )
				( member ( signalRef "@baseboard_fab2_lib.baseboard_fab2(sch_1):m_k_cs_n(2)") )
				( member ( signalRef "@baseboard_fab2_lib.baseboard_fab2(sch_1):m_k_cs_n(3)") )
				( member ( signalRef "@baseboard_fab2_lib.baseboard_fab2(sch_1):m_k_cs_n(4)") )
				( member ( signalRef "@baseboard_fab2_lib.baseboard_fab2(sch_1):m_k_cs_n(5)") )
				( member ( signalRef "@baseboard_fab2_lib.baseboard_fab2(sch_1):m_k_cs_n(6)") )
				( member ( signalRef "@baseboard_fab2_lib.baseboard_fab2(sch_1):m_k_cs_n(7)") )
				( member ( signalRef "@baseboard_fab2_lib.baseboard_fab2(sch_1):m_l_cs_n(0)") )
				( member ( signalRef "@baseboard_fab2_lib.baseboard_fab2(sch_1):m_l_cs_n(1)") )
				( member ( signalRef "@baseboard_fab2_lib.baseboard_fab2(sch_1):m_l_cs_n(2)") )
				( member ( signalRef "@baseboard_fab2_lib.baseboard_fab2(sch_1):m_l_cs_n(3)") )
				( member ( signalRef "@baseboard_fab2_lib.baseboard_fab2(sch_1):m_l_cs_n(4)") )
				( member ( signalRef "@baseboard_fab2_lib.baseboard_fab2(sch_1):m_l_cs_n(5)") )
				( member ( signalRef "@baseboard_fab2_lib.baseboard_fab2(sch_1):m_l_cs_n(6)") )
				( member ( signalRef "@baseboard_fab2_lib.baseboard_fab2(sch_1):m_l_cs_n(7)") )
				( member ( signalRef "@baseboard_fab2_lib.baseboard_fab2(sch_1):m_m_cs_n(0)") )
				( member ( signalRef "@baseboard_fab2_lib.baseboard_fab2(sch_1):m_m_cs_n(1)") )
				( member ( signalRef "@baseboard_fab2_lib.baseboard_fab2(sch_1):m_m_cs_n(2)") )
				( member ( signalRef "@baseboard_fab2_lib.baseboard_fab2(sch_1):m_m_cs_n(3)") )
				( member ( signalRef "@baseboard_fab2_lib.baseboard_fab2(sch_1):m_m_cs_n(4)") )
				( member ( signalRef "@baseboard_fab2_lib.baseboard_fab2(sch_1):m_m_cs_n(5)") )
				( member ( signalRef "@baseboard_fab2_lib.baseboard_fab2(sch_1):m_m_cs_n(6)") )
				( member ( signalRef "@baseboard_fab2_lib.baseboard_fab2(sch_1):m_m_cs_n(7)") )
				( member ( signalRef "@baseboard_fab2_lib.baseboard_fab2(sch_1):m_b_cke(0)") )
				( member ( signalRef "@baseboard_fab2_lib.baseboard_fab2(sch_1):m_b_cke(1)") )
				( member ( signalRef "@baseboard_fab2_lib.baseboard_fab2(sch_1):m_b_cke(2)") )
				( member ( signalRef "@baseboard_fab2_lib.baseboard_fab2(sch_1):m_b_cke(3)") )
				( member ( signalRef "@baseboard_fab2_lib.baseboard_fab2(sch_1):m_c_cke(0)") )
				( member ( signalRef "@baseboard_fab2_lib.baseboard_fab2(sch_1):m_c_cke(1)") )
				( member ( signalRef "@baseboard_fab2_lib.baseboard_fab2(sch_1):m_c_cke(2)") )
				( member ( signalRef "@baseboard_fab2_lib.baseboard_fab2(sch_1):m_c_cke(3)") )
				( member ( signalRef "@baseboard_fab2_lib.baseboard_fab2(sch_1):m_d_cke(0)") )
				( member ( signalRef "@baseboard_fab2_lib.baseboard_fab2(sch_1):m_d_cke(1)") )
				( member ( signalRef "@baseboard_fab2_lib.baseboard_fab2(sch_1):m_d_cke(2)") )
				( member ( signalRef "@baseboard_fab2_lib.baseboard_fab2(sch_1):m_d_cke(3)") )
				( member ( signalRef "@baseboard_fab2_lib.baseboard_fab2(sch_1):m_e_cke(0)") )
				( member ( signalRef "@baseboard_fab2_lib.baseboard_fab2(sch_1):m_e_cke(1)") )
				( member ( signalRef "@baseboard_fab2_lib.baseboard_fab2(sch_1):m_e_cke(2)") )
				( member ( signalRef "@baseboard_fab2_lib.baseboard_fab2(sch_1):m_e_cke(3)") )
				( member ( signalRef "@baseboard_fab2_lib.baseboard_fab2(sch_1):m_f_cke(0)") )
				( member ( signalRef "@baseboard_fab2_lib.baseboard_fab2(sch_1):m_f_cke(1)") )
				( member ( signalRef "@baseboard_fab2_lib.baseboard_fab2(sch_1):m_f_cke(2)") )
				( member ( signalRef "@baseboard_fab2_lib.baseboard_fab2(sch_1):m_f_cke(3)") )
				( member ( signalRef "@baseboard_fab2_lib.baseboard_fab2(sch_1):m_g_cke(0)") )
				( member ( signalRef "@baseboard_fab2_lib.baseboard_fab2(sch_1):m_g_cke(1)") )
				( member ( signalRef "@baseboard_fab2_lib.baseboard_fab2(sch_1):m_g_cke(2)") )
				( member ( signalRef "@baseboard_fab2_lib.baseboard_fab2(sch_1):m_g_cke(3)") )
				( member ( signalRef "@baseboard_fab2_lib.baseboard_fab2(sch_1):m_h_cke(0)") )
				( member ( signalRef "@baseboard_fab2_lib.baseboard_fab2(sch_1):m_h_cke(1)") )
				( member ( signalRef "@baseboard_fab2_lib.baseboard_fab2(sch_1):m_h_cke(2)") )
				( member ( signalRef "@baseboard_fab2_lib.baseboard_fab2(sch_1):m_h_cke(3)") )
				( member ( signalRef "@baseboard_fab2_lib.baseboard_fab2(sch_1):m_j_cke(0)") )
				( member ( signalRef "@baseboard_fab2_lib.baseboard_fab2(sch_1):m_j_cke(1)") )
				( member ( signalRef "@baseboard_fab2_lib.baseboard_fab2(sch_1):m_j_cke(2)") )
				( member ( signalRef "@baseboard_fab2_lib.baseboard_fab2(sch_1):m_j_cke(3)") )
				( member ( signalRef "@baseboard_fab2_lib.baseboard_fab2(sch_1):m_k_cke(0)") )
				( member ( signalRef "@baseboard_fab2_lib.baseboard_fab2(sch_1):m_k_cke(1)") )
				( member ( signalRef "@baseboard_fab2_lib.baseboard_fab2(sch_1):m_k_cke(2)") )
				( member ( signalRef "@baseboard_fab2_lib.baseboard_fab2(sch_1):m_k_cke(3)") )
				( member ( signalRef "@baseboard_fab2_lib.baseboard_fab2(sch_1):m_l_cke(0)") )
				( member ( signalRef "@baseboard_fab2_lib.baseboard_fab2(sch_1):m_l_cke(1)") )
				( member ( signalRef "@baseboard_fab2_lib.baseboard_fab2(sch_1):m_l_cke(2)") )
				( member ( signalRef "@baseboard_fab2_lib.baseboard_fab2(sch_1):m_l_cke(3)") )
				( member ( signalRef "@baseboard_fab2_lib.baseboard_fab2(sch_1):m_m_cke(0)") )
				( member ( signalRef "@baseboard_fab2_lib.baseboard_fab2(sch_1):m_m_cke(1)") )
				( member ( signalRef "@baseboard_fab2_lib.baseboard_fab2(sch_1):m_m_cke(2)") )
				( member ( signalRef "@baseboard_fab2_lib.baseboard_fab2(sch_1):m_m_cke(3)") )
				( member ( signalRef "@baseboard_fab2_lib.baseboard_fab2(sch_1):m_a_ba(0)") )
				( member ( signalRef "@baseboard_fab2_lib.baseboard_fab2(sch_1):m_a_ba(1)") )
				( member ( signalRef "@baseboard_fab2_lib.baseboard_fab2(sch_1):m_b_ba(0)") )
				( member ( signalRef "@baseboard_fab2_lib.baseboard_fab2(sch_1):m_b_ba(1)") )
				( member ( signalRef "@baseboard_fab2_lib.baseboard_fab2(sch_1):m_c_ba(0)") )
				( member ( signalRef "@baseboard_fab2_lib.baseboard_fab2(sch_1):m_c_ba(1)") )
				( member ( signalRef "@baseboard_fab2_lib.baseboard_fab2(sch_1):m_d_ba(0)") )
				( member ( signalRef "@baseboard_fab2_lib.baseboard_fab2(sch_1):m_d_ba(1)") )
				( member ( signalRef "@baseboard_fab2_lib.baseboard_fab2(sch_1):m_e_ba(0)") )
				( member ( signalRef "@baseboard_fab2_lib.baseboard_fab2(sch_1):m_e_ba(1)") )
				( member ( signalRef "@baseboard_fab2_lib.baseboard_fab2(sch_1):m_f_ba(0)") )
				( member ( signalRef "@baseboard_fab2_lib.baseboard_fab2(sch_1):m_f_ba(1)") )
				( member ( signalRef "@baseboard_fab2_lib.baseboard_fab2(sch_1):m_g_ba(0)") )
				( member ( signalRef "@baseboard_fab2_lib.baseboard_fab2(sch_1):m_g_ba(1)") )
				( member ( signalRef "@baseboard_fab2_lib.baseboard_fab2(sch_1):m_h_ba(0)") )
				( member ( signalRef "@baseboard_fab2_lib.baseboard_fab2(sch_1):m_h_ba(1)") )
				( member ( signalRef "@baseboard_fab2_lib.baseboard_fab2(sch_1):m_j_ba(0)") )
				( member ( signalRef "@baseboard_fab2_lib.baseboard_fab2(sch_1):m_j_ba(1)") )
				( member ( signalRef "@baseboard_fab2_lib.baseboard_fab2(sch_1):m_a_ma(8)") )
				( member ( signalRef "@baseboard_fab2_lib.baseboard_fab2(sch_1):m_a_ma(7)") )
				( member ( signalRef "@baseboard_fab2_lib.baseboard_fab2(sch_1):m_a_ma(6)") )
				( member ( signalRef "@baseboard_fab2_lib.baseboard_fab2(sch_1):m_a_ma(5)") )
				( member ( signalRef "@baseboard_fab2_lib.baseboard_fab2(sch_1):m_a_ma(4)") )
				( member ( signalRef "@baseboard_fab2_lib.baseboard_fab2(sch_1):m_a_ma(3)") )
				( member ( signalRef "@baseboard_fab2_lib.baseboard_fab2(sch_1):m_a_act_n") )
				( member ( signalRef "@baseboard_fab2_lib.baseboard_fab2(sch_1):m_a_alert_n") )
				( member ( signalRef "@baseboard_fab2_lib.baseboard_fab2(sch_1):m_a_par") )
				( member ( signalRef "@baseboard_fab2_lib.baseboard_fab2(sch_1):m_a_ma(2)") )
				( member ( signalRef "@baseboard_fab2_lib.baseboard_fab2(sch_1):m_a_ma(1)") )
				( member ( signalRef "@baseboard_fab2_lib.baseboard_fab2(sch_1):m_m_bg(1)") )
				( member ( signalRef "@baseboard_fab2_lib.baseboard_fab2(sch_1):m_m_bg(0)") )
				( member ( signalRef "@baseboard_fab2_lib.baseboard_fab2(sch_1):m_l_bg(0)") )
				( member ( signalRef "@baseboard_fab2_lib.baseboard_fab2(sch_1):m_k_bg(1)") )
				( member ( signalRef "@baseboard_fab2_lib.baseboard_fab2(sch_1):m_j_bg(1)") )
				( member ( signalRef "@baseboard_fab2_lib.baseboard_fab2(sch_1):m_j_bg(0)") )
				( member ( signalRef "@baseboard_fab2_lib.baseboard_fab2(sch_1):m_h_bg(0)") )
				( member ( signalRef "@baseboard_fab2_lib.baseboard_fab2(sch_1):m_g_bg(1)") )
				( member ( signalRef "@baseboard_fab2_lib.baseboard_fab2(sch_1):m_f_bg(1)") )
				( member ( signalRef "@baseboard_fab2_lib.baseboard_fab2(sch_1):m_f_bg(0)") )
				( member ( signalRef "@baseboard_fab2_lib.baseboard_fab2(sch_1):m_e_bg(0)") )
				( member ( signalRef "@baseboard_fab2_lib.baseboard_fab2(sch_1):m_d_bg(1)") )
				( member ( signalRef "@baseboard_fab2_lib.baseboard_fab2(sch_1):m_c_bg(1)") )
				( member ( signalRef "@baseboard_fab2_lib.baseboard_fab2(sch_1):m_c_bg(0)") )
				( member ( signalRef "@baseboard_fab2_lib.baseboard_fab2(sch_1):m_b_bg(0)") )
				( member ( signalRef "@baseboard_fab2_lib.baseboard_fab2(sch_1):m_a_bg(1)") )
				( member ( signalRef "@baseboard_fab2_lib.baseboard_fab2(sch_1):m_m_ba(1)") )
				( member ( signalRef "@baseboard_fab2_lib.baseboard_fab2(sch_1):m_m_ba(0)") )
				( member ( signalRef "@baseboard_fab2_lib.baseboard_fab2(sch_1):m_l_ba(0)") )
				( member ( signalRef "@baseboard_fab2_lib.baseboard_fab2(sch_1):m_k_ba(1)") )
				( member ( signalRef "@baseboard_fab2_lib.baseboard_fab2(sch_1):m_a_ma(0)") )
				( member ( signalRef "@baseboard_fab2_lib.baseboard_fab2(sch_1):m_l_bg(1)") )
				( member ( signalRef "@baseboard_fab2_lib.baseboard_fab2(sch_1):m_k_bg(0)") )
				( member ( signalRef "@baseboard_fab2_lib.baseboard_fab2(sch_1):m_h_bg(1)") )
				( member ( signalRef "@baseboard_fab2_lib.baseboard_fab2(sch_1):m_g_bg(0)") )
				( member ( signalRef "@baseboard_fab2_lib.baseboard_fab2(sch_1):m_e_bg(1)") )
				( member ( signalRef "@baseboard_fab2_lib.baseboard_fab2(sch_1):m_d_bg(0)") )
				( member ( signalRef "@baseboard_fab2_lib.baseboard_fab2(sch_1):m_b_bg(1)") )
				( member ( signalRef "@baseboard_fab2_lib.baseboard_fab2(sch_1):m_a_bg(0)") )
				( member ( signalRef "@baseboard_fab2_lib.baseboard_fab2(sch_1):m_l_ba(1)") )
				( member ( signalRef "@baseboard_fab2_lib.baseboard_fab2(sch_1):m_k_ba(0)") )
				( member ( signalRef "@baseboard_fab2_lib.baseboard_fab2(sch_1):m_a_cs_n(0)") )
				( member ( signalRef "@baseboard_fab2_lib.baseboard_fab2(sch_1):m_a_cs_n(1)") )
				( member ( signalRef "@baseboard_fab2_lib.baseboard_fab2(sch_1):m_a_cs_n(2)") )
				( member ( signalRef "@baseboard_fab2_lib.baseboard_fab2(sch_1):m_a_cs_n(3)") )
				( member ( signalRef "@baseboard_fab2_lib.baseboard_fab2(sch_1):m_a_cs_n(4)") )
				( member ( signalRef "@baseboard_fab2_lib.baseboard_fab2(sch_1):m_a_cs_n(5)") )
				( member ( signalRef "@baseboard_fab2_lib.baseboard_fab2(sch_1):m_a_cs_n(6)") )
				( member ( signalRef "@baseboard_fab2_lib.baseboard_fab2(sch_1):m_a_cs_n(7)") )
				( member ( signalRef "@baseboard_fab2_lib.baseboard_fab2(sch_1):m_b_cs_n(0)") )
				( member ( signalRef "@baseboard_fab2_lib.baseboard_fab2(sch_1):m_b_cs_n(1)") )
				( member ( signalRef "@baseboard_fab2_lib.baseboard_fab2(sch_1):m_b_cs_n(2)") )
				( member ( signalRef "@baseboard_fab2_lib.baseboard_fab2(sch_1):m_b_cs_n(3)") )
				( member ( signalRef "@baseboard_fab2_lib.baseboard_fab2(sch_1):m_b_cs_n(4)") )
				( member ( signalRef "@baseboard_fab2_lib.baseboard_fab2(sch_1):m_b_cs_n(5)") )
				( member ( signalRef "@baseboard_fab2_lib.baseboard_fab2(sch_1):m_b_cs_n(6)") )
				( member ( signalRef "@baseboard_fab2_lib.baseboard_fab2(sch_1):m_b_cs_n(7)") )
				( member ( signalRef "@baseboard_fab2_lib.baseboard_fab2(sch_1):m_c_cs_n(0)") )
				( member ( signalRef "@baseboard_fab2_lib.baseboard_fab2(sch_1):m_c_cs_n(1)") )
				( member ( signalRef "@baseboard_fab2_lib.baseboard_fab2(sch_1):m_c_cs_n(2)") )
				( member ( signalRef "@baseboard_fab2_lib.baseboard_fab2(sch_1):m_c_cs_n(3)") )
				( member ( signalRef "@baseboard_fab2_lib.baseboard_fab2(sch_1):m_c_cs_n(4)") )
				( member ( signalRef "@baseboard_fab2_lib.baseboard_fab2(sch_1):m_c_cs_n(5)") )
				( member ( signalRef "@baseboard_fab2_lib.baseboard_fab2(sch_1):m_c_cs_n(6)") )
				( member ( signalRef "@baseboard_fab2_lib.baseboard_fab2(sch_1):m_c_cs_n(7)") )
				( member ( signalRef "@baseboard_fab2_lib.baseboard_fab2(sch_1):m_d_cs_n(0)") )
				( member ( signalRef "@baseboard_fab2_lib.baseboard_fab2(sch_1):m_d_cs_n(1)") )
				( member ( signalRef "@baseboard_fab2_lib.baseboard_fab2(sch_1):m_d_cs_n(2)") )
				( member ( signalRef "@baseboard_fab2_lib.baseboard_fab2(sch_1):m_d_cs_n(3)") )
				( member ( signalRef "@baseboard_fab2_lib.baseboard_fab2(sch_1):m_d_cs_n(4)") )
				( member ( signalRef "@baseboard_fab2_lib.baseboard_fab2(sch_1):m_d_cs_n(5)") )
				( member ( signalRef "@baseboard_fab2_lib.baseboard_fab2(sch_1):m_d_cs_n(6)") )
				( member ( signalRef "@baseboard_fab2_lib.baseboard_fab2(sch_1):m_d_cs_n(7)") )
				( member ( signalRef "@baseboard_fab2_lib.baseboard_fab2(sch_1):m_e_cs_n(0)") )
				( member ( signalRef "@baseboard_fab2_lib.baseboard_fab2(sch_1):m_e_cs_n(1)") )
				( member ( signalRef "@baseboard_fab2_lib.baseboard_fab2(sch_1):m_e_cs_n(2)") )
				( member ( signalRef "@baseboard_fab2_lib.baseboard_fab2(sch_1):m_e_cs_n(3)") )
				( member ( signalRef "@baseboard_fab2_lib.baseboard_fab2(sch_1):m_e_cs_n(4)") )
				( member ( signalRef "@baseboard_fab2_lib.baseboard_fab2(sch_1):m_e_cs_n(5)") )
				( member ( signalRef "@baseboard_fab2_lib.baseboard_fab2(sch_1):m_e_cs_n(6)") )
				( member ( signalRef "@baseboard_fab2_lib.baseboard_fab2(sch_1):m_e_cs_n(7)") )
				( member ( signalRef "@baseboard_fab2_lib.baseboard_fab2(sch_1):m_f_cs_n(0)") )
				( member ( signalRef "@baseboard_fab2_lib.baseboard_fab2(sch_1):m_f_cs_n(1)") )
				( member ( signalRef "@baseboard_fab2_lib.baseboard_fab2(sch_1):m_f_cs_n(2)") )
				( member ( signalRef "@baseboard_fab2_lib.baseboard_fab2(sch_1):m_f_cs_n(3)") )
				( member ( signalRef "@baseboard_fab2_lib.baseboard_fab2(sch_1):m_f_cs_n(4)") )
				( member ( signalRef "@baseboard_fab2_lib.baseboard_fab2(sch_1):m_f_cs_n(5)") )
				( member ( signalRef "@baseboard_fab2_lib.baseboard_fab2(sch_1):m_f_cs_n(6)") )
				( member ( signalRef "@baseboard_fab2_lib.baseboard_fab2(sch_1):m_f_cs_n(7)") )
				( member ( signalRef "@baseboard_fab2_lib.baseboard_fab2(sch_1):m_g_cs_n(0)") )
				( member ( signalRef "@baseboard_fab2_lib.baseboard_fab2(sch_1):m_g_cs_n(1)") )
				( member ( signalRef "@baseboard_fab2_lib.baseboard_fab2(sch_1):m_g_cs_n(2)") )
				( member ( signalRef "@baseboard_fab2_lib.baseboard_fab2(sch_1):m_g_cs_n(3)") )
				( member ( signalRef "@baseboard_fab2_lib.baseboard_fab2(sch_1):m_g_cs_n(4)") )
				( member ( signalRef "@baseboard_fab2_lib.baseboard_fab2(sch_1):m_g_cs_n(5)") )
				( member ( signalRef "@baseboard_fab2_lib.baseboard_fab2(sch_1):m_g_cs_n(6)") )
				( member ( signalRef "@baseboard_fab2_lib.baseboard_fab2(sch_1):m_g_cs_n(7)") )
				( member ( signalRef "@baseboard_fab2_lib.baseboard_fab2(sch_1):m_h_cs_n(0)") )
				( member ( signalRef "@baseboard_fab2_lib.baseboard_fab2(sch_1):m_h_cs_n(1)") )
				( objectStatus "PNCLS_40-OHM-MS_&_38-OHM-SL_SE" )
			)
			( netClass "@crescent_city_bb_fab1_lib.crescent_city_bb_fab1(sch_1):\40-OHM-MS_&_38-OHM-SL_DIFF\"
				( memberType ( signal ) )
				( physicalCSetRef "@sapphirecity_baseboard_lib.sapphirecity_baseboard(sch_1):\DDR4_2SPC_DQ/DQS\" )
				( objectFlag fObjectPhysical )
				( member ( diffPairRef "@sapphirecity_baseboard_lib.sapphirecity_baseboard(sch_1):\M_H_DQS_D\(2)") )
				( member ( diffPairRef "@sapphirecity_baseboard_lib.sapphirecity_baseboard(sch_1):\M_H_DQS_D\(3)") )
				( member ( diffPairRef "@sapphirecity_baseboard_lib.sapphirecity_baseboard(sch_1):\M_H_DQS_D\(4)") )
				( member ( diffPairRef "@sapphirecity_baseboard_lib.sapphirecity_baseboard(sch_1):\M_H_DQS_D\(5)") )
				( member ( diffPairRef "@sapphirecity_baseboard_lib.sapphirecity_baseboard(sch_1):\M_H_DQS_D\(6)") )
				( member ( diffPairRef "@sapphirecity_baseboard_lib.sapphirecity_baseboard(sch_1):\M_H_DQS_D\(7)") )
				( member ( diffPairRef "@sapphirecity_baseboard_lib.sapphirecity_baseboard(sch_1):\M_H_DQS_D\(8)") )
				( member ( diffPairRef "@sapphirecity_baseboard_lib.sapphirecity_baseboard(sch_1):\M_H_DQS_D\(9)") )
				( member ( diffPairRef "@sapphirecity_baseboard_lib.sapphirecity_baseboard(sch_1):\M_H_DQS_D\(10)") )
				( member ( diffPairRef "@sapphirecity_baseboard_lib.sapphirecity_baseboard(sch_1):\M_H_DQS_D\(11)") )
				( member ( diffPairRef "@sapphirecity_baseboard_lib.sapphirecity_baseboard(sch_1):\M_H_DQS_D\(12)") )
				( member ( diffPairRef "@sapphirecity_baseboard_lib.sapphirecity_baseboard(sch_1):\M_H_DQS_D\(13)") )
				( member ( diffPairRef "@sapphirecity_baseboard_lib.sapphirecity_baseboard(sch_1):\M_H_DQS_D\(14)") )
				( member ( diffPairRef "@sapphirecity_baseboard_lib.sapphirecity_baseboard(sch_1):\M_H_DQS_D\(15)") )
				( member ( diffPairRef "@sapphirecity_baseboard_lib.sapphirecity_baseboard(sch_1):\M_H_DQS_D\(16)") )
				( member ( diffPairRef "@sapphirecity_baseboard_lib.sapphirecity_baseboard(sch_1):\M_H_DQS_D\(17)") )
				( member ( diffPairRef "@sapphirecity_baseboard_lib.sapphirecity_baseboard(sch_1):\M_J_DQS_D\(0)") )
				( member ( diffPairRef "@sapphirecity_baseboard_lib.sapphirecity_baseboard(sch_1):\M_J_DQS_D\(1)") )
				( member ( diffPairRef "@sapphirecity_baseboard_lib.sapphirecity_baseboard(sch_1):\M_J_DQS_D\(2)") )
				( member ( diffPairRef "@sapphirecity_baseboard_lib.sapphirecity_baseboard(sch_1):\M_J_DQS_D\(3)") )
				( member ( diffPairRef "@sapphirecity_baseboard_lib.sapphirecity_baseboard(sch_1):\M_J_DQS_D\(4)") )
				( member ( diffPairRef "@sapphirecity_baseboard_lib.sapphirecity_baseboard(sch_1):\M_J_DQS_D\(5)") )
				( member ( diffPairRef "@sapphirecity_baseboard_lib.sapphirecity_baseboard(sch_1):\M_J_DQS_D\(6)") )
				( member ( diffPairRef "@sapphirecity_baseboard_lib.sapphirecity_baseboard(sch_1):\M_J_DQS_D\(7)") )
				( member ( diffPairRef "@sapphirecity_baseboard_lib.sapphirecity_baseboard(sch_1):\M_J_DQS_D\(8)") )
				( member ( diffPairRef "@sapphirecity_baseboard_lib.sapphirecity_baseboard(sch_1):\M_J_DQS_D\(9)") )
				( member ( diffPairRef "@sapphirecity_baseboard_lib.sapphirecity_baseboard(sch_1):\M_J_DQS_D\(10)") )
				( member ( diffPairRef "@sapphirecity_baseboard_lib.sapphirecity_baseboard(sch_1):\M_J_DQS_D\(11)") )
				( member ( diffPairRef "@sapphirecity_baseboard_lib.sapphirecity_baseboard(sch_1):\M_J_DQS_D\(12)") )
				( member ( diffPairRef "@sapphirecity_baseboard_lib.sapphirecity_baseboard(sch_1):\M_J_DQS_D\(13)") )
				( member ( diffPairRef "@sapphirecity_baseboard_lib.sapphirecity_baseboard(sch_1):\M_J_DQS_D\(14)") )
				( member ( diffPairRef "@sapphirecity_baseboard_lib.sapphirecity_baseboard(sch_1):\M_J_DQS_D\(15)") )
				( member ( diffPairRef "@sapphirecity_baseboard_lib.sapphirecity_baseboard(sch_1):\M_J_DQS_D\(16)") )
				( member ( diffPairRef "@sapphirecity_baseboard_lib.sapphirecity_baseboard(sch_1):\M_J_DQS_D\(17)") )
				( member ( diffPairRef "@sapphirecity_baseboard_lib.sapphirecity_baseboard(sch_1):\M_K_DQS_D\(0)") )
				( member ( diffPairRef "@sapphirecity_baseboard_lib.sapphirecity_baseboard(sch_1):\M_K_DQS_D\(1)") )
				( member ( diffPairRef "@sapphirecity_baseboard_lib.sapphirecity_baseboard(sch_1):\M_K_DQS_D\(2)") )
				( member ( diffPairRef "@sapphirecity_baseboard_lib.sapphirecity_baseboard(sch_1):\M_K_DQS_D\(3)") )
				( member ( diffPairRef "@sapphirecity_baseboard_lib.sapphirecity_baseboard(sch_1):\M_K_DQS_D\(4)") )
				( member ( diffPairRef "@sapphirecity_baseboard_lib.sapphirecity_baseboard(sch_1):\M_K_DQS_D\(5)") )
				( member ( diffPairRef "@sapphirecity_baseboard_lib.sapphirecity_baseboard(sch_1):\M_K_DQS_D\(6)") )
				( member ( diffPairRef "@sapphirecity_baseboard_lib.sapphirecity_baseboard(sch_1):\M_K_DQS_D\(7)") )
				( member ( diffPairRef "@sapphirecity_baseboard_lib.sapphirecity_baseboard(sch_1):\M_K_DQS_D\(8)") )
				( member ( diffPairRef "@sapphirecity_baseboard_lib.sapphirecity_baseboard(sch_1):\M_K_DQS_D\(9)") )
				( member ( diffPairRef "@sapphirecity_baseboard_lib.sapphirecity_baseboard(sch_1):\M_K_DQS_D\(10)") )
				( member ( diffPairRef "@sapphirecity_baseboard_lib.sapphirecity_baseboard(sch_1):\M_K_DQS_D\(11)") )
				( member ( diffPairRef "@sapphirecity_baseboard_lib.sapphirecity_baseboard(sch_1):\M_K_DQS_D\(12)") )
				( member ( diffPairRef "@sapphirecity_baseboard_lib.sapphirecity_baseboard(sch_1):\M_K_DQS_D\(13)") )
				( member ( diffPairRef "@sapphirecity_baseboard_lib.sapphirecity_baseboard(sch_1):\M_K_DQS_D\(14)") )
				( member ( diffPairRef "@sapphirecity_baseboard_lib.sapphirecity_baseboard(sch_1):\M_K_DQS_D\(15)") )
				( member ( diffPairRef "@sapphirecity_baseboard_lib.sapphirecity_baseboard(sch_1):\M_K_DQS_D\(16)") )
				( member ( diffPairRef "@sapphirecity_baseboard_lib.sapphirecity_baseboard(sch_1):\M_K_DQS_D\(17)") )
				( member ( diffPairRef "@sapphirecity_baseboard_lib.sapphirecity_baseboard(sch_1):\M_L_DQS_D\(0)") )
				( member ( diffPairRef "@sapphirecity_baseboard_lib.sapphirecity_baseboard(sch_1):\M_L_DQS_D\(1)") )
				( member ( diffPairRef "@sapphirecity_baseboard_lib.sapphirecity_baseboard(sch_1):\M_L_DQS_D\(2)") )
				( member ( diffPairRef "@sapphirecity_baseboard_lib.sapphirecity_baseboard(sch_1):\M_L_DQS_D\(3)") )
				( member ( diffPairRef "@sapphirecity_baseboard_lib.sapphirecity_baseboard(sch_1):\M_L_DQS_D\(4)") )
				( member ( diffPairRef "@sapphirecity_baseboard_lib.sapphirecity_baseboard(sch_1):\M_L_DQS_D\(5)") )
				( member ( diffPairRef "@sapphirecity_baseboard_lib.sapphirecity_baseboard(sch_1):\M_L_DQS_D\(6)") )
				( member ( diffPairRef "@sapphirecity_baseboard_lib.sapphirecity_baseboard(sch_1):\M_L_DQS_D\(7)") )
				( member ( diffPairRef "@sapphirecity_baseboard_lib.sapphirecity_baseboard(sch_1):\M_L_DQS_D\(8)") )
				( member ( diffPairRef "@sapphirecity_baseboard_lib.sapphirecity_baseboard(sch_1):\M_L_DQS_D\(9)") )
				( member ( diffPairRef "@sapphirecity_baseboard_lib.sapphirecity_baseboard(sch_1):\M_L_DQS_D\(10)") )
				( member ( diffPairRef "@sapphirecity_baseboard_lib.sapphirecity_baseboard(sch_1):\M_L_DQS_D\(11)") )
				( member ( diffPairRef "@sapphirecity_baseboard_lib.sapphirecity_baseboard(sch_1):\M_L_DQS_D\(12)") )
				( member ( diffPairRef "@sapphirecity_baseboard_lib.sapphirecity_baseboard(sch_1):\M_L_DQS_D\(13)") )
				( member ( diffPairRef "@sapphirecity_baseboard_lib.sapphirecity_baseboard(sch_1):\M_L_DQS_D\(14)") )
				( member ( diffPairRef "@sapphirecity_baseboard_lib.sapphirecity_baseboard(sch_1):\M_L_DQS_D\(15)") )
				( member ( diffPairRef "@sapphirecity_baseboard_lib.sapphirecity_baseboard(sch_1):\M_L_DQS_D\(16)") )
				( member ( diffPairRef "@sapphirecity_baseboard_lib.sapphirecity_baseboard(sch_1):\M_L_DQS_D\(17)") )
				( member ( diffPairRef "@sapphirecity_baseboard_lib.sapphirecity_baseboard(sch_1):\M_M_DQS_D\(0)") )
				( member ( diffPairRef "@sapphirecity_baseboard_lib.sapphirecity_baseboard(sch_1):\M_M_DQS_D\(1)") )
				( member ( diffPairRef "@sapphirecity_baseboard_lib.sapphirecity_baseboard(sch_1):\M_M_DQS_D\(2)") )
				( member ( diffPairRef "@sapphirecity_baseboard_lib.sapphirecity_baseboard(sch_1):\M_M_DQS_D\(3)") )
				( member ( diffPairRef "@sapphirecity_baseboard_lib.sapphirecity_baseboard(sch_1):\M_M_DQS_D\(4)") )
				( member ( diffPairRef "@sapphirecity_baseboard_lib.sapphirecity_baseboard(sch_1):\M_M_DQS_D\(5)") )
				( member ( diffPairRef "@sapphirecity_baseboard_lib.sapphirecity_baseboard(sch_1):\M_M_DQS_D\(6)") )
				( member ( diffPairRef "@sapphirecity_baseboard_lib.sapphirecity_baseboard(sch_1):\M_M_DQS_D\(7)") )
				( member ( diffPairRef "@sapphirecity_baseboard_lib.sapphirecity_baseboard(sch_1):\M_M_DQS_D\(8)") )
				( member ( diffPairRef "@sapphirecity_baseboard_lib.sapphirecity_baseboard(sch_1):\M_M_DQS_D\(9)") )
				( member ( diffPairRef "@sapphirecity_baseboard_lib.sapphirecity_baseboard(sch_1):\M_M_DQS_D\(10)") )
				( member ( diffPairRef "@sapphirecity_baseboard_lib.sapphirecity_baseboard(sch_1):\M_M_DQS_D\(11)") )
				( member ( diffPairRef "@sapphirecity_baseboard_lib.sapphirecity_baseboard(sch_1):\M_M_DQS_D\(12)") )
				( member ( diffPairRef "@sapphirecity_baseboard_lib.sapphirecity_baseboard(sch_1):\M_M_DQS_D\(13)") )
				( member ( diffPairRef "@sapphirecity_baseboard_lib.sapphirecity_baseboard(sch_1):\M_M_DQS_D\(14)") )
				( member ( diffPairRef "@sapphirecity_baseboard_lib.sapphirecity_baseboard(sch_1):\M_M_DQS_D\(15)") )
				( member ( diffPairRef "@sapphirecity_baseboard_lib.sapphirecity_baseboard(sch_1):\M_M_DQS_D\(16)") )
				( member ( diffPairRef "@sapphirecity_baseboard_lib.sapphirecity_baseboard(sch_1):\M_M_DQS_D\(17)") )
				( member ( diffPairRef "@sapphirecity_baseboard_lib.sapphirecity_baseboard(sch_1):\M_G_DQS_D\(0)") )
				( member ( diffPairRef "@sapphirecity_baseboard_lib.sapphirecity_baseboard(sch_1):\M_G_DQS_D\(1)") )
				( member ( diffPairRef "@sapphirecity_baseboard_lib.sapphirecity_baseboard(sch_1):\M_G_DQS_D\(2)") )
				( member ( diffPairRef "@sapphirecity_baseboard_lib.sapphirecity_baseboard(sch_1):\M_G_DQS_D\(3)") )
				( member ( diffPairRef "@sapphirecity_baseboard_lib.sapphirecity_baseboard(sch_1):\M_G_DQS_D\(4)") )
				( member ( diffPairRef "@sapphirecity_baseboard_lib.sapphirecity_baseboard(sch_1):\M_G_DQS_D\(5)") )
				( member ( diffPairRef "@sapphirecity_baseboard_lib.sapphirecity_baseboard(sch_1):\M_G_DQS_D\(6)") )
				( member ( diffPairRef "@sapphirecity_baseboard_lib.sapphirecity_baseboard(sch_1):\M_G_DQS_D\(7)") )
				( member ( diffPairRef "@sapphirecity_baseboard_lib.sapphirecity_baseboard(sch_1):\M_G_DQS_D\(8)") )
				( member ( diffPairRef "@sapphirecity_baseboard_lib.sapphirecity_baseboard(sch_1):\M_G_DQS_D\(9)") )
				( member ( diffPairRef "@sapphirecity_baseboard_lib.sapphirecity_baseboard(sch_1):\M_G_DQS_D\(10)") )
				( member ( diffPairRef "@sapphirecity_baseboard_lib.sapphirecity_baseboard(sch_1):\M_G_DQS_D\(11)") )
				( member ( diffPairRef "@sapphirecity_baseboard_lib.sapphirecity_baseboard(sch_1):\M_G_DQS_D\(12)") )
				( member ( diffPairRef "@sapphirecity_baseboard_lib.sapphirecity_baseboard(sch_1):\M_G_DQS_D\(13)") )
				( member ( diffPairRef "@sapphirecity_baseboard_lib.sapphirecity_baseboard(sch_1):\M_G_DQS_D\(14)") )
				( member ( diffPairRef "@sapphirecity_baseboard_lib.sapphirecity_baseboard(sch_1):\M_G_DQS_D\(15)") )
				( member ( diffPairRef "@sapphirecity_baseboard_lib.sapphirecity_baseboard(sch_1):\M_G_DQS_D\(16)") )
				( member ( diffPairRef "@sapphirecity_baseboard_lib.sapphirecity_baseboard(sch_1):\M_G_DQS_D\(17)") )
				( member ( diffPairRef "@sapphirecity_baseboard_lib.sapphirecity_baseboard(sch_1):\M_H_DQS_D\(0)") )
				( member ( diffPairRef "@sapphirecity_baseboard_lib.sapphirecity_baseboard(sch_1):\M_H_DQS_D\(1)") )
				( member ( diffPairRef "@sapphirecity_baseboard_lib.sapphirecity_baseboard(sch_1):\M_A_CLK_D\(0)") )
				( member ( diffPairRef "@sapphirecity_baseboard_lib.sapphirecity_baseboard(sch_1):\M_A_CLK_D\(1)") )
				( member ( diffPairRef "@sapphirecity_baseboard_lib.sapphirecity_baseboard(sch_1):\M_A_CLK_D\(2)") )
				( member ( diffPairRef "@sapphirecity_baseboard_lib.sapphirecity_baseboard(sch_1):\M_A_CLK_D\(3)") )
				( member ( diffPairRef "@sapphirecity_baseboard_lib.sapphirecity_baseboard(sch_1):\M_B_CLK_D\(0)") )
				( member ( diffPairRef "@sapphirecity_baseboard_lib.sapphirecity_baseboard(sch_1):\M_B_CLK_D\(1)") )
				( member ( diffPairRef "@sapphirecity_baseboard_lib.sapphirecity_baseboard(sch_1):\M_B_CLK_D\(2)") )
				( member ( diffPairRef "@sapphirecity_baseboard_lib.sapphirecity_baseboard(sch_1):\M_B_CLK_D\(3)") )
				( member ( diffPairRef "@sapphirecity_baseboard_lib.sapphirecity_baseboard(sch_1):\M_C_CLK_D\(0)") )
				( member ( diffPairRef "@sapphirecity_baseboard_lib.sapphirecity_baseboard(sch_1):\M_C_CLK_D\(2)") )
				( member ( diffPairRef "@sapphirecity_baseboard_lib.sapphirecity_baseboard(sch_1):\M_D_CLK_D\(0)") )
				( member ( diffPairRef "@sapphirecity_baseboard_lib.sapphirecity_baseboard(sch_1):\M_D_CLK_D\(2)") )
				( member ( diffPairRef "@sapphirecity_baseboard_lib.sapphirecity_baseboard(sch_1):\DP_M_D_CLK_D1\") )
				( member ( diffPairRef "@sapphirecity_baseboard_lib.sapphirecity_baseboard(sch_1):\DP_M_D_CLK_D3\") )
				( member ( diffPairRef "@sapphirecity_baseboard_lib.sapphirecity_baseboard(sch_1):\M_E_CLK_D\(0)") )
				( member ( diffPairRef "@sapphirecity_baseboard_lib.sapphirecity_baseboard(sch_1):\M_E_CLK_D\(1)") )
				( member ( diffPairRef "@sapphirecity_baseboard_lib.sapphirecity_baseboard(sch_1):\M_E_CLK_D\(2)") )
				( member ( diffPairRef "@sapphirecity_baseboard_lib.sapphirecity_baseboard(sch_1):\M_E_CLK_D\(3)") )
				( member ( diffPairRef "@sapphirecity_baseboard_lib.sapphirecity_baseboard(sch_1):\M_F_CLK_D\(0)") )
				( member ( diffPairRef "@sapphirecity_baseboard_lib.sapphirecity_baseboard(sch_1):\M_F_CLK_D\(2)") )
				( member ( diffPairRef "@crescent_city_bb_fab1_lib.crescent_city_bb_fab1(sch_1):\DP_M_G_CLK\(1)") )
				( member ( diffPairRef "@crescent_city_bb_fab1_lib.crescent_city_bb_fab1(sch_1):\DP_M_G_CLK\(3)") )
				( member ( diffPairRef "@sapphirecity_baseboard_lib.sapphirecity_baseboard(sch_1):\M_G_CLK_D\(0)") )
				( member ( diffPairRef "@sapphirecity_baseboard_lib.sapphirecity_baseboard(sch_1):\M_G_CLK_D\(1)") )
				( member ( diffPairRef "@sapphirecity_baseboard_lib.sapphirecity_baseboard(sch_1):\M_G_CLK_D\(2)") )
				( member ( diffPairRef "@sapphirecity_baseboard_lib.sapphirecity_baseboard(sch_1):\M_G_CLK_D\(3)") )
				( member ( diffPairRef "@sapphirecity_baseboard_lib.sapphirecity_baseboard(sch_1):\M_H_CLK_D\(0)") )
				( member ( diffPairRef "@sapphirecity_baseboard_lib.sapphirecity_baseboard(sch_1):\M_H_CLK_D\(1)") )
				( member ( diffPairRef "@sapphirecity_baseboard_lib.sapphirecity_baseboard(sch_1):\M_H_CLK_D\(2)") )
				( member ( diffPairRef "@sapphirecity_baseboard_lib.sapphirecity_baseboard(sch_1):\M_H_CLK_D\(3)") )
				( member ( diffPairRef "@crescent_city_bb_fab1_lib.crescent_city_bb_fab1(sch_1):\DP_M_J_CLK\(1)") )
				( member ( diffPairRef "@crescent_city_bb_fab1_lib.crescent_city_bb_fab1(sch_1):\DP_M_J_CLK\(3)") )
				( member ( diffPairRef "@sapphirecity_baseboard_lib.sapphirecity_baseboard(sch_1):\M_J_CLK_D\(0)") )
				( member ( diffPairRef "@sapphirecity_baseboard_lib.sapphirecity_baseboard(sch_1):\M_J_CLK_D\(2)") )
				( member ( diffPairRef "@crescent_city_bb_fab1_lib.crescent_city_bb_fab1(sch_1):\DP_M_K_CLK\(1)") )
				( member ( diffPairRef "@crescent_city_bb_fab1_lib.crescent_city_bb_fab1(sch_1):\DP_M_K_CLK\(3)") )
				( member ( diffPairRef "@sapphirecity_baseboard_lib.sapphirecity_baseboard(sch_1):\M_K_CLK_D\(0)") )
				( member ( diffPairRef "@sapphirecity_baseboard_lib.sapphirecity_baseboard(sch_1):\M_K_CLK_D\(1)") )
				( member ( diffPairRef "@sapphirecity_baseboard_lib.sapphirecity_baseboard(sch_1):\M_K_CLK_D\(2)") )
				( member ( diffPairRef "@sapphirecity_baseboard_lib.sapphirecity_baseboard(sch_1):\M_K_CLK_D\(3)") )
				( member ( diffPairRef "@sapphirecity_baseboard_lib.sapphirecity_baseboard(sch_1):\M_L_CLK_D\(0)") )
				( member ( diffPairRef "@sapphirecity_baseboard_lib.sapphirecity_baseboard(sch_1):\M_L_CLK_D\(1)") )
				( member ( diffPairRef "@sapphirecity_baseboard_lib.sapphirecity_baseboard(sch_1):\M_L_CLK_D\(2)") )
				( member ( diffPairRef "@sapphirecity_baseboard_lib.sapphirecity_baseboard(sch_1):\M_L_CLK_D\(3)") )
				( member ( diffPairRef "@sapphirecity_baseboard_lib.sapphirecity_baseboard(sch_1):\M_M_CLK_D\(0)") )
				( member ( diffPairRef "@sapphirecity_baseboard_lib.sapphirecity_baseboard(sch_1):\M_D_CLK_D\(1)") )
				( member ( diffPairRef "@sapphirecity_baseboard_lib.sapphirecity_baseboard(sch_1):\M_M_CLK_D\(2)") )
				( member ( diffPairRef "@sapphirecity_baseboard_lib.sapphirecity_baseboard(sch_1):\M_D_CLK_D\(3)") )
				( member ( signalRef "@baseboard_fab2_lib.baseboard_fab2(sch_1):m_k_dqs_dp(10)") )
				( member ( signalRef "@baseboard_fab2_lib.baseboard_fab2(sch_1):m_k_dqs_dp(11)") )
				( member ( signalRef "@baseboard_fab2_lib.baseboard_fab2(sch_1):m_k_dqs_dp(12)") )
				( member ( signalRef "@baseboard_fab2_lib.baseboard_fab2(sch_1):m_k_dqs_dp(13)") )
				( member ( signalRef "@baseboard_fab2_lib.baseboard_fab2(sch_1):m_k_dqs_dp(14)") )
				( member ( signalRef "@baseboard_fab2_lib.baseboard_fab2(sch_1):m_k_dqs_dp(15)") )
				( member ( signalRef "@baseboard_fab2_lib.baseboard_fab2(sch_1):m_k_dqs_dp(16)") )
				( member ( signalRef "@baseboard_fab2_lib.baseboard_fab2(sch_1):m_k_dqs_dp(17)") )
				( member ( signalRef "@baseboard_fab2_lib.baseboard_fab2(sch_1):m_l_dqs_dn(0)") )
				( member ( signalRef "@baseboard_fab2_lib.baseboard_fab2(sch_1):m_l_dqs_dn(1)") )
				( member ( signalRef "@baseboard_fab2_lib.baseboard_fab2(sch_1):m_l_dqs_dn(2)") )
				( member ( signalRef "@baseboard_fab2_lib.baseboard_fab2(sch_1):m_l_dqs_dn(3)") )
				( member ( signalRef "@baseboard_fab2_lib.baseboard_fab2(sch_1):m_l_dqs_dn(4)") )
				( member ( signalRef "@baseboard_fab2_lib.baseboard_fab2(sch_1):m_l_dqs_dn(5)") )
				( member ( signalRef "@baseboard_fab2_lib.baseboard_fab2(sch_1):m_l_dqs_dn(6)") )
				( member ( signalRef "@baseboard_fab2_lib.baseboard_fab2(sch_1):m_l_dqs_dn(7)") )
				( member ( signalRef "@baseboard_fab2_lib.baseboard_fab2(sch_1):m_l_dqs_dn(8)") )
				( member ( signalRef "@baseboard_fab2_lib.baseboard_fab2(sch_1):m_l_dqs_dn(9)") )
				( member ( signalRef "@baseboard_fab2_lib.baseboard_fab2(sch_1):m_l_dqs_dn(10)") )
				( member ( signalRef "@baseboard_fab2_lib.baseboard_fab2(sch_1):m_l_dqs_dn(11)") )
				( member ( signalRef "@baseboard_fab2_lib.baseboard_fab2(sch_1):m_l_dqs_dn(12)") )
				( member ( signalRef "@baseboard_fab2_lib.baseboard_fab2(sch_1):m_l_dqs_dn(13)") )
				( member ( signalRef "@baseboard_fab2_lib.baseboard_fab2(sch_1):m_l_dqs_dn(14)") )
				( member ( signalRef "@baseboard_fab2_lib.baseboard_fab2(sch_1):m_l_dqs_dn(15)") )
				( member ( signalRef "@baseboard_fab2_lib.baseboard_fab2(sch_1):m_l_dqs_dn(16)") )
				( member ( signalRef "@baseboard_fab2_lib.baseboard_fab2(sch_1):m_l_dqs_dn(17)") )
				( member ( signalRef "@baseboard_fab2_lib.baseboard_fab2(sch_1):m_l_dqs_dp(0)") )
				( member ( signalRef "@baseboard_fab2_lib.baseboard_fab2(sch_1):m_l_dqs_dp(1)") )
				( member ( signalRef "@baseboard_fab2_lib.baseboard_fab2(sch_1):m_l_dqs_dp(2)") )
				( member ( signalRef "@baseboard_fab2_lib.baseboard_fab2(sch_1):m_l_dqs_dp(3)") )
				( member ( signalRef "@baseboard_fab2_lib.baseboard_fab2(sch_1):m_l_dqs_dp(4)") )
				( member ( signalRef "@baseboard_fab2_lib.baseboard_fab2(sch_1):m_l_dqs_dp(5)") )
				( member ( signalRef "@baseboard_fab2_lib.baseboard_fab2(sch_1):m_l_dqs_dp(6)") )
				( member ( signalRef "@baseboard_fab2_lib.baseboard_fab2(sch_1):m_l_dqs_dp(7)") )
				( member ( signalRef "@baseboard_fab2_lib.baseboard_fab2(sch_1):m_l_dqs_dp(8)") )
				( member ( signalRef "@baseboard_fab2_lib.baseboard_fab2(sch_1):m_l_dqs_dp(9)") )
				( member ( signalRef "@baseboard_fab2_lib.baseboard_fab2(sch_1):m_l_dqs_dp(10)") )
				( member ( signalRef "@baseboard_fab2_lib.baseboard_fab2(sch_1):m_l_dqs_dp(11)") )
				( member ( signalRef "@baseboard_fab2_lib.baseboard_fab2(sch_1):m_l_dqs_dp(12)") )
				( member ( signalRef "@baseboard_fab2_lib.baseboard_fab2(sch_1):m_l_dqs_dp(13)") )
				( member ( signalRef "@baseboard_fab2_lib.baseboard_fab2(sch_1):m_l_dqs_dp(14)") )
				( member ( signalRef "@baseboard_fab2_lib.baseboard_fab2(sch_1):m_l_dqs_dp(15)") )
				( member ( signalRef "@baseboard_fab2_lib.baseboard_fab2(sch_1):m_l_dqs_dp(16)") )
				( member ( signalRef "@baseboard_fab2_lib.baseboard_fab2(sch_1):m_l_dqs_dp(17)") )
				( member ( signalRef "@baseboard_fab2_lib.baseboard_fab2(sch_1):m_m_dqs_dn(0)") )
				( member ( signalRef "@baseboard_fab2_lib.baseboard_fab2(sch_1):m_m_dqs_dn(1)") )
				( member ( signalRef "@baseboard_fab2_lib.baseboard_fab2(sch_1):m_m_dqs_dn(2)") )
				( member ( signalRef "@baseboard_fab2_lib.baseboard_fab2(sch_1):m_m_dqs_dn(3)") )
				( member ( signalRef "@baseboard_fab2_lib.baseboard_fab2(sch_1):m_m_dqs_dn(4)") )
				( member ( signalRef "@baseboard_fab2_lib.baseboard_fab2(sch_1):m_m_dqs_dn(5)") )
				( member ( signalRef "@baseboard_fab2_lib.baseboard_fab2(sch_1):m_m_dqs_dn(6)") )
				( member ( signalRef "@baseboard_fab2_lib.baseboard_fab2(sch_1):m_m_dqs_dn(7)") )
				( member ( signalRef "@baseboard_fab2_lib.baseboard_fab2(sch_1):m_m_dqs_dn(8)") )
				( member ( signalRef "@baseboard_fab2_lib.baseboard_fab2(sch_1):m_m_dqs_dn(9)") )
				( member ( signalRef "@baseboard_fab2_lib.baseboard_fab2(sch_1):m_m_dqs_dn(10)") )
				( member ( signalRef "@baseboard_fab2_lib.baseboard_fab2(sch_1):m_m_dqs_dn(11)") )
				( member ( signalRef "@baseboard_fab2_lib.baseboard_fab2(sch_1):m_m_dqs_dn(12)") )
				( member ( signalRef "@baseboard_fab2_lib.baseboard_fab2(sch_1):m_m_dqs_dn(13)") )
				( member ( signalRef "@baseboard_fab2_lib.baseboard_fab2(sch_1):m_m_dqs_dn(14)") )
				( member ( signalRef "@baseboard_fab2_lib.baseboard_fab2(sch_1):m_m_dqs_dn(15)") )
				( member ( signalRef "@baseboard_fab2_lib.baseboard_fab2(sch_1):m_m_dqs_dn(16)") )
				( member ( signalRef "@baseboard_fab2_lib.baseboard_fab2(sch_1):m_m_dqs_dn(17)") )
				( member ( signalRef "@baseboard_fab2_lib.baseboard_fab2(sch_1):m_m_dqs_dp(0)") )
				( member ( signalRef "@baseboard_fab2_lib.baseboard_fab2(sch_1):m_m_dqs_dp(1)") )
				( member ( signalRef "@baseboard_fab2_lib.baseboard_fab2(sch_1):m_m_dqs_dp(2)") )
				( member ( signalRef "@baseboard_fab2_lib.baseboard_fab2(sch_1):m_m_dqs_dp(3)") )
				( member ( signalRef "@baseboard_fab2_lib.baseboard_fab2(sch_1):m_m_dqs_dp(4)") )
				( member ( signalRef "@baseboard_fab2_lib.baseboard_fab2(sch_1):m_m_dqs_dp(5)") )
				( member ( signalRef "@baseboard_fab2_lib.baseboard_fab2(sch_1):m_m_dqs_dp(6)") )
				( member ( signalRef "@baseboard_fab2_lib.baseboard_fab2(sch_1):m_m_dqs_dp(7)") )
				( member ( signalRef "@baseboard_fab2_lib.baseboard_fab2(sch_1):m_m_dqs_dp(8)") )
				( member ( signalRef "@baseboard_fab2_lib.baseboard_fab2(sch_1):m_m_dqs_dp(9)") )
				( member ( signalRef "@baseboard_fab2_lib.baseboard_fab2(sch_1):m_m_dqs_dp(10)") )
				( member ( signalRef "@baseboard_fab2_lib.baseboard_fab2(sch_1):m_m_dqs_dp(11)") )
				( member ( signalRef "@baseboard_fab2_lib.baseboard_fab2(sch_1):m_m_dqs_dp(12)") )
				( member ( signalRef "@baseboard_fab2_lib.baseboard_fab2(sch_1):m_m_dqs_dp(13)") )
				( member ( signalRef "@baseboard_fab2_lib.baseboard_fab2(sch_1):m_m_dqs_dp(14)") )
				( member ( signalRef "@baseboard_fab2_lib.baseboard_fab2(sch_1):m_m_dqs_dp(15)") )
				( member ( signalRef "@baseboard_fab2_lib.baseboard_fab2(sch_1):m_m_dqs_dp(16)") )
				( member ( signalRef "@baseboard_fab2_lib.baseboard_fab2(sch_1):m_m_dqs_dp(17)") )
				( member ( signalRef "@baseboard_fab2_lib.baseboard_fab2(sch_1):m_h_dqs_dn(0)") )
				( member ( signalRef "@baseboard_fab2_lib.baseboard_fab2(sch_1):m_h_dqs_dn(1)") )
				( member ( signalRef "@baseboard_fab2_lib.baseboard_fab2(sch_1):m_h_dqs_dn(2)") )
				( member ( signalRef "@baseboard_fab2_lib.baseboard_fab2(sch_1):m_h_dqs_dn(3)") )
				( member ( signalRef "@baseboard_fab2_lib.baseboard_fab2(sch_1):m_h_dqs_dn(4)") )
				( member ( signalRef "@baseboard_fab2_lib.baseboard_fab2(sch_1):m_h_dqs_dn(5)") )
				( member ( signalRef "@baseboard_fab2_lib.baseboard_fab2(sch_1):m_h_dqs_dn(6)") )
				( member ( signalRef "@baseboard_fab2_lib.baseboard_fab2(sch_1):m_h_dqs_dn(7)") )
				( member ( signalRef "@baseboard_fab2_lib.baseboard_fab2(sch_1):m_h_dqs_dn(8)") )
				( member ( signalRef "@baseboard_fab2_lib.baseboard_fab2(sch_1):m_h_dqs_dn(9)") )
				( member ( signalRef "@baseboard_fab2_lib.baseboard_fab2(sch_1):m_h_dqs_dn(10)") )
				( member ( signalRef "@baseboard_fab2_lib.baseboard_fab2(sch_1):m_h_dqs_dn(11)") )
				( member ( signalRef "@baseboard_fab2_lib.baseboard_fab2(sch_1):m_h_dqs_dn(12)") )
				( member ( signalRef "@baseboard_fab2_lib.baseboard_fab2(sch_1):m_h_dqs_dn(13)") )
				( member ( signalRef "@baseboard_fab2_lib.baseboard_fab2(sch_1):m_h_dqs_dn(14)") )
				( member ( signalRef "@baseboard_fab2_lib.baseboard_fab2(sch_1):m_h_dqs_dn(15)") )
				( member ( signalRef "@baseboard_fab2_lib.baseboard_fab2(sch_1):m_h_dqs_dn(16)") )
				( member ( signalRef "@baseboard_fab2_lib.baseboard_fab2(sch_1):m_h_dqs_dn(17)") )
				( member ( signalRef "@baseboard_fab2_lib.baseboard_fab2(sch_1):m_h_dqs_dp(0)") )
				( member ( signalRef "@baseboard_fab2_lib.baseboard_fab2(sch_1):m_h_dqs_dp(1)") )
				( member ( signalRef "@baseboard_fab2_lib.baseboard_fab2(sch_1):m_h_dqs_dp(2)") )
				( member ( signalRef "@baseboard_fab2_lib.baseboard_fab2(sch_1):m_h_dqs_dp(3)") )
				( member ( signalRef "@baseboard_fab2_lib.baseboard_fab2(sch_1):m_h_dqs_dp(4)") )
				( member ( signalRef "@baseboard_fab2_lib.baseboard_fab2(sch_1):m_h_dqs_dp(5)") )
				( member ( signalRef "@baseboard_fab2_lib.baseboard_fab2(sch_1):m_h_dqs_dp(6)") )
				( member ( signalRef "@baseboard_fab2_lib.baseboard_fab2(sch_1):m_h_dqs_dp(7)") )
				( member ( signalRef "@baseboard_fab2_lib.baseboard_fab2(sch_1):m_h_dqs_dp(8)") )
				( member ( signalRef "@baseboard_fab2_lib.baseboard_fab2(sch_1):m_h_dqs_dp(9)") )
				( member ( signalRef "@baseboard_fab2_lib.baseboard_fab2(sch_1):m_h_dqs_dp(10)") )
				( member ( signalRef "@baseboard_fab2_lib.baseboard_fab2(sch_1):m_h_dqs_dp(11)") )
				( member ( signalRef "@baseboard_fab2_lib.baseboard_fab2(sch_1):m_h_dqs_dp(12)") )
				( member ( signalRef "@baseboard_fab2_lib.baseboard_fab2(sch_1):m_h_dqs_dp(13)") )
				( member ( signalRef "@baseboard_fab2_lib.baseboard_fab2(sch_1):m_h_dqs_dp(14)") )
				( member ( signalRef "@baseboard_fab2_lib.baseboard_fab2(sch_1):m_h_dqs_dp(15)") )
				( member ( signalRef "@baseboard_fab2_lib.baseboard_fab2(sch_1):m_h_dqs_dp(16)") )
				( member ( signalRef "@baseboard_fab2_lib.baseboard_fab2(sch_1):m_h_dqs_dp(17)") )
				( member ( signalRef "@baseboard_fab2_lib.baseboard_fab2(sch_1):m_j_dqs_dn(0)") )
				( member ( signalRef "@baseboard_fab2_lib.baseboard_fab2(sch_1):m_j_dqs_dn(1)") )
				( member ( signalRef "@baseboard_fab2_lib.baseboard_fab2(sch_1):m_j_dqs_dn(2)") )
				( member ( signalRef "@baseboard_fab2_lib.baseboard_fab2(sch_1):m_j_dqs_dn(3)") )
				( member ( signalRef "@baseboard_fab2_lib.baseboard_fab2(sch_1):m_j_dqs_dn(4)") )
				( member ( signalRef "@baseboard_fab2_lib.baseboard_fab2(sch_1):m_j_dqs_dn(5)") )
				( member ( signalRef "@baseboard_fab2_lib.baseboard_fab2(sch_1):m_j_dqs_dn(6)") )
				( member ( signalRef "@baseboard_fab2_lib.baseboard_fab2(sch_1):m_j_dqs_dn(7)") )
				( member ( signalRef "@baseboard_fab2_lib.baseboard_fab2(sch_1):m_j_dqs_dn(8)") )
				( member ( signalRef "@baseboard_fab2_lib.baseboard_fab2(sch_1):m_j_dqs_dn(9)") )
				( member ( signalRef "@baseboard_fab2_lib.baseboard_fab2(sch_1):m_j_dqs_dn(10)") )
				( member ( signalRef "@baseboard_fab2_lib.baseboard_fab2(sch_1):m_j_dqs_dn(11)") )
				( member ( signalRef "@baseboard_fab2_lib.baseboard_fab2(sch_1):m_j_dqs_dn(12)") )
				( member ( signalRef "@baseboard_fab2_lib.baseboard_fab2(sch_1):m_j_dqs_dn(13)") )
				( member ( signalRef "@baseboard_fab2_lib.baseboard_fab2(sch_1):m_j_dqs_dn(14)") )
				( member ( signalRef "@baseboard_fab2_lib.baseboard_fab2(sch_1):m_j_dqs_dn(15)") )
				( member ( signalRef "@baseboard_fab2_lib.baseboard_fab2(sch_1):m_j_dqs_dn(16)") )
				( member ( signalRef "@baseboard_fab2_lib.baseboard_fab2(sch_1):m_j_dqs_dn(17)") )
				( member ( signalRef "@baseboard_fab2_lib.baseboard_fab2(sch_1):m_j_dqs_dp(0)") )
				( member ( signalRef "@baseboard_fab2_lib.baseboard_fab2(sch_1):m_j_dqs_dp(1)") )
				( member ( signalRef "@baseboard_fab2_lib.baseboard_fab2(sch_1):m_j_dqs_dp(2)") )
				( member ( signalRef "@baseboard_fab2_lib.baseboard_fab2(sch_1):m_j_dqs_dp(3)") )
				( member ( signalRef "@baseboard_fab2_lib.baseboard_fab2(sch_1):m_j_dqs_dp(4)") )
				( member ( signalRef "@baseboard_fab2_lib.baseboard_fab2(sch_1):m_j_dqs_dp(5)") )
				( member ( signalRef "@baseboard_fab2_lib.baseboard_fab2(sch_1):m_j_dqs_dp(6)") )
				( member ( signalRef "@baseboard_fab2_lib.baseboard_fab2(sch_1):m_j_dqs_dp(7)") )
				( member ( signalRef "@baseboard_fab2_lib.baseboard_fab2(sch_1):m_j_dqs_dp(8)") )
				( member ( signalRef "@baseboard_fab2_lib.baseboard_fab2(sch_1):m_j_dqs_dp(9)") )
				( member ( signalRef "@baseboard_fab2_lib.baseboard_fab2(sch_1):m_j_dqs_dp(10)") )
				( member ( signalRef "@baseboard_fab2_lib.baseboard_fab2(sch_1):m_j_dqs_dp(11)") )
				( member ( signalRef "@baseboard_fab2_lib.baseboard_fab2(sch_1):m_j_dqs_dp(12)") )
				( member ( signalRef "@baseboard_fab2_lib.baseboard_fab2(sch_1):m_j_dqs_dp(13)") )
				( member ( signalRef "@baseboard_fab2_lib.baseboard_fab2(sch_1):m_j_dqs_dp(14)") )
				( member ( signalRef "@baseboard_fab2_lib.baseboard_fab2(sch_1):m_j_dqs_dp(15)") )
				( member ( signalRef "@baseboard_fab2_lib.baseboard_fab2(sch_1):m_j_dqs_dp(16)") )
				( member ( signalRef "@baseboard_fab2_lib.baseboard_fab2(sch_1):m_j_dqs_dp(17)") )
				( member ( signalRef "@baseboard_fab2_lib.baseboard_fab2(sch_1):m_k_dqs_dn(0)") )
				( member ( signalRef "@baseboard_fab2_lib.baseboard_fab2(sch_1):m_k_dqs_dn(1)") )
				( member ( signalRef "@baseboard_fab2_lib.baseboard_fab2(sch_1):m_k_dqs_dn(2)") )
				( member ( signalRef "@baseboard_fab2_lib.baseboard_fab2(sch_1):m_k_dqs_dn(3)") )
				( member ( signalRef "@baseboard_fab2_lib.baseboard_fab2(sch_1):m_k_dqs_dn(4)") )
				( member ( signalRef "@baseboard_fab2_lib.baseboard_fab2(sch_1):m_k_dqs_dn(5)") )
				( member ( signalRef "@baseboard_fab2_lib.baseboard_fab2(sch_1):m_k_dqs_dn(6)") )
				( member ( signalRef "@baseboard_fab2_lib.baseboard_fab2(sch_1):m_k_dqs_dn(7)") )
				( member ( signalRef "@baseboard_fab2_lib.baseboard_fab2(sch_1):m_k_dqs_dn(8)") )
				( member ( signalRef "@baseboard_fab2_lib.baseboard_fab2(sch_1):m_k_dqs_dn(9)") )
				( member ( signalRef "@baseboard_fab2_lib.baseboard_fab2(sch_1):m_k_dqs_dn(10)") )
				( member ( signalRef "@baseboard_fab2_lib.baseboard_fab2(sch_1):m_k_dqs_dn(11)") )
				( member ( signalRef "@baseboard_fab2_lib.baseboard_fab2(sch_1):m_k_dqs_dn(12)") )
				( member ( signalRef "@baseboard_fab2_lib.baseboard_fab2(sch_1):m_k_dqs_dn(13)") )
				( member ( signalRef "@baseboard_fab2_lib.baseboard_fab2(sch_1):m_k_dqs_dn(14)") )
				( member ( signalRef "@baseboard_fab2_lib.baseboard_fab2(sch_1):m_k_dqs_dn(15)") )
				( member ( signalRef "@baseboard_fab2_lib.baseboard_fab2(sch_1):m_k_dqs_dn(16)") )
				( member ( signalRef "@baseboard_fab2_lib.baseboard_fab2(sch_1):m_k_dqs_dn(17)") )
				( member ( signalRef "@baseboard_fab2_lib.baseboard_fab2(sch_1):m_k_dqs_dp(0)") )
				( member ( signalRef "@baseboard_fab2_lib.baseboard_fab2(sch_1):m_k_dqs_dp(1)") )
				( member ( signalRef "@baseboard_fab2_lib.baseboard_fab2(sch_1):m_k_dqs_dp(2)") )
				( member ( signalRef "@baseboard_fab2_lib.baseboard_fab2(sch_1):m_k_dqs_dp(3)") )
				( member ( signalRef "@baseboard_fab2_lib.baseboard_fab2(sch_1):m_k_dqs_dp(4)") )
				( member ( signalRef "@baseboard_fab2_lib.baseboard_fab2(sch_1):m_k_dqs_dp(5)") )
				( member ( signalRef "@baseboard_fab2_lib.baseboard_fab2(sch_1):m_k_dqs_dp(6)") )
				( member ( signalRef "@baseboard_fab2_lib.baseboard_fab2(sch_1):m_k_dqs_dp(7)") )
				( member ( signalRef "@baseboard_fab2_lib.baseboard_fab2(sch_1):m_k_dqs_dp(8)") )
				( member ( signalRef "@baseboard_fab2_lib.baseboard_fab2(sch_1):m_k_dqs_dp(9)") )
				( member ( signalRef "@baseboard_fab2_lib.baseboard_fab2(sch_1):m_d_dqs_dp(8)") )
				( member ( signalRef "@baseboard_fab2_lib.baseboard_fab2(sch_1):m_d_dqs_dp(9)") )
				( member ( signalRef "@baseboard_fab2_lib.baseboard_fab2(sch_1):m_d_dqs_dp(10)") )
				( member ( signalRef "@baseboard_fab2_lib.baseboard_fab2(sch_1):m_d_dqs_dp(11)") )
				( member ( signalRef "@baseboard_fab2_lib.baseboard_fab2(sch_1):m_d_dqs_dp(12)") )
				( member ( signalRef "@baseboard_fab2_lib.baseboard_fab2(sch_1):m_d_dqs_dp(13)") )
				( member ( signalRef "@baseboard_fab2_lib.baseboard_fab2(sch_1):m_d_dqs_dp(14)") )
				( member ( signalRef "@baseboard_fab2_lib.baseboard_fab2(sch_1):m_d_dqs_dp(15)") )
				( member ( signalRef "@baseboard_fab2_lib.baseboard_fab2(sch_1):m_d_dqs_dp(16)") )
				( member ( signalRef "@baseboard_fab2_lib.baseboard_fab2(sch_1):m_d_dqs_dp(17)") )
				( member ( signalRef "@baseboard_fab2_lib.baseboard_fab2(sch_1):m_e_dqs_dp(0)") )
				( member ( signalRef "@baseboard_fab2_lib.baseboard_fab2(sch_1):m_e_dqs_dp(1)") )
				( member ( signalRef "@baseboard_fab2_lib.baseboard_fab2(sch_1):m_e_dqs_dp(2)") )
				( member ( signalRef "@baseboard_fab2_lib.baseboard_fab2(sch_1):m_e_dqs_dp(3)") )
				( member ( signalRef "@baseboard_fab2_lib.baseboard_fab2(sch_1):m_e_dqs_dp(4)") )
				( member ( signalRef "@baseboard_fab2_lib.baseboard_fab2(sch_1):m_e_dqs_dp(5)") )
				( member ( signalRef "@baseboard_fab2_lib.baseboard_fab2(sch_1):m_e_dqs_dp(6)") )
				( member ( signalRef "@baseboard_fab2_lib.baseboard_fab2(sch_1):m_e_dqs_dp(7)") )
				( member ( signalRef "@baseboard_fab2_lib.baseboard_fab2(sch_1):m_e_dqs_dp(8)") )
				( member ( signalRef "@baseboard_fab2_lib.baseboard_fab2(sch_1):m_e_dqs_dp(9)") )
				( member ( signalRef "@baseboard_fab2_lib.baseboard_fab2(sch_1):m_e_dqs_dp(10)") )
				( member ( signalRef "@baseboard_fab2_lib.baseboard_fab2(sch_1):m_e_dqs_dp(11)") )
				( member ( signalRef "@baseboard_fab2_lib.baseboard_fab2(sch_1):m_e_dqs_dp(12)") )
				( member ( signalRef "@baseboard_fab2_lib.baseboard_fab2(sch_1):m_e_dqs_dp(13)") )
				( member ( signalRef "@baseboard_fab2_lib.baseboard_fab2(sch_1):m_e_dqs_dp(14)") )
				( member ( signalRef "@baseboard_fab2_lib.baseboard_fab2(sch_1):m_e_dqs_dp(15)") )
				( member ( signalRef "@baseboard_fab2_lib.baseboard_fab2(sch_1):m_e_dqs_dp(16)") )
				( member ( signalRef "@baseboard_fab2_lib.baseboard_fab2(sch_1):m_e_dqs_dp(17)") )
				( member ( signalRef "@baseboard_fab2_lib.baseboard_fab2(sch_1):m_f_dqs_dn(0)") )
				( member ( signalRef "@baseboard_fab2_lib.baseboard_fab2(sch_1):m_f_dqs_dn(1)") )
				( member ( signalRef "@baseboard_fab2_lib.baseboard_fab2(sch_1):m_f_dqs_dn(2)") )
				( member ( signalRef "@baseboard_fab2_lib.baseboard_fab2(sch_1):m_f_dqs_dn(3)") )
				( member ( signalRef "@baseboard_fab2_lib.baseboard_fab2(sch_1):m_f_dqs_dn(4)") )
				( member ( signalRef "@baseboard_fab2_lib.baseboard_fab2(sch_1):m_f_dqs_dn(5)") )
				( member ( signalRef "@baseboard_fab2_lib.baseboard_fab2(sch_1):m_f_dqs_dn(6)") )
				( member ( signalRef "@baseboard_fab2_lib.baseboard_fab2(sch_1):m_f_dqs_dn(7)") )
				( member ( signalRef "@baseboard_fab2_lib.baseboard_fab2(sch_1):m_f_dqs_dn(8)") )
				( member ( signalRef "@baseboard_fab2_lib.baseboard_fab2(sch_1):m_f_dqs_dn(9)") )
				( member ( signalRef "@baseboard_fab2_lib.baseboard_fab2(sch_1):m_f_dqs_dn(10)") )
				( member ( signalRef "@baseboard_fab2_lib.baseboard_fab2(sch_1):m_f_dqs_dn(11)") )
				( member ( signalRef "@baseboard_fab2_lib.baseboard_fab2(sch_1):m_f_dqs_dn(12)") )
				( member ( signalRef "@baseboard_fab2_lib.baseboard_fab2(sch_1):m_f_dqs_dn(13)") )
				( member ( signalRef "@baseboard_fab2_lib.baseboard_fab2(sch_1):m_f_dqs_dn(14)") )
				( member ( signalRef "@baseboard_fab2_lib.baseboard_fab2(sch_1):m_f_dqs_dn(15)") )
				( member ( signalRef "@baseboard_fab2_lib.baseboard_fab2(sch_1):m_f_dqs_dn(16)") )
				( member ( signalRef "@baseboard_fab2_lib.baseboard_fab2(sch_1):m_f_dqs_dn(17)") )
				( member ( signalRef "@baseboard_fab2_lib.baseboard_fab2(sch_1):m_f_dqs_dp(0)") )
				( member ( signalRef "@baseboard_fab2_lib.baseboard_fab2(sch_1):m_f_dqs_dp(1)") )
				( member ( signalRef "@baseboard_fab2_lib.baseboard_fab2(sch_1):m_f_dqs_dp(2)") )
				( member ( signalRef "@baseboard_fab2_lib.baseboard_fab2(sch_1):m_f_dqs_dp(3)") )
				( member ( signalRef "@baseboard_fab2_lib.baseboard_fab2(sch_1):m_f_dqs_dp(4)") )
				( member ( signalRef "@baseboard_fab2_lib.baseboard_fab2(sch_1):m_f_dqs_dp(5)") )
				( member ( signalRef "@baseboard_fab2_lib.baseboard_fab2(sch_1):m_f_dqs_dp(6)") )
				( member ( signalRef "@baseboard_fab2_lib.baseboard_fab2(sch_1):m_f_dqs_dp(7)") )
				( member ( signalRef "@baseboard_fab2_lib.baseboard_fab2(sch_1):m_f_dqs_dp(8)") )
				( member ( signalRef "@baseboard_fab2_lib.baseboard_fab2(sch_1):m_f_dqs_dp(9)") )
				( member ( signalRef "@baseboard_fab2_lib.baseboard_fab2(sch_1):m_f_dqs_dp(10)") )
				( member ( signalRef "@baseboard_fab2_lib.baseboard_fab2(sch_1):m_f_dqs_dp(11)") )
				( member ( signalRef "@baseboard_fab2_lib.baseboard_fab2(sch_1):m_f_dqs_dp(12)") )
				( member ( signalRef "@baseboard_fab2_lib.baseboard_fab2(sch_1):m_f_dqs_dp(13)") )
				( member ( signalRef "@baseboard_fab2_lib.baseboard_fab2(sch_1):m_f_dqs_dp(14)") )
				( member ( signalRef "@baseboard_fab2_lib.baseboard_fab2(sch_1):m_f_dqs_dp(15)") )
				( member ( signalRef "@baseboard_fab2_lib.baseboard_fab2(sch_1):m_f_dqs_dp(16)") )
				( member ( signalRef "@baseboard_fab2_lib.baseboard_fab2(sch_1):m_f_dqs_dp(17)") )
				( member ( signalRef "@baseboard_fab2_lib.baseboard_fab2(sch_1):m_g_dqs_dn(0)") )
				( member ( signalRef "@baseboard_fab2_lib.baseboard_fab2(sch_1):m_g_dqs_dn(1)") )
				( member ( signalRef "@baseboard_fab2_lib.baseboard_fab2(sch_1):m_g_dqs_dn(2)") )
				( member ( signalRef "@baseboard_fab2_lib.baseboard_fab2(sch_1):m_g_dqs_dn(3)") )
				( member ( signalRef "@baseboard_fab2_lib.baseboard_fab2(sch_1):m_g_dqs_dn(4)") )
				( member ( signalRef "@baseboard_fab2_lib.baseboard_fab2(sch_1):m_g_dqs_dn(5)") )
				( member ( signalRef "@baseboard_fab2_lib.baseboard_fab2(sch_1):m_g_dqs_dn(6)") )
				( member ( signalRef "@baseboard_fab2_lib.baseboard_fab2(sch_1):m_g_dqs_dn(7)") )
				( member ( signalRef "@baseboard_fab2_lib.baseboard_fab2(sch_1):m_g_dqs_dn(8)") )
				( member ( signalRef "@baseboard_fab2_lib.baseboard_fab2(sch_1):m_g_dqs_dn(9)") )
				( member ( signalRef "@baseboard_fab2_lib.baseboard_fab2(sch_1):m_g_dqs_dn(10)") )
				( member ( signalRef "@baseboard_fab2_lib.baseboard_fab2(sch_1):m_g_dqs_dn(11)") )
				( member ( signalRef "@baseboard_fab2_lib.baseboard_fab2(sch_1):m_g_dqs_dn(12)") )
				( member ( signalRef "@baseboard_fab2_lib.baseboard_fab2(sch_1):m_g_dqs_dn(13)") )
				( member ( signalRef "@baseboard_fab2_lib.baseboard_fab2(sch_1):m_g_dqs_dn(14)") )
				( member ( signalRef "@baseboard_fab2_lib.baseboard_fab2(sch_1):m_g_dqs_dn(15)") )
				( member ( signalRef "@baseboard_fab2_lib.baseboard_fab2(sch_1):m_g_dqs_dn(16)") )
				( member ( signalRef "@baseboard_fab2_lib.baseboard_fab2(sch_1):m_g_dqs_dn(17)") )
				( member ( signalRef "@baseboard_fab2_lib.baseboard_fab2(sch_1):m_g_dqs_dp(0)") )
				( member ( signalRef "@baseboard_fab2_lib.baseboard_fab2(sch_1):m_g_dqs_dp(1)") )
				( member ( signalRef "@baseboard_fab2_lib.baseboard_fab2(sch_1):m_g_dqs_dp(2)") )
				( member ( signalRef "@baseboard_fab2_lib.baseboard_fab2(sch_1):m_g_dqs_dp(3)") )
				( member ( signalRef "@baseboard_fab2_lib.baseboard_fab2(sch_1):m_g_dqs_dp(4)") )
				( member ( signalRef "@baseboard_fab2_lib.baseboard_fab2(sch_1):m_g_dqs_dp(5)") )
				( member ( signalRef "@baseboard_fab2_lib.baseboard_fab2(sch_1):m_g_dqs_dp(6)") )
				( member ( signalRef "@baseboard_fab2_lib.baseboard_fab2(sch_1):m_g_dqs_dp(7)") )
				( member ( signalRef "@baseboard_fab2_lib.baseboard_fab2(sch_1):m_g_dqs_dp(8)") )
				( member ( signalRef "@baseboard_fab2_lib.baseboard_fab2(sch_1):m_g_dqs_dp(9)") )
				( member ( signalRef "@baseboard_fab2_lib.baseboard_fab2(sch_1):m_g_dqs_dp(10)") )
				( member ( signalRef "@baseboard_fab2_lib.baseboard_fab2(sch_1):m_g_dqs_dp(11)") )
				( member ( signalRef "@baseboard_fab2_lib.baseboard_fab2(sch_1):m_g_dqs_dp(12)") )
				( member ( signalRef "@baseboard_fab2_lib.baseboard_fab2(sch_1):m_g_dqs_dp(13)") )
				( member ( signalRef "@baseboard_fab2_lib.baseboard_fab2(sch_1):m_g_dqs_dp(14)") )
				( member ( signalRef "@baseboard_fab2_lib.baseboard_fab2(sch_1):m_g_dqs_dp(15)") )
				( member ( signalRef "@baseboard_fab2_lib.baseboard_fab2(sch_1):m_g_dqs_dp(16)") )
				( member ( signalRef "@baseboard_fab2_lib.baseboard_fab2(sch_1):m_g_dqs_dp(17)") )
				( member ( signalRef "@baseboard_fab2_lib.baseboard_fab2(sch_1):m_b_dqs_dn(16)") )
				( member ( signalRef "@baseboard_fab2_lib.baseboard_fab2(sch_1):m_b_dqs_dn(17)") )
				( member ( signalRef "@baseboard_fab2_lib.baseboard_fab2(sch_1):m_b_dqs_dp(0)") )
				( member ( signalRef "@baseboard_fab2_lib.baseboard_fab2(sch_1):m_b_dqs_dp(1)") )
				( member ( signalRef "@baseboard_fab2_lib.baseboard_fab2(sch_1):m_b_dqs_dp(2)") )
				( member ( signalRef "@baseboard_fab2_lib.baseboard_fab2(sch_1):m_b_dqs_dp(3)") )
				( member ( signalRef "@baseboard_fab2_lib.baseboard_fab2(sch_1):m_b_dqs_dp(4)") )
				( member ( signalRef "@baseboard_fab2_lib.baseboard_fab2(sch_1):m_b_dqs_dp(5)") )
				( member ( signalRef "@baseboard_fab2_lib.baseboard_fab2(sch_1):m_b_dqs_dp(6)") )
				( member ( signalRef "@baseboard_fab2_lib.baseboard_fab2(sch_1):m_b_dqs_dp(7)") )
				( member ( signalRef "@baseboard_fab2_lib.baseboard_fab2(sch_1):m_b_dqs_dp(8)") )
				( member ( signalRef "@baseboard_fab2_lib.baseboard_fab2(sch_1):m_b_dqs_dp(9)") )
				( member ( signalRef "@baseboard_fab2_lib.baseboard_fab2(sch_1):m_b_dqs_dp(10)") )
				( member ( signalRef "@baseboard_fab2_lib.baseboard_fab2(sch_1):m_b_dqs_dp(11)") )
				( member ( signalRef "@baseboard_fab2_lib.baseboard_fab2(sch_1):m_b_dqs_dp(12)") )
				( member ( signalRef "@baseboard_fab2_lib.baseboard_fab2(sch_1):m_b_dqs_dp(13)") )
				( member ( signalRef "@baseboard_fab2_lib.baseboard_fab2(sch_1):m_b_dqs_dp(14)") )
				( member ( signalRef "@baseboard_fab2_lib.baseboard_fab2(sch_1):m_b_dqs_dp(15)") )
				( member ( signalRef "@baseboard_fab2_lib.baseboard_fab2(sch_1):m_b_dqs_dp(16)") )
				( member ( signalRef "@baseboard_fab2_lib.baseboard_fab2(sch_1):m_b_dqs_dp(17)") )
				( member ( signalRef "@baseboard_fab2_lib.baseboard_fab2(sch_1):m_c_dqs_dn(0)") )
				( member ( signalRef "@baseboard_fab2_lib.baseboard_fab2(sch_1):m_c_dqs_dn(1)") )
				( member ( signalRef "@baseboard_fab2_lib.baseboard_fab2(sch_1):m_c_dqs_dn(2)") )
				( member ( signalRef "@baseboard_fab2_lib.baseboard_fab2(sch_1):m_c_dqs_dn(3)") )
				( member ( signalRef "@baseboard_fab2_lib.baseboard_fab2(sch_1):m_c_dqs_dn(4)") )
				( member ( signalRef "@baseboard_fab2_lib.baseboard_fab2(sch_1):m_c_dqs_dn(5)") )
				( member ( signalRef "@baseboard_fab2_lib.baseboard_fab2(sch_1):m_c_dqs_dn(6)") )
				( member ( signalRef "@baseboard_fab2_lib.baseboard_fab2(sch_1):m_c_dqs_dn(7)") )
				( member ( signalRef "@baseboard_fab2_lib.baseboard_fab2(sch_1):m_c_dqs_dn(8)") )
				( member ( signalRef "@baseboard_fab2_lib.baseboard_fab2(sch_1):m_c_dqs_dn(9)") )
				( member ( signalRef "@baseboard_fab2_lib.baseboard_fab2(sch_1):m_c_dqs_dn(10)") )
				( member ( signalRef "@baseboard_fab2_lib.baseboard_fab2(sch_1):m_c_dqs_dn(11)") )
				( member ( signalRef "@baseboard_fab2_lib.baseboard_fab2(sch_1):m_c_dqs_dn(12)") )
				( member ( signalRef "@baseboard_fab2_lib.baseboard_fab2(sch_1):m_c_dqs_dn(13)") )
				( member ( signalRef "@baseboard_fab2_lib.baseboard_fab2(sch_1):m_c_dqs_dn(14)") )
				( member ( signalRef "@baseboard_fab2_lib.baseboard_fab2(sch_1):m_c_dqs_dn(15)") )
				( member ( signalRef "@baseboard_fab2_lib.baseboard_fab2(sch_1):m_c_dqs_dn(16)") )
				( member ( signalRef "@baseboard_fab2_lib.baseboard_fab2(sch_1):m_c_dqs_dn(17)") )
				( member ( signalRef "@baseboard_fab2_lib.baseboard_fab2(sch_1):m_e_dqs_dn(0)") )
				( member ( signalRef "@baseboard_fab2_lib.baseboard_fab2(sch_1):m_e_dqs_dn(1)") )
				( member ( signalRef "@baseboard_fab2_lib.baseboard_fab2(sch_1):m_e_dqs_dn(2)") )
				( member ( signalRef "@baseboard_fab2_lib.baseboard_fab2(sch_1):m_e_dqs_dn(3)") )
				( member ( signalRef "@baseboard_fab2_lib.baseboard_fab2(sch_1):m_e_dqs_dn(4)") )
				( member ( signalRef "@baseboard_fab2_lib.baseboard_fab2(sch_1):m_e_dqs_dn(5)") )
				( member ( signalRef "@baseboard_fab2_lib.baseboard_fab2(sch_1):m_e_dqs_dn(6)") )
				( member ( signalRef "@baseboard_fab2_lib.baseboard_fab2(sch_1):m_e_dqs_dn(7)") )
				( member ( signalRef "@baseboard_fab2_lib.baseboard_fab2(sch_1):m_e_dqs_dn(8)") )
				( member ( signalRef "@baseboard_fab2_lib.baseboard_fab2(sch_1):m_e_dqs_dn(9)") )
				( member ( signalRef "@baseboard_fab2_lib.baseboard_fab2(sch_1):m_e_dqs_dn(10)") )
				( member ( signalRef "@baseboard_fab2_lib.baseboard_fab2(sch_1):m_e_dqs_dn(11)") )
				( member ( signalRef "@baseboard_fab2_lib.baseboard_fab2(sch_1):m_e_dqs_dn(12)") )
				( member ( signalRef "@baseboard_fab2_lib.baseboard_fab2(sch_1):m_e_dqs_dn(13)") )
				( member ( signalRef "@baseboard_fab2_lib.baseboard_fab2(sch_1):m_e_dqs_dn(14)") )
				( member ( signalRef "@baseboard_fab2_lib.baseboard_fab2(sch_1):m_e_dqs_dn(15)") )
				( member ( signalRef "@baseboard_fab2_lib.baseboard_fab2(sch_1):m_e_dqs_dn(16)") )
				( member ( signalRef "@baseboard_fab2_lib.baseboard_fab2(sch_1):m_e_dqs_dn(17)") )
				( member ( signalRef "@baseboard_fab2_lib.baseboard_fab2(sch_1):m_c_dqs_dp(0)") )
				( member ( signalRef "@baseboard_fab2_lib.baseboard_fab2(sch_1):m_c_dqs_dp(1)") )
				( member ( signalRef "@baseboard_fab2_lib.baseboard_fab2(sch_1):m_c_dqs_dp(2)") )
				( member ( signalRef "@baseboard_fab2_lib.baseboard_fab2(sch_1):m_c_dqs_dp(3)") )
				( member ( signalRef "@baseboard_fab2_lib.baseboard_fab2(sch_1):m_c_dqs_dp(4)") )
				( member ( signalRef "@baseboard_fab2_lib.baseboard_fab2(sch_1):m_c_dqs_dp(5)") )
				( member ( signalRef "@baseboard_fab2_lib.baseboard_fab2(sch_1):m_c_dqs_dp(6)") )
				( member ( signalRef "@baseboard_fab2_lib.baseboard_fab2(sch_1):m_c_dqs_dp(7)") )
				( member ( signalRef "@baseboard_fab2_lib.baseboard_fab2(sch_1):m_c_dqs_dp(8)") )
				( member ( signalRef "@baseboard_fab2_lib.baseboard_fab2(sch_1):m_c_dqs_dp(9)") )
				( member ( signalRef "@baseboard_fab2_lib.baseboard_fab2(sch_1):m_c_dqs_dp(10)") )
				( member ( signalRef "@baseboard_fab2_lib.baseboard_fab2(sch_1):m_c_dqs_dp(11)") )
				( member ( signalRef "@baseboard_fab2_lib.baseboard_fab2(sch_1):m_c_dqs_dp(12)") )
				( member ( signalRef "@baseboard_fab2_lib.baseboard_fab2(sch_1):m_c_dqs_dp(13)") )
				( member ( signalRef "@baseboard_fab2_lib.baseboard_fab2(sch_1):m_c_dqs_dp(14)") )
				( member ( signalRef "@baseboard_fab2_lib.baseboard_fab2(sch_1):m_c_dqs_dp(15)") )
				( member ( signalRef "@baseboard_fab2_lib.baseboard_fab2(sch_1):m_c_dqs_dp(16)") )
				( member ( signalRef "@baseboard_fab2_lib.baseboard_fab2(sch_1):m_c_dqs_dp(17)") )
				( member ( signalRef "@baseboard_fab2_lib.baseboard_fab2(sch_1):m_d_dqs_dn(0)") )
				( member ( signalRef "@baseboard_fab2_lib.baseboard_fab2(sch_1):m_d_dqs_dn(1)") )
				( member ( signalRef "@baseboard_fab2_lib.baseboard_fab2(sch_1):m_d_dqs_dn(2)") )
				( member ( signalRef "@baseboard_fab2_lib.baseboard_fab2(sch_1):m_d_dqs_dn(3)") )
				( member ( signalRef "@baseboard_fab2_lib.baseboard_fab2(sch_1):m_d_dqs_dn(4)") )
				( member ( signalRef "@baseboard_fab2_lib.baseboard_fab2(sch_1):m_d_dqs_dn(5)") )
				( member ( signalRef "@baseboard_fab2_lib.baseboard_fab2(sch_1):m_d_dqs_dn(6)") )
				( member ( signalRef "@baseboard_fab2_lib.baseboard_fab2(sch_1):m_d_dqs_dn(7)") )
				( member ( signalRef "@baseboard_fab2_lib.baseboard_fab2(sch_1):m_d_dqs_dn(8)") )
				( member ( signalRef "@baseboard_fab2_lib.baseboard_fab2(sch_1):m_d_dqs_dn(9)") )
				( member ( signalRef "@baseboard_fab2_lib.baseboard_fab2(sch_1):m_d_dqs_dn(10)") )
				( member ( signalRef "@baseboard_fab2_lib.baseboard_fab2(sch_1):m_d_dqs_dn(11)") )
				( member ( signalRef "@baseboard_fab2_lib.baseboard_fab2(sch_1):m_d_dqs_dn(12)") )
				( member ( signalRef "@baseboard_fab2_lib.baseboard_fab2(sch_1):m_d_dqs_dn(13)") )
				( member ( signalRef "@baseboard_fab2_lib.baseboard_fab2(sch_1):m_d_dqs_dn(14)") )
				( member ( signalRef "@baseboard_fab2_lib.baseboard_fab2(sch_1):m_d_dqs_dn(15)") )
				( member ( signalRef "@baseboard_fab2_lib.baseboard_fab2(sch_1):m_d_dqs_dn(16)") )
				( member ( signalRef "@baseboard_fab2_lib.baseboard_fab2(sch_1):m_d_dqs_dn(17)") )
				( member ( signalRef "@baseboard_fab2_lib.baseboard_fab2(sch_1):m_d_dqs_dp(0)") )
				( member ( signalRef "@baseboard_fab2_lib.baseboard_fab2(sch_1):m_d_dqs_dp(1)") )
				( member ( signalRef "@baseboard_fab2_lib.baseboard_fab2(sch_1):m_d_dqs_dp(2)") )
				( member ( signalRef "@baseboard_fab2_lib.baseboard_fab2(sch_1):m_d_dqs_dp(3)") )
				( member ( signalRef "@baseboard_fab2_lib.baseboard_fab2(sch_1):m_d_dqs_dp(4)") )
				( member ( signalRef "@baseboard_fab2_lib.baseboard_fab2(sch_1):m_d_dqs_dp(5)") )
				( member ( signalRef "@baseboard_fab2_lib.baseboard_fab2(sch_1):m_d_dqs_dp(6)") )
				( member ( signalRef "@baseboard_fab2_lib.baseboard_fab2(sch_1):m_d_dqs_dp(7)") )
				( member ( signalRef "@baseboard_fab2_lib.baseboard_fab2(sch_1):m_a_dqs_dn(0)") )
				( member ( signalRef "@baseboard_fab2_lib.baseboard_fab2(sch_1):m_a_dqs_dn(1)") )
				( member ( signalRef "@baseboard_fab2_lib.baseboard_fab2(sch_1):m_a_dqs_dn(2)") )
				( member ( signalRef "@baseboard_fab2_lib.baseboard_fab2(sch_1):m_a_dqs_dn(3)") )
				( member ( signalRef "@baseboard_fab2_lib.baseboard_fab2(sch_1):m_a_dqs_dn(4)") )
				( member ( signalRef "@baseboard_fab2_lib.baseboard_fab2(sch_1):m_a_dqs_dn(5)") )
				( member ( signalRef "@baseboard_fab2_lib.baseboard_fab2(sch_1):m_a_dqs_dn(6)") )
				( member ( signalRef "@baseboard_fab2_lib.baseboard_fab2(sch_1):m_a_dqs_dn(7)") )
				( member ( signalRef "@baseboard_fab2_lib.baseboard_fab2(sch_1):m_a_dqs_dn(8)") )
				( member ( signalRef "@baseboard_fab2_lib.baseboard_fab2(sch_1):m_a_dqs_dn(9)") )
				( member ( signalRef "@baseboard_fab2_lib.baseboard_fab2(sch_1):m_a_dqs_dn(10)") )
				( member ( signalRef "@baseboard_fab2_lib.baseboard_fab2(sch_1):m_a_dqs_dn(11)") )
				( member ( signalRef "@baseboard_fab2_lib.baseboard_fab2(sch_1):m_a_dqs_dn(12)") )
				( member ( signalRef "@baseboard_fab2_lib.baseboard_fab2(sch_1):m_a_dqs_dn(13)") )
				( member ( signalRef "@baseboard_fab2_lib.baseboard_fab2(sch_1):m_a_dqs_dn(14)") )
				( member ( signalRef "@baseboard_fab2_lib.baseboard_fab2(sch_1):m_a_dqs_dn(15)") )
				( member ( signalRef "@baseboard_fab2_lib.baseboard_fab2(sch_1):m_a_dqs_dn(16)") )
				( member ( signalRef "@baseboard_fab2_lib.baseboard_fab2(sch_1):m_a_dqs_dn(17)") )
				( member ( signalRef "@baseboard_fab2_lib.baseboard_fab2(sch_1):m_a_dqs_dp(0)") )
				( member ( signalRef "@baseboard_fab2_lib.baseboard_fab2(sch_1):m_a_dqs_dp(1)") )
				( member ( signalRef "@baseboard_fab2_lib.baseboard_fab2(sch_1):m_a_dqs_dp(2)") )
				( member ( signalRef "@baseboard_fab2_lib.baseboard_fab2(sch_1):m_a_dqs_dp(3)") )
				( member ( signalRef "@baseboard_fab2_lib.baseboard_fab2(sch_1):m_a_dqs_dp(4)") )
				( member ( signalRef "@baseboard_fab2_lib.baseboard_fab2(sch_1):m_a_dqs_dp(5)") )
				( member ( signalRef "@baseboard_fab2_lib.baseboard_fab2(sch_1):m_a_dqs_dp(6)") )
				( member ( signalRef "@baseboard_fab2_lib.baseboard_fab2(sch_1):m_a_dqs_dp(7)") )
				( member ( signalRef "@baseboard_fab2_lib.baseboard_fab2(sch_1):m_a_dqs_dp(8)") )
				( member ( signalRef "@baseboard_fab2_lib.baseboard_fab2(sch_1):m_a_dqs_dp(9)") )
				( member ( signalRef "@baseboard_fab2_lib.baseboard_fab2(sch_1):m_a_dqs_dp(10)") )
				( member ( signalRef "@baseboard_fab2_lib.baseboard_fab2(sch_1):m_a_dqs_dp(11)") )
				( member ( signalRef "@baseboard_fab2_lib.baseboard_fab2(sch_1):m_a_dqs_dp(12)") )
				( member ( signalRef "@baseboard_fab2_lib.baseboard_fab2(sch_1):m_a_dqs_dp(13)") )
				( member ( signalRef "@baseboard_fab2_lib.baseboard_fab2(sch_1):m_a_dqs_dp(14)") )
				( member ( signalRef "@baseboard_fab2_lib.baseboard_fab2(sch_1):m_a_dqs_dp(15)") )
				( member ( signalRef "@baseboard_fab2_lib.baseboard_fab2(sch_1):m_a_dqs_dp(16)") )
				( member ( signalRef "@baseboard_fab2_lib.baseboard_fab2(sch_1):m_a_dqs_dp(17)") )
				( member ( signalRef "@baseboard_fab2_lib.baseboard_fab2(sch_1):m_b_dqs_dn(0)") )
				( member ( signalRef "@baseboard_fab2_lib.baseboard_fab2(sch_1):m_b_dqs_dn(1)") )
				( member ( signalRef "@baseboard_fab2_lib.baseboard_fab2(sch_1):m_b_dqs_dn(2)") )
				( member ( signalRef "@baseboard_fab2_lib.baseboard_fab2(sch_1):m_b_dqs_dn(3)") )
				( member ( signalRef "@baseboard_fab2_lib.baseboard_fab2(sch_1):m_b_dqs_dn(4)") )
				( member ( signalRef "@baseboard_fab2_lib.baseboard_fab2(sch_1):m_b_dqs_dn(5)") )
				( member ( signalRef "@baseboard_fab2_lib.baseboard_fab2(sch_1):m_b_dqs_dn(6)") )
				( member ( signalRef "@baseboard_fab2_lib.baseboard_fab2(sch_1):m_b_dqs_dn(7)") )
				( member ( signalRef "@baseboard_fab2_lib.baseboard_fab2(sch_1):m_b_dqs_dn(8)") )
				( member ( signalRef "@baseboard_fab2_lib.baseboard_fab2(sch_1):m_b_dqs_dn(9)") )
				( member ( signalRef "@baseboard_fab2_lib.baseboard_fab2(sch_1):m_b_dqs_dn(10)") )
				( member ( signalRef "@baseboard_fab2_lib.baseboard_fab2(sch_1):m_b_dqs_dn(11)") )
				( member ( signalRef "@baseboard_fab2_lib.baseboard_fab2(sch_1):m_b_dqs_dn(12)") )
				( member ( signalRef "@baseboard_fab2_lib.baseboard_fab2(sch_1):m_b_dqs_dn(13)") )
				( member ( signalRef "@baseboard_fab2_lib.baseboard_fab2(sch_1):m_b_dqs_dn(14)") )
				( member ( signalRef "@baseboard_fab2_lib.baseboard_fab2(sch_1):m_b_dqs_dn(15)") )
				( objectStatus "PNCLS_40-OHM-MS_&_38-OHM-SL_DIFF" )
			)
			( netClass "@crescent_city_bb_fab1_lib.crescent_city_bb_fab1(sch_1):\PNCLS_50-OHM_SE\"
				( memberType ( signal ) )
				( physicalCSetRef "@sapphirecity_baseboard_lib.sapphirecity_baseboard(sch_1):\50_OHMS-SE\" )
				( objectFlag fObjectPhysical )
				( member ( netGroupRef "@crescent_city_bb_fab1_lib.crescent_city_bb_fab1(sch_1):\#SPI_SW\") )
				( member ( signalRef "@baseboard_fab2_lib.baseboard_fab2(sch_1):tp_10gbe_kr0_mon_dn") )
				( member ( signalRef "@baseboard_fab2_lib.baseboard_fab2(sch_1):tp_10gbe_kr0_mon_dp") )
				( member ( signalRef "@baseboard_fab2_lib.baseboard_fab2(sch_1):tp_10gbe_kr1_mon_dn") )
				( member ( signalRef "@baseboard_fab2_lib.baseboard_fab2(sch_1):tp_10gbe_kr1_mon_dp") )
				( member ( signalRef "@baseboard_fab2_lib.baseboard_fab2(sch_1):tp_33p_33m_smbadr") )
				( member ( signalRef "@baseboard_fab2_lib.baseboard_fab2(sch_1):fm_cpu_err0_lvt3_bmc_n") )
				( member ( signalRef "@baseboard_fab2_lib.baseboard_fab2(sch_1):fm_cpu0_rc_error_n") )
				( member ( signalRef "@baseboard_fab2_lib.baseboard_fab2(sch_1):fm_cpu1_rc_error_n") )
				( member ( signalRef "@baseboard_fab2_lib.baseboard_fab2(sch_1):tp_pvccin_cpu0_ph1_gl_1") )
				( member ( signalRef "@baseboard_fab2_lib.baseboard_fab2(sch_1):tp_pvccin_cpu0_ph1_gl_0") )
				( member ( signalRef "@baseboard_fab2_lib.baseboard_fab2(sch_1):tp_ext_mdio_i2c_sel") )
				( member ( signalRef "@baseboard_fab2_lib.baseboard_fab2(sch_1):jtag_mcp_cpu0_tdi") )
				( member ( signalRef "@baseboard_fab2_lib.baseboard_fab2(sch_1):tp_spi_switch1_3") )
				( member ( signalRef "@baseboard_fab2_lib.baseboard_fab2(sch_1):tp_spi_switch1_6") )
				( member ( signalRef "@baseboard_fab2_lib.baseboard_fab2(sch_1):tp_spi_switch1_9") )
				( member ( signalRef "@baseboard_fab2_lib.baseboard_fab2(sch_1):tp_spi_switch1_10") )
				( member ( signalRef "@baseboard_fab2_lib.baseboard_fab2(sch_1):tp_spi_switch1_11") )
				( member ( signalRef "@baseboard_fab2_lib.baseboard_fab2(sch_1):tp_spi_switch1_12") )
				( member ( signalRef "@baseboard_fab2_lib.baseboard_fab2(sch_1):tp_spi_switch1_13") )
				( member ( signalRef "@baseboard_fab2_lib.baseboard_fab2(sch_1):tp_spi_switch1_14") )
				( member ( signalRef "@baseboard_fab2_lib.baseboard_fab2(sch_1):tp_spi_0_0") )
				( member ( signalRef "@baseboard_fab2_lib.baseboard_fab2(sch_1):tp_spi_0_1") )
				( member ( signalRef "@baseboard_fab2_lib.baseboard_fab2(sch_1):tp_spi_0_2") )
				( member ( signalRef "@baseboard_fab2_lib.baseboard_fab2(sch_1):tp_spi_0_3") )
				( member ( signalRef "@baseboard_fab2_lib.baseboard_fab2(sch_1):tp_spi_0_4") )
				( member ( signalRef "@baseboard_fab2_lib.baseboard_fab2(sch_1):tp_spi_0_5") )
				( member ( signalRef "@baseboard_fab2_lib.baseboard_fab2(sch_1):tp_spi_0_6") )
				( member ( signalRef "@baseboard_fab2_lib.baseboard_fab2(sch_1):tp_spi_1_0") )
				( member ( signalRef "@baseboard_fab2_lib.baseboard_fab2(sch_1):tp_spi_1_1") )
				( member ( signalRef "@baseboard_fab2_lib.baseboard_fab2(sch_1):tp_spi_1_2") )
				( member ( signalRef "@baseboard_fab2_lib.baseboard_fab2(sch_1):tp_spi_1_3") )
				( member ( signalRef "@baseboard_fab2_lib.baseboard_fab2(sch_1):tp_spi_1_4") )
				( member ( signalRef "@baseboard_fab2_lib.baseboard_fab2(sch_1):tp_spi_1_5") )
				( member ( signalRef "@baseboard_fab2_lib.baseboard_fab2(sch_1):tp_spi_1_6") )
				( member ( signalRef "@baseboard_fab2_lib.baseboard_fab2(sch_1):tp_spi_2_6") )
				( member ( signalRef "@baseboard_fab2_lib.baseboard_fab2(sch_1):tp_spi_2_5") )
				( member ( signalRef "@baseboard_fab2_lib.baseboard_fab2(sch_1):tp_spi_2_4") )
				( member ( signalRef "@baseboard_fab2_lib.baseboard_fab2(sch_1):tp_spi_2_3") )
				( member ( signalRef "@baseboard_fab2_lib.baseboard_fab2(sch_1):tp_spi_2_2") )
				( member ( signalRef "@baseboard_fab2_lib.baseboard_fab2(sch_1):tp_spi_2_1") )
				( member ( signalRef "@baseboard_fab2_lib.baseboard_fab2(sch_1):tp_spi_2_0") )
				( member ( signalRef "@baseboard_fab2_lib.baseboard_fab2(sch_1):tp_sprv_sdp0") )
				( member ( signalRef "@baseboard_fab2_lib.baseboard_fab2(sch_1):tp_sprv_sdp1") )
				( member ( signalRef "@baseboard_fab2_lib.baseboard_fab2(sch_1):tp_sprv_sdp2") )
				( member ( signalRef "@baseboard_fab2_lib.baseboard_fab2(sch_1):tp_sprv_sdp3") )
				( member ( signalRef "@baseboard_fab2_lib.baseboard_fab2(sch_1):tp_usb2_p8_dn") )
				( member ( signalRef "@baseboard_fab2_lib.baseboard_fab2(sch_1):tp_usb2_p8_dp") )
				( member ( signalRef "@baseboard_fab2_lib.baseboard_fab2(sch_1):tp_usb2_p9_dn") )
				( member ( signalRef "@baseboard_fab2_lib.baseboard_fab2(sch_1):tp_usb2_p9_dp") )
				( member ( signalRef "@baseboard_fab2_lib.baseboard_fab2(sch_1):tp_usb2_p02_dn") )
				( member ( signalRef "@baseboard_fab2_lib.baseboard_fab2(sch_1):tp_usb2_p02_dp") )
				( member ( signalRef "@baseboard_fab2_lib.baseboard_fab2(sch_1):tp_usb2_p03_dn") )
				( member ( signalRef "@baseboard_fab2_lib.baseboard_fab2(sch_1):tp_usb2_p03_dp") )
				( member ( signalRef "@baseboard_fab2_lib.baseboard_fab2(sch_1):tp_usb2_p06_dn") )
				( member ( signalRef "@baseboard_fab2_lib.baseboard_fab2(sch_1):tp_usb2_p06_dp") )
				( member ( signalRef "@baseboard_fab2_lib.baseboard_fab2(sch_1):tp_usb2_p07_dn") )
				( member ( signalRef "@baseboard_fab2_lib.baseboard_fab2(sch_1):tp_usb2_p07_dp") )
				( member ( signalRef "@baseboard_fab2_lib.baseboard_fab2(sch_1):tp_usb2_p10_dn") )
				( member ( signalRef "@baseboard_fab2_lib.baseboard_fab2(sch_1):tp_usb2_p10_dp") )
				( member ( signalRef "@baseboard_fab2_lib.baseboard_fab2(sch_1):tp_usb2_p11_dn") )
				( member ( signalRef "@baseboard_fab2_lib.baseboard_fab2(sch_1):tp_usb2_p11_dp") )
				( member ( signalRef "@baseboard_fab2_lib.baseboard_fab2(sch_1):tp_usb2_p12_dn") )
				( member ( signalRef "@baseboard_fab2_lib.baseboard_fab2(sch_1):tp_usb2_p12_dp") )
				( member ( signalRef "@baseboard_fab2_lib.baseboard_fab2(sch_1):tp_usb2_p13_dn") )
				( member ( signalRef "@baseboard_fab2_lib.baseboard_fab2(sch_1):tp_usb2_p13_dp") )
				( member ( signalRef "@baseboard_fab2_lib.baseboard_fab2(sch_1):tp_usb2_p14_dn") )
				( member ( signalRef "@baseboard_fab2_lib.baseboard_fab2(sch_1):tp_usb2_p14_dp") )
				( member ( signalRef "@baseboard_fab2_lib.baseboard_fab2(sch_1):fm_cpu0_stl_brd_osc_en") )
				( member ( signalRef "@baseboard_fab2_lib.baseboard_fab2(sch_1):tp_usb3_p02_rxn") )
				( member ( signalRef "@baseboard_fab2_lib.baseboard_fab2(sch_1):tp_usb3_p02_rxp") )
				( member ( signalRef "@baseboard_fab2_lib.baseboard_fab2(sch_1):tp_usb3_p02_txn") )
				( member ( signalRef "@baseboard_fab2_lib.baseboard_fab2(sch_1):tp_usb3_p02_txp") )
				( member ( signalRef "@baseboard_fab2_lib.baseboard_fab2(sch_1):tp_usb3_p03_rxn") )
				( member ( signalRef "@baseboard_fab2_lib.baseboard_fab2(sch_1):tp_usb3_p03_rxp") )
				( member ( signalRef "@baseboard_fab2_lib.baseboard_fab2(sch_1):tp_usb3_p03_txn") )
				( member ( signalRef "@baseboard_fab2_lib.baseboard_fab2(sch_1):tp_usb3_p03_txp") )
				( member ( signalRef "@baseboard_fab2_lib.baseboard_fab2(sch_1):tp_usb3_p04_rxn") )
				( member ( signalRef "@baseboard_fab2_lib.baseboard_fab2(sch_1):tp_usb3_p04_rxp") )
				( member ( signalRef "@baseboard_fab2_lib.baseboard_fab2(sch_1):tp_usb3_p04_txn") )
				( member ( signalRef "@baseboard_fab2_lib.baseboard_fab2(sch_1):tp_usb3_p04_txp") )
				( member ( signalRef "@baseboard_fab2_lib.baseboard_fab2(sch_1):tp_vgahs_gpioj4") )
				( member ( signalRef "@baseboard_fab2_lib.baseboard_fab2(sch_1):tp_vgavs_gpioj5") )
				( member ( signalRef "@baseboard_fab2_lib.baseboard_fab2(sch_1):tp_vr_pvccio_cpu0_aiinsen") )
				( member ( signalRef "@baseboard_fab2_lib.baseboard_fab2(sch_1):tp_vr_pvccio_cpu1_aiinsen") )
				( member ( signalRef "@baseboard_fab2_lib.baseboard_fab2(sch_1):tp_vr_pvnn_pch_aiinsen") )
				( member ( signalRef "@baseboard_fab2_lib.baseboard_fab2(sch_1):tp_xdp_cpu_obsdata_c0") )
				( member ( signalRef "@baseboard_fab2_lib.baseboard_fab2(sch_1):tp_xdp_cpu_obsdata_c1") )
				( member ( signalRef "@baseboard_fab2_lib.baseboard_fab2(sch_1):tp_xdp_cpu_obsdata_c2") )
				( member ( signalRef "@baseboard_fab2_lib.baseboard_fab2(sch_1):tp_xdp_cpu_obsdata_c3") )
				( member ( signalRef "@baseboard_fab2_lib.baseboard_fab2(sch_1):tp_xdp_cpu_obsdata_d0") )
				( member ( signalRef "@baseboard_fab2_lib.baseboard_fab2(sch_1):tp_xdp_cpu_obsdata_d1") )
				( member ( signalRef "@baseboard_fab2_lib.baseboard_fab2(sch_1):tp_xdp_cpu_obsdata_d2") )
				( member ( signalRef "@baseboard_fab2_lib.baseboard_fab2(sch_1):tp_xdp_cpu_obsdata_d3") )
				( member ( signalRef "@baseboard_fab2_lib.baseboard_fab2(sch_1):tp_xdp_cpu_obsfn_c0") )
				( member ( signalRef "@baseboard_fab2_lib.baseboard_fab2(sch_1):tp_xdp_cpu0_obsdata_a0_mbp2_n") )
				( member ( signalRef "@baseboard_fab2_lib.baseboard_fab2(sch_1):tp_xdp_cpu0_obsdata_a1_mbp3_n") )
				( member ( signalRef "@baseboard_fab2_lib.baseboard_fab2(sch_1):tp_xdp_cpu0_obsdata_a2_mbp4_n") )
				( member ( signalRef "@baseboard_fab2_lib.baseboard_fab2(sch_1):tp_xdp_cpu0_obsdata_a3_mbp5_n") )
				( member ( signalRef "@baseboard_fab2_lib.baseboard_fab2(sch_1):tp_xdp_cpu1_obsdata_b0_mbp2_n") )
				( member ( signalRef "@baseboard_fab2_lib.baseboard_fab2(sch_1):tp_xdp_cpu1_obsdata_b1_mbp3_n") )
				( member ( signalRef "@baseboard_fab2_lib.baseboard_fab2(sch_1):tp_xdp_cpu1_obsdata_b2_mbp4_n") )
				( member ( signalRef "@baseboard_fab2_lib.baseboard_fab2(sch_1):tp_xdp_cpu1_obsdata_b3_mbp5_n") )
				( member ( signalRef "@baseboard_fab2_lib.baseboard_fab2(sch_1):tp_xdp_obsdata_a0") )
				( member ( signalRef "@baseboard_fab2_lib.baseboard_fab2(sch_1):tp_xdp_obsdata_a1") )
				( member ( signalRef "@baseboard_fab2_lib.baseboard_fab2(sch_1):tp_xdp_obsdata_a2") )
				( member ( signalRef "@baseboard_fab2_lib.baseboard_fab2(sch_1):tp_xdp_obsdata_a3") )
				( member ( signalRef "@baseboard_fab2_lib.baseboard_fab2(sch_1):tp_xdp_obsdata_b0") )
				( member ( signalRef "@baseboard_fab2_lib.baseboard_fab2(sch_1):tp_xdp_obsdata_b1") )
				( member ( signalRef "@baseboard_fab2_lib.baseboard_fab2(sch_1):tp_xdp_obsdata_b2") )
				( member ( signalRef "@baseboard_fab2_lib.baseboard_fab2(sch_1):tp_xdp_obsdata_b3") )
				( member ( signalRef "@baseboard_fab2_lib.baseboard_fab2(sch_1):tp_xdp_obsfn_b0") )
				( member ( signalRef "@baseboard_fab2_lib.baseboard_fab2(sch_1):tp_xdp_obsfn_b1") )
				( member ( signalRef "@baseboard_fab2_lib.baseboard_fab2(sch_1):tp_p3e_cpu1_pe2_rsr_rxn(0)") )
				( member ( signalRef "@baseboard_fab2_lib.baseboard_fab2(sch_1):tp_p3e_cpu1_pe2_rsr_rxn(1)") )
				( member ( signalRef "@baseboard_fab2_lib.baseboard_fab2(sch_1):tp_p3e_cpu1_pe2_rsr_rxn(2)") )
				( member ( signalRef "@baseboard_fab2_lib.baseboard_fab2(sch_1):tp_p3e_cpu1_pe2_rsr_rxn(3)") )
				( member ( signalRef "@baseboard_fab2_lib.baseboard_fab2(sch_1):tp_p3e_cpu1_pe2_rsr_rxn(4)") )
				( member ( signalRef "@baseboard_fab2_lib.baseboard_fab2(sch_1):tp_p3e_cpu1_pe2_rsr_rxn(5)") )
				( member ( signalRef "@baseboard_fab2_lib.baseboard_fab2(sch_1):tp_p3e_cpu1_pe2_rsr_rxn(6)") )
				( member ( signalRef "@baseboard_fab2_lib.baseboard_fab2(sch_1):tp_p3e_cpu1_pe2_rsr_rxn(7)") )
				( member ( signalRef "@baseboard_fab2_lib.baseboard_fab2(sch_1):tp_p3e_cpu1_pe2_rsr_rxn(8)") )
				( member ( signalRef "@baseboard_fab2_lib.baseboard_fab2(sch_1):tp_p3e_cpu1_pe2_rsr_rxn(9)") )
				( member ( signalRef "@baseboard_fab2_lib.baseboard_fab2(sch_1):tp_p3e_cpu1_pe2_rsr_rxn(10)") )
				( member ( signalRef "@baseboard_fab2_lib.baseboard_fab2(sch_1):tp_p3e_cpu1_pe2_rsr_rxn(11)") )
				( member ( signalRef "@baseboard_fab2_lib.baseboard_fab2(sch_1):tp_p3e_cpu1_pe2_rsr_rxn(12)") )
				( member ( signalRef "@baseboard_fab2_lib.baseboard_fab2(sch_1):tp_p3e_cpu1_pe2_rsr_rxn(13)") )
				( member ( signalRef "@baseboard_fab2_lib.baseboard_fab2(sch_1):tp_p3e_cpu1_pe2_rsr_rxn(14)") )
				( member ( signalRef "@baseboard_fab2_lib.baseboard_fab2(sch_1):tp_p3e_cpu1_pe2_rsr_rxn(15)") )
				( member ( signalRef "@baseboard_fab2_lib.baseboard_fab2(sch_1):tp_p3e_cpu1_pe2_rsr_rxp(0)") )
				( member ( signalRef "@baseboard_fab2_lib.baseboard_fab2(sch_1):tp_p3e_cpu1_pe2_rsr_rxp(1)") )
				( member ( signalRef "@baseboard_fab2_lib.baseboard_fab2(sch_1):tp_p3e_cpu1_pe2_rsr_rxp(2)") )
				( member ( signalRef "@baseboard_fab2_lib.baseboard_fab2(sch_1):tp_p3e_cpu1_pe2_rsr_rxp(3)") )
				( member ( signalRef "@baseboard_fab2_lib.baseboard_fab2(sch_1):tp_p3e_cpu1_pe2_rsr_rxp(4)") )
				( member ( signalRef "@baseboard_fab2_lib.baseboard_fab2(sch_1):tp_p3e_cpu1_pe2_rsr_rxp(5)") )
				( member ( signalRef "@baseboard_fab2_lib.baseboard_fab2(sch_1):tp_p3e_cpu1_pe2_rsr_rxp(6)") )
				( member ( signalRef "@baseboard_fab2_lib.baseboard_fab2(sch_1):tp_p3e_cpu1_pe2_rsr_rxp(7)") )
				( member ( signalRef "@baseboard_fab2_lib.baseboard_fab2(sch_1):tp_p3e_cpu1_pe2_rsr_rxp(8)") )
				( member ( signalRef "@baseboard_fab2_lib.baseboard_fab2(sch_1):tp_p3e_cpu1_pe2_rsr_rxp(9)") )
				( member ( signalRef "@baseboard_fab2_lib.baseboard_fab2(sch_1):tp_p3e_cpu1_pe2_rsr_rxp(10)") )
				( member ( signalRef "@baseboard_fab2_lib.baseboard_fab2(sch_1):tp_p3e_cpu1_pe2_rsr_rxp(11)") )
				( member ( signalRef "@baseboard_fab2_lib.baseboard_fab2(sch_1):tp_p3e_cpu1_pe2_rsr_rxp(12)") )
				( member ( signalRef "@baseboard_fab2_lib.baseboard_fab2(sch_1):tp_p3e_cpu1_pe2_rsr_rxp(13)") )
				( member ( signalRef "@baseboard_fab2_lib.baseboard_fab2(sch_1):tp_p3e_cpu1_pe2_rsr_rxp(14)") )
				( member ( signalRef "@baseboard_fab2_lib.baseboard_fab2(sch_1):tp_p3e_cpu1_pe2_rsr_rxp(15)") )
				( member ( signalRef "@baseboard_fab2_lib.baseboard_fab2(sch_1):tp_p3e_cpu1_pe2_rsr_txn(0)") )
				( member ( signalRef "@baseboard_fab2_lib.baseboard_fab2(sch_1):tp_p3e_cpu1_pe2_rsr_txn(1)") )
				( member ( signalRef "@baseboard_fab2_lib.baseboard_fab2(sch_1):tp_p3e_cpu1_pe2_rsr_txn(2)") )
				( member ( signalRef "@baseboard_fab2_lib.baseboard_fab2(sch_1):tp_p3e_cpu1_pe2_rsr_txn(3)") )
				( member ( signalRef "@baseboard_fab2_lib.baseboard_fab2(sch_1):tp_p3e_cpu1_pe2_rsr_txn(4)") )
				( member ( signalRef "@baseboard_fab2_lib.baseboard_fab2(sch_1):tp_p3e_cpu1_pe2_rsr_txn(5)") )
				( member ( signalRef "@baseboard_fab2_lib.baseboard_fab2(sch_1):tp_p3e_cpu1_pe2_rsr_txn(6)") )
				( member ( signalRef "@baseboard_fab2_lib.baseboard_fab2(sch_1):tp_p3e_cpu1_pe2_rsr_txn(7)") )
				( member ( signalRef "@baseboard_fab2_lib.baseboard_fab2(sch_1):tp_p3e_cpu1_pe2_rsr_txn(8)") )
				( member ( signalRef "@baseboard_fab2_lib.baseboard_fab2(sch_1):tp_p3e_cpu1_pe2_rsr_txn(9)") )
				( member ( signalRef "@baseboard_fab2_lib.baseboard_fab2(sch_1):tp_p3e_cpu1_pe2_rsr_txn(10)") )
				( member ( signalRef "@baseboard_fab2_lib.baseboard_fab2(sch_1):tp_p3e_cpu1_pe2_rsr_txn(11)") )
				( member ( signalRef "@baseboard_fab2_lib.baseboard_fab2(sch_1):tp_p3e_cpu1_pe2_rsr_txn(12)") )
				( member ( signalRef "@baseboard_fab2_lib.baseboard_fab2(sch_1):tp_p3e_cpu1_pe2_rsr_txn(13)") )
				( member ( signalRef "@baseboard_fab2_lib.baseboard_fab2(sch_1):tp_p3e_cpu1_pe2_rsr_txn(14)") )
				( member ( signalRef "@baseboard_fab2_lib.baseboard_fab2(sch_1):tp_p3e_cpu1_pe2_rsr_txn(15)") )
				( member ( signalRef "@baseboard_fab2_lib.baseboard_fab2(sch_1):tp_p3e_cpu1_pe2_rsr_txp(0)") )
				( member ( signalRef "@baseboard_fab2_lib.baseboard_fab2(sch_1):tp_p3e_cpu1_pe2_rsr_txp(1)") )
				( member ( signalRef "@baseboard_fab2_lib.baseboard_fab2(sch_1):tp_p3e_cpu1_pe2_rsr_txp(2)") )
				( member ( signalRef "@baseboard_fab2_lib.baseboard_fab2(sch_1):tp_p3e_cpu1_pe2_rsr_txp(3)") )
				( member ( signalRef "@baseboard_fab2_lib.baseboard_fab2(sch_1):tp_p3e_cpu1_pe2_rsr_txp(4)") )
				( member ( signalRef "@baseboard_fab2_lib.baseboard_fab2(sch_1):tp_p3e_cpu1_pe2_rsr_txp(5)") )
				( member ( signalRef "@baseboard_fab2_lib.baseboard_fab2(sch_1):tp_p3e_cpu1_pe2_rsr_txp(6)") )
				( member ( signalRef "@baseboard_fab2_lib.baseboard_fab2(sch_1):tp_p3e_cpu1_pe2_rsr_txp(7)") )
				( member ( signalRef "@baseboard_fab2_lib.baseboard_fab2(sch_1):tp_p3e_cpu1_pe2_rsr_txp(8)") )
				( member ( signalRef "@baseboard_fab2_lib.baseboard_fab2(sch_1):tp_p3e_cpu1_pe2_rsr_txp(9)") )
				( member ( signalRef "@baseboard_fab2_lib.baseboard_fab2(sch_1):tp_p3e_cpu1_pe2_rsr_txp(10)") )
				( member ( signalRef "@baseboard_fab2_lib.baseboard_fab2(sch_1):tp_p3e_cpu1_pe2_rsr_txp(11)") )
				( member ( signalRef "@baseboard_fab2_lib.baseboard_fab2(sch_1):tp_p3e_cpu1_pe2_rsr_txp(12)") )
				( member ( signalRef "@baseboard_fab2_lib.baseboard_fab2(sch_1):tp_p3e_cpu1_pe2_rsr_txp(13)") )
				( member ( signalRef "@baseboard_fab2_lib.baseboard_fab2(sch_1):tp_p3e_cpu1_pe2_rsr_txp(14)") )
				( member ( signalRef "@baseboard_fab2_lib.baseboard_fab2(sch_1):tp_p3e_cpu1_pe2_rsr_txp(15)") )
				( member ( signalRef "@baseboard_fab2_lib.baseboard_fab2(sch_1):tp_rgmii1txctl_gpiot1") )
				( member ( signalRef "@baseboard_fab2_lib.baseboard_fab2(sch_1):tp_rgmii1txd2_gpiot4") )
				( member ( signalRef "@baseboard_fab2_lib.baseboard_fab2(sch_1):tp_rgmii1txd3_gpiot5") )
				( member ( signalRef "@baseboard_fab2_lib.baseboard_fab2(sch_1):tp_rgmii2txctl_gpiot7") )
				( member ( signalRef "@baseboard_fab2_lib.baseboard_fab2(sch_1):tp_rgmii2txd2_gpiot4") )
				( member ( signalRef "@baseboard_fab2_lib.baseboard_fab2(sch_1):tp_rgmii2txd3_gpiot5") )
				( member ( signalRef "@baseboard_fab2_lib.baseboard_fab2(sch_1):tp_cpld1_pr11b") )
				( member ( signalRef "@baseboard_fab2_lib.baseboard_fab2(sch_1):tp_rst_cpu1_cd_hfi0_n") )
				( member ( signalRef "@baseboard_fab2_lib.baseboard_fab2(sch_1):tp_cpld1_pt17b_pclkc0_1") )
				( member ( signalRef "@baseboard_fab2_lib.baseboard_fab2(sch_1):tp_cpld1_pt13a") )
				( member ( signalRef "@baseboard_fab2_lib.baseboard_fab2(sch_1):tp_cpld1_pt11b") )
				( member ( signalRef "@baseboard_fab2_lib.baseboard_fab2(sch_1):tp_cpld1_pt11a") )
				( member ( signalRef "@baseboard_fab2_lib.baseboard_fab2(sch_1):tp_bmc_disable") )
				( member ( signalRef "@baseboard_fab2_lib.baseboard_fab2(sch_1):tp_rst_rtcrst_n") )
				( member ( signalRef "@baseboard_fab2_lib.baseboard_fab2(sch_1):tp_rsvd_b1") )
				( member ( signalRef "@baseboard_fab2_lib.baseboard_fab2(sch_1):tp_sgpio_sata_clock1_r") )
				( member ( signalRef "@baseboard_fab2_lib.baseboard_fab2(sch_1):tp_sgpio_sata_data1_r") )
				( member ( signalRef "@baseboard_fab2_lib.baseboard_fab2(sch_1):tp_sgpio_sata_load1_r") )
				( member ( signalRef "@baseboard_fab2_lib.baseboard_fab2(sch_1):tp_slg55021_p3v3_8") )
				( member ( signalRef "@baseboard_fab2_lib.baseboard_fab2(sch_1):tp_slg55021_p5v_8") )
				( member ( signalRef "@baseboard_fab2_lib.baseboard_fab2(sch_1):tp_slg55021_p12v_fan_8") )
				( member ( signalRef "@baseboard_fab2_lib.baseboard_fab2(sch_1):tp_slp_lan_n") )
				( member ( signalRef "@baseboard_fab2_lib.baseboard_fab2(sch_1):tp_smb_cpu1_cd_hfi0_i2cclk") )
				( member ( signalRef "@baseboard_fab2_lib.baseboard_fab2(sch_1):tp_smb_cpu1_cd_hfi0_i2cdat") )
				( member ( signalRef "@baseboard_fab2_lib.baseboard_fab2(sch_1):tp_smb_ddr_abc_en") )
				( member ( signalRef "@baseboard_fab2_lib.baseboard_fab2(sch_1):tp_smb_ddr_def_en") )
				( member ( signalRef "@baseboard_fab2_lib.baseboard_fab2(sch_1):tp_smb_ddr_ghj_en") )
				( member ( signalRef "@baseboard_fab2_lib.baseboard_fab2(sch_1):tp_smb_ddr_klm_en") )
				( member ( signalRef "@baseboard_fab2_lib.baseboard_fab2(sch_1):tp_smb_pehpcpu1_en") )
				( member ( signalRef "@baseboard_fab2_lib.baseboard_fab2(sch_1):fm_cpu0_sm_wp") )
				( member ( signalRef "@baseboard_fab2_lib.baseboard_fab2(sch_1):tp_spi_bmc_bt_d2") )
				( member ( signalRef "@baseboard_fab2_lib.baseboard_fab2(sch_1):tp_spi_pch_bios_clk_r") )
				( member ( signalRef "@baseboard_fab2_lib.baseboard_fab2(sch_1):tp_spi_pch_bios_cs0_r_n") )
				( member ( signalRef "@baseboard_fab2_lib.baseboard_fab2(sch_1):tp_spi_pch_bios_miso_r") )
				( member ( signalRef "@baseboard_fab2_lib.baseboard_fab2(sch_1):tp_spi_pch_bios_mosi_r") )
				( member ( signalRef "@baseboard_fab2_lib.baseboard_fab2(sch_1):tp_spi_pch_cs1_r1_n") )
				( member ( signalRef "@baseboard_fab2_lib.baseboard_fab2(sch_1):tp_pvddq_abc_ph2_gl_1") )
				( member ( signalRef "@baseboard_fab2_lib.baseboard_fab2(sch_1):tp_pvccin_cpu0_ph2_gl_1") )
				( member ( signalRef "@baseboard_fab2_lib.baseboard_fab2(sch_1):tp_pvddq_ghj_ph3_imon") )
				( member ( signalRef "@baseboard_fab2_lib.baseboard_fab2(sch_1):tp_pvddq_ghj_ph3_imon_ref") )
				( member ( signalRef "@baseboard_fab2_lib.baseboard_fab2(sch_1):tp_pvddq_ghj_pwm3") )
				( member ( signalRef "@baseboard_fab2_lib.baseboard_fab2(sch_1):tp_pvddq_ghj_reset_n") )
				( member ( signalRef "@baseboard_fab2_lib.baseboard_fab2(sch_1):tp_pvddq_klm_bpwm1") )
				( member ( signalRef "@baseboard_fab2_lib.baseboard_fab2(sch_1):tp_pvddq_klm_bref1") )
				( member ( signalRef "@baseboard_fab2_lib.baseboard_fab2(sch_1):tp_pvddq_klm_btsen") )
				( member ( signalRef "@baseboard_fab2_lib.baseboard_fab2(sch_1):tp_pvddq_klm_bvref") )
				( member ( signalRef "@baseboard_fab2_lib.baseboard_fab2(sch_1):tp_pvddq_klm_bvsen") )
				( member ( signalRef "@baseboard_fab2_lib.baseboard_fab2(sch_1):tp_pvddq_def_ph1_gl_1") )
				( member ( signalRef "@baseboard_fab2_lib.baseboard_fab2(sch_1):tp_pvccin_cpu0_ph3_gl_1") )
				( member ( signalRef "@baseboard_fab2_lib.baseboard_fab2(sch_1):tp_pvddq_def_ph2_gl_1") )
				( member ( signalRef "@baseboard_fab2_lib.baseboard_fab2(sch_1):tp_pvccin_cpu0_ph4_gl_1") )
				( member ( signalRef "@baseboard_fab2_lib.baseboard_fab2(sch_1):tp_pvddq_klm_ph3_imon") )
				( member ( signalRef "@baseboard_fab2_lib.baseboard_fab2(sch_1):tp_pvddq_klm_ph3_imon_ref") )
				( member ( signalRef "@baseboard_fab2_lib.baseboard_fab2(sch_1):tp_pvddq_klm_reset_n") )
				( member ( signalRef "@baseboard_fab2_lib.baseboard_fab2(sch_1):tp_pvddq_ghj_ph1_gl_1") )
				( member ( signalRef "@baseboard_fab2_lib.baseboard_fab2(sch_1):tp_pvccio_cpu1_gl_1") )
				( member ( signalRef "@baseboard_fab2_lib.baseboard_fab2(sch_1):tp_pvnn_pch_pinalrt_n") )
				( member ( signalRef "@baseboard_fab2_lib.baseboard_fab2(sch_1):tp_pvnn_pch_reset_n") )
				( member ( signalRef "@baseboard_fab2_lib.baseboard_fab2(sch_1):tp_pvnn_pch_svid_alert") )
				( member ( signalRef "@baseboard_fab2_lib.baseboard_fab2(sch_1):tp_pvnn_pch_vclk") )
				( member ( signalRef "@baseboard_fab2_lib.baseboard_fab2(sch_1):tp_pvnn_pch_vdio") )
				( member ( signalRef "@baseboard_fab2_lib.baseboard_fab2(sch_1):tp_pvddq_ghj_ph2_gl_1") )
				( member ( signalRef "@baseboard_fab2_lib.baseboard_fab2(sch_1):tp_pvccin_cpu0_ph5_gl_1") )
				( member ( signalRef "@baseboard_fab2_lib.baseboard_fab2(sch_1):fm_cpu0_vrm_322m_156m_osc_en") )
				( member ( signalRef "@baseboard_fab2_lib.baseboard_fab2(sch_1):fm_cpu0_vrm_osc_en") )
				( member ( signalRef "@baseboard_fab2_lib.baseboard_fab2(sch_1):jtag_mcp_cpu0_tdi_r") )
				( member ( signalRef "@baseboard_fab2_lib.baseboard_fab2(sch_1):tp_cpld1_pt19d") )
				( member ( signalRef "@baseboard_fab2_lib.baseboard_fab2(sch_1):tp_cpld1_pb8d") )
				( member ( signalRef "@baseboard_fab2_lib.baseboard_fab2(sch_1):tp_cpld1_pt22d") )
				( member ( signalRef "@baseboard_fab2_lib.baseboard_fab2(sch_1):tp_pvddq_abc_ph1_gl_1") )
				( member ( signalRef "@baseboard_fab2_lib.baseboard_fab2(sch_1):tp_pvccio_cpu0_gl_1") )
				( member ( signalRef "@baseboard_fab2_lib.baseboard_fab2(sch_1):tp_p3e_cpu1_pe1_mp_rxn(0)") )
				( member ( signalRef "@baseboard_fab2_lib.baseboard_fab2(sch_1):tp_p3e_cpu1_pe1_mp_rxn(1)") )
				( member ( signalRef "@baseboard_fab2_lib.baseboard_fab2(sch_1):tp_p3e_cpu1_pe1_mp_rxn(2)") )
				( member ( signalRef "@baseboard_fab2_lib.baseboard_fab2(sch_1):tp_p3e_cpu1_pe1_mp_rxn(3)") )
				( member ( signalRef "@baseboard_fab2_lib.baseboard_fab2(sch_1):tp_p3e_cpu1_pe1_mp_rxn(4)") )
				( member ( signalRef "@baseboard_fab2_lib.baseboard_fab2(sch_1):tp_p3e_cpu1_pe1_mp_rxn(5)") )
				( member ( signalRef "@baseboard_fab2_lib.baseboard_fab2(sch_1):tp_p3e_cpu1_pe1_mp_rxn(6)") )
				( member ( signalRef "@baseboard_fab2_lib.baseboard_fab2(sch_1):tp_p3e_cpu1_pe1_mp_rxn(7)") )
				( member ( signalRef "@baseboard_fab2_lib.baseboard_fab2(sch_1):tp_p3e_cpu1_pe1_mp_rxp(0)") )
				( member ( signalRef "@baseboard_fab2_lib.baseboard_fab2(sch_1):tp_p3e_cpu1_pe1_mp_rxp(1)") )
				( member ( signalRef "@baseboard_fab2_lib.baseboard_fab2(sch_1):tp_p3e_cpu1_pe1_mp_rxp(2)") )
				( member ( signalRef "@baseboard_fab2_lib.baseboard_fab2(sch_1):tp_p3e_cpu1_pe1_mp_rxp(3)") )
				( member ( signalRef "@baseboard_fab2_lib.baseboard_fab2(sch_1):tp_p3e_cpu1_pe1_mp_rxp(4)") )
				( member ( signalRef "@baseboard_fab2_lib.baseboard_fab2(sch_1):tp_p3e_cpu1_pe1_mp_rxp(5)") )
				( member ( signalRef "@baseboard_fab2_lib.baseboard_fab2(sch_1):tp_p3e_cpu1_pe1_mp_rxp(6)") )
				( member ( signalRef "@baseboard_fab2_lib.baseboard_fab2(sch_1):tp_p3e_cpu1_pe1_mp_rxp(7)") )
				( member ( signalRef "@baseboard_fab2_lib.baseboard_fab2(sch_1):tp_p3e_cpu1_pe1_mp_txn(0)") )
				( member ( signalRef "@baseboard_fab2_lib.baseboard_fab2(sch_1):tp_p3e_cpu1_pe1_mp_txn(1)") )
				( member ( signalRef "@baseboard_fab2_lib.baseboard_fab2(sch_1):tp_p3e_cpu1_pe1_mp_txn(2)") )
				( member ( signalRef "@baseboard_fab2_lib.baseboard_fab2(sch_1):tp_p3e_cpu1_pe1_mp_txn(3)") )
				( member ( signalRef "@baseboard_fab2_lib.baseboard_fab2(sch_1):tp_p3e_cpu1_pe1_mp_txn(4)") )
				( member ( signalRef "@baseboard_fab2_lib.baseboard_fab2(sch_1):tp_p3e_cpu1_pe1_mp_txn(5)") )
				( member ( signalRef "@baseboard_fab2_lib.baseboard_fab2(sch_1):tp_p3e_cpu1_pe1_mp_txn(6)") )
				( member ( signalRef "@baseboard_fab2_lib.baseboard_fab2(sch_1):tp_p3e_cpu1_pe1_mp_txn(7)") )
				( member ( signalRef "@baseboard_fab2_lib.baseboard_fab2(sch_1):tp_p3e_cpu1_pe1_mp_txp(0)") )
				( member ( signalRef "@baseboard_fab2_lib.baseboard_fab2(sch_1):tp_p3e_cpu1_pe1_mp_txp(1)") )
				( member ( signalRef "@baseboard_fab2_lib.baseboard_fab2(sch_1):tp_p3e_cpu1_pe1_mp_txp(2)") )
				( member ( signalRef "@baseboard_fab2_lib.baseboard_fab2(sch_1):tp_p3e_cpu1_pe1_mp_txp(3)") )
				( member ( signalRef "@baseboard_fab2_lib.baseboard_fab2(sch_1):tp_p3e_cpu1_pe1_mp_txp(4)") )
				( member ( signalRef "@baseboard_fab2_lib.baseboard_fab2(sch_1):tp_p3e_cpu1_pe1_mp_txp(5)") )
				( member ( signalRef "@baseboard_fab2_lib.baseboard_fab2(sch_1):tp_p3e_cpu1_pe1_mp_txp(6)") )
				( member ( signalRef "@baseboard_fab2_lib.baseboard_fab2(sch_1):tp_p3e_cpu1_pe1_mp_txp(7)") )
				( member ( signalRef "@baseboard_fab2_lib.baseboard_fab2(sch_1):tp_p3e_cpu1_pe1_rsr3_rxn(8)") )
				( member ( signalRef "@baseboard_fab2_lib.baseboard_fab2(sch_1):tp_p3e_cpu1_pe1_rsr3_rxn(9)") )
				( member ( signalRef "@baseboard_fab2_lib.baseboard_fab2(sch_1):tp_p3e_cpu1_pe1_rsr3_rxn(10)") )
				( member ( signalRef "@baseboard_fab2_lib.baseboard_fab2(sch_1):tp_p3e_cpu1_pe1_rsr3_rxn(11)") )
				( member ( signalRef "@baseboard_fab2_lib.baseboard_fab2(sch_1):tp_p3e_cpu1_pe1_rsr3_rxn(12)") )
				( member ( signalRef "@baseboard_fab2_lib.baseboard_fab2(sch_1):tp_p3e_cpu1_pe1_rsr3_rxn(13)") )
				( member ( signalRef "@baseboard_fab2_lib.baseboard_fab2(sch_1):tp_p3e_cpu1_pe1_rsr3_rxn(14)") )
				( member ( signalRef "@baseboard_fab2_lib.baseboard_fab2(sch_1):tp_p3e_cpu1_pe1_rsr3_rxn(15)") )
				( member ( signalRef "@baseboard_fab2_lib.baseboard_fab2(sch_1):tp_p3e_cpu1_pe1_rsr3_rxp(8)") )
				( member ( signalRef "@baseboard_fab2_lib.baseboard_fab2(sch_1):tp_p3e_cpu1_pe1_rsr3_rxp(9)") )
				( member ( signalRef "@baseboard_fab2_lib.baseboard_fab2(sch_1):tp_p3e_cpu1_pe1_rsr3_rxp(10)") )
				( member ( signalRef "@baseboard_fab2_lib.baseboard_fab2(sch_1):tp_p3e_cpu1_pe1_rsr3_rxp(11)") )
				( member ( signalRef "@baseboard_fab2_lib.baseboard_fab2(sch_1):tp_p3e_cpu1_pe1_rsr3_rxp(12)") )
				( member ( signalRef "@baseboard_fab2_lib.baseboard_fab2(sch_1):tp_p3e_cpu1_pe1_rsr3_rxp(13)") )
				( member ( signalRef "@baseboard_fab2_lib.baseboard_fab2(sch_1):tp_p3e_cpu1_pe1_rsr3_rxp(14)") )
				( member ( signalRef "@baseboard_fab2_lib.baseboard_fab2(sch_1):tp_p3e_cpu1_pe1_rsr3_rxp(15)") )
				( member ( signalRef "@baseboard_fab2_lib.baseboard_fab2(sch_1):tp_p3e_cpu1_pe1_rsr3_txn(8)") )
				( member ( signalRef "@baseboard_fab2_lib.baseboard_fab2(sch_1):tp_p3e_cpu1_pe1_rsr3_txn(9)") )
				( member ( signalRef "@baseboard_fab2_lib.baseboard_fab2(sch_1):tp_p3e_cpu1_pe1_rsr3_txn(10)") )
				( member ( signalRef "@baseboard_fab2_lib.baseboard_fab2(sch_1):tp_p3e_cpu1_pe1_rsr3_txn(11)") )
				( member ( signalRef "@baseboard_fab2_lib.baseboard_fab2(sch_1):tp_p3e_cpu1_pe1_rsr3_txn(12)") )
				( member ( signalRef "@baseboard_fab2_lib.baseboard_fab2(sch_1):tp_p3e_cpu1_pe1_rsr3_txn(13)") )
				( member ( signalRef "@baseboard_fab2_lib.baseboard_fab2(sch_1):tp_p3e_cpu1_pe1_rsr3_txn(14)") )
				( member ( signalRef "@baseboard_fab2_lib.baseboard_fab2(sch_1):tp_p3e_cpu1_pe1_rsr3_txn(15)") )
				( member ( signalRef "@baseboard_fab2_lib.baseboard_fab2(sch_1):tp_p3e_cpu1_pe1_rsr3_txp(8)") )
				( member ( signalRef "@baseboard_fab2_lib.baseboard_fab2(sch_1):tp_p3e_cpu1_pe1_rsr3_txp(9)") )
				( member ( signalRef "@baseboard_fab2_lib.baseboard_fab2(sch_1):tp_p3e_cpu1_pe1_rsr3_txp(10)") )
				( member ( signalRef "@baseboard_fab2_lib.baseboard_fab2(sch_1):tp_p3e_cpu1_pe1_rsr3_txp(11)") )
				( member ( signalRef "@baseboard_fab2_lib.baseboard_fab2(sch_1):tp_p3e_cpu1_pe1_rsr3_txp(12)") )
				( member ( signalRef "@baseboard_fab2_lib.baseboard_fab2(sch_1):tp_p3e_cpu1_pe1_rsr3_txp(13)") )
				( member ( signalRef "@baseboard_fab2_lib.baseboard_fab2(sch_1):tp_p3e_cpu1_pe1_rsr3_txp(14)") )
				( member ( signalRef "@baseboard_fab2_lib.baseboard_fab2(sch_1):tp_p3e_cpu1_pe1_rsr3_txp(15)") )
				( member ( signalRef "@baseboard_fab2_lib.baseboard_fab2(sch_1):tp_pi7c9x1172_rtsa_n") )
				( member ( signalRef "@baseboard_fab2_lib.baseboard_fab2(sch_1):tp_pi7c9x1172_rtsb_n") )
				( member ( signalRef "@baseboard_fab2_lib.baseboard_fab2(sch_1):tp_pi7c9x1172_so") )
				( member ( signalRef "@baseboard_fab2_lib.baseboard_fab2(sch_1):tp_cpld1_pr12d") )
				( member ( signalRef "@baseboard_fab2_lib.baseboard_fab2(sch_1):tp_pltrst_cpu_n") )
				( member ( signalRef "@baseboard_fab2_lib.baseboard_fab2(sch_1):tp_pm_sync_gtl") )
				( member ( signalRef "@baseboard_fab2_lib.baseboard_fab2(sch_1):tp_pvccin_cpu0_airef6") )
				( member ( signalRef "@baseboard_fab2_lib.baseboard_fab2(sch_1):tp_pvccin_cpu0_aisen6") )
				( member ( signalRef "@baseboard_fab2_lib.baseboard_fab2(sch_1):tp_pvccin_cpu0_apwm6") )
				( member ( signalRef "@baseboard_fab2_lib.baseboard_fab2(sch_1):tp_pvccin_cpu0_fault1_20") )
				( member ( signalRef "@baseboard_fab2_lib.baseboard_fab2(sch_1):tp_pvccin_cpu0_gp1") )
				( member ( signalRef "@baseboard_fab2_lib.baseboard_fab2(sch_1):tp_pvccin_cpu1_ph4_gl_1") )
				( member ( signalRef "@baseboard_fab2_lib.baseboard_fab2(sch_1):fm_cpu1_stl_brd_osc_en") )
				( member ( signalRef "@baseboard_fab2_lib.baseboard_fab2(sch_1):tp_pvccin_cpu0_reset") )
				( member ( signalRef "@baseboard_fab2_lib.baseboard_fab2(sch_1):tp_pvccin_cpu1_airef6") )
				( member ( signalRef "@baseboard_fab2_lib.baseboard_fab2(sch_1):tp_pvccin_cpu1_aisen6") )
				( member ( signalRef "@baseboard_fab2_lib.baseboard_fab2(sch_1):tp_pvccin_cpu1_apwm6") )
				( member ( signalRef "@baseboard_fab2_lib.baseboard_fab2(sch_1):tp_pvccin_cpu1_fault1_20") )
				( member ( signalRef "@baseboard_fab2_lib.baseboard_fab2(sch_1):tp_pvccin_cpu1_gp1") )
				( member ( signalRef "@baseboard_fab2_lib.baseboard_fab2(sch_1):tp_pvccinc_cpu1_ph1_gl_1") )
				( member ( signalRef "@baseboard_fab2_lib.baseboard_fab2(sch_1):fm_cpu0_mcp_clk_en_n") )
				( member ( signalRef "@baseboard_fab2_lib.baseboard_fab2(sch_1):tp_pvccinc_cpu1_ph2_gl_1") )
				( member ( signalRef "@baseboard_fab2_lib.baseboard_fab2(sch_1):fm_cpu1_mcp_clk_en_n") )
				( member ( signalRef "@baseboard_fab2_lib.baseboard_fab2(sch_1):fm_pch_bmc_thermtrip_exi_strap_n") )
				( member ( signalRef "@baseboard_fab2_lib.baseboard_fab2(sch_1):fm_db1200zl_bclks_en_n") )
				( member ( signalRef "@baseboard_fab2_lib.baseboard_fab2(sch_1):fm_156m_cpu0_brd_osc_en") )
				( member ( signalRef "@baseboard_fab2_lib.baseboard_fab2(sch_1):fm_cpu1_vrm_osc_en") )
				( member ( signalRef "@baseboard_fab2_lib.baseboard_fab2(sch_1):fm_156m_cpu1_brd_osc_en") )
				( member ( signalRef "@baseboard_fab2_lib.baseboard_fab2(sch_1):fm_cpu1_vrm_322m_156m_osc_en") )
				( member ( signalRef "@baseboard_fab2_lib.baseboard_fab2(sch_1):tp_pvccin_cpu1_reset_n") )
				( member ( signalRef "@baseboard_fab2_lib.baseboard_fab2(sch_1):tp_pvccio_cpu0_biref1") )
				( member ( signalRef "@baseboard_fab2_lib.baseboard_fab2(sch_1):tp_pvccio_cpu0_bpwm1") )
				( member ( signalRef "@baseboard_fab2_lib.baseboard_fab2(sch_1):tp_pvccio_cpu0_btsen") )
				( member ( signalRef "@baseboard_fab2_lib.baseboard_fab2(sch_1):tp_pvccio_cpu0_bvref") )
				( member ( signalRef "@baseboard_fab2_lib.baseboard_fab2(sch_1):tp_pvccio_cpu0_bvsen") )
				( member ( signalRef "@baseboard_fab2_lib.baseboard_fab2(sch_1):tp_vr_pvccio_cpu0_mp0") )
				( member ( signalRef "@baseboard_fab2_lib.baseboard_fab2(sch_1):tp_vr_pvccio_cpu0_mp1") )
				( member ( signalRef "@baseboard_fab2_lib.baseboard_fab2(sch_1):tp_pvccio_cpu0_pinalrt_n") )
				( member ( signalRef "@baseboard_fab2_lib.baseboard_fab2(sch_1):tp_pvccio_cpu0_reset_n") )
				( member ( signalRef "@baseboard_fab2_lib.baseboard_fab2(sch_1):tp_pvccio_cpu1_biref1") )
				( member ( signalRef "@baseboard_fab2_lib.baseboard_fab2(sch_1):tp_pvccio_cpu1_bpwm1") )
				( member ( signalRef "@baseboard_fab2_lib.baseboard_fab2(sch_1):tp_pvccio_cpu1_btsen") )
				( member ( signalRef "@baseboard_fab2_lib.baseboard_fab2(sch_1):tp_pvccio_cpu1_bvref") )
				( member ( signalRef "@baseboard_fab2_lib.baseboard_fab2(sch_1):tp_pvccio_cpu1_bvsen") )
				( member ( signalRef "@baseboard_fab2_lib.baseboard_fab2(sch_1):tp_vr_pvccio_cpu1_mp0") )
				( member ( signalRef "@baseboard_fab2_lib.baseboard_fab2(sch_1):tp_vr_pvccio_cpu1_mp1") )
				( member ( signalRef "@baseboard_fab2_lib.baseboard_fab2(sch_1):tp_pvccio_cpu1_pinalrt_n") )
				( member ( signalRef "@baseboard_fab2_lib.baseboard_fab2(sch_1):tp_pvccio_cpu1_reset_n") )
				( member ( signalRef "@baseboard_fab2_lib.baseboard_fab2(sch_1):tp_pvddq_abc_bpwm1") )
				( member ( signalRef "@baseboard_fab2_lib.baseboard_fab2(sch_1):tp_pvddq_abc_bref1") )
				( member ( signalRef "@baseboard_fab2_lib.baseboard_fab2(sch_1):tp_pvddq_abc_btsen") )
				( member ( signalRef "@baseboard_fab2_lib.baseboard_fab2(sch_1):tp_pvddq_abc_bvref") )
				( member ( signalRef "@baseboard_fab2_lib.baseboard_fab2(sch_1):tp_pvddq_abc_bvsen") )
				( member ( signalRef "@baseboard_fab2_lib.baseboard_fab2(sch_1):fm_cpu0_rc_en") )
				( member ( signalRef "@baseboard_fab2_lib.baseboard_fab2(sch_1):tp_pvddq_abc_mp1") )
				( member ( signalRef "@baseboard_fab2_lib.baseboard_fab2(sch_1):tp_pvddq_abc_ph3_imon") )
				( member ( signalRef "@baseboard_fab2_lib.baseboard_fab2(sch_1):tp_pvddq_abc_ph3_imon_ref") )
				( member ( signalRef "@baseboard_fab2_lib.baseboard_fab2(sch_1):tp_pvddq_abc_pinalrt_n") )
				( member ( signalRef "@baseboard_fab2_lib.baseboard_fab2(sch_1):tp_pvddq_abc_pwm3") )
				( member ( signalRef "@baseboard_fab2_lib.baseboard_fab2(sch_1):tp_pvddq_abc_reset_n") )
				( member ( signalRef "@baseboard_fab2_lib.baseboard_fab2(sch_1):tp_pvddq_def_bpwm1") )
				( member ( signalRef "@baseboard_fab2_lib.baseboard_fab2(sch_1):tp_pvddq_def_bref1") )
				( member ( signalRef "@baseboard_fab2_lib.baseboard_fab2(sch_1):tp_pvddq_def_btsen") )
				( member ( signalRef "@baseboard_fab2_lib.baseboard_fab2(sch_1):tp_pvddq_def_bvref") )
				( member ( signalRef "@baseboard_fab2_lib.baseboard_fab2(sch_1):tp_pvddq_def_bvsen") )
				( member ( signalRef "@baseboard_fab2_lib.baseboard_fab2(sch_1):tp_jumper_block_1_1") )
				( member ( signalRef "@baseboard_fab2_lib.baseboard_fab2(sch_1):tp_pvddq_def_mp1") )
				( member ( signalRef "@baseboard_fab2_lib.baseboard_fab2(sch_1):tp_pvddq_def_ph3_imon") )
				( member ( signalRef "@baseboard_fab2_lib.baseboard_fab2(sch_1):tp_pvddq_def_ph3_imon_ref") )
				( member ( signalRef "@baseboard_fab2_lib.baseboard_fab2(sch_1):tp_pvddq_def_pinalrt_n") )
				( member ( signalRef "@baseboard_fab2_lib.baseboard_fab2(sch_1):tp_pvddq_def_pwm3") )
				( member ( signalRef "@baseboard_fab2_lib.baseboard_fab2(sch_1):tp_pvddq_def_reset_n") )
				( member ( signalRef "@baseboard_fab2_lib.baseboard_fab2(sch_1):tp_pvddq_ghj_bpwm1") )
				( member ( signalRef "@baseboard_fab2_lib.baseboard_fab2(sch_1):tp_pvddq_ghj_bref1") )
				( member ( signalRef "@baseboard_fab2_lib.baseboard_fab2(sch_1):tp_pvddq_ghj_btsen") )
				( member ( signalRef "@baseboard_fab2_lib.baseboard_fab2(sch_1):tp_pvddq_ghj_bvref") )
				( member ( signalRef "@baseboard_fab2_lib.baseboard_fab2(sch_1):tp_pvddq_ghj_bvsen") )
				( member ( signalRef "@baseboard_fab2_lib.baseboard_fab2(sch_1):fm_cpu1_rc_en") )
				( member ( signalRef "@baseboard_fab2_lib.baseboard_fab2(sch_1):tp_pvddq_ghj_mp1") )
				( member ( signalRef "@baseboard_fab2_lib.baseboard_fab2(sch_1):tp_pvddq_klm_ph1_gl_1") )
				( member ( signalRef "@baseboard_fab2_lib.baseboard_fab2(sch_1):tp_pvddq_klm_ph2_gl_1") )
				( member ( signalRef "@baseboard_fab2_lib.baseboard_fab2(sch_1):tp_pvnn_pch_gl_1") )
				( member ( signalRef "@baseboard_fab2_lib.baseboard_fab2(sch_1):tp_pvsa_cpu0_gl_1") )
				( member ( signalRef "@baseboard_fab2_lib.baseboard_fab2(sch_1):tp_p1v05_pch_gl_1") )
				( member ( signalRef "@baseboard_fab2_lib.baseboard_fab2(sch_1):tp_shared_kr_mdc_0") )
				( member ( signalRef "@baseboard_fab2_lib.baseboard_fab2(sch_1):tp_rsvd(0)") )
				( member ( signalRef "@baseboard_fab2_lib.baseboard_fab2(sch_1):nc_pvccin_cpu0_ph1_p31") )
				( member ( signalRef "@baseboard_fab2_lib.baseboard_fab2(sch_1):nc_pvccin_cpu0_ph2_p31") )
				( member ( signalRef "@baseboard_fab2_lib.baseboard_fab2(sch_1):nc_pvccin_cpu0_ph3_p31") )
				( member ( signalRef "@baseboard_fab2_lib.baseboard_fab2(sch_1):nc_pvccin_cpu0_ph4_p31") )
				( member ( signalRef "@baseboard_fab2_lib.baseboard_fab2(sch_1):nc_pvccin_cpu0_ph5_p31") )
				( member ( signalRef "@baseboard_fab2_lib.baseboard_fab2(sch_1):nc_pvccio_cpu0_ph1_p31") )
				( member ( signalRef "@baseboard_fab2_lib.baseboard_fab2(sch_1):nc_pvccio_cpu1_ph1_p31") )
				( member ( signalRef "@baseboard_fab2_lib.baseboard_fab2(sch_1):nc_pvddq_abc_ph1_p31") )
				( member ( signalRef "@baseboard_fab2_lib.baseboard_fab2(sch_1):nc_pvddq_abc_ph2_p31") )
				( member ( signalRef "@baseboard_fab2_lib.baseboard_fab2(sch_1):nc_pvddq_def_ph1_p31") )
				( member ( signalRef "@baseboard_fab2_lib.baseboard_fab2(sch_1):nc_pvddq_def_ph2_p31") )
				( member ( signalRef "@baseboard_fab2_lib.baseboard_fab2(sch_1):nc_pvddq_ghj_ph1_p31") )
				( member ( signalRef "@baseboard_fab2_lib.baseboard_fab2(sch_1):nc_pvddq_ghj_ph2_p31") )
				( member ( signalRef "@baseboard_fab2_lib.baseboard_fab2(sch_1):nc_pvddq_klm_ph1_p31") )
				( member ( signalRef "@baseboard_fab2_lib.baseboard_fab2(sch_1):nc_pvddq_klm_ph2_p31") )
				( member ( signalRef "@baseboard_fab2_lib.baseboard_fab2(sch_1):nc_pvnn_pch_ph1_p31") )
				( member ( signalRef "@baseboard_fab2_lib.baseboard_fab2(sch_1):nc_pvsa_cpu0_p31") )
				( member ( signalRef "@baseboard_fab2_lib.baseboard_fab2(sch_1):tp_cpld1_pb16b_pclkc2_1") )
				( member ( signalRef "@baseboard_fab2_lib.baseboard_fab2(sch_1):tp_led_cpu1_cd_hfi0_n") )
				( member ( signalRef "@baseboard_fab2_lib.baseboard_fab2(sch_1):tp_cpld1_pl1b_l_gpllc_fb") )
				( member ( signalRef "@baseboard_fab2_lib.baseboard_fab2(sch_1):jtag_mcp_cpu1_tdi") )
				( member ( signalRef "@baseboard_fab2_lib.baseboard_fab2(sch_1):tp_cpld1_pb11b_pclkc2_0") )
				( member ( signalRef "@baseboard_fab2_lib.baseboard_fab2(sch_1):tp_me_rcvr_boot") )
				( member ( signalRef "@baseboard_fab2_lib.baseboard_fab2(sch_1):tp_m_bmc_ddr3_mioz") )
				( member ( signalRef "@baseboard_fab2_lib.baseboard_fab2(sch_1):tp_nmi_cpu0") )
				( member ( signalRef "@baseboard_fab2_lib.baseboard_fab2(sch_1):tp_password_clear") )
				( member ( signalRef "@baseboard_fab2_lib.baseboard_fab2(sch_1):tp_pch_dispa_bclk") )
				( member ( signalRef "@baseboard_fab2_lib.baseboard_fab2(sch_1):tp_pch_dispa_sdi") )
				( member ( signalRef "@baseboard_fab2_lib.baseboard_fab2(sch_1):tp_pch_dispa_sdo") )
				( member ( signalRef "@baseboard_fab2_lib.baseboard_fab2(sch_1):fm_global_rst_warn_n") )
				( member ( signalRef "@baseboard_fab2_lib.baseboard_fab2(sch_1):tp_pch_gpp_d12") )
				( member ( signalRef "@baseboard_fab2_lib.baseboard_fab2(sch_1):tp_pch_gpp_f12") )
				( member ( signalRef "@baseboard_fab2_lib.baseboard_fab2(sch_1):tp_jumper_block_1_2") )
				( member ( signalRef "@baseboard_fab2_lib.baseboard_fab2(sch_1):fm_gbe1_lvc3_mod_abs") )
				( member ( signalRef "@baseboard_fab2_lib.baseboard_fab2(sch_1):\tp_jumper_block_ 1_7\") )
				( member ( signalRef "@baseboard_fab2_lib.baseboard_fab2(sch_1):tp_pch_gpp_j21") )
				( member ( signalRef "@baseboard_fab2_lib.baseboard_fab2(sch_1):fm_gbe0_lvc3_mod_abs") )
				( member ( signalRef "@baseboard_fab2_lib.baseboard_fab2(sch_1):tp_pch_gpp_j23") )
				( member ( signalRef "@baseboard_fab2_lib.baseboard_fab2(sch_1):led_gbe_p2_1") )
				( member ( signalRef "@baseboard_fab2_lib.baseboard_fab2(sch_1):led_gbe_p3_0") )
				( member ( signalRef "@baseboard_fab2_lib.baseboard_fab2(sch_1):fm_pvcciomcp_cpu0_en") )
				( member ( signalRef "@baseboard_fab2_lib.baseboard_fab2(sch_1):fm_pvcciomcp_cpu1_en") )
				( member ( signalRef "@baseboard_fab2_lib.baseboard_fab2(sch_1):fm_pvccmcp_cpu0_en") )
				( member ( signalRef "@baseboard_fab2_lib.baseboard_fab2(sch_1):fm_p1v8mcp_cpu0_en") )
				( member ( signalRef "@baseboard_fab2_lib.baseboard_fab2(sch_1):pwrgd_pvcciomcp_cpu1") )
				( member ( signalRef "@baseboard_fab2_lib.baseboard_fab2(sch_1):fm_pwrbrk_n") )
				( member ( signalRef "@baseboard_fab2_lib.baseboard_fab2(sch_1):pwrgd_pvccmcp_cpu0") )
				( member ( signalRef "@baseboard_fab2_lib.baseboard_fab2(sch_1):pwrgd_pvccmcp_cpu1") )
				( member ( signalRef "@baseboard_fab2_lib.baseboard_fab2(sch_1):pwrgd_p1v8mcp_cpu0") )
				( member ( signalRef "@baseboard_fab2_lib.baseboard_fab2(sch_1):led_gbe_p2_0") )
				( member ( signalRef "@baseboard_fab2_lib.baseboard_fab2(sch_1):tp_pch_hda_bclk") )
				( member ( signalRef "@baseboard_fab2_lib.baseboard_fab2(sch_1):tp_pch_hda_sdi_0") )
				( member ( signalRef "@baseboard_fab2_lib.baseboard_fab2(sch_1):tp_pch_hda_sdi_1") )
				( member ( signalRef "@baseboard_fab2_lib.baseboard_fab2(sch_1):tp_pch_hda_sync") )
				( member ( signalRef "@baseboard_fab2_lib.baseboard_fab2(sch_1):tp_pch_hsa_rst_n") )
				( member ( signalRef "@baseboard_fab2_lib.baseboard_fab2(sch_1):tp_pch_rsvd0") )
				( member ( signalRef "@baseboard_fab2_lib.baseboard_fab2(sch_1):tp_pch_rsvd1") )
				( member ( signalRef "@baseboard_fab2_lib.baseboard_fab2(sch_1):tp_pch_rsvd2") )
				( member ( signalRef "@baseboard_fab2_lib.baseboard_fab2(sch_1):tp_pch_rsvd3") )
				( member ( signalRef "@baseboard_fab2_lib.baseboard_fab2(sch_1):tp_pch_rsvd4") )
				( member ( signalRef "@baseboard_fab2_lib.baseboard_fab2(sch_1):tp_pch_rsvd5") )
				( member ( signalRef "@baseboard_fab2_lib.baseboard_fab2(sch_1):tp_pch_rsvd6") )
				( member ( signalRef "@baseboard_fab2_lib.baseboard_fab2(sch_1):tp_pch_rsvd7") )
				( member ( signalRef "@baseboard_fab2_lib.baseboard_fab2(sch_1):tp_pch_rsvd8") )
				( member ( signalRef "@baseboard_fab2_lib.baseboard_fab2(sch_1):tp_pch_rsvd9") )
				( member ( signalRef "@baseboard_fab2_lib.baseboard_fab2(sch_1):tp_pch_rsvd12") )
				( member ( signalRef "@baseboard_fab2_lib.baseboard_fab2(sch_1):tp_pch_rsvd13") )
				( member ( signalRef "@baseboard_fab2_lib.baseboard_fab2(sch_1):tp_pch_rsvd14") )
				( member ( signalRef "@baseboard_fab2_lib.baseboard_fab2(sch_1):tp_pch_rsvd15") )
				( member ( signalRef "@baseboard_fab2_lib.baseboard_fab2(sch_1):tp_pch_rsvd16") )
				( member ( signalRef "@baseboard_fab2_lib.baseboard_fab2(sch_1):tp_pch_rsvd17") )
				( member ( signalRef "@baseboard_fab2_lib.baseboard_fab2(sch_1):tp_pch_rsvd18") )
				( member ( signalRef "@baseboard_fab2_lib.baseboard_fab2(sch_1):tp_pch_rsvd19") )
				( member ( signalRef "@baseboard_fab2_lib.baseboard_fab2(sch_1):tp_pch_rsvd20") )
				( member ( signalRef "@baseboard_fab2_lib.baseboard_fab2(sch_1):tp_pch_rsvd21") )
				( member ( signalRef "@baseboard_fab2_lib.baseboard_fab2(sch_1):tp_pch_rsvd22") )
				( member ( signalRef "@baseboard_fab2_lib.baseboard_fab2(sch_1):tp_pch_rsvd23") )
				( member ( signalRef "@baseboard_fab2_lib.baseboard_fab2(sch_1):tp_pch_rsvd24") )
				( member ( signalRef "@baseboard_fab2_lib.baseboard_fab2(sch_1):tp_pch_rsvd25") )
				( member ( signalRef "@baseboard_fab2_lib.baseboard_fab2(sch_1):tp_pch_rsvd26") )
				( member ( signalRef "@baseboard_fab2_lib.baseboard_fab2(sch_1):tp_pch_rsvd27") )
				( member ( signalRef "@baseboard_fab2_lib.baseboard_fab2(sch_1):tp_pch_rsvd28") )
				( member ( signalRef "@baseboard_fab2_lib.baseboard_fab2(sch_1):tp_pch_rsvd29") )
				( member ( signalRef "@baseboard_fab2_lib.baseboard_fab2(sch_1):tp_pch_rsvd30") )
				( member ( signalRef "@baseboard_fab2_lib.baseboard_fab2(sch_1):tp_pch_rsvd31") )
				( member ( signalRef "@baseboard_fab2_lib.baseboard_fab2(sch_1):tp_pch_rsvd32") )
				( member ( signalRef "@baseboard_fab2_lib.baseboard_fab2(sch_1):tp_pch_rsvd33") )
				( member ( signalRef "@baseboard_fab2_lib.baseboard_fab2(sch_1):tp_pch_rsvd34") )
				( member ( signalRef "@baseboard_fab2_lib.baseboard_fab2(sch_1):tp_pch_rsvd35") )
				( member ( signalRef "@baseboard_fab2_lib.baseboard_fab2(sch_1):tp_pch_rsvd36") )
				( member ( signalRef "@baseboard_fab2_lib.baseboard_fab2(sch_1):tp_pch_rsvd37") )
				( member ( signalRef "@baseboard_fab2_lib.baseboard_fab2(sch_1):tp_pch_rsvd38") )
				( member ( signalRef "@baseboard_fab2_lib.baseboard_fab2(sch_1):tp_pch_rsvd41") )
				( member ( signalRef "@baseboard_fab2_lib.baseboard_fab2(sch_1):tp_pch_rsvd42") )
				( member ( signalRef "@baseboard_fab2_lib.baseboard_fab2(sch_1):tp_pch_rsvd45") )
				( member ( signalRef "@baseboard_fab2_lib.baseboard_fab2(sch_1):tp_pch_rsvd46") )
				( member ( signalRef "@baseboard_fab2_lib.baseboard_fab2(sch_1):tp_pch_rsvd47") )
				( member ( signalRef "@baseboard_fab2_lib.baseboard_fab2(sch_1):tp_pch_rsvd48") )
				( member ( signalRef "@baseboard_fab2_lib.baseboard_fab2(sch_1):tp_pch_rsvd49") )
				( member ( signalRef "@baseboard_fab2_lib.baseboard_fab2(sch_1):tp_pch_rsvd50") )
				( member ( signalRef "@baseboard_fab2_lib.baseboard_fab2(sch_1):tp_pch_rsvd51") )
				( member ( signalRef "@baseboard_fab2_lib.baseboard_fab2(sch_1):tp_pch_rsvd52") )
				( member ( signalRef "@baseboard_fab2_lib.baseboard_fab2(sch_1):tp_pch_rsvd53") )
				( member ( signalRef "@baseboard_fab2_lib.baseboard_fab2(sch_1):tp_pch_rsvd54") )
				( member ( signalRef "@baseboard_fab2_lib.baseboard_fab2(sch_1):tp_pch_rsvd55") )
				( member ( signalRef "@baseboard_fab2_lib.baseboard_fab2(sch_1):tp_pch_rsvd58") )
				( member ( signalRef "@baseboard_fab2_lib.baseboard_fab2(sch_1):tp_pch_rsvd59") )
				( member ( signalRef "@baseboard_fab2_lib.baseboard_fab2(sch_1):tp_pch_rsvd64") )
				( member ( signalRef "@baseboard_fab2_lib.baseboard_fab2(sch_1):tp_pch_rsvd65") )
				( member ( signalRef "@baseboard_fab2_lib.baseboard_fab2(sch_1):fm_cpu_bmc_init") )
				( member ( signalRef "@baseboard_fab2_lib.baseboard_fab2(sch_1):fm_cpu_err0_pch_n") )
				( member ( signalRef "@baseboard_fab2_lib.baseboard_fab2(sch_1):fm_cpu_err1_pch_n") )
				( member ( signalRef "@baseboard_fab2_lib.baseboard_fab2(sch_1):tp_pi7c9x1172_enir_n") )
				( member ( signalRef "@baseboard_fab2_lib.baseboard_fab2(sch_1):tp_pi7c9x1172_en485_n") )
				( member ( signalRef "@baseboard_fab2_lib.baseboard_fab2(sch_1):tp_cpu1_upi2_rsvd_ch13") )
				( member ( signalRef "@baseboard_fab2_lib.baseboard_fab2(sch_1):tp_cpu1_upi2_rsvd_cj14") )
				( member ( signalRef "@baseboard_fab2_lib.baseboard_fab2(sch_1):tp_cpu1_upi2_rsvd_ck13") )
				( member ( signalRef "@baseboard_fab2_lib.baseboard_fab2(sch_1):tp_cpu1_upi2_rsvd_cm13") )
				( member ( signalRef "@baseboard_fab2_lib.baseboard_fab2(sch_1):tp_cpu1_upi2_rsvd_cr14") )
				( member ( signalRef "@baseboard_fab2_lib.baseboard_fab2(sch_1):tp_cpu1_upi2_rsvd_cu14") )
				( member ( signalRef "@baseboard_fab2_lib.baseboard_fab2(sch_1):tp_cpu1_upi2_rsvd_cv13") )
				( member ( signalRef "@baseboard_fab2_lib.baseboard_fab2(sch_1):tp_cpu1_upi2_rsvd_cw14") )
				( member ( signalRef "@baseboard_fab2_lib.baseboard_fab2(sch_1):tp_cpu1_upi2_rsvd_cw16") )
				( member ( signalRef "@baseboard_fab2_lib.baseboard_fab2(sch_1):tp_cpu1_upi2_rsvd_da16") )
				( member ( signalRef "@baseboard_fab2_lib.baseboard_fab2(sch_1):tp_cpu1_upi2_rsvd_db15") )
				( member ( signalRef "@baseboard_fab2_lib.baseboard_fab2(sch_1):tp_cpu1_upi2_rsvd_dc16") )
				( member ( signalRef "@baseboard_fab2_lib.baseboard_fab2(sch_1):tp_cpu1_upi2_rsvd_dd15") )
				( member ( signalRef "@baseboard_fab2_lib.baseboard_fab2(sch_1):tp_cpu1_upi2_rsvd_dd17") )
				( member ( signalRef "@baseboard_fab2_lib.baseboard_fab2(sch_1):tp_cpu1_upi2_rsvd_de16") )
				( member ( signalRef "@baseboard_fab2_lib.baseboard_fab2(sch_1):tp_cpu1_upi2_rsvd_df15") )
				( member ( signalRef "@baseboard_fab2_lib.baseboard_fab2(sch_1):tp_cpu1_upi2_rsvd_df17") )
				( member ( signalRef "@baseboard_fab2_lib.baseboard_fab2(sch_1):tp_cpu1_upi2_rsvd_dg18") )
				( member ( signalRef "@baseboard_fab2_lib.baseboard_fab2(sch_1):tp_cpu1_upi2_rsvd_dg20") )
				( member ( signalRef "@baseboard_fab2_lib.baseboard_fab2(sch_1):tp_cpu1_upi2_rsvd_dh17") )
				( member ( signalRef "@baseboard_fab2_lib.baseboard_fab2(sch_1):tp_cpu1_upi2_rsvd_dh19") )
				( member ( signalRef "@baseboard_fab2_lib.baseboard_fab2(sch_1):tp_cpu1_upi2_rsvd_dj18") )
				( member ( signalRef "@baseboard_fab2_lib.baseboard_fab2(sch_1):tp_cpu1_upi2_rsvd_dj20") )
				( member ( signalRef "@baseboard_fab2_lib.baseboard_fab2(sch_1):tp_cpu1_upi2_rsvd_dk17") )
				( member ( signalRef "@baseboard_fab2_lib.baseboard_fab2(sch_1):tp_cpu1_upi2_rsvd_dk19") )
				( member ( signalRef "@baseboard_fab2_lib.baseboard_fab2(sch_1):tp_cpu1_upi2_rsvd_dl20") )
				( member ( signalRef "@baseboard_fab2_lib.baseboard_fab2(sch_1):tp_cpu1_upi2_rsvd_dm21") )
				( member ( signalRef "@baseboard_fab2_lib.baseboard_fab2(sch_1):tp_cpu1_upi2_rsvd_dn20") )
				( member ( signalRef "@baseboard_fab2_lib.baseboard_fab2(sch_1):tp_cpu1_upi2_rsvd_dp21") )
				( member ( signalRef "@baseboard_fab2_lib.baseboard_fab2(sch_1):tp_cpu1_upi2_rsvd_dt21") )
				( member ( signalRef "@baseboard_fab2_lib.baseboard_fab2(sch_1):tp_dacb") )
				( member ( signalRef "@baseboard_fab2_lib.baseboard_fab2(sch_1):tp_dacg") )
				( member ( signalRef "@baseboard_fab2_lib.baseboard_fab2(sch_1):tp_dacr") )
				( member ( signalRef "@baseboard_fab2_lib.baseboard_fab2(sch_1):tp_ddcclk_gpioj6") )
				( member ( signalRef "@baseboard_fab2_lib.baseboard_fab2(sch_1):tp_ddcdat_gpioj7") )
				( member ( signalRef "@baseboard_fab2_lib.baseboard_fab2(sch_1):tp_fan_0") )
				( member ( signalRef "@baseboard_fab2_lib.baseboard_fab2(sch_1):tp_fan_1") )
				( member ( signalRef "@baseboard_fab2_lib.baseboard_fab2(sch_1):fm_battery_sense_en_n") )
				( member ( signalRef "@baseboard_fab2_lib.baseboard_fab2(sch_1):pu_fab2_marker_cpld") )
				( member ( signalRef "@baseboard_fab2_lib.baseboard_fab2(sch_1):tp_fet_q56_3") )
				( member ( signalRef "@baseboard_fab2_lib.baseboard_fab2(sch_1):tp_fet_q56_4") )
				( member ( signalRef "@baseboard_fab2_lib.baseboard_fab2(sch_1):tp_cpld1_pr10c") )
				( member ( signalRef "@baseboard_fab2_lib.baseboard_fab2(sch_1):tp_cpld1_pl2b_l_gpllc_in") )
				( member ( signalRef "@baseboard_fab2_lib.baseboard_fab2(sch_1):tp_cpld1_pb8a_mclk_cclk") )
				( member ( signalRef "@baseboard_fab2_lib.baseboard_fab2(sch_1):tp_cpld1_pb5a_csspin") )
				( member ( signalRef "@baseboard_fab2_lib.baseboard_fab2(sch_1):tp_cpld1_pb8b_so_spiso") )
				( member ( signalRef "@baseboard_fab2_lib.baseboard_fab2(sch_1):tp_fm_cpu1_cd_hfi0_modprst_n") )
				( member ( signalRef "@baseboard_fab2_lib.baseboard_fab2(sch_1):tp_cpld1_pt20b") )
				( member ( signalRef "@baseboard_fab2_lib.baseboard_fab2(sch_1):tp_cpld1_pt20a") )
				( member ( signalRef "@baseboard_fab2_lib.baseboard_fab2(sch_1):jtag_mcp_cpu1_tdi_r") )
				( member ( signalRef "@baseboard_fab2_lib.baseboard_fab2(sch_1):tp_cpld1_pt22c") )
				( member ( signalRef "@baseboard_fab2_lib.baseboard_fab2(sch_1):tp_fm_qat_cbl_prsnt0_r_n") )
				( member ( signalRef "@baseboard_fab2_lib.baseboard_fab2(sch_1):tp_fm_qat_cbl_prsnt1_n_r") )
				( member ( signalRef "@baseboard_fab2_lib.baseboard_fab2(sch_1):tp_fm_qat_cbl_prsnt2_n") )
				( member ( signalRef "@baseboard_fab2_lib.baseboard_fab2(sch_1):vr_pvccin_cpu1_ph4_ocset") )
				( member ( signalRef "@baseboard_fab2_lib.baseboard_fab2(sch_1):tp_cpld1_pl1a_l_gpllt_fb") )
				( member ( signalRef "@baseboard_fab2_lib.baseboard_fab2(sch_1):tp_fm_wake_n") )
				( member ( signalRef "@baseboard_fab2_lib.baseboard_fab2(sch_1):tp_cpld1_pl7d_pclkt4_0") )
				( member ( signalRef "@baseboard_fab2_lib.baseboard_fab2(sch_1):tp_gpioe7_rxd3") )
				( member ( signalRef "@baseboard_fab2_lib.baseboard_fab2(sch_1):jtag_mcp_mux_tdi") )
				( member ( signalRef "@baseboard_fab2_lib.baseboard_fab2(sch_1):tp_jumper_block_1_8") )
				( member ( signalRef "@baseboard_fab2_lib.baseboard_fab2(sch_1):tp_jumper_block_2_8") )
				( member ( signalRef "@baseboard_fab2_lib.baseboard_fab2(sch_1):tp_gpiom5_nrts2_vpib7") )
				( member ( signalRef "@baseboard_fab2_lib.baseboard_fab2(sch_1):tp_gpio0_dsrb_n") )
				( member ( signalRef "@baseboard_fab2_lib.baseboard_fab2(sch_1):tp_gpio1_dtrb_n") )
				( member ( signalRef "@baseboard_fab2_lib.baseboard_fab2(sch_1):tp_gpio2_cdb_n") )
				( member ( signalRef "@baseboard_fab2_lib.baseboard_fab2(sch_1):tp_gpio3_rib_n") )
				( member ( signalRef "@baseboard_fab2_lib.baseboard_fab2(sch_1):tp_gpio4_dsra_n") )
				( member ( signalRef "@baseboard_fab2_lib.baseboard_fab2(sch_1):tp_gpio5_dtra_n") )
				( member ( signalRef "@baseboard_fab2_lib.baseboard_fab2(sch_1):tp_gpio6_cda_n") )
				( member ( signalRef "@baseboard_fab2_lib.baseboard_fab2(sch_1):tp_gpio7_ria_n") )
				( member ( signalRef "@baseboard_fab2_lib.baseboard_fab2(sch_1):tp_hfi_io_conn0_rsvd_17") )
				( member ( signalRef "@baseboard_fab2_lib.baseboard_fab2(sch_1):tp_hsc_alert2_n") )
				( member ( signalRef "@baseboard_fab2_lib.baseboard_fab2(sch_1):tp_hsc_mclk") )
				( member ( signalRef "@baseboard_fab2_lib.baseboard_fab2(sch_1):tp_hsc_mdat") )
				( member ( signalRef "@baseboard_fab2_lib.baseboard_fab2(sch_1):tp_hsc_spissn") )
				( member ( signalRef "@baseboard_fab2_lib.baseboard_fab2(sch_1):tp_jumper_block_2_10") )
				( member ( signalRef "@baseboard_fab2_lib.baseboard_fab2(sch_1):tp_ie_debug_mode") )
				( member ( signalRef "@baseboard_fab2_lib.baseboard_fab2(sch_1):tp_ioa5") )
				( member ( signalRef "@baseboard_fab2_lib.baseboard_fab2(sch_1):tp_ioe4") )
				( member ( signalRef "@baseboard_fab2_lib.baseboard_fab2(sch_1):tp_iof4") )
				( member ( signalRef "@baseboard_fab2_lib.baseboard_fab2(sch_1):tp_iog3") )
				( member ( signalRef "@baseboard_fab2_lib.baseboard_fab2(sch_1):tp_ioh3") )
				( member ( signalRef "@baseboard_fab2_lib.baseboard_fab2(sch_1):tp_ioh4") )
				( member ( signalRef "@baseboard_fab2_lib.baseboard_fab2(sch_1):tp_ioi4") )
				( member ( signalRef "@baseboard_fab2_lib.baseboard_fab2(sch_1):tp_irq_cpu1_cd_hfi0_n") )
				( member ( signalRef "@baseboard_fab2_lib.baseboard_fab2(sch_1):tp_cpld1_pt16b") )
				( member ( signalRef "@baseboard_fab2_lib.baseboard_fab2(sch_1):tp_jtag_bmc_rtck") )
				( member ( signalRef "@baseboard_fab2_lib.baseboard_fab2(sch_1):tp_k4b1g16_bmc_nc0") )
				( member ( signalRef "@baseboard_fab2_lib.baseboard_fab2(sch_1):tp_k4b1g16_bmc_nc1") )
				( member ( signalRef "@baseboard_fab2_lib.baseboard_fab2(sch_1):tp_k4b1g16_bmc_nc2") )
				( member ( signalRef "@baseboard_fab2_lib.baseboard_fab2(sch_1):tp_k4b1g16_bmc_nc3") )
				( member ( signalRef "@baseboard_fab2_lib.baseboard_fab2(sch_1):tp_k4b1g16_bmc_nc4") )
				( member ( signalRef "@baseboard_fab2_lib.baseboard_fab2(sch_1):nc_p1v05_pch_stby_ph1_p31") )
				( member ( signalRef "@baseboard_fab2_lib.baseboard_fab2(sch_1):fm_pwrbrk_slot_n") )
				( member ( signalRef "@baseboard_fab2_lib.baseboard_fab2(sch_1):fm_gbe2_lvc3_mod_abs") )
				( member ( signalRef "@baseboard_fab2_lib.baseboard_fab2(sch_1):fm_gbe3_lvc3_mod_abs") )
				( member ( signalRef "@baseboard_fab2_lib.baseboard_fab2(sch_1):pwrgd_p5v_n") )
				( member ( signalRef "@baseboard_fab2_lib.baseboard_fab2(sch_1):tp_cpu1_rsvd_199") )
				( member ( signalRef "@baseboard_fab2_lib.baseboard_fab2(sch_1):tp_cpu1_rsvd_204") )
				( member ( signalRef "@baseboard_fab2_lib.baseboard_fab2(sch_1):tp_cpu1_rsvd_205") )
				( member ( signalRef "@baseboard_fab2_lib.baseboard_fab2(sch_1):tp_cpu1_rsvd_208") )
				( member ( signalRef "@baseboard_fab2_lib.baseboard_fab2(sch_1):tp_cpu1_rsvd_210") )
				( member ( signalRef "@baseboard_fab2_lib.baseboard_fab2(sch_1):tp_cpu1_rsvd_211") )
				( member ( signalRef "@baseboard_fab2_lib.baseboard_fab2(sch_1):tp_cpu1_rsvd_212") )
				( member ( signalRef "@baseboard_fab2_lib.baseboard_fab2(sch_1):tp_cpu1_rsvd_214") )
				( member ( signalRef "@baseboard_fab2_lib.baseboard_fab2(sch_1):tp_cpu1_rsvd_216") )
				( member ( signalRef "@baseboard_fab2_lib.baseboard_fab2(sch_1):tp_cpu1_rsvd_217") )
				( member ( signalRef "@baseboard_fab2_lib.baseboard_fab2(sch_1):tp_cpu1_rsvd_218") )
				( member ( signalRef "@baseboard_fab2_lib.baseboard_fab2(sch_1):tp_cpu1_rsvd_219") )
				( member ( signalRef "@baseboard_fab2_lib.baseboard_fab2(sch_1):tp_cpu1_rsvd_222") )
				( member ( signalRef "@baseboard_fab2_lib.baseboard_fab2(sch_1):tp_cpu1_rsvd_223") )
				( member ( signalRef "@baseboard_fab2_lib.baseboard_fab2(sch_1):tp_cpu1_rsvd_224") )
				( member ( signalRef "@baseboard_fab2_lib.baseboard_fab2(sch_1):tp_cpu1_rsvd_225") )
				( member ( signalRef "@baseboard_fab2_lib.baseboard_fab2(sch_1):tp_cpu1_rsvd_226") )
				( member ( signalRef "@baseboard_fab2_lib.baseboard_fab2(sch_1):tp_cpu1_rsvd_227") )
				( member ( signalRef "@baseboard_fab2_lib.baseboard_fab2(sch_1):tp_cpu1_rsvd_228") )
				( member ( signalRef "@baseboard_fab2_lib.baseboard_fab2(sch_1):tp_cpu1_rsvd_229") )
				( member ( signalRef "@baseboard_fab2_lib.baseboard_fab2(sch_1):tp_cpu1_rsvd_230") )
				( member ( signalRef "@baseboard_fab2_lib.baseboard_fab2(sch_1):tp_cpu1_rsvd_231") )
				( member ( signalRef "@baseboard_fab2_lib.baseboard_fab2(sch_1):tp_cpu1_rsvd_232") )
				( member ( signalRef "@baseboard_fab2_lib.baseboard_fab2(sch_1):tp_cpu1_rsvd_233") )
				( member ( signalRef "@baseboard_fab2_lib.baseboard_fab2(sch_1):tp_cpu1_rsvd_234") )
				( member ( signalRef "@baseboard_fab2_lib.baseboard_fab2(sch_1):tp_cpu1_rsvd_235") )
				( member ( signalRef "@baseboard_fab2_lib.baseboard_fab2(sch_1):tp_cpu1_rsvd_236") )
				( member ( signalRef "@baseboard_fab2_lib.baseboard_fab2(sch_1):tp_cpu1_rsvd_237") )
				( member ( signalRef "@baseboard_fab2_lib.baseboard_fab2(sch_1):tp_cpu1_rsvd_238") )
				( member ( signalRef "@baseboard_fab2_lib.baseboard_fab2(sch_1):tp_cpu1_rsvd_239") )
				( member ( signalRef "@baseboard_fab2_lib.baseboard_fab2(sch_1):tp_cpu1_rsvd_240") )
				( member ( signalRef "@baseboard_fab2_lib.baseboard_fab2(sch_1):tp_cpu1_rsvd_241") )
				( member ( signalRef "@baseboard_fab2_lib.baseboard_fab2(sch_1):tp_cpu1_rsvd_242") )
				( member ( signalRef "@baseboard_fab2_lib.baseboard_fab2(sch_1):tp_cpu1_rsvd_243") )
				( member ( signalRef "@baseboard_fab2_lib.baseboard_fab2(sch_1):tp_cpu1_rsvd_244") )
				( member ( signalRef "@baseboard_fab2_lib.baseboard_fab2(sch_1):tp_cpu1_rsvd_245") )
				( member ( signalRef "@baseboard_fab2_lib.baseboard_fab2(sch_1):tp_cpu1_rsvd_246") )
				( member ( signalRef "@baseboard_fab2_lib.baseboard_fab2(sch_1):tp_cpu1_rsvd_247") )
				( member ( signalRef "@baseboard_fab2_lib.baseboard_fab2(sch_1):tp_cpu1_rsvd_248") )
				( member ( signalRef "@baseboard_fab2_lib.baseboard_fab2(sch_1):tp_cpu1_rsvd_249") )
				( member ( signalRef "@baseboard_fab2_lib.baseboard_fab2(sch_1):tp_cpu1_rsvd_250") )
				( member ( signalRef "@baseboard_fab2_lib.baseboard_fab2(sch_1):tp_cpu1_rsvd_251") )
				( member ( signalRef "@baseboard_fab2_lib.baseboard_fab2(sch_1):tp_cpu1_rsvd_252") )
				( member ( signalRef "@baseboard_fab2_lib.baseboard_fab2(sch_1):tp_cpu1_rsvd_253") )
				( member ( signalRef "@baseboard_fab2_lib.baseboard_fab2(sch_1):tp_cpu1_rsvd_254") )
				( member ( signalRef "@baseboard_fab2_lib.baseboard_fab2(sch_1):tp_cpu1_rsvd_255") )
				( member ( signalRef "@baseboard_fab2_lib.baseboard_fab2(sch_1):tp_cpu1_rsvd_256") )
				( member ( signalRef "@baseboard_fab2_lib.baseboard_fab2(sch_1):tp_ie_fm_uv_threshold_set") )
				( member ( signalRef "@baseboard_fab2_lib.baseboard_fab2(sch_1):tp_cpu1_rsvd_258") )
				( member ( signalRef "@baseboard_fab2_lib.baseboard_fab2(sch_1):tp_cpu1_rsvd_259") )
				( member ( signalRef "@baseboard_fab2_lib.baseboard_fab2(sch_1):tp_cpu1_rsvd_260") )
				( member ( signalRef "@baseboard_fab2_lib.baseboard_fab2(sch_1):tp_cpu1_rsvd_261") )
				( member ( signalRef "@baseboard_fab2_lib.baseboard_fab2(sch_1):tp_cpu1_rsvd_262") )
				( member ( signalRef "@baseboard_fab2_lib.baseboard_fab2(sch_1):tp_cpu1_rsvd_263") )
				( member ( signalRef "@baseboard_fab2_lib.baseboard_fab2(sch_1):tp_cpu1_rsvd_264") )
				( member ( signalRef "@baseboard_fab2_lib.baseboard_fab2(sch_1):tp_cpu1_rsvd_265") )
				( member ( signalRef "@baseboard_fab2_lib.baseboard_fab2(sch_1):tp_cpu1_rsvd_266") )
				( member ( signalRef "@baseboard_fab2_lib.baseboard_fab2(sch_1):tp_cpu1_rsvd_267") )
				( member ( signalRef "@baseboard_fab2_lib.baseboard_fab2(sch_1):tp_cpu1_rsvd_268") )
				( member ( signalRef "@baseboard_fab2_lib.baseboard_fab2(sch_1):tp_cpu1_rsvd_269") )
				( member ( signalRef "@baseboard_fab2_lib.baseboard_fab2(sch_1):tp_cpu1_rsvd_270") )
				( member ( signalRef "@baseboard_fab2_lib.baseboard_fab2(sch_1):tp_cpu1_rsvd_271") )
				( member ( signalRef "@baseboard_fab2_lib.baseboard_fab2(sch_1):tp_cpu1_rsvd_272") )
				( member ( signalRef "@baseboard_fab2_lib.baseboard_fab2(sch_1):tp_cpu1_rsvd_273") )
				( member ( signalRef "@baseboard_fab2_lib.baseboard_fab2(sch_1):tp_cpu1_rsvd_274") )
				( member ( signalRef "@baseboard_fab2_lib.baseboard_fab2(sch_1):tp_cpu1_rsvd_276") )
				( member ( signalRef "@baseboard_fab2_lib.baseboard_fab2(sch_1):tp_cpu1_rsvd_277") )
				( member ( signalRef "@baseboard_fab2_lib.baseboard_fab2(sch_1):tp_cpu1_rsvd_278") )
				( member ( signalRef "@baseboard_fab2_lib.baseboard_fab2(sch_1):tp_cpu1_rsvd_279") )
				( member ( signalRef "@baseboard_fab2_lib.baseboard_fab2(sch_1):tp_cpu1_rsvd_280") )
				( member ( signalRef "@baseboard_fab2_lib.baseboard_fab2(sch_1):tp_cpu1_rsvd_281") )
				( member ( signalRef "@baseboard_fab2_lib.baseboard_fab2(sch_1):tp_cpu1_rsvd_284") )
				( member ( signalRef "@baseboard_fab2_lib.baseboard_fab2(sch_1):tp_cpu1_rsvd_285") )
				( member ( signalRef "@baseboard_fab2_lib.baseboard_fab2(sch_1):tp_cpu1_rsvd_286") )
				( member ( signalRef "@baseboard_fab2_lib.baseboard_fab2(sch_1):tp_cpu1_rsvd_288") )
				( member ( signalRef "@baseboard_fab2_lib.baseboard_fab2(sch_1):tp_cpu1_rsvd_289") )
				( member ( signalRef "@baseboard_fab2_lib.baseboard_fab2(sch_1):tp_cpu1_rsvd_290") )
				( member ( signalRef "@baseboard_fab2_lib.baseboard_fab2(sch_1):tp_cpu1_rsvd_291") )
				( member ( signalRef "@baseboard_fab2_lib.baseboard_fab2(sch_1):tp_cpu1_rsvd_292") )
				( member ( signalRef "@baseboard_fab2_lib.baseboard_fab2(sch_1):tp_cpu1_rsvd_293") )
				( member ( signalRef "@baseboard_fab2_lib.baseboard_fab2(sch_1):tp_cpu1_rsvd_300") )
				( member ( signalRef "@baseboard_fab2_lib.baseboard_fab2(sch_1):fm_cpu0_prochot_pch_n") )
				( member ( signalRef "@baseboard_fab2_lib.baseboard_fab2(sch_1):fm_cpu1_prochot_pch_n") )
				( member ( signalRef "@baseboard_fab2_lib.baseboard_fab2(sch_1):fm_cpu1_sm_wp") )
				( member ( signalRef "@baseboard_fab2_lib.baseboard_fab2(sch_1):tp_cpu1_socket_id_2") )
				( member ( signalRef "@baseboard_fab2_lib.baseboard_fab2(sch_1):tp_cpu1_test_6") )
				( member ( signalRef "@baseboard_fab2_lib.baseboard_fab2(sch_1):tp_cpu1_test_7") )
				( member ( signalRef "@baseboard_fab2_lib.baseboard_fab2(sch_1):tp_cpu1_test_8") )
				( member ( signalRef "@baseboard_fab2_lib.baseboard_fab2(sch_1):tp_cpu1_test_9") )
				( member ( signalRef "@baseboard_fab2_lib.baseboard_fab2(sch_1):tp_cpu1_test_10") )
				( member ( signalRef "@baseboard_fab2_lib.baseboard_fab2(sch_1):tp_cpu1_upi2_rsvd_ca12") )
				( member ( signalRef "@baseboard_fab2_lib.baseboard_fab2(sch_1):tp_cpu1_upi2_rsvd_cb11") )
				( member ( signalRef "@baseboard_fab2_lib.baseboard_fab2(sch_1):tp_cpu1_upi2_rsvd_cc10") )
				( member ( signalRef "@baseboard_fab2_lib.baseboard_fab2(sch_1):tp_cpu1_upi2_rsvd_cc12") )
				( member ( signalRef "@baseboard_fab2_lib.baseboard_fab2(sch_1):tp_cpu1_upi2_rsvd_cd11") )
				( member ( signalRef "@baseboard_fab2_lib.baseboard_fab2(sch_1):tp_cpu1_upi2_rsvd_ce12") )
				( member ( signalRef "@baseboard_fab2_lib.baseboard_fab2(sch_1):tp_cpu1_upi2_rsvd_cf11") )
				( member ( signalRef "@baseboard_fab2_lib.baseboard_fab2(sch_1):tp_cpu1_upi2_rsvd_cf13") )
				( member ( signalRef "@baseboard_fab2_lib.baseboard_fab2(sch_1):tp_cpu1_upi2_rsvd_cg12") )
				( member ( signalRef "@baseboard_fab2_lib.baseboard_fab2(sch_1):tp_cpu1_upi2_rsvd_ch11") )
				( member ( signalRef "@baseboard_fab2_lib.baseboard_fab2(sch_1):tp_cpu1_rsvd_32") )
				( member ( signalRef "@baseboard_fab2_lib.baseboard_fab2(sch_1):tp_cpu1_rsvd_33") )
				( member ( signalRef "@baseboard_fab2_lib.baseboard_fab2(sch_1):tp_cpu1_rsvd_34") )
				( member ( signalRef "@baseboard_fab2_lib.baseboard_fab2(sch_1):tp_cpu1_rsvd_35") )
				( member ( signalRef "@baseboard_fab2_lib.baseboard_fab2(sch_1):tp_cpu1_rsvd_36") )
				( member ( signalRef "@baseboard_fab2_lib.baseboard_fab2(sch_1):tp_cpu1_rsvd_37") )
				( member ( signalRef "@baseboard_fab2_lib.baseboard_fab2(sch_1):tp_cpu1_rsvd_38") )
				( member ( signalRef "@baseboard_fab2_lib.baseboard_fab2(sch_1):tp_cpu1_rsvd_39") )
				( member ( signalRef "@baseboard_fab2_lib.baseboard_fab2(sch_1):tp_cpu1_rsvd_40") )
				( member ( signalRef "@baseboard_fab2_lib.baseboard_fab2(sch_1):tp_cpu1_rsvd_41") )
				( member ( signalRef "@baseboard_fab2_lib.baseboard_fab2(sch_1):tp_cpu1_rsvd_42") )
				( member ( signalRef "@baseboard_fab2_lib.baseboard_fab2(sch_1):tp_cpu1_rsvd_43") )
				( member ( signalRef "@baseboard_fab2_lib.baseboard_fab2(sch_1):tp_cpu1_rsvd_44") )
				( member ( signalRef "@baseboard_fab2_lib.baseboard_fab2(sch_1):tp_cpu1_rsvd_45") )
				( member ( signalRef "@baseboard_fab2_lib.baseboard_fab2(sch_1):tp_cpu1_rsvd_46") )
				( member ( signalRef "@baseboard_fab2_lib.baseboard_fab2(sch_1):tp_cpu1_rsvd_47") )
				( member ( signalRef "@baseboard_fab2_lib.baseboard_fab2(sch_1):tp_cpu1_rsvd_48") )
				( member ( signalRef "@baseboard_fab2_lib.baseboard_fab2(sch_1):tp_cpu1_rsvd_49") )
				( member ( signalRef "@baseboard_fab2_lib.baseboard_fab2(sch_1):tp_cpu1_rsvd_50") )
				( member ( signalRef "@baseboard_fab2_lib.baseboard_fab2(sch_1):tp_cpu1_rsvd_51") )
				( member ( signalRef "@baseboard_fab2_lib.baseboard_fab2(sch_1):tp_cpu1_rsvd_53") )
				( member ( signalRef "@baseboard_fab2_lib.baseboard_fab2(sch_1):tp_cpu1_rsvd_54") )
				( member ( signalRef "@baseboard_fab2_lib.baseboard_fab2(sch_1):tp_cpu1_rsvd_55") )
				( member ( signalRef "@baseboard_fab2_lib.baseboard_fab2(sch_1):tp_cpu1_rsvd_56") )
				( member ( signalRef "@baseboard_fab2_lib.baseboard_fab2(sch_1):tp_cpu1_rsvd_57") )
				( member ( signalRef "@baseboard_fab2_lib.baseboard_fab2(sch_1):tp_cpu1_rsvd_59") )
				( member ( signalRef "@baseboard_fab2_lib.baseboard_fab2(sch_1):tp_cpu1_rsvd_60") )
				( member ( signalRef "@baseboard_fab2_lib.baseboard_fab2(sch_1):tp_cpu1_rsvd_61") )
				( member ( signalRef "@baseboard_fab2_lib.baseboard_fab2(sch_1):tp_cpu1_rsvd_64") )
				( member ( signalRef "@baseboard_fab2_lib.baseboard_fab2(sch_1):tp_cpu1_rsvd_66") )
				( member ( signalRef "@baseboard_fab2_lib.baseboard_fab2(sch_1):tp_cpu1_rsvd_67") )
				( member ( signalRef "@baseboard_fab2_lib.baseboard_fab2(sch_1):tp_cpu1_rsvd_69") )
				( member ( signalRef "@baseboard_fab2_lib.baseboard_fab2(sch_1):tp_cpu1_rsvd_70") )
				( member ( signalRef "@baseboard_fab2_lib.baseboard_fab2(sch_1):tp_cpu1_rsvd_72") )
				( member ( signalRef "@baseboard_fab2_lib.baseboard_fab2(sch_1):tp_cpu1_rsvd_73") )
				( member ( signalRef "@baseboard_fab2_lib.baseboard_fab2(sch_1):tp_cpu1_rsvd_82") )
				( member ( signalRef "@baseboard_fab2_lib.baseboard_fab2(sch_1):tp_cpu1_rsvd_85") )
				( member ( signalRef "@baseboard_fab2_lib.baseboard_fab2(sch_1):tp_cpu1_rsvd_90") )
				( member ( signalRef "@baseboard_fab2_lib.baseboard_fab2(sch_1):tp_cpu1_rsvd_91") )
				( member ( signalRef "@baseboard_fab2_lib.baseboard_fab2(sch_1):tp_cpu1_rsvd_94") )
				( member ( signalRef "@baseboard_fab2_lib.baseboard_fab2(sch_1):tp_cpu1_rsvd_95") )
				( member ( signalRef "@baseboard_fab2_lib.baseboard_fab2(sch_1):tp_cpu1_rsvd_97") )
				( member ( signalRef "@baseboard_fab2_lib.baseboard_fab2(sch_1):tp_cpu1_rsvd_99") )
				( member ( signalRef "@baseboard_fab2_lib.baseboard_fab2(sch_1):tp_cpu1_rsvd_100") )
				( member ( signalRef "@baseboard_fab2_lib.baseboard_fab2(sch_1):tp_cpu1_rsvd_101") )
				( member ( signalRef "@baseboard_fab2_lib.baseboard_fab2(sch_1):tp_cpu1_rsvd_105") )
				( member ( signalRef "@baseboard_fab2_lib.baseboard_fab2(sch_1):tp_cpu1_rsvd_106") )
				( member ( signalRef "@baseboard_fab2_lib.baseboard_fab2(sch_1):tp_cpu1_rsvd_108") )
				( member ( signalRef "@baseboard_fab2_lib.baseboard_fab2(sch_1):tp_cpu1_rsvd_111") )
				( member ( signalRef "@baseboard_fab2_lib.baseboard_fab2(sch_1):tp_cpu1_rsvd_113") )
				( member ( signalRef "@baseboard_fab2_lib.baseboard_fab2(sch_1):tp_cpu1_rsvd_114") )
				( member ( signalRef "@baseboard_fab2_lib.baseboard_fab2(sch_1):tp_cpu1_rsvd_117") )
				( member ( signalRef "@baseboard_fab2_lib.baseboard_fab2(sch_1):tp_cpu1_rsvd_119") )
				( member ( signalRef "@baseboard_fab2_lib.baseboard_fab2(sch_1):tp_cpu1_rsvd_121") )
				( member ( signalRef "@baseboard_fab2_lib.baseboard_fab2(sch_1):tp_cpu1_rsvd_123") )
				( member ( signalRef "@baseboard_fab2_lib.baseboard_fab2(sch_1):tp_cpu1_rsvd_124") )
				( member ( signalRef "@baseboard_fab2_lib.baseboard_fab2(sch_1):tp_cpu1_rsvd_144") )
				( member ( signalRef "@baseboard_fab2_lib.baseboard_fab2(sch_1):tp_cpu1_rsvd_145") )
				( member ( signalRef "@baseboard_fab2_lib.baseboard_fab2(sch_1):tp_cpu1_rsvd_146") )
				( member ( signalRef "@baseboard_fab2_lib.baseboard_fab2(sch_1):tp_cpu1_rsvd_147") )
				( member ( signalRef "@baseboard_fab2_lib.baseboard_fab2(sch_1):tp_cpu1_rsvd_148") )
				( member ( signalRef "@baseboard_fab2_lib.baseboard_fab2(sch_1):tp_cpu1_rsvd_149") )
				( member ( signalRef "@baseboard_fab2_lib.baseboard_fab2(sch_1):tp_cpu1_rsvd_150") )
				( member ( signalRef "@baseboard_fab2_lib.baseboard_fab2(sch_1):tp_cpu1_rsvd_151") )
				( member ( signalRef "@baseboard_fab2_lib.baseboard_fab2(sch_1):tp_cpu1_rsvd_152") )
				( member ( signalRef "@baseboard_fab2_lib.baseboard_fab2(sch_1):tp_cpu1_rsvd_154") )
				( member ( signalRef "@baseboard_fab2_lib.baseboard_fab2(sch_1):tp_cpu1_rsvd_155") )
				( member ( signalRef "@baseboard_fab2_lib.baseboard_fab2(sch_1):tp_cpu1_rsvd_156") )
				( member ( signalRef "@baseboard_fab2_lib.baseboard_fab2(sch_1):tp_cpu1_rsvd_157") )
				( member ( signalRef "@baseboard_fab2_lib.baseboard_fab2(sch_1):tp_cpu1_rsvd_158") )
				( member ( signalRef "@baseboard_fab2_lib.baseboard_fab2(sch_1):tp_cpu1_rsvd_159") )
				( member ( signalRef "@baseboard_fab2_lib.baseboard_fab2(sch_1):tp_cpu1_rsvd_160") )
				( member ( signalRef "@baseboard_fab2_lib.baseboard_fab2(sch_1):tp_cpu1_rsvd_161") )
				( member ( signalRef "@baseboard_fab2_lib.baseboard_fab2(sch_1):tp_cpu1_rsvd_162") )
				( member ( signalRef "@baseboard_fab2_lib.baseboard_fab2(sch_1):tp_cpu1_rsvd_163") )
				( member ( signalRef "@baseboard_fab2_lib.baseboard_fab2(sch_1):tp_cpu1_rsvd_164") )
				( member ( signalRef "@baseboard_fab2_lib.baseboard_fab2(sch_1):tp_cpu1_rsvd_166") )
				( member ( signalRef "@baseboard_fab2_lib.baseboard_fab2(sch_1):tp_cpu1_rsvd_167") )
				( member ( signalRef "@baseboard_fab2_lib.baseboard_fab2(sch_1):tp_cpu1_rsvd_168") )
				( member ( signalRef "@baseboard_fab2_lib.baseboard_fab2(sch_1):tp_cpu1_rsvd_169") )
				( member ( signalRef "@baseboard_fab2_lib.baseboard_fab2(sch_1):tp_cpu1_rsvd_170") )
				( member ( signalRef "@baseboard_fab2_lib.baseboard_fab2(sch_1):tp_cpu1_rsvd_171") )
				( member ( signalRef "@baseboard_fab2_lib.baseboard_fab2(sch_1):tp_cpu1_rsvd_172") )
				( member ( signalRef "@baseboard_fab2_lib.baseboard_fab2(sch_1):tp_cpu1_rsvd_173") )
				( member ( signalRef "@baseboard_fab2_lib.baseboard_fab2(sch_1):tp_cpu1_rsvd_174") )
				( member ( signalRef "@baseboard_fab2_lib.baseboard_fab2(sch_1):tp_cpu1_rsvd_175") )
				( member ( signalRef "@baseboard_fab2_lib.baseboard_fab2(sch_1):tp_cpu1_rsvd_176") )
				( member ( signalRef "@baseboard_fab2_lib.baseboard_fab2(sch_1):tp_cpu1_rsvd_177") )
				( member ( signalRef "@baseboard_fab2_lib.baseboard_fab2(sch_1):tp_cpu1_rsvd_178") )
				( member ( signalRef "@baseboard_fab2_lib.baseboard_fab2(sch_1):tp_cpu1_rsvd_179") )
				( member ( signalRef "@baseboard_fab2_lib.baseboard_fab2(sch_1):tp_cpu1_rsvd_180") )
				( member ( signalRef "@baseboard_fab2_lib.baseboard_fab2(sch_1):tp_cpu1_rsvd_181") )
				( member ( signalRef "@baseboard_fab2_lib.baseboard_fab2(sch_1):tp_cpu1_rsvd_182") )
				( member ( signalRef "@baseboard_fab2_lib.baseboard_fab2(sch_1):tp_cpu1_rsvd_183") )
				( member ( signalRef "@baseboard_fab2_lib.baseboard_fab2(sch_1):tp_cpu1_rsvd_184") )
				( member ( signalRef "@baseboard_fab2_lib.baseboard_fab2(sch_1):tp_cpu1_rsvd_186") )
				( member ( signalRef "@baseboard_fab2_lib.baseboard_fab2(sch_1):tp_cpu1_rsvd_189") )
				( member ( signalRef "@baseboard_fab2_lib.baseboard_fab2(sch_1):tp_cpu1_rsvd_190") )
				( member ( signalRef "@baseboard_fab2_lib.baseboard_fab2(sch_1):tp_cpu1_rsvd_194") )
				( member ( signalRef "@baseboard_fab2_lib.baseboard_fab2(sch_1):tp_cpu1_rsvd_198") )
				( member ( signalRef "@baseboard_fab2_lib.baseboard_fab2(sch_1):tp_cpu0_test_9") )
				( member ( signalRef "@baseboard_fab2_lib.baseboard_fab2(sch_1):tp_cpu0_test_10") )
				( member ( signalRef "@baseboard_fab2_lib.baseboard_fab2(sch_1):tp_cpu0_upi2_rsvd_ca12") )
				( member ( signalRef "@baseboard_fab2_lib.baseboard_fab2(sch_1):tp_cpu0_upi2_rsvd_cb11") )
				( member ( signalRef "@baseboard_fab2_lib.baseboard_fab2(sch_1):tp_cpu0_upi2_rsvd_cc10") )
				( member ( signalRef "@baseboard_fab2_lib.baseboard_fab2(sch_1):tp_cpu0_upi2_rsvd_cc12") )
				( member ( signalRef "@baseboard_fab2_lib.baseboard_fab2(sch_1):tp_cpu0_upi2_rsvd_cd11") )
				( member ( signalRef "@baseboard_fab2_lib.baseboard_fab2(sch_1):tp_cpu0_upi2_rsvd_ce12") )
				( member ( signalRef "@baseboard_fab2_lib.baseboard_fab2(sch_1):tp_cpu0_upi2_rsvd_cf11") )
				( member ( signalRef "@baseboard_fab2_lib.baseboard_fab2(sch_1):tp_cpu0_upi2_rsvd_cf13") )
				( member ( signalRef "@baseboard_fab2_lib.baseboard_fab2(sch_1):tp_cpu0_upi2_rsvd_cg12") )
				( member ( signalRef "@baseboard_fab2_lib.baseboard_fab2(sch_1):tp_cpu0_upi2_rsvd_ch11") )
				( member ( signalRef "@baseboard_fab2_lib.baseboard_fab2(sch_1):tp_cpu0_upi2_rsvd_ch13") )
				( member ( signalRef "@baseboard_fab2_lib.baseboard_fab2(sch_1):tp_cpu0_upi2_rsvd_cj14") )
				( member ( signalRef "@baseboard_fab2_lib.baseboard_fab2(sch_1):tp_cpu0_upi2_rsvd_ck13") )
				( member ( signalRef "@baseboard_fab2_lib.baseboard_fab2(sch_1):tp_cpu0_upi2_rsvd_cm13") )
				( member ( signalRef "@baseboard_fab2_lib.baseboard_fab2(sch_1):tp_cpu0_upi2_rsvd_cr14") )
				( member ( signalRef "@baseboard_fab2_lib.baseboard_fab2(sch_1):tp_cpu0_upi2_rsvd_cu14") )
				( member ( signalRef "@baseboard_fab2_lib.baseboard_fab2(sch_1):tp_cpu0_upi2_rsvd_cv13") )
				( member ( signalRef "@baseboard_fab2_lib.baseboard_fab2(sch_1):tp_cpu0_upi2_rsvd_cw14") )
				( member ( signalRef "@baseboard_fab2_lib.baseboard_fab2(sch_1):tp_cpu0_upi2_rsvd_cw16") )
				( member ( signalRef "@baseboard_fab2_lib.baseboard_fab2(sch_1):tp_cpu0_upi2_rsvd_da16") )
				( member ( signalRef "@baseboard_fab2_lib.baseboard_fab2(sch_1):tp_cpu0_upi2_rsvd_db15") )
				( member ( signalRef "@baseboard_fab2_lib.baseboard_fab2(sch_1):tp_cpu0_upi2_rsvd_dc16") )
				( member ( signalRef "@baseboard_fab2_lib.baseboard_fab2(sch_1):tp_cpu0_upi2_rsvd_dd15") )
				( member ( signalRef "@baseboard_fab2_lib.baseboard_fab2(sch_1):tp_cpu0_upi2_rsvd_dd17") )
				( member ( signalRef "@baseboard_fab2_lib.baseboard_fab2(sch_1):tp_cpu0_upi2_rsvd_de16") )
				( member ( signalRef "@baseboard_fab2_lib.baseboard_fab2(sch_1):tp_cpu0_upi2_rsvd_df15") )
				( member ( signalRef "@baseboard_fab2_lib.baseboard_fab2(sch_1):tp_cpu0_upi2_rsvd_df17") )
				( member ( signalRef "@baseboard_fab2_lib.baseboard_fab2(sch_1):tp_cpu0_upi2_rsvd_dg18") )
				( member ( signalRef "@baseboard_fab2_lib.baseboard_fab2(sch_1):tp_cpu0_upi2_rsvd_dg20") )
				( member ( signalRef "@baseboard_fab2_lib.baseboard_fab2(sch_1):tp_cpu0_upi2_rsvd_dh17") )
				( member ( signalRef "@baseboard_fab2_lib.baseboard_fab2(sch_1):tp_cpu0_upi2_rsvd_dh19") )
				( member ( signalRef "@baseboard_fab2_lib.baseboard_fab2(sch_1):tp_cpu0_upi2_rsvd_dj18") )
				( member ( signalRef "@baseboard_fab2_lib.baseboard_fab2(sch_1):tp_cpu0_upi2_rsvd_dj20") )
				( member ( signalRef "@baseboard_fab2_lib.baseboard_fab2(sch_1):tp_cpu0_upi2_rsvd_dk17") )
				( member ( signalRef "@baseboard_fab2_lib.baseboard_fab2(sch_1):tp_cpu0_upi2_rsvd_dk19") )
				( member ( signalRef "@baseboard_fab2_lib.baseboard_fab2(sch_1):tp_cpu0_upi2_rsvd_dl20") )
				( member ( signalRef "@baseboard_fab2_lib.baseboard_fab2(sch_1):tp_cpu0_upi2_rsvd_dm21") )
				( member ( signalRef "@baseboard_fab2_lib.baseboard_fab2(sch_1):tp_cpu0_upi2_rsvd_dn20") )
				( member ( signalRef "@baseboard_fab2_lib.baseboard_fab2(sch_1):tp_cpu0_upi2_rsvd_dp21") )
				( member ( signalRef "@baseboard_fab2_lib.baseboard_fab2(sch_1):tp_cpu0_upi2_rsvd_dt21") )
				( member ( signalRef "@baseboard_fab2_lib.baseboard_fab2(sch_1):tp_cpu1_dmi_rx_dn0") )
				( member ( signalRef "@baseboard_fab2_lib.baseboard_fab2(sch_1):tp_cpu1_dmi_rx_dn1") )
				( member ( signalRef "@baseboard_fab2_lib.baseboard_fab2(sch_1):tp_cpu1_dmi_rx_dn2") )
				( member ( signalRef "@baseboard_fab2_lib.baseboard_fab2(sch_1):tp_cpu1_dmi_rx_dn3") )
				( member ( signalRef "@baseboard_fab2_lib.baseboard_fab2(sch_1):tp_cpu1_dmi_rx_dp0") )
				( member ( signalRef "@baseboard_fab2_lib.baseboard_fab2(sch_1):tp_cpu1_dmi_rx_dp1") )
				( member ( signalRef "@baseboard_fab2_lib.baseboard_fab2(sch_1):tp_cpu1_dmi_rx_dp2") )
				( member ( signalRef "@baseboard_fab2_lib.baseboard_fab2(sch_1):tp_cpu1_dmi_rx_dp3") )
				( member ( signalRef "@baseboard_fab2_lib.baseboard_fab2(sch_1):tp_cpu1_dmi_tx_dn0") )
				( member ( signalRef "@baseboard_fab2_lib.baseboard_fab2(sch_1):tp_cpu1_dmi_tx_dn1") )
				( member ( signalRef "@baseboard_fab2_lib.baseboard_fab2(sch_1):tp_cpu1_dmi_tx_dn2") )
				( member ( signalRef "@baseboard_fab2_lib.baseboard_fab2(sch_1):tp_cpu1_dmi_tx_dn3") )
				( member ( signalRef "@baseboard_fab2_lib.baseboard_fab2(sch_1):tp_cpu1_dmi_tx_dp0") )
				( member ( signalRef "@baseboard_fab2_lib.baseboard_fab2(sch_1):tp_cpu1_dmi_tx_dp1") )
				( member ( signalRef "@baseboard_fab2_lib.baseboard_fab2(sch_1):tp_cpu1_dmi_tx_dp2") )
				( member ( signalRef "@baseboard_fab2_lib.baseboard_fab2(sch_1):tp_cpu1_dmi_tx_dp3") )
				( member ( signalRef "@baseboard_fab2_lib.baseboard_fab2(sch_1):tp_cpu1_kti2_amonv") )
				( member ( signalRef "@baseboard_fab2_lib.baseboard_fab2(sch_1):tp_cpu1_kti2_dfx_dn") )
				( member ( signalRef "@baseboard_fab2_lib.baseboard_fab2(sch_1):tp_cpu1_nmi") )
				( member ( signalRef "@baseboard_fab2_lib.baseboard_fab2(sch_1):fm_usb_p0_en_boot_bios_strap_n") )
				( member ( signalRef "@baseboard_fab2_lib.baseboard_fab2(sch_1):vr_pvccio_cpu0_en") )
				( member ( signalRef "@baseboard_fab2_lib.baseboard_fab2(sch_1):tp_cpu1_proc_dis_g_n") )
				( member ( signalRef "@baseboard_fab2_lib.baseboard_fab2(sch_1):tp_cpu1_rsvd_test_5") )
				( member ( signalRef "@baseboard_fab2_lib.baseboard_fab2(sch_1):tp_cpu1_rsvd_test_11") )
				( member ( signalRef "@baseboard_fab2_lib.baseboard_fab2(sch_1):tp_cpu1_rsvd_0") )
				( member ( signalRef "@baseboard_fab2_lib.baseboard_fab2(sch_1):tp_cpu1_rsvd_1") )
				( member ( signalRef "@baseboard_fab2_lib.baseboard_fab2(sch_1):tp_cpu1_rsvd_2") )
				( member ( signalRef "@baseboard_fab2_lib.baseboard_fab2(sch_1):tp_cpu1_rsvd_3") )
				( member ( signalRef "@baseboard_fab2_lib.baseboard_fab2(sch_1):tp_cpu1_rsvd_4") )
				( member ( signalRef "@baseboard_fab2_lib.baseboard_fab2(sch_1):tp_cpu1_rsvd_5") )
				( member ( signalRef "@baseboard_fab2_lib.baseboard_fab2(sch_1):tp_cpu1_rsvd_6") )
				( member ( signalRef "@baseboard_fab2_lib.baseboard_fab2(sch_1):tp_cpu1_rsvd_7") )
				( member ( signalRef "@baseboard_fab2_lib.baseboard_fab2(sch_1):tp_cpu1_rsvd_8") )
				( member ( signalRef "@baseboard_fab2_lib.baseboard_fab2(sch_1):tp_cpu1_rsvd_9") )
				( member ( signalRef "@baseboard_fab2_lib.baseboard_fab2(sch_1):tp_cpu1_rsvd_10") )
				( member ( signalRef "@baseboard_fab2_lib.baseboard_fab2(sch_1):tp_cpu1_rsvd_11") )
				( member ( signalRef "@baseboard_fab2_lib.baseboard_fab2(sch_1):tp_cpu1_rsvd_12") )
				( member ( signalRef "@baseboard_fab2_lib.baseboard_fab2(sch_1):tp_cpu1_rsvd_13") )
				( member ( signalRef "@baseboard_fab2_lib.baseboard_fab2(sch_1):tp_cpu1_rsvd_14") )
				( member ( signalRef "@baseboard_fab2_lib.baseboard_fab2(sch_1):tp_cpu1_rsvd_15") )
				( member ( signalRef "@baseboard_fab2_lib.baseboard_fab2(sch_1):tp_cpu1_rsvd_16") )
				( member ( signalRef "@baseboard_fab2_lib.baseboard_fab2(sch_1):tp_cpu1_rsvd_17") )
				( member ( signalRef "@baseboard_fab2_lib.baseboard_fab2(sch_1):tp_cpu1_rsvd_18") )
				( member ( signalRef "@baseboard_fab2_lib.baseboard_fab2(sch_1):tp_cpu1_rsvd_19") )
				( member ( signalRef "@baseboard_fab2_lib.baseboard_fab2(sch_1):tp_cpu1_rsvd_20") )
				( member ( signalRef "@baseboard_fab2_lib.baseboard_fab2(sch_1):tp_cpu1_rsvd_21") )
				( member ( signalRef "@baseboard_fab2_lib.baseboard_fab2(sch_1):tp_cpu1_rsvd_22") )
				( member ( signalRef "@baseboard_fab2_lib.baseboard_fab2(sch_1):tp_cpu1_rsvd_23") )
				( member ( signalRef "@baseboard_fab2_lib.baseboard_fab2(sch_1):tp_cpu1_rsvd_24") )
				( member ( signalRef "@baseboard_fab2_lib.baseboard_fab2(sch_1):tp_cpu1_rsvd_25") )
				( member ( signalRef "@baseboard_fab2_lib.baseboard_fab2(sch_1):tp_cpu1_rsvd_26") )
				( member ( signalRef "@baseboard_fab2_lib.baseboard_fab2(sch_1):tp_cpu1_rsvd_27") )
				( member ( signalRef "@baseboard_fab2_lib.baseboard_fab2(sch_1):tp_cpu1_rsvd_28") )
				( member ( signalRef "@baseboard_fab2_lib.baseboard_fab2(sch_1):tp_cpu1_rsvd_29") )
				( member ( signalRef "@baseboard_fab2_lib.baseboard_fab2(sch_1):tp_cpu1_rsvd_30") )
				( member ( signalRef "@baseboard_fab2_lib.baseboard_fab2(sch_1):tp_cpu1_rsvd_31") )
				( member ( signalRef "@baseboard_fab2_lib.baseboard_fab2(sch_1):tp_cpu0_rsvd_177") )
				( member ( signalRef "@baseboard_fab2_lib.baseboard_fab2(sch_1):tp_cpu0_rsvd_178") )
				( member ( signalRef "@baseboard_fab2_lib.baseboard_fab2(sch_1):tp_cpu0_rsvd_179") )
				( member ( signalRef "@baseboard_fab2_lib.baseboard_fab2(sch_1):tp_cpu0_rsvd_180") )
				( member ( signalRef "@baseboard_fab2_lib.baseboard_fab2(sch_1):tp_cpu0_rsvd_181") )
				( member ( signalRef "@baseboard_fab2_lib.baseboard_fab2(sch_1):tp_cpu0_rsvd_182") )
				( member ( signalRef "@baseboard_fab2_lib.baseboard_fab2(sch_1):tp_cpu0_rsvd_183") )
				( member ( signalRef "@baseboard_fab2_lib.baseboard_fab2(sch_1):tp_cpu0_rsvd_184") )
				( member ( signalRef "@baseboard_fab2_lib.baseboard_fab2(sch_1):tp_cpu0_rsvd_186") )
				( member ( signalRef "@baseboard_fab2_lib.baseboard_fab2(sch_1):tp_cpu0_rsvd_189") )
				( member ( signalRef "@baseboard_fab2_lib.baseboard_fab2(sch_1):tp_cpu0_rsvd_190") )
				( member ( signalRef "@baseboard_fab2_lib.baseboard_fab2(sch_1):tp_cpu0_rsvd_194") )
				( member ( signalRef "@baseboard_fab2_lib.baseboard_fab2(sch_1):tp_cpu0_rsvd_198") )
				( member ( signalRef "@baseboard_fab2_lib.baseboard_fab2(sch_1):tp_cpu0_rsvd_199") )
				( member ( signalRef "@baseboard_fab2_lib.baseboard_fab2(sch_1):tp_cpu0_rsvd_204") )
				( member ( signalRef "@baseboard_fab2_lib.baseboard_fab2(sch_1):tp_cpu0_rsvd_205") )
				( member ( signalRef "@baseboard_fab2_lib.baseboard_fab2(sch_1):tp_cpu0_rsvd_208") )
				( member ( signalRef "@baseboard_fab2_lib.baseboard_fab2(sch_1):tp_cpu0_rsvd_210") )
				( member ( signalRef "@baseboard_fab2_lib.baseboard_fab2(sch_1):tp_cpu0_rsvd_211") )
				( member ( signalRef "@baseboard_fab2_lib.baseboard_fab2(sch_1):tp_cpu0_rsvd_212") )
				( member ( signalRef "@baseboard_fab2_lib.baseboard_fab2(sch_1):tp_cpu0_rsvd_214") )
				( member ( signalRef "@baseboard_fab2_lib.baseboard_fab2(sch_1):tp_cpu0_rsvd_216") )
				( member ( signalRef "@baseboard_fab2_lib.baseboard_fab2(sch_1):tp_cpu0_rsvd_217") )
				( member ( signalRef "@baseboard_fab2_lib.baseboard_fab2(sch_1):tp_cpu0_rsvd_218") )
				( member ( signalRef "@baseboard_fab2_lib.baseboard_fab2(sch_1):tp_cpu0_rsvd_219") )
				( member ( signalRef "@baseboard_fab2_lib.baseboard_fab2(sch_1):tp_cpu0_rsvd_222") )
				( member ( signalRef "@baseboard_fab2_lib.baseboard_fab2(sch_1):tp_cpu0_rsvd_223") )
				( member ( signalRef "@baseboard_fab2_lib.baseboard_fab2(sch_1):tp_cpu0_rsvd_224") )
				( member ( signalRef "@baseboard_fab2_lib.baseboard_fab2(sch_1):tp_cpu0_rsvd_225") )
				( member ( signalRef "@baseboard_fab2_lib.baseboard_fab2(sch_1):tp_cpu0_rsvd_226") )
				( member ( signalRef "@baseboard_fab2_lib.baseboard_fab2(sch_1):tp_cpu0_rsvd_227") )
				( member ( signalRef "@baseboard_fab2_lib.baseboard_fab2(sch_1):tp_cpu0_rsvd_228") )
				( member ( signalRef "@baseboard_fab2_lib.baseboard_fab2(sch_1):tp_cpu0_rsvd_229") )
				( member ( signalRef "@baseboard_fab2_lib.baseboard_fab2(sch_1):tp_cpu0_rsvd_230") )
				( member ( signalRef "@baseboard_fab2_lib.baseboard_fab2(sch_1):tp_cpu0_rsvd_231") )
				( member ( signalRef "@baseboard_fab2_lib.baseboard_fab2(sch_1):tp_cpu0_rsvd_232") )
				( member ( signalRef "@baseboard_fab2_lib.baseboard_fab2(sch_1):tp_cpu0_rsvd_233") )
				( member ( signalRef "@baseboard_fab2_lib.baseboard_fab2(sch_1):tp_cpu0_rsvd_234") )
				( member ( signalRef "@baseboard_fab2_lib.baseboard_fab2(sch_1):tp_cpu0_rsvd_235") )
				( member ( signalRef "@baseboard_fab2_lib.baseboard_fab2(sch_1):tp_cpu0_rsvd_236") )
				( member ( signalRef "@baseboard_fab2_lib.baseboard_fab2(sch_1):tp_cpu0_rsvd_237") )
				( member ( signalRef "@baseboard_fab2_lib.baseboard_fab2(sch_1):tp_cpu0_rsvd_238") )
				( member ( signalRef "@baseboard_fab2_lib.baseboard_fab2(sch_1):tp_cpu0_rsvd_239") )
				( member ( signalRef "@baseboard_fab2_lib.baseboard_fab2(sch_1):tp_cpu0_rsvd_240") )
				( member ( signalRef "@baseboard_fab2_lib.baseboard_fab2(sch_1):tp_cpu0_rsvd_241") )
				( member ( signalRef "@baseboard_fab2_lib.baseboard_fab2(sch_1):tp_cpu0_rsvd_242") )
				( member ( signalRef "@baseboard_fab2_lib.baseboard_fab2(sch_1):tp_cpu0_rsvd_243") )
				( member ( signalRef "@baseboard_fab2_lib.baseboard_fab2(sch_1):tp_cpu0_rsvd_244") )
				( member ( signalRef "@baseboard_fab2_lib.baseboard_fab2(sch_1):tp_cpu0_rsvd_245") )
				( member ( signalRef "@baseboard_fab2_lib.baseboard_fab2(sch_1):tp_cpu0_rsvd_246") )
				( member ( signalRef "@baseboard_fab2_lib.baseboard_fab2(sch_1):tp_cpu0_rsvd_247") )
				( member ( signalRef "@baseboard_fab2_lib.baseboard_fab2(sch_1):tp_cpu0_rsvd_248") )
				( member ( signalRef "@baseboard_fab2_lib.baseboard_fab2(sch_1):tp_cpu0_rsvd_249") )
				( member ( signalRef "@baseboard_fab2_lib.baseboard_fab2(sch_1):tp_cpu0_rsvd_250") )
				( member ( signalRef "@baseboard_fab2_lib.baseboard_fab2(sch_1):tp_cpu0_rsvd_251") )
				( member ( signalRef "@baseboard_fab2_lib.baseboard_fab2(sch_1):tp_cpu0_rsvd_252") )
				( member ( signalRef "@baseboard_fab2_lib.baseboard_fab2(sch_1):tp_cpu0_rsvd_253") )
				( member ( signalRef "@baseboard_fab2_lib.baseboard_fab2(sch_1):tp_cpu0_rsvd_254") )
				( member ( signalRef "@baseboard_fab2_lib.baseboard_fab2(sch_1):tp_cpu0_rsvd_255") )
				( member ( signalRef "@baseboard_fab2_lib.baseboard_fab2(sch_1):tp_cpu0_rsvd_256") )
				( member ( signalRef "@baseboard_fab2_lib.baseboard_fab2(sch_1):tp_jumper_block_2_12") )
				( member ( signalRef "@baseboard_fab2_lib.baseboard_fab2(sch_1):tp_cpu0_rsvd_258") )
				( member ( signalRef "@baseboard_fab2_lib.baseboard_fab2(sch_1):tp_cpu0_rsvd_259") )
				( member ( signalRef "@baseboard_fab2_lib.baseboard_fab2(sch_1):tp_cpu0_rsvd_260") )
				( member ( signalRef "@baseboard_fab2_lib.baseboard_fab2(sch_1):tp_cpu0_rsvd_261") )
				( member ( signalRef "@baseboard_fab2_lib.baseboard_fab2(sch_1):tp_cpu0_rsvd_262") )
				( member ( signalRef "@baseboard_fab2_lib.baseboard_fab2(sch_1):tp_cpu0_rsvd_263") )
				( member ( signalRef "@baseboard_fab2_lib.baseboard_fab2(sch_1):tp_cpu0_rsvd_264") )
				( member ( signalRef "@baseboard_fab2_lib.baseboard_fab2(sch_1):tp_cpu0_rsvd_265") )
				( member ( signalRef "@baseboard_fab2_lib.baseboard_fab2(sch_1):tp_cpu0_rsvd_266") )
				( member ( signalRef "@baseboard_fab2_lib.baseboard_fab2(sch_1):tp_cpu0_rsvd_267") )
				( member ( signalRef "@baseboard_fab2_lib.baseboard_fab2(sch_1):tp_cpu0_rsvd_268") )
				( member ( signalRef "@baseboard_fab2_lib.baseboard_fab2(sch_1):tp_cpu0_rsvd_269") )
				( member ( signalRef "@baseboard_fab2_lib.baseboard_fab2(sch_1):tp_cpu0_rsvd_270") )
				( member ( signalRef "@baseboard_fab2_lib.baseboard_fab2(sch_1):tp_cpu0_rsvd_271") )
				( member ( signalRef "@baseboard_fab2_lib.baseboard_fab2(sch_1):tp_cpu0_rsvd_272") )
				( member ( signalRef "@baseboard_fab2_lib.baseboard_fab2(sch_1):tp_cpu0_rsvd_273") )
				( member ( signalRef "@baseboard_fab2_lib.baseboard_fab2(sch_1):tp_cpu0_rsvd_274") )
				( member ( signalRef "@baseboard_fab2_lib.baseboard_fab2(sch_1):tp_cpu0_rsvd_276") )
				( member ( signalRef "@baseboard_fab2_lib.baseboard_fab2(sch_1):tp_cpu0_rsvd_277") )
				( member ( signalRef "@baseboard_fab2_lib.baseboard_fab2(sch_1):tp_cpu0_rsvd_278") )
				( member ( signalRef "@baseboard_fab2_lib.baseboard_fab2(sch_1):tp_cpu0_rsvd_279") )
				( member ( signalRef "@baseboard_fab2_lib.baseboard_fab2(sch_1):tp_cpu0_rsvd_280") )
				( member ( signalRef "@baseboard_fab2_lib.baseboard_fab2(sch_1):tp_cpu0_rsvd_281") )
				( member ( signalRef "@baseboard_fab2_lib.baseboard_fab2(sch_1):tp_cpu0_rsvd_284") )
				( member ( signalRef "@baseboard_fab2_lib.baseboard_fab2(sch_1):tp_cpu0_rsvd_285") )
				( member ( signalRef "@baseboard_fab2_lib.baseboard_fab2(sch_1):tp_cpu0_rsvd_286") )
				( member ( signalRef "@baseboard_fab2_lib.baseboard_fab2(sch_1):tp_cpu0_rsvd_288") )
				( member ( signalRef "@baseboard_fab2_lib.baseboard_fab2(sch_1):tp_cpu0_rsvd_289") )
				( member ( signalRef "@baseboard_fab2_lib.baseboard_fab2(sch_1):tp_cpu0_rsvd_290") )
				( member ( signalRef "@baseboard_fab2_lib.baseboard_fab2(sch_1):tp_cpu0_rsvd_291") )
				( member ( signalRef "@baseboard_fab2_lib.baseboard_fab2(sch_1):tp_cpu0_rsvd_292") )
				( member ( signalRef "@baseboard_fab2_lib.baseboard_fab2(sch_1):tp_cpu0_rsvd_293") )
				( member ( signalRef "@baseboard_fab2_lib.baseboard_fab2(sch_1):tp_cpu0_rsvd_300") )
				( member ( signalRef "@baseboard_fab2_lib.baseboard_fab2(sch_1):h_cpu0_memabc_memhot_pch_n") )
				( member ( signalRef "@baseboard_fab2_lib.baseboard_fab2(sch_1):h_cpu0_memdef_memhot_pch_n") )
				( member ( signalRef "@baseboard_fab2_lib.baseboard_fab2(sch_1):tp_cpu0_socket_id_2") )
				( member ( signalRef "@baseboard_fab2_lib.baseboard_fab2(sch_1):tp_cpu0_test_6") )
				( member ( signalRef "@baseboard_fab2_lib.baseboard_fab2(sch_1):tp_cpu0_test_7") )
				( member ( signalRef "@baseboard_fab2_lib.baseboard_fab2(sch_1):tp_cpu0_test_8") )
				( member ( signalRef "@baseboard_fab2_lib.baseboard_fab2(sch_1):tp_cpu0_rsvd_19") )
				( member ( signalRef "@baseboard_fab2_lib.baseboard_fab2(sch_1):tp_cpu0_rsvd_20") )
				( member ( signalRef "@baseboard_fab2_lib.baseboard_fab2(sch_1):tp_cpu0_rsvd_21") )
				( member ( signalRef "@baseboard_fab2_lib.baseboard_fab2(sch_1):tp_cpu0_rsvd_22") )
				( member ( signalRef "@baseboard_fab2_lib.baseboard_fab2(sch_1):tp_cpu0_rsvd_23") )
				( member ( signalRef "@baseboard_fab2_lib.baseboard_fab2(sch_1):tp_cpu0_rsvd_24") )
				( member ( signalRef "@baseboard_fab2_lib.baseboard_fab2(sch_1):tp_cpu0_rsvd_25") )
				( member ( signalRef "@baseboard_fab2_lib.baseboard_fab2(sch_1):tp_cpu0_rsvd_26") )
				( member ( signalRef "@baseboard_fab2_lib.baseboard_fab2(sch_1):tp_cpu0_rsvd_27") )
				( member ( signalRef "@baseboard_fab2_lib.baseboard_fab2(sch_1):tp_cpu0_rsvd_28") )
				( member ( signalRef "@baseboard_fab2_lib.baseboard_fab2(sch_1):tp_cpu0_rsvd_29") )
				( member ( signalRef "@baseboard_fab2_lib.baseboard_fab2(sch_1):tp_cpu0_rsvd_30") )
				( member ( signalRef "@baseboard_fab2_lib.baseboard_fab2(sch_1):tp_cpu0_rsvd_31") )
				( member ( signalRef "@baseboard_fab2_lib.baseboard_fab2(sch_1):tp_cpu0_rsvd_32") )
				( member ( signalRef "@baseboard_fab2_lib.baseboard_fab2(sch_1):tp_cpu0_rsvd_33") )
				( member ( signalRef "@baseboard_fab2_lib.baseboard_fab2(sch_1):tp_cpu0_rsvd_34") )
				( member ( signalRef "@baseboard_fab2_lib.baseboard_fab2(sch_1):tp_cpu0_rsvd_35") )
				( member ( signalRef "@baseboard_fab2_lib.baseboard_fab2(sch_1):tp_cpu0_rsvd_36") )
				( member ( signalRef "@baseboard_fab2_lib.baseboard_fab2(sch_1):tp_cpu0_rsvd_37") )
				( member ( signalRef "@baseboard_fab2_lib.baseboard_fab2(sch_1):tp_cpu0_rsvd_38") )
				( member ( signalRef "@baseboard_fab2_lib.baseboard_fab2(sch_1):tp_cpu0_rsvd_39") )
				( member ( signalRef "@baseboard_fab2_lib.baseboard_fab2(sch_1):tp_cpu0_rsvd_40") )
				( member ( signalRef "@baseboard_fab2_lib.baseboard_fab2(sch_1):tp_cpu0_rsvd_41") )
				( member ( signalRef "@baseboard_fab2_lib.baseboard_fab2(sch_1):tp_cpu0_rsvd_42") )
				( member ( signalRef "@baseboard_fab2_lib.baseboard_fab2(sch_1):tp_cpu0_rsvd_43") )
				( member ( signalRef "@baseboard_fab2_lib.baseboard_fab2(sch_1):tp_cpu0_rsvd_44") )
				( member ( signalRef "@baseboard_fab2_lib.baseboard_fab2(sch_1):tp_cpu0_rsvd_45") )
				( member ( signalRef "@baseboard_fab2_lib.baseboard_fab2(sch_1):tp_cpu0_rsvd_46") )
				( member ( signalRef "@baseboard_fab2_lib.baseboard_fab2(sch_1):tp_cpu0_rsvd_47") )
				( member ( signalRef "@baseboard_fab2_lib.baseboard_fab2(sch_1):tp_cpu0_rsvd_48") )
				( member ( signalRef "@baseboard_fab2_lib.baseboard_fab2(sch_1):tp_cpu0_rsvd_49") )
				( member ( signalRef "@baseboard_fab2_lib.baseboard_fab2(sch_1):tp_cpu0_rsvd_50") )
				( member ( signalRef "@baseboard_fab2_lib.baseboard_fab2(sch_1):tp_cpu0_rsvd_51") )
				( member ( signalRef "@baseboard_fab2_lib.baseboard_fab2(sch_1):tp_cpu0_rsvd_53") )
				( member ( signalRef "@baseboard_fab2_lib.baseboard_fab2(sch_1):tp_cpu0_rsvd_54") )
				( member ( signalRef "@baseboard_fab2_lib.baseboard_fab2(sch_1):tp_cpu0_rsvd_55") )
				( member ( signalRef "@baseboard_fab2_lib.baseboard_fab2(sch_1):tp_cpu0_rsvd_56") )
				( member ( signalRef "@baseboard_fab2_lib.baseboard_fab2(sch_1):tp_cpu0_rsvd_57") )
				( member ( signalRef "@baseboard_fab2_lib.baseboard_fab2(sch_1):tp_cpu0_rsvd_59") )
				( member ( signalRef "@baseboard_fab2_lib.baseboard_fab2(sch_1):tp_cpu0_rsvd_60") )
				( member ( signalRef "@baseboard_fab2_lib.baseboard_fab2(sch_1):tp_cpu0_rsvd_61") )
				( member ( signalRef "@baseboard_fab2_lib.baseboard_fab2(sch_1):tp_cpu0_rsvd_64") )
				( member ( signalRef "@baseboard_fab2_lib.baseboard_fab2(sch_1):tp_cpu0_rsvd_66") )
				( member ( signalRef "@baseboard_fab2_lib.baseboard_fab2(sch_1):tp_cpu0_rsvd_67") )
				( member ( signalRef "@baseboard_fab2_lib.baseboard_fab2(sch_1):tp_cpu0_rsvd_69") )
				( member ( signalRef "@baseboard_fab2_lib.baseboard_fab2(sch_1):tp_cpu0_rsvd_70") )
				( member ( signalRef "@baseboard_fab2_lib.baseboard_fab2(sch_1):tp_cpu0_rsvd_72") )
				( member ( signalRef "@baseboard_fab2_lib.baseboard_fab2(sch_1):tp_cpu0_rsvd_73") )
				( member ( signalRef "@baseboard_fab2_lib.baseboard_fab2(sch_1):tp_cpu0_rsvd_82") )
				( member ( signalRef "@baseboard_fab2_lib.baseboard_fab2(sch_1):tp_cpu0_rsvd_85") )
				( member ( signalRef "@baseboard_fab2_lib.baseboard_fab2(sch_1):tp_cpu0_rsvd_90") )
				( member ( signalRef "@baseboard_fab2_lib.baseboard_fab2(sch_1):tp_cpu0_rsvd_91") )
				( member ( signalRef "@baseboard_fab2_lib.baseboard_fab2(sch_1):tp_cpu0_rsvd_94") )
				( member ( signalRef "@baseboard_fab2_lib.baseboard_fab2(sch_1):tp_cpu0_rsvd_95") )
				( member ( signalRef "@baseboard_fab2_lib.baseboard_fab2(sch_1):tp_cpu0_rsvd_97") )
				( member ( signalRef "@baseboard_fab2_lib.baseboard_fab2(sch_1):tp_cpu0_rsvd_99") )
				( member ( signalRef "@baseboard_fab2_lib.baseboard_fab2(sch_1):tp_cpu0_rsvd_100") )
				( member ( signalRef "@baseboard_fab2_lib.baseboard_fab2(sch_1):tp_cpu0_rsvd_101") )
				( member ( signalRef "@baseboard_fab2_lib.baseboard_fab2(sch_1):tp_cpu0_rsvd_105") )
				( member ( signalRef "@baseboard_fab2_lib.baseboard_fab2(sch_1):tp_cpu0_rsvd_106") )
				( member ( signalRef "@baseboard_fab2_lib.baseboard_fab2(sch_1):tp_cpu0_rsvd_108") )
				( member ( signalRef "@baseboard_fab2_lib.baseboard_fab2(sch_1):tp_cpu0_rsvd_111") )
				( member ( signalRef "@baseboard_fab2_lib.baseboard_fab2(sch_1):tp_cpu0_rsvd_113") )
				( member ( signalRef "@baseboard_fab2_lib.baseboard_fab2(sch_1):tp_cpu0_rsvd_114") )
				( member ( signalRef "@baseboard_fab2_lib.baseboard_fab2(sch_1):tp_cpu0_rsvd_117") )
				( member ( signalRef "@baseboard_fab2_lib.baseboard_fab2(sch_1):tp_cpu0_rsvd_119") )
				( member ( signalRef "@baseboard_fab2_lib.baseboard_fab2(sch_1):tp_cpu0_rsvd_121") )
				( member ( signalRef "@baseboard_fab2_lib.baseboard_fab2(sch_1):tp_cpu0_rsvd_123") )
				( member ( signalRef "@baseboard_fab2_lib.baseboard_fab2(sch_1):tp_cpu0_rsvd_124") )
				( member ( signalRef "@baseboard_fab2_lib.baseboard_fab2(sch_1):tp_cpu0_rsvd_144") )
				( member ( signalRef "@baseboard_fab2_lib.baseboard_fab2(sch_1):tp_cpu0_rsvd_145") )
				( member ( signalRef "@baseboard_fab2_lib.baseboard_fab2(sch_1):tp_cpu0_rsvd_146") )
				( member ( signalRef "@baseboard_fab2_lib.baseboard_fab2(sch_1):tp_cpu0_rsvd_147") )
				( member ( signalRef "@baseboard_fab2_lib.baseboard_fab2(sch_1):tp_cpu0_rsvd_148") )
				( member ( signalRef "@baseboard_fab2_lib.baseboard_fab2(sch_1):tp_cpu0_rsvd_149") )
				( member ( signalRef "@baseboard_fab2_lib.baseboard_fab2(sch_1):tp_cpu0_rsvd_150") )
				( member ( signalRef "@baseboard_fab2_lib.baseboard_fab2(sch_1):tp_cpu0_rsvd_151") )
				( member ( signalRef "@baseboard_fab2_lib.baseboard_fab2(sch_1):tp_cpu0_rsvd_152") )
				( member ( signalRef "@baseboard_fab2_lib.baseboard_fab2(sch_1):tp_cpu0_rsvd_154") )
				( member ( signalRef "@baseboard_fab2_lib.baseboard_fab2(sch_1):tp_cpu0_rsvd_155") )
				( member ( signalRef "@baseboard_fab2_lib.baseboard_fab2(sch_1):tp_cpu0_rsvd_156") )
				( member ( signalRef "@baseboard_fab2_lib.baseboard_fab2(sch_1):tp_cpu0_rsvd_157") )
				( member ( signalRef "@baseboard_fab2_lib.baseboard_fab2(sch_1):tp_cpu0_rsvd_158") )
				( member ( signalRef "@baseboard_fab2_lib.baseboard_fab2(sch_1):tp_cpu0_rsvd_159") )
				( member ( signalRef "@baseboard_fab2_lib.baseboard_fab2(sch_1):tp_cpu0_rsvd_160") )
				( member ( signalRef "@baseboard_fab2_lib.baseboard_fab2(sch_1):tp_cpu0_rsvd_161") )
				( member ( signalRef "@baseboard_fab2_lib.baseboard_fab2(sch_1):tp_cpu0_rsvd_162") )
				( member ( signalRef "@baseboard_fab2_lib.baseboard_fab2(sch_1):tp_cpu0_rsvd_163") )
				( member ( signalRef "@baseboard_fab2_lib.baseboard_fab2(sch_1):tp_cpu0_rsvd_164") )
				( member ( signalRef "@baseboard_fab2_lib.baseboard_fab2(sch_1):tp_cpu0_rsvd_166") )
				( member ( signalRef "@baseboard_fab2_lib.baseboard_fab2(sch_1):tp_cpu0_rsvd_167") )
				( member ( signalRef "@baseboard_fab2_lib.baseboard_fab2(sch_1):tp_cpu0_rsvd_168") )
				( member ( signalRef "@baseboard_fab2_lib.baseboard_fab2(sch_1):tp_cpu0_rsvd_169") )
				( member ( signalRef "@baseboard_fab2_lib.baseboard_fab2(sch_1):tp_cpu0_rsvd_170") )
				( member ( signalRef "@baseboard_fab2_lib.baseboard_fab2(sch_1):tp_cpu0_rsvd_171") )
				( member ( signalRef "@baseboard_fab2_lib.baseboard_fab2(sch_1):tp_cpu0_rsvd_172") )
				( member ( signalRef "@baseboard_fab2_lib.baseboard_fab2(sch_1):tp_cpu0_rsvd_173") )
				( member ( signalRef "@baseboard_fab2_lib.baseboard_fab2(sch_1):tp_cpu0_rsvd_174") )
				( member ( signalRef "@baseboard_fab2_lib.baseboard_fab2(sch_1):tp_cpu0_rsvd_175") )
				( member ( signalRef "@baseboard_fab2_lib.baseboard_fab2(sch_1):tp_cpu0_rsvd_176") )
				( member ( signalRef "@baseboard_fab2_lib.baseboard_fab2(sch_1):tp_ch_g_dimm_g0_rfu_0") )
				( member ( signalRef "@baseboard_fab2_lib.baseboard_fab2(sch_1):tp_ch_g_dimm_g0_rfu_1") )
				( member ( signalRef "@baseboard_fab2_lib.baseboard_fab2(sch_1):tp_ch_g_dimm_g0_rfu_2") )
				( member ( signalRef "@baseboard_fab2_lib.baseboard_fab2(sch_1):tp_ch_g_dimm0_rfu_0") )
				( member ( signalRef "@baseboard_fab2_lib.baseboard_fab2(sch_1):tp_ch_g_dimm0_rfu_1") )
				( member ( signalRef "@baseboard_fab2_lib.baseboard_fab2(sch_1):tp_ch_g_dimm0_rfu_2") )
				( member ( signalRef "@baseboard_fab2_lib.baseboard_fab2(sch_1):tp_ch_h_dimm_h0_rfu_0") )
				( member ( signalRef "@baseboard_fab2_lib.baseboard_fab2(sch_1):tp_ch_h_dimm_h0_rfu_1") )
				( member ( signalRef "@baseboard_fab2_lib.baseboard_fab2(sch_1):tp_ch_h_dimm_h0_rfu_2") )
				( member ( signalRef "@baseboard_fab2_lib.baseboard_fab2(sch_1):tp_ch_h_dimm0_rfu_0") )
				( member ( signalRef "@baseboard_fab2_lib.baseboard_fab2(sch_1):tp_ch_h_dimm0_rfu_1") )
				( member ( signalRef "@baseboard_fab2_lib.baseboard_fab2(sch_1):tp_ch_h_dimm0_rfu_2") )
				( member ( signalRef "@baseboard_fab2_lib.baseboard_fab2(sch_1):tp_ch_j_dimm_j0_rfu_0") )
				( member ( signalRef "@baseboard_fab2_lib.baseboard_fab2(sch_1):tp_ch_j_dimm_j0_rfu_1") )
				( member ( signalRef "@baseboard_fab2_lib.baseboard_fab2(sch_1):tp_ch_j_dimm_j0_rfu_2") )
				( member ( signalRef "@baseboard_fab2_lib.baseboard_fab2(sch_1):tp_ch_j_dimm_j1_rfu_0") )
				( member ( signalRef "@baseboard_fab2_lib.baseboard_fab2(sch_1):tp_ch_j_dimm_j1_rfu_1") )
				( member ( signalRef "@baseboard_fab2_lib.baseboard_fab2(sch_1):tp_ch_j_dimm_j1_rfu_2") )
				( member ( signalRef "@baseboard_fab2_lib.baseboard_fab2(sch_1):tp_ch_k_dimm_k0_rfu_0") )
				( member ( signalRef "@baseboard_fab2_lib.baseboard_fab2(sch_1):tp_ch_k_dimm_k0_rfu_1") )
				( member ( signalRef "@baseboard_fab2_lib.baseboard_fab2(sch_1):tp_ch_k_dimm_k0_rfu_2") )
				( member ( signalRef "@baseboard_fab2_lib.baseboard_fab2(sch_1):tp_ch_k_dimm0_rfu_0") )
				( member ( signalRef "@baseboard_fab2_lib.baseboard_fab2(sch_1):tp_ch_k_dimm0_rfu_1") )
				( member ( signalRef "@baseboard_fab2_lib.baseboard_fab2(sch_1):tp_ch_k_dimm0_rfu_2") )
				( member ( signalRef "@baseboard_fab2_lib.baseboard_fab2(sch_1):tp_ch_l_dimm_l0_rfu_0") )
				( member ( signalRef "@baseboard_fab2_lib.baseboard_fab2(sch_1):tp_ch_l_dimm_l0_rfu_1") )
				( member ( signalRef "@baseboard_fab2_lib.baseboard_fab2(sch_1):tp_ch_l_dimm_l0_rfu_2") )
				( member ( signalRef "@baseboard_fab2_lib.baseboard_fab2(sch_1):tp_ch_l_dimm0_rfu_0") )
				( member ( signalRef "@baseboard_fab2_lib.baseboard_fab2(sch_1):tp_ch_l_dimm0_rfu_1") )
				( member ( signalRef "@baseboard_fab2_lib.baseboard_fab2(sch_1):tp_ch_l_dimm0_rfu_2") )
				( member ( signalRef "@baseboard_fab2_lib.baseboard_fab2(sch_1):tp_ch_m_dimm_m0_rfu_0") )
				( member ( signalRef "@baseboard_fab2_lib.baseboard_fab2(sch_1):tp_ch_m_dimm_m0_rfu_1") )
				( member ( signalRef "@baseboard_fab2_lib.baseboard_fab2(sch_1):tp_ch_m_dimm_m0_rfu_2") )
				( member ( signalRef "@baseboard_fab2_lib.baseboard_fab2(sch_1):tp_ch_m_dimm_m1_rfu_0") )
				( member ( signalRef "@baseboard_fab2_lib.baseboard_fab2(sch_1):tp_ch_m_dimm_m1_rfu_1") )
				( member ( signalRef "@baseboard_fab2_lib.baseboard_fab2(sch_1):tp_ch_m_dimm_m1_rfu_2") )
				( member ( signalRef "@baseboard_fab2_lib.baseboard_fab2(sch_1):tp_clk_24m_pmsync2") )
				( member ( signalRef "@baseboard_fab2_lib.baseboard_fab2(sch_1):tp_clk_96m_ckmng_n") )
				( member ( signalRef "@baseboard_fab2_lib.baseboard_fab2(sch_1):tp_clk_96m_ckmng_p") )
				( member ( signalRef "@baseboard_fab2_lib.baseboard_fab2(sch_1):tp_clk_100m_nsscc0_dn") )
				( member ( signalRef "@baseboard_fab2_lib.baseboard_fab2(sch_1):tp_clk_100m_nsscc0_dp") )
				( member ( signalRef "@baseboard_fab2_lib.baseboard_fab2(sch_1):tp_clk_100m_nsscc1_dn") )
				( member ( signalRef "@baseboard_fab2_lib.baseboard_fab2(sch_1):tp_clk_100m_nsscc1_dp") )
				( member ( signalRef "@baseboard_fab2_lib.baseboard_fab2(sch_1):tp_clk_100m_plat1_dn") )
				( member ( signalRef "@baseboard_fab2_lib.baseboard_fab2(sch_1):tp_clk_100m_plat1_dp") )
				( member ( signalRef "@baseboard_fab2_lib.baseboard_fab2(sch_1):tp_clk_100m_r_dn") )
				( member ( signalRef "@baseboard_fab2_lib.baseboard_fab2(sch_1):tp_clk_100m_r_dp") )
				( member ( signalRef "@baseboard_fab2_lib.baseboard_fab2(sch_1):tp_clk_100m_src12_dn") )
				( member ( signalRef "@baseboard_fab2_lib.baseboard_fab2(sch_1):tp_clk_100m_src12_dp") )
				( member ( signalRef "@baseboard_fab2_lib.baseboard_fab2(sch_1):tp_clk_100m_src13_dn") )
				( member ( signalRef "@baseboard_fab2_lib.baseboard_fab2(sch_1):tp_clk_100m_src13_dp") )
				( member ( signalRef "@baseboard_fab2_lib.baseboard_fab2(sch_1):tp_clk_125m") )
				( member ( signalRef "@baseboard_fab2_lib.baseboard_fab2(sch_1):tp_clk_125m_bmca") )
				( member ( signalRef "@baseboard_fab2_lib.baseboard_fab2(sch_1):tp_clk5_50m_ckmng") )
				( member ( signalRef "@baseboard_fab2_lib.baseboard_fab2(sch_1):tp_cpld1_pr9c") )
				( member ( signalRef "@baseboard_fab2_lib.baseboard_fab2(sch_1):tp_cpld1_pr9d") )
				( member ( signalRef "@baseboard_fab2_lib.baseboard_fab2(sch_1):tp_cpld1_pr7c") )
				( member ( signalRef "@baseboard_fab2_lib.baseboard_fab2(sch_1):tp_cpld1_pr9a") )
				( member ( signalRef "@baseboard_fab2_lib.baseboard_fab2(sch_1):tp_cpld1_pr7d") )
				( member ( signalRef "@baseboard_fab2_lib.baseboard_fab2(sch_1):tp_cpld1_pr7a_pclkt1_0") )
				( member ( signalRef "@baseboard_fab2_lib.baseboard_fab2(sch_1):tp_cpld1_pr7b_pclkc1_0") )
				( member ( signalRef "@baseboard_fab2_lib.baseboard_fab2(sch_1):jtag_mcp_tck") )
				( member ( signalRef "@baseboard_fab2_lib.baseboard_fab2(sch_1):tp_pvccin_cpu1_ph5_gl_1") )
				( member ( signalRef "@baseboard_fab2_lib.baseboard_fab2(sch_1):tp_cpld1_pb25b_si_sispi") )
				( member ( signalRef "@baseboard_fab2_lib.baseboard_fab2(sch_1):tp_cpld1_pl12b_pclkc3_0") )
				( member ( signalRef "@baseboard_fab2_lib.baseboard_fab2(sch_1):jtag_mcp_mux_tdo") )
				( member ( signalRef "@baseboard_fab2_lib.baseboard_fab2(sch_1):tp_pvccin_cpu1_ph3_gl_1") )
				( member ( signalRef "@baseboard_fab2_lib.baseboard_fab2(sch_1):vr_pvccin_cpu1_ph5_ocset") )
				( member ( signalRef "@baseboard_fab2_lib.baseboard_fab2(sch_1):tp_cpld1_pt20d_programn") )
				( member ( signalRef "@baseboard_fab2_lib.baseboard_fab2(sch_1):tp_cpld1_pt24c_initn") )
				( member ( signalRef "@baseboard_fab2_lib.baseboard_fab2(sch_1):tp_cpld1_pt24d_done") )
				( member ( signalRef "@baseboard_fab2_lib.baseboard_fab2(sch_1):tp_cpu_pch_trigger_in") )
				( member ( signalRef "@baseboard_fab2_lib.baseboard_fab2(sch_1):tp_cpu_pch_trigger_out") )
				( member ( signalRef "@baseboard_fab2_lib.baseboard_fab2(sch_1):tp_cpu0_kti2_amonv") )
				( member ( signalRef "@baseboard_fab2_lib.baseboard_fab2(sch_1):tp_cpu0_kti2_dfx_dn") )
				( member ( signalRef "@baseboard_fab2_lib.baseboard_fab2(sch_1):tp_cpu0_pe_hp_scl") )
				( member ( signalRef "@baseboard_fab2_lib.baseboard_fab2(sch_1):tp_cpu0_pe_hp_sda") )
				( member ( signalRef "@baseboard_fab2_lib.baseboard_fab2(sch_1):tp_cpu0_procdis_g_n") )
				( member ( signalRef "@baseboard_fab2_lib.baseboard_fab2(sch_1):tp_cpu0_rsvd_test_5") )
				( member ( signalRef "@baseboard_fab2_lib.baseboard_fab2(sch_1):tp_cpu0_rsvd_test_11") )
				( member ( signalRef "@baseboard_fab2_lib.baseboard_fab2(sch_1):tp_cpu0_rsvd_0") )
				( member ( signalRef "@baseboard_fab2_lib.baseboard_fab2(sch_1):tp_cpu0_rsvd_1") )
				( member ( signalRef "@baseboard_fab2_lib.baseboard_fab2(sch_1):tp_cpu0_rsvd_2") )
				( member ( signalRef "@baseboard_fab2_lib.baseboard_fab2(sch_1):tp_cpu0_rsvd_3") )
				( member ( signalRef "@baseboard_fab2_lib.baseboard_fab2(sch_1):tp_cpu0_rsvd_4") )
				( member ( signalRef "@baseboard_fab2_lib.baseboard_fab2(sch_1):tp_cpu0_rsvd_5") )
				( member ( signalRef "@baseboard_fab2_lib.baseboard_fab2(sch_1):tp_cpu0_rsvd_6") )
				( member ( signalRef "@baseboard_fab2_lib.baseboard_fab2(sch_1):tp_cpu0_rsvd_7") )
				( member ( signalRef "@baseboard_fab2_lib.baseboard_fab2(sch_1):tp_cpu0_rsvd_8") )
				( member ( signalRef "@baseboard_fab2_lib.baseboard_fab2(sch_1):tp_cpu0_rsvd_9") )
				( member ( signalRef "@baseboard_fab2_lib.baseboard_fab2(sch_1):tp_cpu0_rsvd_10") )
				( member ( signalRef "@baseboard_fab2_lib.baseboard_fab2(sch_1):tp_cpu0_rsvd_11") )
				( member ( signalRef "@baseboard_fab2_lib.baseboard_fab2(sch_1):tp_cpu0_rsvd_12") )
				( member ( signalRef "@baseboard_fab2_lib.baseboard_fab2(sch_1):tp_cpu0_rsvd_13") )
				( member ( signalRef "@baseboard_fab2_lib.baseboard_fab2(sch_1):tp_cpu0_rsvd_14") )
				( member ( signalRef "@baseboard_fab2_lib.baseboard_fab2(sch_1):tp_cpu0_rsvd_15") )
				( member ( signalRef "@baseboard_fab2_lib.baseboard_fab2(sch_1):tp_cpu0_rsvd_16") )
				( member ( signalRef "@baseboard_fab2_lib.baseboard_fab2(sch_1):tp_cpu0_rsvd_17") )
				( member ( signalRef "@baseboard_fab2_lib.baseboard_fab2(sch_1):tp_cpu0_rsvd_18") )
				( member ( signalRef "@baseboard_fab2_lib.baseboard_fab2(sch_1):pu_cpu1_legacy_skt") )
				( member ( signalRef "@baseboard_fab2_lib.baseboard_fab2(sch_1):pu_cpu1_safe_mode_boot") )
				( member ( signalRef "@baseboard_fab2_lib.baseboard_fab2(sch_1):pu_cpu1_socket_id_0") )
				( member ( signalRef "@baseboard_fab2_lib.baseboard_fab2(sch_1):pu_cpu1_socket_id_1") )
				( member ( signalRef "@baseboard_fab2_lib.baseboard_fab2(sch_1):pu_cpu1_tsc_sync") )
				( member ( signalRef "@baseboard_fab2_lib.baseboard_fab2(sch_1):pu_cpu1_txt_agent") )
				( member ( signalRef "@baseboard_fab2_lib.baseboard_fab2(sch_1):pu_datain1_sata_0_r") )
				( member ( signalRef "@baseboard_fab2_lib.baseboard_fab2(sch_1):pu_datain1_sata_1_r") )
				( member ( signalRef "@baseboard_fab2_lib.baseboard_fab2(sch_1):pu_datain1_sata_2") )
				( member ( signalRef "@baseboard_fab2_lib.baseboard_fab2(sch_1):pu_fm_rcin_n") )
				( member ( signalRef "@baseboard_fab2_lib.baseboard_fab2(sch_1):pu_gtl2014_1_dir") )
				( member ( signalRef "@baseboard_fab2_lib.baseboard_fab2(sch_1):pu_gtl2014_2_dir") )
				( member ( signalRef "@baseboard_fab2_lib.baseboard_fab2(sch_1):pu_irq_pch_sci_whea_n") )
				( member ( signalRef "@baseboard_fab2_lib.baseboard_fab2(sch_1):pu_irq_vralert_n") )
				( member ( signalRef "@baseboard_fab2_lib.baseboard_fab2(sch_1):pu_key_conn_pin2_r") )
				( member ( signalRef "@baseboard_fab2_lib.baseboard_fab2(sch_1):pu_lpc_clkrun_n") )
				( member ( signalRef "@baseboard_fab2_lib.baseboard_fab2(sch_1):pu_lpc_pme_n") )
				( member ( signalRef "@baseboard_fab2_lib.baseboard_fab2(sch_1):tp_pch_gpp_l10") )
				( member ( signalRef "@baseboard_fab2_lib.baseboard_fab2(sch_1):pu_nv_hold_n") )
				( member ( signalRef "@baseboard_fab2_lib.baseboard_fab2(sch_1):pu_nv_wp_n") )
				( member ( signalRef "@baseboard_fab2_lib.baseboard_fab2(sch_1):pu_pch_tls_enable_strap") )
				( member ( signalRef "@baseboard_fab2_lib.baseboard_fab2(sch_1):pu_pi7c9x1172_i2c_spi_n") )
				( member ( signalRef "@baseboard_fab2_lib.baseboard_fab2(sch_1):pu_rst_perst_bit0") )
				( member ( signalRef "@baseboard_fab2_lib.baseboard_fab2(sch_1):pu_rst_perst_bit1") )
				( member ( signalRef "@baseboard_fab2_lib.baseboard_fab2(sch_1):pwrgd_p12v_main_r") )
				( member ( signalRef "@baseboard_fab2_lib.baseboard_fab2(sch_1):smb_pch_mezz_lom0_scl") )
				( member ( signalRef "@baseboard_fab2_lib.baseboard_fab2(sch_1):smb_pch_mezz_lom1_sda") )
				( member ( signalRef "@baseboard_fab2_lib.baseboard_fab2(sch_1):smb_pch_mezz_lom2_scl") )
				( member ( signalRef "@baseboard_fab2_lib.baseboard_fab2(sch_1):smb_pch_mezz_lom2_sda") )
				( member ( signalRef "@baseboard_fab2_lib.baseboard_fab2(sch_1):smb_pch_mezz_lom3_scl") )
				( member ( signalRef "@baseboard_fab2_lib.baseboard_fab2(sch_1):smb_pch_mezz_lom0_sda") )
				( member ( signalRef "@baseboard_fab2_lib.baseboard_fab2(sch_1):smb_pch_mezz_lom1_scl") )
				( member ( signalRef "@baseboard_fab2_lib.baseboard_fab2(sch_1):pu_spi_bmc_bt_hold_n") )
				( member ( signalRef "@baseboard_fab2_lib.baseboard_fab2(sch_1):pu_spi_bmc_bt_wp_n") )
				( member ( signalRef "@baseboard_fab2_lib.baseboard_fab2(sch_1):pu_spi_flash_reset_2_n") )
				( member ( signalRef "@baseboard_fab2_lib.baseboard_fab2(sch_1):pu_spi0_rst") )
				( member ( signalRef "@baseboard_fab2_lib.baseboard_fab2(sch_1):pu_spi1_rst") )
				( member ( signalRef "@baseboard_fab2_lib.baseboard_fab2(sch_1):pu_sprv_lan_pwr_good") )
				( member ( signalRef "@baseboard_fab2_lib.baseboard_fab2(sch_1):pu_thermtrip_force_n") )
				( member ( signalRef "@baseboard_fab2_lib.baseboard_fab2(sch_1):pu_tmp421_1_a1") )
				( member ( signalRef "@baseboard_fab2_lib.baseboard_fab2(sch_1):pu_tmp421_2_a0") )
				( member ( signalRef "@baseboard_fab2_lib.baseboard_fab2(sch_1):pu_tri_state_en") )
				( member ( signalRef "@baseboard_fab2_lib.baseboard_fab2(sch_1):pu_vr_pvccin_cpu0_flt1_smbalt_n_imon") )
				( member ( signalRef "@baseboard_fab2_lib.baseboard_fab2(sch_1):pu_vr_pvccin_cpu0_imon") )
				( member ( signalRef "@baseboard_fab2_lib.baseboard_fab2(sch_1):pu_vr_pvccin_cpu1_flt1_smbalt_n_imon") )
				( member ( signalRef "@baseboard_fab2_lib.baseboard_fab2(sch_1):pu_vr_pvccio_cpu0_fault1") )
				( member ( signalRef "@baseboard_fab2_lib.baseboard_fab2(sch_1):pu_vr_pvccio_cpu1_fault1") )
				( member ( signalRef "@baseboard_fab2_lib.baseboard_fab2(sch_1):pu_vr_pvddq_abc_fault1") )
				( member ( signalRef "@baseboard_fab2_lib.baseboard_fab2(sch_1):pu_vr_pvddq_def_fault1") )
				( member ( signalRef "@baseboard_fab2_lib.baseboard_fab2(sch_1):pu_vr_pvddq_ghj_fault1") )
				( member ( signalRef "@baseboard_fab2_lib.baseboard_fab2(sch_1):pu_vr_pvddq_klm_fault1") )
				( member ( signalRef "@baseboard_fab2_lib.baseboard_fab2(sch_1):pu_vr_pvnn_pch_fault1") )
				( member ( signalRef "@baseboard_fab2_lib.baseboard_fab2(sch_1):pu_10gbe_lom_pci_disable_n") )
				( member ( signalRef "@baseboard_fab2_lib.baseboard_fab2(sch_1):tp_adc128_vref") )
				( member ( signalRef "@baseboard_fab2_lib.baseboard_fab2(sch_1):tp_cpu0_rsvd_275") )
				( member ( signalRef "@baseboard_fab2_lib.baseboard_fab2(sch_1):tp_bios_recover_boot") )
				( member ( signalRef "@baseboard_fab2_lib.baseboard_fab2(sch_1):tp_bios_usb_recovery") )
				( member ( signalRef "@baseboard_fab2_lib.baseboard_fab2(sch_1):tp_cd_hfi1_cpu1_int_n") )
				( member ( signalRef "@baseboard_fab2_lib.baseboard_fab2(sch_1):tp_cd_hfi1_cpu1_i2cdat") )
				( member ( signalRef "@baseboard_fab2_lib.baseboard_fab2(sch_1):tp_cd_hfi1_cpu1_i2clk") )
				( member ( signalRef "@baseboard_fab2_lib.baseboard_fab2(sch_1):tp_cd_hfi1_cpu1_led_n") )
				( member ( signalRef "@baseboard_fab2_lib.baseboard_fab2(sch_1):tp_cd_hfi1_cpu1_modprst_n") )
				( member ( signalRef "@baseboard_fab2_lib.baseboard_fab2(sch_1):tp_cd_hfi1_cpu1_reset_n") )
				( member ( signalRef "@baseboard_fab2_lib.baseboard_fab2(sch_1):tp_ch_a_dimm_a0_rfu_0") )
				( member ( signalRef "@baseboard_fab2_lib.baseboard_fab2(sch_1):tp_ch_a_dimm_a0_rfu_1") )
				( member ( signalRef "@baseboard_fab2_lib.baseboard_fab2(sch_1):tp_ch_a_dimm_a0_rfu_2") )
				( member ( signalRef "@baseboard_fab2_lib.baseboard_fab2(sch_1):tp_ch_a_dimm_a1_rfu_0") )
				( member ( signalRef "@baseboard_fab2_lib.baseboard_fab2(sch_1):tp_ch_a_dimm_a1_rfu_1") )
				( member ( signalRef "@baseboard_fab2_lib.baseboard_fab2(sch_1):tp_ch_a_dimm_a1_rfu_2") )
				( member ( signalRef "@baseboard_fab2_lib.baseboard_fab2(sch_1):tp_ch_b_dimm_b0_rfu_0") )
				( member ( signalRef "@baseboard_fab2_lib.baseboard_fab2(sch_1):tp_ch_b_dimm_b0_rfu_1") )
				( member ( signalRef "@baseboard_fab2_lib.baseboard_fab2(sch_1):tp_ch_b_dimm_b0_rfu_2") )
				( member ( signalRef "@baseboard_fab2_lib.baseboard_fab2(sch_1):tp_ch_b_dimm_b1_rfu_0") )
				( member ( signalRef "@baseboard_fab2_lib.baseboard_fab2(sch_1):tp_ch_b_dimm_b1_rfu_1") )
				( member ( signalRef "@baseboard_fab2_lib.baseboard_fab2(sch_1):tp_ch_b_dimm_b1_rfu_2") )
				( member ( signalRef "@baseboard_fab2_lib.baseboard_fab2(sch_1):tp_ch_c_dimm_c0_rfu_0") )
				( member ( signalRef "@baseboard_fab2_lib.baseboard_fab2(sch_1):tp_ch_c_dimm_c0_rfu_1") )
				( member ( signalRef "@baseboard_fab2_lib.baseboard_fab2(sch_1):tp_ch_c_dimm_c0_rfu_2") )
				( member ( signalRef "@baseboard_fab2_lib.baseboard_fab2(sch_1):tp_ch_c_dimm_c1_rfu_0") )
				( member ( signalRef "@baseboard_fab2_lib.baseboard_fab2(sch_1):tp_ch_c_dimm_c1_rfu_1") )
				( member ( signalRef "@baseboard_fab2_lib.baseboard_fab2(sch_1):tp_ch_c_dimm_c1_rfu_2") )
				( member ( signalRef "@baseboard_fab2_lib.baseboard_fab2(sch_1):tp_ch_d_dimm_d0_rfu_0") )
				( member ( signalRef "@baseboard_fab2_lib.baseboard_fab2(sch_1):tp_ch_d_dimm_d0_rfu_1") )
				( member ( signalRef "@baseboard_fab2_lib.baseboard_fab2(sch_1):tp_ch_d_dimm_d0_rfu_2") )
				( member ( signalRef "@baseboard_fab2_lib.baseboard_fab2(sch_1):tp_ch_d_dimm_d1_rfu_0") )
				( member ( signalRef "@baseboard_fab2_lib.baseboard_fab2(sch_1):tp_ch_d_dimm_d1_rfu_1") )
				( member ( signalRef "@baseboard_fab2_lib.baseboard_fab2(sch_1):tp_ch_d_dimm_d1_rfu_2") )
				( member ( signalRef "@baseboard_fab2_lib.baseboard_fab2(sch_1):tp_ch_e_dimm_e0_rfu_0") )
				( member ( signalRef "@baseboard_fab2_lib.baseboard_fab2(sch_1):tp_ch_e_dimm_e0_rfu_1") )
				( member ( signalRef "@baseboard_fab2_lib.baseboard_fab2(sch_1):tp_ch_e_dimm_e0_rfu_2") )
				( member ( signalRef "@baseboard_fab2_lib.baseboard_fab2(sch_1):tp_ch_e_dimm_e1_rfu_0") )
				( member ( signalRef "@baseboard_fab2_lib.baseboard_fab2(sch_1):tp_ch_e_dimm_e1_rfu_1") )
				( member ( signalRef "@baseboard_fab2_lib.baseboard_fab2(sch_1):tp_ch_e_dimm_e1_rfu_2") )
				( member ( signalRef "@baseboard_fab2_lib.baseboard_fab2(sch_1):tp_ch_f_dimm_f0_rfu_0") )
				( member ( signalRef "@baseboard_fab2_lib.baseboard_fab2(sch_1):tp_ch_f_dimm_f0_rfu_1") )
				( member ( signalRef "@baseboard_fab2_lib.baseboard_fab2(sch_1):tp_ch_f_dimm_f0_rfu_2") )
				( member ( signalRef "@baseboard_fab2_lib.baseboard_fab2(sch_1):tp_ch_f_dimm_f1_rfu_0") )
				( member ( signalRef "@baseboard_fab2_lib.baseboard_fab2(sch_1):tp_ch_f_dimm_f1_rfu_1") )
				( member ( signalRef "@baseboard_fab2_lib.baseboard_fab2(sch_1):tp_ch_f_dimm_f1_rfu_2") )
				( member ( signalRef "@baseboard_fab2_lib.baseboard_fab2(sch_1):nc_pvddq_abc_dnc0") )
				( member ( signalRef "@baseboard_fab2_lib.baseboard_fab2(sch_1):nc_pvddq_abc_dnc1") )
				( member ( signalRef "@baseboard_fab2_lib.baseboard_fab2(sch_1):tp_pvddq_abc_ph1_gl_0") )
				( member ( signalRef "@baseboard_fab2_lib.baseboard_fab2(sch_1):tp_pvddq_abc_ph2_gl_0") )
				( member ( signalRef "@baseboard_fab2_lib.baseboard_fab2(sch_1):nc_pvddq_def_dnc0") )
				( member ( signalRef "@baseboard_fab2_lib.baseboard_fab2(sch_1):nc_pvddq_def_dnc1") )
				( member ( signalRef "@baseboard_fab2_lib.baseboard_fab2(sch_1):tp_pvddq_def_ph1_gl_0") )
				( member ( signalRef "@baseboard_fab2_lib.baseboard_fab2(sch_1):tp_pvddq_def_ph2_gl_0") )
				( member ( signalRef "@baseboard_fab2_lib.baseboard_fab2(sch_1):nc_pvddq_ghj_dnc0") )
				( member ( signalRef "@baseboard_fab2_lib.baseboard_fab2(sch_1):nc_pvddq_ghj_dnc1") )
				( member ( signalRef "@baseboard_fab2_lib.baseboard_fab2(sch_1):tp_pvddq_ghj_ph1_gl_0") )
				( member ( signalRef "@baseboard_fab2_lib.baseboard_fab2(sch_1):tp_pvddq_ghj_ph2_gl_0") )
				( member ( signalRef "@baseboard_fab2_lib.baseboard_fab2(sch_1):nc_pvddq_ghj_pinalrt_n") )
				( member ( signalRef "@baseboard_fab2_lib.baseboard_fab2(sch_1):nc_pvddq_klm_dnc0") )
				( member ( signalRef "@baseboard_fab2_lib.baseboard_fab2(sch_1):nc_pvddq_klm_dnc1") )
				( member ( signalRef "@baseboard_fab2_lib.baseboard_fab2(sch_1):nc_pvddq_klm_gp0") )
				( member ( signalRef "@baseboard_fab2_lib.baseboard_fab2(sch_1):nc_pvddq_klm_gp1") )
				( member ( signalRef "@baseboard_fab2_lib.baseboard_fab2(sch_1):tp_pvddq_klm_ph1_gl_0") )
				( member ( signalRef "@baseboard_fab2_lib.baseboard_fab2(sch_1):tp_pvddq_klm_ph2_gl_0") )
				( member ( signalRef "@baseboard_fab2_lib.baseboard_fab2(sch_1):nc_pvddq_klm_pinalrt_n") )
				( member ( signalRef "@baseboard_fab2_lib.baseboard_fab2(sch_1):nc_pvddq_klm_pwm3") )
				( member ( signalRef "@baseboard_fab2_lib.baseboard_fab2(sch_1):nc_pvnn_pch_dnc0") )
				( member ( signalRef "@baseboard_fab2_lib.baseboard_fab2(sch_1):nc_pvnn_pch_dnc1") )
				( member ( signalRef "@baseboard_fab2_lib.baseboard_fab2(sch_1):nc_pvnn_pch_dnc2") )
				( member ( signalRef "@baseboard_fab2_lib.baseboard_fab2(sch_1):nc_pvnn_pch_dnc3") )
				( member ( signalRef "@baseboard_fab2_lib.baseboard_fab2(sch_1):nc_pvnn_pch_dnc4") )
				( member ( signalRef "@baseboard_fab2_lib.baseboard_fab2(sch_1):tp_pvddq_def_mp2") )
				( member ( signalRef "@baseboard_fab2_lib.baseboard_fab2(sch_1):tp_pvnn_pch_gl_0") )
				( member ( signalRef "@baseboard_fab2_lib.baseboard_fab2(sch_1):tp_pvsa_cpu0_gl_0") )
				( member ( signalRef "@baseboard_fab2_lib.baseboard_fab2(sch_1):tp_pvsa_cpu1_gl_0") )
				( member ( signalRef "@baseboard_fab2_lib.baseboard_fab2(sch_1):tp_p1v05_pch_gl_0") )
				( member ( signalRef "@baseboard_fab2_lib.baseboard_fab2(sch_1):nc_sprngvlle_22") )
				( member ( signalRef "@baseboard_fab2_lib.baseboard_fab2(sch_1):tp_usb_esd_ac2") )
				( member ( signalRef "@baseboard_fab2_lib.baseboard_fab2(sch_1):tp_usb_esd_ac3") )
				( member ( signalRef "@baseboard_fab2_lib.baseboard_fab2(sch_1):tp_usb_esd_out2") )
				( member ( signalRef "@baseboard_fab2_lib.baseboard_fab2(sch_1):tp_usb_esd_out3") )
				( member ( signalRef "@baseboard_fab2_lib.baseboard_fab2(sch_1):nic_led_act_anode_r") )
				( member ( signalRef "@baseboard_fab2_lib.baseboard_fab2(sch_1):pd_adcrext") )
				( member ( signalRef "@baseboard_fab2_lib.baseboard_fab2(sch_1):tp_cpu0_rsvd_282") )
				( member ( signalRef "@baseboard_fab2_lib.baseboard_fab2(sch_1):pd_ckmng_oe") )
				( member ( signalRef "@baseboard_fab2_lib.baseboard_fab2(sch_1):pd_cpu0_bist_enable") )
				( member ( signalRef "@baseboard_fab2_lib.baseboard_fab2(sch_1):pd_cpu0_dmimode_override") )
				( member ( signalRef "@baseboard_fab2_lib.baseboard_fab2(sch_1):pd_cpu0_ksfc_dis") )
				( member ( signalRef "@baseboard_fab2_lib.baseboard_fab2(sch_1):pd_cpu0_mcp01_dmon") )
				( member ( signalRef "@baseboard_fab2_lib.baseboard_fab2(sch_1):pd_cpu0_test12") )
				( member ( signalRef "@baseboard_fab2_lib.baseboard_fab2(sch_1):pd_cpu0_test13") )
				( member ( signalRef "@baseboard_fab2_lib.baseboard_fab2(sch_1):pd_cpu0_test14") )
				( member ( signalRef "@baseboard_fab2_lib.baseboard_fab2(sch_1):pd_cpu0_txt_plten") )
				( member ( signalRef "@baseboard_fab2_lib.baseboard_fab2(sch_1):pd_cpu1_bist_enable") )
				( member ( signalRef "@baseboard_fab2_lib.baseboard_fab2(sch_1):pd_cpu1_dmimode_override") )
				( member ( signalRef "@baseboard_fab2_lib.baseboard_fab2(sch_1):pd_cpu1_ksfc_dis") )
				( member ( signalRef "@baseboard_fab2_lib.baseboard_fab2(sch_1):pd_cpu1_mcp01_dmon") )
				( member ( signalRef "@baseboard_fab2_lib.baseboard_fab2(sch_1):pd_cpu1_test12") )
				( member ( signalRef "@baseboard_fab2_lib.baseboard_fab2(sch_1):pd_cpu1_test13") )
				( member ( signalRef "@baseboard_fab2_lib.baseboard_fab2(sch_1):pd_cpu1_test14") )
				( member ( signalRef "@baseboard_fab2_lib.baseboard_fab2(sch_1):pd_cpu1_txt_plten") )
				( member ( signalRef "@baseboard_fab2_lib.baseboard_fab2(sch_1):pd_dir_2") )
				( member ( signalRef "@baseboard_fab2_lib.baseboard_fab2(sch_1):pd_fru_wp") )
				( member ( signalRef "@baseboard_fab2_lib.baseboard_fab2(sch_1):pd_gtl2014_1_vref") )
				( member ( signalRef "@baseboard_fab2_lib.baseboard_fab2(sch_1):pd_gtl2014_2_vref") )
				( member ( signalRef "@baseboard_fab2_lib.baseboard_fab2(sch_1):pd_gtl2104_dir_0") )
				( member ( signalRef "@baseboard_fab2_lib.baseboard_fab2(sch_1):pd_gtl2104_dir_1") )
				( member ( signalRef "@baseboard_fab2_lib.baseboard_fab2(sch_1):pd_gtl2104_4_dir") )
				( member ( signalRef "@baseboard_fab2_lib.baseboard_fab2(sch_1):pd_hsc_retry_n") )
				( member ( signalRef "@baseboard_fab2_lib.baseboard_fab2(sch_1):pd_ie_debug_mode") )
				( member ( signalRef "@baseboard_fab2_lib.baseboard_fab2(sch_1):pd_me_rcvr_n") )
				( member ( signalRef "@baseboard_fab2_lib.baseboard_fab2(sch_1):pd_password_clear") )
				( member ( signalRef "@baseboard_fab2_lib.baseboard_fab2(sch_1):tp_pvddq_abc_mp2") )
				( member ( signalRef "@baseboard_fab2_lib.baseboard_fab2(sch_1):pd_perext") )
				( member ( signalRef "@baseboard_fab2_lib.baseboard_fab2(sch_1):pd_rst_rtcrst_n") )
				( member ( signalRef "@baseboard_fab2_lib.baseboard_fab2(sch_1):pd_sata0_controller_type_r") )
				( member ( signalRef "@baseboard_fab2_lib.baseboard_fab2(sch_1):pd_sata1_controller_type_r") )
				( member ( signalRef "@baseboard_fab2_lib.baseboard_fab2(sch_1):pd_sata2_controller_type") )
				( member ( signalRef "@baseboard_fab2_lib.baseboard_fab2(sch_1):smb_pch_mezz_lom3_sda") )
				( member ( signalRef "@baseboard_fab2_lib.baseboard_fab2(sch_1):tp_pch_gpp_j17") )
				( member ( signalRef "@baseboard_fab2_lib.baseboard_fab2(sch_1):pd_sprv_rset") )
				( member ( signalRef "@baseboard_fab2_lib.baseboard_fab2(sch_1):pd_sp_entest") )
				( member ( signalRef "@baseboard_fab2_lib.baseboard_fab2(sch_1):pd_tmp421_1_a0") )
				( member ( signalRef "@baseboard_fab2_lib.baseboard_fab2(sch_1):pd_tmp421_2_a1") )
				( member ( signalRef "@baseboard_fab2_lib.baseboard_fab2(sch_1):pd_usb_bmc_p1_dn") )
				( member ( signalRef "@baseboard_fab2_lib.baseboard_fab2(sch_1):pd_usb_bmc_p1_dp") )
				( member ( signalRef "@baseboard_fab2_lib.baseboard_fab2(sch_1):pu_adr_timer_hold_off_n") )
				( member ( signalRef "@baseboard_fab2_lib.baseboard_fab2(sch_1):pu_at24c64_a2") )
				( member ( signalRef "@baseboard_fab2_lib.baseboard_fab2(sch_1):pu_bios_recover_boot") )
				( member ( signalRef "@baseboard_fab2_lib.baseboard_fab2(sch_1):pu_bios_spi_hold0_n") )
				( member ( signalRef "@baseboard_fab2_lib.baseboard_fab2(sch_1):pu_bios_spi_hold1_n") )
				( member ( signalRef "@baseboard_fab2_lib.baseboard_fab2(sch_1):pu_bios_spi_wp1_n") )
				( member ( signalRef "@baseboard_fab2_lib.baseboard_fab2(sch_1):pu_bios_usb_recovery") )
				( member ( signalRef "@baseboard_fab2_lib.baseboard_fab2(sch_1):h_cpu0_bmcinit") )
				( member ( signalRef "@baseboard_fab2_lib.baseboard_fab2(sch_1):pu_cpu0_ear_n") )
				( member ( signalRef "@baseboard_fab2_lib.baseboard_fab2(sch_1):pu_cpu0_frmagent") )
				( member ( signalRef "@baseboard_fab2_lib.baseboard_fab2(sch_1):pu_cpu0_legacy_skt") )
				( member ( signalRef "@baseboard_fab2_lib.baseboard_fab2(sch_1):pu_cpu0_safe_mode_boot") )
				( member ( signalRef "@baseboard_fab2_lib.baseboard_fab2(sch_1):pu_cpu0_socket_id_0") )
				( member ( signalRef "@baseboard_fab2_lib.baseboard_fab2(sch_1):pu_cpu0_socket_id_1") )
				( member ( signalRef "@baseboard_fab2_lib.baseboard_fab2(sch_1):pu_cpu0_tsc_sync") )
				( member ( signalRef "@baseboard_fab2_lib.baseboard_fab2(sch_1):pu_cpu0_txt_agent") )
				( member ( signalRef "@baseboard_fab2_lib.baseboard_fab2(sch_1):h_cpu1_bmcinit") )
				( member ( signalRef "@baseboard_fab2_lib.baseboard_fab2(sch_1):pu_cpu1_ear_n") )
				( member ( signalRef "@baseboard_fab2_lib.baseboard_fab2(sch_1):pu_cpu1_frmagent") )
				( member ( signalRef "@baseboard_fab2_lib.baseboard_fab2(sch_1):tp_pvnn_pch_mp3") )
				( member ( signalRef "@baseboard_fab2_lib.baseboard_fab2(sch_1):tp_pch_gpp_j19") )
				( member ( signalRef "@baseboard_fab2_lib.baseboard_fab2(sch_1):led_hfi0_cpu0_n") )
				( member ( signalRef "@baseboard_fab2_lib.baseboard_fab2(sch_1):led_hfi1_cpu0_n") )
				( member ( signalRef "@baseboard_fab2_lib.baseboard_fab2(sch_1):led_lan_0_n") )
				( member ( signalRef "@baseboard_fab2_lib.baseboard_fab2(sch_1):led_lan_0_r_n") )
				( member ( signalRef "@baseboard_fab2_lib.baseboard_fab2(sch_1):led_lan_1_n") )
				( member ( signalRef "@baseboard_fab2_lib.baseboard_fab2(sch_1):tp_vr_pvccio_cpu0_mp2") )
				( member ( signalRef "@baseboard_fab2_lib.baseboard_fab2(sch_1):led_lan_1_r_n") )
				( member ( signalRef "@baseboard_fab2_lib.baseboard_fab2(sch_1):led_lan_2_n") )
				( member ( signalRef "@baseboard_fab2_lib.baseboard_fab2(sch_1):led_lan_2_r_n") )
				( member ( signalRef "@baseboard_fab2_lib.baseboard_fab2(sch_1):led_pch_sata_hdd_n") )
				( member ( signalRef "@baseboard_fab2_lib.baseboard_fab2(sch_1):led_pch_ssata_hdd_n") )
				( member ( signalRef "@baseboard_fab2_lib.baseboard_fab2(sch_1):led_postcode_0") )
				( member ( signalRef "@baseboard_fab2_lib.baseboard_fab2(sch_1):led_postcode_0_r") )
				( member ( signalRef "@baseboard_fab2_lib.baseboard_fab2(sch_1):led_postcode_1") )
				( member ( signalRef "@baseboard_fab2_lib.baseboard_fab2(sch_1):led_postcode_1_r") )
				( member ( signalRef "@baseboard_fab2_lib.baseboard_fab2(sch_1):led_postcode_2") )
				( member ( signalRef "@baseboard_fab2_lib.baseboard_fab2(sch_1):led_postcode_2_r") )
				( member ( signalRef "@baseboard_fab2_lib.baseboard_fab2(sch_1):led_postcode_3") )
				( member ( signalRef "@baseboard_fab2_lib.baseboard_fab2(sch_1):led_postcode_3_r") )
				( member ( signalRef "@baseboard_fab2_lib.baseboard_fab2(sch_1):led_postcode_4") )
				( member ( signalRef "@baseboard_fab2_lib.baseboard_fab2(sch_1):led_postcode_4_r") )
				( member ( signalRef "@baseboard_fab2_lib.baseboard_fab2(sch_1):led_postcode_5") )
				( member ( signalRef "@baseboard_fab2_lib.baseboard_fab2(sch_1):led_postcode_5_r") )
				( member ( signalRef "@baseboard_fab2_lib.baseboard_fab2(sch_1):led_postcode_6") )
				( member ( signalRef "@baseboard_fab2_lib.baseboard_fab2(sch_1):led_postcode_6_r") )
				( member ( signalRef "@baseboard_fab2_lib.baseboard_fab2(sch_1):led_postcode_7") )
				( member ( signalRef "@baseboard_fab2_lib.baseboard_fab2(sch_1):led_postcode_7_r") )
				( member ( signalRef "@baseboard_fab2_lib.baseboard_fab2(sch_1):led_p5v_stby") )
				( member ( signalRef "@baseboard_fab2_lib.baseboard_fab2(sch_1):led_sas_act_r_n") )
				( member ( signalRef "@baseboard_fab2_lib.baseboard_fab2(sch_1):led_sata_act_r_n") )
				( member ( signalRef "@baseboard_fab2_lib.baseboard_fab2(sch_1):nc_clk_156m_cpu0_osc") )
				( member ( signalRef "@baseboard_fab2_lib.baseboard_fab2(sch_1):nc_clk_156m_cpu1_osc") )
				( member ( signalRef "@baseboard_fab2_lib.baseboard_fab2(sch_1):nc_cpld1") )
				( member ( signalRef "@baseboard_fab2_lib.baseboard_fab2(sch_1):nc_db1200zl(0)") )
				( member ( signalRef "@baseboard_fab2_lib.baseboard_fab2(sch_1):nc_db1200zl(1)") )
				( member ( signalRef "@baseboard_fab2_lib.baseboard_fab2(sch_1):nc_db1200zl(2)") )
				( member ( signalRef "@baseboard_fab2_lib.baseboard_fab2(sch_1):tp_slg55021_p12v_main_8") )
				( member ( signalRef "@baseboard_fab2_lib.baseboard_fab2(sch_1):tp_led_m2_act_n") )
				( member ( signalRef "@baseboard_fab2_lib.baseboard_fab2(sch_1):nc_m2(0)") )
				( member ( signalRef "@baseboard_fab2_lib.baseboard_fab2(sch_1):nc_m2(1)") )
				( member ( signalRef "@baseboard_fab2_lib.baseboard_fab2(sch_1):nc_m2(2)") )
				( member ( signalRef "@baseboard_fab2_lib.baseboard_fab2(sch_1):nc_m2(3)") )
				( member ( signalRef "@baseboard_fab2_lib.baseboard_fab2(sch_1):nc_m2(4)") )
				( member ( signalRef "@baseboard_fab2_lib.baseboard_fab2(sch_1):nc_m2(5)") )
				( member ( signalRef "@baseboard_fab2_lib.baseboard_fab2(sch_1):nc_m2(6)") )
				( member ( signalRef "@baseboard_fab2_lib.baseboard_fab2(sch_1):nc_m2(7)") )
				( member ( signalRef "@baseboard_fab2_lib.baseboard_fab2(sch_1):nc_m2(8)") )
				( member ( signalRef "@baseboard_fab2_lib.baseboard_fab2(sch_1):nc_m2(9)") )
				( member ( signalRef "@baseboard_fab2_lib.baseboard_fab2(sch_1):nc_m2(10)") )
				( member ( signalRef "@baseboard_fab2_lib.baseboard_fab2(sch_1):nc_m2(11)") )
				( member ( signalRef "@baseboard_fab2_lib.baseboard_fab2(sch_1):nc_m2(12)") )
				( member ( signalRef "@baseboard_fab2_lib.baseboard_fab2(sch_1):nc_m2(13)") )
				( member ( signalRef "@baseboard_fab2_lib.baseboard_fab2(sch_1):nc_m2(14)") )
				( member ( signalRef "@baseboard_fab2_lib.baseboard_fab2(sch_1):nc_m2(15)") )
				( member ( signalRef "@baseboard_fab2_lib.baseboard_fab2(sch_1):nc_m2(16)") )
				( member ( signalRef "@baseboard_fab2_lib.baseboard_fab2(sch_1):nc_m2(17)") )
				( member ( signalRef "@baseboard_fab2_lib.baseboard_fab2(sch_1):nc_m2(18)") )
				( member ( signalRef "@baseboard_fab2_lib.baseboard_fab2(sch_1):tp_cpu0_rsvd_283") )
				( member ( signalRef "@baseboard_fab2_lib.baseboard_fab2(sch_1):tp_m2_devslp") )
				( member ( signalRef "@baseboard_fab2_lib.baseboard_fab2(sch_1):tp_m2_32m_susclk") )
				( member ( signalRef "@baseboard_fab2_lib.baseboard_fab2(sch_1):nc_pi7c9x1172_1") )
				( member ( signalRef "@baseboard_fab2_lib.baseboard_fab2(sch_1):nc_pi7c9x1172_8") )
				( member ( signalRef "@baseboard_fab2_lib.baseboard_fab2(sch_1):tp_pvsa_cpu1_gl_1") )
				( member ( signalRef "@baseboard_fab2_lib.baseboard_fab2(sch_1):tp_pvccin_cpu0_ph2_gl_0") )
				( member ( signalRef "@baseboard_fab2_lib.baseboard_fab2(sch_1):tp_pvccin_cpu0_ph3_gl_0") )
				( member ( signalRef "@baseboard_fab2_lib.baseboard_fab2(sch_1):tp_pvccin_cpu0_ph4_gl_0") )
				( member ( signalRef "@baseboard_fab2_lib.baseboard_fab2(sch_1):led_gbe_p0_0") )
				( member ( signalRef "@baseboard_fab2_lib.baseboard_fab2(sch_1):tp_pvccin_cpu0_ph5_gl_0") )
				( member ( signalRef "@baseboard_fab2_lib.baseboard_fab2(sch_1):tp_pvccinc_cpu1_ph1_gl_0") )
				( member ( signalRef "@baseboard_fab2_lib.baseboard_fab2(sch_1):tp_pvccinc_cpu1_ph2_gl_0") )
				( member ( signalRef "@baseboard_fab2_lib.baseboard_fab2(sch_1):tp_pvccin_cpu1_ph3_gl_0") )
				( member ( signalRef "@baseboard_fab2_lib.baseboard_fab2(sch_1):tp_pvccin_cpu1_ph4_gl_0") )
				( member ( signalRef "@baseboard_fab2_lib.baseboard_fab2(sch_1):tp_pvccin_cpu1_ph5_gl_0") )
				( member ( signalRef "@baseboard_fab2_lib.baseboard_fab2(sch_1):nc_pvccio_cpu0_dnc0") )
				( member ( signalRef "@baseboard_fab2_lib.baseboard_fab2(sch_1):nc_pvccio_cpu0_dnc1") )
				( member ( signalRef "@baseboard_fab2_lib.baseboard_fab2(sch_1):nc_pvccio_cpu0_dnc2") )
				( member ( signalRef "@baseboard_fab2_lib.baseboard_fab2(sch_1):nc_pvccio_cpu0_dnc3") )
				( member ( signalRef "@baseboard_fab2_lib.baseboard_fab2(sch_1):nc_pvccio_cpu0_dnc4") )
				( member ( signalRef "@baseboard_fab2_lib.baseboard_fab2(sch_1):tp_pvddq_ghj_mp2") )
				( member ( signalRef "@baseboard_fab2_lib.baseboard_fab2(sch_1):tp_pvccio_cpu0_gl_0") )
				( member ( signalRef "@baseboard_fab2_lib.baseboard_fab2(sch_1):nc_pvccio_cpu1_dnc0") )
				( member ( signalRef "@baseboard_fab2_lib.baseboard_fab2(sch_1):nc_pvccio_cpu1_dnc1") )
				( member ( signalRef "@baseboard_fab2_lib.baseboard_fab2(sch_1):nc_pvccio_cpu1_dnc2") )
				( member ( signalRef "@baseboard_fab2_lib.baseboard_fab2(sch_1):nc_pvccio_cpu1_dnc3") )
				( member ( signalRef "@baseboard_fab2_lib.baseboard_fab2(sch_1):nc_pvccio_cpu1_dnc4") )
				( member ( signalRef "@baseboard_fab2_lib.baseboard_fab2(sch_1):tp_pvnn_pch_mp2") )
				( member ( signalRef "@baseboard_fab2_lib.baseboard_fab2(sch_1):tp_pvccio_cpu1_gl_0") )
				( member ( signalRef "@baseboard_fab2_lib.baseboard_fab2(sch_1):rst_pcie_riser1_perst_r_n") )
				( member ( signalRef "@baseboard_fab2_lib.baseboard_fab2(sch_1):rst_system_btn_buf_n") )
				( member ( signalRef "@baseboard_fab2_lib.baseboard_fab2(sch_1):sgpio_pch_ssata_dout0") )
				( member ( signalRef "@baseboard_fab2_lib.baseboard_fab2(sch_1):fm_cpu0_prochot_lvt3_k_n") )
				( member ( signalRef "@baseboard_fab2_lib.baseboard_fab2(sch_1):fm_cpu_err0_lvt3_k_n") )
				( member ( signalRef "@baseboard_fab2_lib.baseboard_fab2(sch_1):fm_cpu0_prochot_lvt3_r_n") )
				( member ( signalRef "@baseboard_fab2_lib.baseboard_fab2(sch_1):fm_cpu_err1_lvt3_bmc_n") )
				( member ( signalRef "@baseboard_fab2_lib.baseboard_fab2(sch_1):uart_mux_out_r") )
				( member ( signalRef "@baseboard_fab2_lib.baseboard_fab2(sch_1):led_gbe_p0_1") )
				( member ( signalRef "@baseboard_fab2_lib.baseboard_fab2(sch_1):xdp_pch_cpu_tck0") )
				( member ( signalRef "@baseboard_fab2_lib.baseboard_fab2(sch_1):xtal_pch_48m_in") )
				( member ( signalRef "@baseboard_fab2_lib.baseboard_fab2(sch_1):xtal_pch_48m_out") )
				( member ( signalRef "@baseboard_fab2_lib.baseboard_fab2(sch_1):jtag_mcp_tck_r") )
				( member ( signalRef "@baseboard_fab2_lib.baseboard_fab2(sch_1):xtal_25mhz_in") )
				( member ( signalRef "@baseboard_fab2_lib.baseboard_fab2(sch_1):xtal_25mhz_in_r") )
				( member ( signalRef "@baseboard_fab2_lib.baseboard_fab2(sch_1):xtal_25mhz_out_r") )
				( member ( signalRef "@baseboard_fab2_lib.baseboard_fab2(sch_1):xtal_33k_rtc1") )
				( member ( signalRef "@baseboard_fab2_lib.baseboard_fab2(sch_1):xtal_33k_rtc2") )
				( member ( signalRef "@baseboard_fab2_lib.baseboard_fab2(sch_1):fm_cpu0_prochot_lvt3_bmc_n") )
				( member ( signalRef "@baseboard_fab2_lib.baseboard_fab2(sch_1):fan_tach0_r") )
				( member ( signalRef "@baseboard_fab2_lib.baseboard_fab2(sch_1):led_gbe_p1_0") )
				( member ( signalRef "@baseboard_fab2_lib.baseboard_fab2(sch_1):vr_pvccin_cpu1_ph2_ocset") )
				( member ( signalRef "@baseboard_fab2_lib.baseboard_fab2(sch_1):vr_pvccin_cpu1_ph3_ocset") )
				( member ( signalRef "@baseboard_fab2_lib.baseboard_fab2(sch_1):nc_pvccin_cpu1_ph1_p31") )
				( member ( signalRef "@baseboard_fab2_lib.baseboard_fab2(sch_1):nc_pvccin_cpu1_ph2_p31") )
				( member ( signalRef "@baseboard_fab2_lib.baseboard_fab2(sch_1):nc_pvccin_cpu1_ph3_p31") )
				( member ( signalRef "@baseboard_fab2_lib.baseboard_fab2(sch_1):led_gbe_p1_1") )
				( member ( signalRef "@baseboard_fab2_lib.baseboard_fab2(sch_1):tp_usb3_p05_rxn") )
				( member ( signalRef "@baseboard_fab2_lib.baseboard_fab2(sch_1):tp_usb3_p05_rxp") )
				( member ( signalRef "@baseboard_fab2_lib.baseboard_fab2(sch_1):tp_usb3_p05_txn") )
				( member ( signalRef "@baseboard_fab2_lib.baseboard_fab2(sch_1):tp_usb3_p05_txp") )
				( member ( signalRef "@baseboard_fab2_lib.baseboard_fab2(sch_1):tp_usb3_p06_rxn") )
				( member ( signalRef "@baseboard_fab2_lib.baseboard_fab2(sch_1):tp_usb3_p06_rxp") )
				( member ( signalRef "@baseboard_fab2_lib.baseboard_fab2(sch_1):tp_usb3_p06_txn") )
				( member ( signalRef "@baseboard_fab2_lib.baseboard_fab2(sch_1):tp_usb3_p06_txp") )
				( member ( signalRef "@baseboard_fab2_lib.baseboard_fab2(sch_1):fan_pwm_out_sys0_r") )
				( member ( signalRef "@baseboard_fab2_lib.baseboard_fab2(sch_1):rmii_sprngvlle_bmc_pch_rxd0_r1") )
				( member ( signalRef "@baseboard_fab2_lib.baseboard_fab2(sch_1):rmii_sprngvlle_bmc_pch_rxd1_r1") )
				( member ( signalRef "@baseboard_fab2_lib.baseboard_fab2(sch_1):svid_alert_pvccio_cpu1") )
				( member ( signalRef "@baseboard_fab2_lib.baseboard_fab2(sch_1):svid_alert_pvccio_cpu0") )
				( member ( signalRef "@baseboard_fab2_lib.baseboard_fab2(sch_1):fan_pwm_out_sys1_buf") )
				( member ( signalRef "@baseboard_fab2_lib.baseboard_fab2(sch_1):fan_pwm_out_sys1_r") )
				( member ( signalRef "@baseboard_fab2_lib.baseboard_fab2(sch_1):fm_cpu1_prochot_lvt3_bmc_n") )
				( member ( signalRef "@baseboard_fab2_lib.baseboard_fab2(sch_1):tp_vr_pvccio_cpu0_mp3") )
				( member ( signalRef "@baseboard_fab2_lib.baseboard_fab2(sch_1):fm_bmc_nmi_n") )
				( member ( signalRef "@baseboard_fab2_lib.baseboard_fab2(sch_1):fm_bmc_sys_throttle_r_n") )
				( member ( signalRef "@baseboard_fab2_lib.baseboard_fab2(sch_1):clk_25m_bmc_r") )
				( member ( signalRef "@baseboard_fab2_lib.baseboard_fab2(sch_1):clk_32k_susclk_pld_r") )
				( member ( signalRef "@baseboard_fab2_lib.baseboard_fab2(sch_1):fm_cpu_caterr_lvt3_n") )
				( member ( signalRef "@baseboard_fab2_lib.baseboard_fab2(sch_1):rst_bmc_ddr3_buf_in_n") )
				( member ( signalRef "@baseboard_fab2_lib.baseboard_fab2(sch_1):fm_cpu_err0_lvt3_n") )
				( member ( signalRef "@baseboard_fab2_lib.baseboard_fab2(sch_1):fm_cpu_err0_lvt3_r_n") )
				( member ( signalRef "@baseboard_fab2_lib.baseboard_fab2(sch_1):fm_cpu_err1_lvt3_n") )
				( member ( signalRef "@baseboard_fab2_lib.baseboard_fab2(sch_1):fm_cpu_err1_lvt3_r_n") )
				( member ( signalRef "@baseboard_fab2_lib.baseboard_fab2(sch_1):fm_cpu_err2_lvt3_n") )
				( member ( signalRef "@baseboard_fab2_lib.baseboard_fab2(sch_1):tp_pch_gpp_l11") )
				( member ( signalRef "@baseboard_fab2_lib.baseboard_fab2(sch_1):clk_50m_ckmng_pch_10gbe") )
				( member ( signalRef "@baseboard_fab2_lib.baseboard_fab2(sch_1):clk_50m_ckmng_ocp_r") )
				( member ( signalRef "@baseboard_fab2_lib.baseboard_fab2(sch_1):clk_50m_ckmng_ocp") )
				( member ( signalRef "@baseboard_fab2_lib.baseboard_fab2(sch_1):clk_50m_ckmng_bmc_1_r") )
				( member ( signalRef "@baseboard_fab2_lib.baseboard_fab2(sch_1):clk_50m_ckmng_bmc_1") )
				( member ( signalRef "@baseboard_fab2_lib.baseboard_fab2(sch_1):fan_pwm_out_sys0_buf") )
				( member ( signalRef "@baseboard_fab2_lib.baseboard_fab2(sch_1):clk_50m_ckmng_pch_10gbe_r") )
				( member ( signalRef "@baseboard_fab2_lib.baseboard_fab2(sch_1):fm_cpu_msmi_lvt3_n") )
				( member ( signalRef "@baseboard_fab2_lib.baseboard_fab2(sch_1):fm_cpu_msmi_lvt3_r_n") )
				( member ( signalRef "@baseboard_fab2_lib.baseboard_fab2(sch_1):clk_32k_susclk_pld") )
				( member ( signalRef "@baseboard_fab2_lib.baseboard_fab2(sch_1):fm_cpu0_fivr_fault_lvt3") )
				( member ( signalRef "@baseboard_fab2_lib.baseboard_fab2(sch_1):fm_cpu0_fivr_fault_lvt3_n") )
				( member ( signalRef "@baseboard_fab2_lib.baseboard_fab2(sch_1):fm_cpu0_fivr_fault_lvt3_r_n") )
				( member ( signalRef "@baseboard_fab2_lib.baseboard_fab2(sch_1):fm_cpu0_fivr_fault_lvt3_r2_n") )
				( member ( signalRef "@baseboard_fab2_lib.baseboard_fab2(sch_1):fm_cpu0_prochot_lvt3_n") )
				( member ( signalRef "@baseboard_fab2_lib.baseboard_fab2(sch_1):fm_cpu_err2_lvt3_r_n") )
				( member ( signalRef "@baseboard_fab2_lib.baseboard_fab2(sch_1):fm_cpu0_thermtrip_lvt3_n") )
				( member ( signalRef "@baseboard_fab2_lib.baseboard_fab2(sch_1):fm_cpu0_thermtrip_lvt3_r_n") )
				( member ( signalRef "@baseboard_fab2_lib.baseboard_fab2(sch_1):fm_cpu1_fivr_fault_lvt3") )
				( member ( signalRef "@baseboard_fab2_lib.baseboard_fab2(sch_1):fm_cpu1_fivr_fault_lvt3_n") )
				( member ( signalRef "@baseboard_fab2_lib.baseboard_fab2(sch_1):fm_cpu1_fivr_fault_lvt3_r_n") )
				( member ( signalRef "@baseboard_fab2_lib.baseboard_fab2(sch_1):fm_cpu1_fivr_fault_lvt3_r1_n") )
				( member ( signalRef "@baseboard_fab2_lib.baseboard_fab2(sch_1):fm_cpu1_prochot_lvt3_n") )
				( member ( signalRef "@baseboard_fab2_lib.baseboard_fab2(sch_1):fm_cpu_caterr_lvt3_r2_n") )
				( member ( signalRef "@baseboard_fab2_lib.baseboard_fab2(sch_1):fm_cpu1_thermtrip_lvt3_n") )
				( member ( signalRef "@baseboard_fab2_lib.baseboard_fab2(sch_1):fm_cpu1_thermtrip_lvt3_r_n") )
				( member ( signalRef "@baseboard_fab2_lib.baseboard_fab2(sch_1):fm_ctnr_ps_on") )
				( member ( signalRef "@baseboard_fab2_lib.baseboard_fab2(sch_1):fm_ctnr_ps_on_r") )
				( member ( signalRef "@baseboard_fab2_lib.baseboard_fab2(sch_1):fm_db_uart_sel0_n") )
				( member ( signalRef "@baseboard_fab2_lib.baseboard_fab2(sch_1):fm_debug_rst_btn_n") )
				( member ( signalRef "@baseboard_fab2_lib.baseboard_fab2(sch_1):fm_debug_rst_btn_r1_n") )
				( member ( signalRef "@baseboard_fab2_lib.baseboard_fab2(sch_1):fm_m2_det_lvc3") )
				( member ( signalRef "@baseboard_fab2_lib.baseboard_fab2(sch_1):clk_25m_bmc") )
				( member ( signalRef "@baseboard_fab2_lib.baseboard_fab2(sch_1):fm_nmi_event_n") )
				( member ( signalRef "@baseboard_fab2_lib.baseboard_fab2(sch_1):fm_pch_sata_raid_key") )
				( member ( signalRef "@baseboard_fab2_lib.baseboard_fab2(sch_1):fm_pch_sata_raid_key_r") )
				( member ( signalRef "@baseboard_fab2_lib.baseboard_fab2(sch_1):fm_pvtt_ghj_en_r") )
				( member ( signalRef "@baseboard_fab2_lib.baseboard_fab2(sch_1):fm_pvtt_klm_en_r") )
				( member ( signalRef "@baseboard_fab2_lib.baseboard_fab2(sch_1):fm_pwr_btn_n") )
				( member ( signalRef "@baseboard_fab2_lib.baseboard_fab2(sch_1):fm_pwr_btn_r_n") )
				( member ( signalRef "@baseboard_fab2_lib.baseboard_fab2(sch_1):spi_switch_mosi_r0") )
				( member ( signalRef "@baseboard_fab2_lib.baseboard_fab2(sch_1):spi_switch_mosi_r1") )
				( member ( signalRef "@baseboard_fab2_lib.baseboard_fab2(sch_1):smb_slotx24_pch_stby_lvc3_scl") )
				( member ( signalRef "@baseboard_fab2_lib.baseboard_fab2(sch_1):pu_24m_osc_oe") )
				( member ( signalRef "@baseboard_fab2_lib.baseboard_fab2(sch_1):pwrgd_p1v8mcp_cpu1") )
				( member ( signalRef "@baseboard_fab2_lib.baseboard_fab2(sch_1):a_hsc_low_drain") )
				( member ( signalRef "@baseboard_fab2_lib.baseboard_fab2(sch_1):fm_bmc_disable") )
				( member ( signalRef "@baseboard_fab2_lib.baseboard_fab2(sch_1):fm_bmc_enable_n") )
				( member ( signalRef "@baseboard_fab2_lib.baseboard_fab2(sch_1):rst_bmc_srst_n") )
				( member ( signalRef "@baseboard_fab2_lib.baseboard_fab2(sch_1):pwrgd_pvccio_cpu0") )
				( member ( signalRef "@baseboard_fab2_lib.baseboard_fab2(sch_1):pwrgd_pvccio_cpu1") )
				( member ( signalRef "@baseboard_fab2_lib.baseboard_fab2(sch_1):pwrgd_pvccio_cpu1_r") )
				( member ( signalRef "@baseboard_fab2_lib.baseboard_fab2(sch_1):xdp_spi_pch_mosi_boot_halt_n") )
				( member ( signalRef "@baseboard_fab2_lib.baseboard_fab2(sch_1):fan_pwm_out_sys0_r1") )
				( member ( signalRef "@baseboard_fab2_lib.baseboard_fab2(sch_1):fan_tach1_r") )
				( member ( signalRef "@baseboard_fab2_lib.baseboard_fab2(sch_1):fan_tach2_r") )
				( member ( signalRef "@baseboard_fab2_lib.baseboard_fab2(sch_1):fan_tach3_r") )
				( member ( signalRef "@baseboard_fab2_lib.baseboard_fab2(sch_1):fm_adr_smi_gpio_r_n") )
				( member ( signalRef "@baseboard_fab2_lib.baseboard_fab2(sch_1):rst_pch_sysrst_btn_out_n") )
				( member ( signalRef "@baseboard_fab2_lib.baseboard_fab2(sch_1):rst_pltrst_top_swap") )
				( member ( signalRef "@baseboard_fab2_lib.baseboard_fab2(sch_1):smb_pehpcpu1_stby_lvc3_r_scl") )
				( member ( signalRef "@baseboard_fab2_lib.baseboard_fab2(sch_1):smb_pehpcpu1_stby_lvc3_r_sda") )
				( member ( signalRef "@baseboard_fab2_lib.baseboard_fab2(sch_1):fm_pvccin_pvccsa_cpu0_en_lvc1") )
				( member ( signalRef "@baseboard_fab2_lib.baseboard_fab2(sch_1):fm_pvddq_def_en") )
				( member ( signalRef "@baseboard_fab2_lib.baseboard_fab2(sch_1):fm_pvddq_klm_en") )
				( member ( signalRef "@baseboard_fab2_lib.baseboard_fab2(sch_1):vr_pvccin_cpu0_vren") )
				( member ( signalRef "@baseboard_fab2_lib.baseboard_fab2(sch_1):vr_pvddq_def_vren") )
				( member ( signalRef "@baseboard_fab2_lib.baseboard_fab2(sch_1):vr_pvddq_klm_vren") )
				( member ( signalRef "@baseboard_fab2_lib.baseboard_fab2(sch_1):vr_pvnn_pch_vren") )
				( member ( signalRef "@baseboard_fab2_lib.baseboard_fab2(sch_1):vr_p3v3_stby_en") )
				( member ( signalRef "@baseboard_fab2_lib.baseboard_fab2(sch_1):jtag_mcp_tms_r") )
				( member ( signalRef "@baseboard_fab2_lib.baseboard_fab2(sch_1):fm_bmc_fault_led") )
				( member ( signalRef "@baseboard_fab2_lib.baseboard_fab2(sch_1):fm_red_led_anode") )
				( member ( signalRef "@baseboard_fab2_lib.baseboard_fab2(sch_1):fm_red_led_cathode") )
				( member ( signalRef "@baseboard_fab2_lib.baseboard_fab2(sch_1):fp_led_hdd_activity_and_n") )
				( member ( signalRef "@baseboard_fab2_lib.baseboard_fab2(sch_1):fp_led_hdd_activity_and_r_n") )
				( member ( signalRef "@baseboard_fab2_lib.baseboard_fab2(sch_1):svid_vdio_pvccio_cpu0") )
				( member ( signalRef "@baseboard_fab2_lib.baseboard_fab2(sch_1):svid_vdio_pvccio_cpu1") )
				( member ( signalRef "@baseboard_fab2_lib.baseboard_fab2(sch_1):rst_rsmrst_dly") )
				( member ( signalRef "@baseboard_fab2_lib.baseboard_fab2(sch_1):tp_cpld1_pb16a_pclkt2_1") )
				( member ( signalRef "@baseboard_fab2_lib.baseboard_fab2(sch_1):tp_cpld1_pt24b") )
				( member ( signalRef "@baseboard_fab2_lib.baseboard_fab2(sch_1):tp_cpu0_rsvd_test_3") )
				( member ( signalRef "@baseboard_fab2_lib.baseboard_fab2(sch_1):fm_pvccin_pvccsa_cpu1_en_lvc1") )
				( member ( signalRef "@baseboard_fab2_lib.baseboard_fab2(sch_1):clk_50m_ckmng_bmc_2_r") )
				( member ( signalRef "@baseboard_fab2_lib.baseboard_fab2(sch_1):fm_cpu1_prochot_lvt3_k_n") )
				( member ( signalRef "@baseboard_fab2_lib.baseboard_fab2(sch_1):clk_50m_ckmng_sprvlle") )
				( member ( signalRef "@baseboard_fab2_lib.baseboard_fab2(sch_1):clk_50m_ckmng_sprvlle_r") )
				( member ( signalRef "@baseboard_fab2_lib.baseboard_fab2(sch_1):fm_adr_complete_abc_n") )
				( member ( signalRef "@baseboard_fab2_lib.baseboard_fab2(sch_1):fm_adr_complete_def_n") )
				( member ( signalRef "@baseboard_fab2_lib.baseboard_fab2(sch_1):fm_adr_complete_ghj_n") )
				( member ( signalRef "@baseboard_fab2_lib.baseboard_fab2(sch_1):fm_adr_complete_klm_n") )
				( member ( signalRef "@baseboard_fab2_lib.baseboard_fab2(sch_1):fm_mem_therm_event_lvt3_n") )
				( member ( signalRef "@baseboard_fab2_lib.baseboard_fab2(sch_1):irq_dimm_save_n") )
				( member ( signalRef "@baseboard_fab2_lib.baseboard_fab2(sch_1):spi_nic_cs_n") )
				( member ( signalRef "@baseboard_fab2_lib.baseboard_fab2(sch_1):spi_nic_cs_r_n") )
				( member ( signalRef "@baseboard_fab2_lib.baseboard_fab2(sch_1):spi_nic_miso") )
				( member ( signalRef "@baseboard_fab2_lib.baseboard_fab2(sch_1):spi_nic_miso_r") )
				( member ( signalRef "@baseboard_fab2_lib.baseboard_fab2(sch_1):spi_nic_mosi") )
				( member ( signalRef "@baseboard_fab2_lib.baseboard_fab2(sch_1):spi_nic_mosi_r") )
				( member ( signalRef "@baseboard_fab2_lib.baseboard_fab2(sch_1):spi_nic_sclk") )
				( member ( signalRef "@baseboard_fab2_lib.baseboard_fab2(sch_1):spi_nic_sclk_r") )
				( member ( signalRef "@baseboard_fab2_lib.baseboard_fab2(sch_1):fm_bmc_cpld_mp_rst_n") )
				( member ( signalRef "@baseboard_fab2_lib.baseboard_fab2(sch_1):fm_cpld_dbg_pwr_en_r_n") )
				( member ( signalRef "@baseboard_fab2_lib.baseboard_fab2(sch_1):fm_oc_detect_en_n") )
				( member ( signalRef "@baseboard_fab2_lib.baseboard_fab2(sch_1):irq_dimm_save_r_n") )
				( member ( signalRef "@baseboard_fab2_lib.baseboard_fab2(sch_1):fm_cpld_dbg_pwr_en") )
				( member ( signalRef "@baseboard_fab2_lib.baseboard_fab2(sch_1):fm_pvddq_abc_en") )
				( member ( signalRef "@baseboard_fab2_lib.baseboard_fab2(sch_1):irq_oob_mgmt_riser_alert_n") )
				( member ( signalRef "@baseboard_fab2_lib.baseboard_fab2(sch_1):fm_pch_pld_data_r") )
				( member ( signalRef "@baseboard_fab2_lib.baseboard_fab2(sch_1):vr_pvddq_ghj_vren") )
				( member ( signalRef "@baseboard_fab2_lib.baseboard_fab2(sch_1):fm_pvddq_ghj_en") )
				( member ( signalRef "@baseboard_fab2_lib.baseboard_fab2(sch_1):vr_pvddq_abc_vren") )
				( member ( signalRef "@baseboard_fab2_lib.baseboard_fab2(sch_1):fm_pvpp_cpu0_en") )
				( member ( signalRef "@baseboard_fab2_lib.baseboard_fab2(sch_1):fm_pvpp_cpu1_en") )
				( member ( signalRef "@baseboard_fab2_lib.baseboard_fab2(sch_1):clk_25m_cpld_r") )
				( member ( signalRef "@baseboard_fab2_lib.baseboard_fab2(sch_1):clk_25m_cpld") )
				( member ( signalRef "@baseboard_fab2_lib.baseboard_fab2(sch_1):clk_50m_ckmng_bmc_2") )
				( member ( signalRef "@baseboard_fab2_lib.baseboard_fab2(sch_1):sp1_host_bridge_uart_tx") )
				( member ( signalRef "@baseboard_fab2_lib.baseboard_fab2(sch_1):fm_sint_prsnt_n") )
				( member ( signalRef "@baseboard_fab2_lib.baseboard_fab2(sch_1):fm_adr_complete_r") )
				( member ( signalRef "@baseboard_fab2_lib.baseboard_fab2(sch_1):fm_adr_complete_r1") )
				( member ( signalRef "@baseboard_fab2_lib.baseboard_fab2(sch_1):uart_bridge_rxd5") )
				( member ( signalRef "@baseboard_fab2_lib.baseboard_fab2(sch_1):rst_bmc_sysrst_btn_out_b_r_n") )
				( member ( signalRef "@baseboard_fab2_lib.baseboard_fab2(sch_1):fm_adr_complete_dly") )
				( member ( signalRef "@baseboard_fab2_lib.baseboard_fab2(sch_1):fan_tach1_cpu1_d1") )
				( member ( signalRef "@baseboard_fab2_lib.baseboard_fab2(sch_1):uart_bridge_txd5") )
				( member ( signalRef "@baseboard_fab2_lib.baseboard_fab2(sch_1):pwrgd_cpu0_g_r") )
				( member ( signalRef "@baseboard_fab2_lib.baseboard_fab2(sch_1):sp1_host_bridge_uart_rx") )
				( member ( signalRef "@baseboard_fab2_lib.baseboard_fab2(sch_1):fm_pch_pld_data") )
				( member ( signalRef "@baseboard_fab2_lib.baseboard_fab2(sch_1):irq_pch_nic_alert_n") )
				( member ( signalRef "@baseboard_fab2_lib.baseboard_fab2(sch_1):fm_cpld_dbg_pwr_en_n") )
				( member ( signalRef "@baseboard_fab2_lib.baseboard_fab2(sch_1):fm_cpld_uart_ch_lock_n") )
				( member ( signalRef "@baseboard_fab2_lib.baseboard_fab2(sch_1):fm_flash_desc_override") )
				( member ( signalRef "@baseboard_fab2_lib.baseboard_fab2(sch_1):fm_flash_desc_override_r") )
				( member ( signalRef "@baseboard_fab2_lib.baseboard_fab2(sch_1):fm_mem_therm_event_pch_n") )
				( member ( signalRef "@baseboard_fab2_lib.baseboard_fab2(sch_1):fm_pch_pwrbtn_out_n") )
				( member ( signalRef "@baseboard_fab2_lib.baseboard_fab2(sch_1):clk_24m_bmc_clkin_r") )
				( member ( signalRef "@baseboard_fab2_lib.baseboard_fab2(sch_1):fm_p1v8mcp_cpu1_en") )
				( member ( signalRef "@baseboard_fab2_lib.baseboard_fab2(sch_1):fm_pvpp_pvddq_cpu0_en_abc") )
				( member ( signalRef "@baseboard_fab2_lib.baseboard_fab2(sch_1):fm_pvpp_pvddq_cpu0_en_def") )
				( member ( signalRef "@baseboard_fab2_lib.baseboard_fab2(sch_1):fm_pvpp_pvddq_cpu1_en_ghj") )
				( member ( signalRef "@baseboard_fab2_lib.baseboard_fab2(sch_1):fm_pvpp_pvddq_cpu1_en_klm") )
				( member ( signalRef "@baseboard_fab2_lib.baseboard_fab2(sch_1):fm_thermtrip_dly_r") )
				( member ( signalRef "@baseboard_fab2_lib.baseboard_fab2(sch_1):fm_uart_alert_n") )
				( member ( signalRef "@baseboard_fab2_lib.baseboard_fab2(sch_1):fan_tach3_cpu1_d1") )
				( member ( signalRef "@baseboard_fab2_lib.baseboard_fab2(sch_1):fan_tach1_cpu1_d2") )
				( member ( signalRef "@baseboard_fab2_lib.baseboard_fab2(sch_1):fan_tach3_cpu1_d2") )
				( member ( signalRef "@baseboard_fab2_lib.baseboard_fab2(sch_1):nc_pvccin_cpu1_ph4_p31") )
				( member ( signalRef "@baseboard_fab2_lib.baseboard_fab2(sch_1):xdp_cpu_tck_buf") )
				( member ( signalRef "@baseboard_fab2_lib.baseboard_fab2(sch_1):tp_vr_pvccio_cpu1_mp2") )
				( member ( signalRef "@baseboard_fab2_lib.baseboard_fab2(sch_1):nc_pvccin_cpu1_ph5_p31") )
				( member ( signalRef "@baseboard_fab2_lib.baseboard_fab2(sch_1):nc_pvsa_cpu1_p31") )
				( member ( signalRef "@baseboard_fab2_lib.baseboard_fab2(sch_1):rmii_bmc_ocp_rxd0_r") )
				( member ( signalRef "@baseboard_fab2_lib.baseboard_fab2(sch_1):rmii_bmc_ocp_crsdv_r") )
				( member ( signalRef "@baseboard_fab2_lib.baseboard_fab2(sch_1):smb_pehpcpu1_stby_lvc3_scl") )
				( member ( signalRef "@baseboard_fab2_lib.baseboard_fab2(sch_1):smb_pehpcpu1_stby_lvc3_sda") )
				( member ( signalRef "@baseboard_fab2_lib.baseboard_fab2(sch_1):rmii_bmc_pch_sprngvlle_rxer_r") )
				( member ( signalRef "@baseboard_fab2_lib.baseboard_fab2(sch_1):rmii_bmc_ocp_rxer_r") )
				( member ( signalRef "@baseboard_fab2_lib.baseboard_fab2(sch_1):rmii_bmc_ocp_rxd1_r") )
				( member ( signalRef "@baseboard_fab2_lib.baseboard_fab2(sch_1):rmii_pch_sprngvlle_arb_in_r") )
				( member ( signalRef "@baseboard_fab2_lib.baseboard_fab2(sch_1):smb_sensor_bmc_stby_lvc3_scl") )
				( member ( signalRef "@baseboard_fab2_lib.baseboard_fab2(sch_1):h_cpu0_fast_wake_b_n") )
				( member ( signalRef "@baseboard_fab2_lib.baseboard_fab2(sch_1):rmii_pch_sprngvlle_arb_out_r") )
				( member ( signalRef "@baseboard_fab2_lib.baseboard_fab2(sch_1):pu_jtag_sprv_tck") )
				( member ( signalRef "@baseboard_fab2_lib.baseboard_fab2(sch_1):pu_jtag_sprv_tdo") )
				( member ( signalRef "@baseboard_fab2_lib.baseboard_fab2(sch_1):pu_jtag_sprv_tms") )
				( member ( signalRef "@baseboard_fab2_lib.baseboard_fab2(sch_1):pu_jtag_sprv_tdi") )
				( member ( signalRef "@baseboard_fab2_lib.baseboard_fab2(sch_1):smb_sensor_stby_lvc3_scl") )
				( member ( signalRef "@baseboard_fab2_lib.baseboard_fab2(sch_1):smb_slotx24_bmc_stby_lvc3_scl") )
				( member ( signalRef "@baseboard_fab2_lib.baseboard_fab2(sch_1):smb_host_stby_lvc3_scl_r2") )
				( member ( signalRef "@baseboard_fab2_lib.baseboard_fab2(sch_1):sgpio_bmc_ld_n") )
				( member ( signalRef "@baseboard_fab2_lib.baseboard_fab2(sch_1):sgpio_bmc_ld_r_n") )
				( member ( signalRef "@baseboard_fab2_lib.baseboard_fab2(sch_1):h_cpu_err1_gtl_r_n") )
				( member ( signalRef "@baseboard_fab2_lib.baseboard_fab2(sch_1):spa_mid_dbg_rx") )
				( member ( signalRef "@baseboard_fab2_lib.baseboard_fab2(sch_1):spa_mid_dbg_tx") )
				( member ( signalRef "@baseboard_fab2_lib.baseboard_fab2(sch_1):spa_sin_sw_r") )
				( member ( signalRef "@baseboard_fab2_lib.baseboard_fab2(sch_1):fm_pvtt_def_en_r") )
				( member ( signalRef "@baseboard_fab2_lib.baseboard_fab2(sch_1):spi_pch_tpm_cs_n") )
				( member ( signalRef "@baseboard_fab2_lib.baseboard_fab2(sch_1):fm_ssata_pcie_m2_sel") )
				( member ( signalRef "@baseboard_fab2_lib.baseboard_fab2(sch_1):sp1_bmc_host_uart_rx") )
				( member ( signalRef "@baseboard_fab2_lib.baseboard_fab2(sch_1):sp1_bmc_host_uart_tx") )
				( member ( signalRef "@baseboard_fab2_lib.baseboard_fab2(sch_1):sp2_bmc_cm_uart_rx") )
				( member ( signalRef "@baseboard_fab2_lib.baseboard_fab2(sch_1):fp_pwr_btn_r1_n") )
				( member ( signalRef "@baseboard_fab2_lib.baseboard_fab2(sch_1):sp2_bmc_cm_uart_tx") )
				( member ( signalRef "@baseboard_fab2_lib.baseboard_fab2(sch_1):fp_rst_btn_r_n") )
				( member ( signalRef "@baseboard_fab2_lib.baseboard_fab2(sch_1):uart_mux_in_r") )
				( member ( signalRef "@baseboard_fab2_lib.baseboard_fab2(sch_1):h_cpu_caterr_g_n") )
				( member ( signalRef "@baseboard_fab2_lib.baseboard_fab2(sch_1):uart_bmc_rxd5") )
				( member ( signalRef "@baseboard_fab2_lib.baseboard_fab2(sch_1):uart_bmc_txd5") )
				( member ( signalRef "@baseboard_fab2_lib.baseboard_fab2(sch_1):fm_prsnt_2_2_n") )
				( member ( signalRef "@baseboard_fab2_lib.baseboard_fab2(sch_1):fm_prsnt_2_1_n") )
				( member ( signalRef "@baseboard_fab2_lib.baseboard_fab2(sch_1):h_cpu_msmi_g_n") )
				( member ( signalRef "@baseboard_fab2_lib.baseboard_fab2(sch_1):fm_100m_n") )
				( member ( signalRef "@baseboard_fab2_lib.baseboard_fab2(sch_1):fp_nmi_btn_r_n") )
				( member ( signalRef "@baseboard_fab2_lib.baseboard_fab2(sch_1):sgpio_bmc_clk") )
				( member ( signalRef "@baseboard_fab2_lib.baseboard_fab2(sch_1):h_cpu0_abc_memhot_lvt3_r_n") )
				( member ( signalRef "@baseboard_fab2_lib.baseboard_fab2(sch_1):sgpio_bmc_clk_r") )
				( member ( signalRef "@baseboard_fab2_lib.baseboard_fab2(sch_1):sgpio_pch_sata_clock") )
				( member ( signalRef "@baseboard_fab2_lib.baseboard_fab2(sch_1):sgpio_pch_sata_clock_r") )
				( member ( signalRef "@baseboard_fab2_lib.baseboard_fab2(sch_1):sgpio_pch_sata_dout0") )
				( member ( signalRef "@baseboard_fab2_lib.baseboard_fab2(sch_1):sgpio_pch_sata_dout0_r") )
				( member ( signalRef "@baseboard_fab2_lib.baseboard_fab2(sch_1):sgpio_pch_sata_load") )
				( member ( signalRef "@baseboard_fab2_lib.baseboard_fab2(sch_1):sgpio_pch_sata_load_r") )
				( member ( signalRef "@baseboard_fab2_lib.baseboard_fab2(sch_1):sgpio_pch_ssata_clock") )
				( member ( signalRef "@baseboard_fab2_lib.baseboard_fab2(sch_1):sgpio_pch_ssata_clock_r") )
				( member ( signalRef "@baseboard_fab2_lib.baseboard_fab2(sch_1):sgpio_pch_ssata_dout0_r") )
				( member ( signalRef "@baseboard_fab2_lib.baseboard_fab2(sch_1):sgpio_pch_ssata_load") )
				( member ( signalRef "@baseboard_fab2_lib.baseboard_fab2(sch_1):sgpio_pch_ssata_load_r") )
				( member ( signalRef "@baseboard_fab2_lib.baseboard_fab2(sch_1):fm_adr_mode_sel_r") )
				( member ( signalRef "@baseboard_fab2_lib.baseboard_fab2(sch_1):fm_cpld_adr_trigger_r_n") )
				( member ( signalRef "@baseboard_fab2_lib.baseboard_fab2(sch_1):fm_cpu_caterr_dly_lvt3_n") )
				( member ( signalRef "@baseboard_fab2_lib.baseboard_fab2(sch_1):h_cpu0_caterr_g_n") )
				( member ( signalRef "@baseboard_fab2_lib.baseboard_fab2(sch_1):fm_uart_pres_n") )
				( member ( signalRef "@baseboard_fab2_lib.baseboard_fab2(sch_1):irq_hsc_fault_r_n") )
				( member ( signalRef "@baseboard_fab2_lib.baseboard_fab2(sch_1):irq_pvccin_cpu0_vrhot_lvc3_r_n") )
				( member ( signalRef "@baseboard_fab2_lib.baseboard_fab2(sch_1):irq_pvccin_cpu1_vrhot_lvc3_r_n") )
				( member ( signalRef "@baseboard_fab2_lib.baseboard_fab2(sch_1):irq_pvddq_abc_vrhot_lvt3_r_n") )
				( member ( signalRef "@baseboard_fab2_lib.baseboard_fab2(sch_1):irq_pvddq_def_vrhot_lvt3_r_n") )
				( member ( signalRef "@baseboard_fab2_lib.baseboard_fab2(sch_1):irq_pvddq_ghj_vrhot_lvt3_r_n") )
				( member ( signalRef "@baseboard_fab2_lib.baseboard_fab2(sch_1):irq_pvddq_klm_vrhot_lvt3_r_n") )
				( member ( signalRef "@baseboard_fab2_lib.baseboard_fab2(sch_1):irq_sml1_pmbus_alert_r_n") )
				( member ( signalRef "@baseboard_fab2_lib.baseboard_fab2(sch_1):irq_vm_int_r_n") )
				( member ( signalRef "@baseboard_fab2_lib.baseboard_fab2(sch_1):tp_vr_pvccio_cpu1_mp3") )
				( member ( signalRef "@baseboard_fab2_lib.baseboard_fab2(sch_1):vid_pch_core_pvnn_aux_vid_0") )
				( member ( signalRef "@baseboard_fab2_lib.baseboard_fab2(sch_1):h_cpu0_def_memhot_lvt3_r_n") )
				( member ( signalRef "@baseboard_fab2_lib.baseboard_fab2(sch_1):h_cpu0_err0_g_n") )
				( member ( signalRef "@baseboard_fab2_lib.baseboard_fab2(sch_1):h_cpu0_err1_g_n") )
				( member ( signalRef "@baseboard_fab2_lib.baseboard_fab2(sch_1):fm_uart_sel_n") )
				( member ( signalRef "@baseboard_fab2_lib.baseboard_fab2(sch_1):fp_pwr_btn_r_n") )
				( member ( signalRef "@baseboard_fab2_lib.baseboard_fab2(sch_1):fm_uart_switch_n") )
				( member ( signalRef "@baseboard_fab2_lib.baseboard_fab2(sch_1):fm_bios_top_swap") )
				( member ( signalRef "@baseboard_fab2_lib.baseboard_fab2(sch_1):h_cpu0_memabc_memhot_lvt3_n") )
				( member ( signalRef "@baseboard_fab2_lib.baseboard_fab2(sch_1):fm_bios_top_swap_spkr") )
				( member ( signalRef "@baseboard_fab2_lib.baseboard_fab2(sch_1):fm_bios_top_swap_spkr_r") )
				( member ( signalRef "@baseboard_fab2_lib.baseboard_fab2(sch_1):fm_fast_prochot_en_n") )
				( member ( signalRef "@baseboard_fab2_lib.baseboard_fab2(sch_1):fm_pch_bmc_thermtrip_n") )
				( member ( signalRef "@baseboard_fab2_lib.baseboard_fab2(sch_1):fm_pmbus_alert_buf_en_n") )
				( member ( signalRef "@baseboard_fab2_lib.baseboard_fab2(sch_1):fm_pwr_led") )
				( member ( signalRef "@baseboard_fab2_lib.baseboard_fab2(sch_1):fm_pwr_led_a") )
				( member ( signalRef "@baseboard_fab2_lib.baseboard_fab2(sch_1):fm_pwr_led_k") )
				( member ( signalRef "@baseboard_fab2_lib.baseboard_fab2(sch_1):fm_pwr_led_n") )
				( member ( signalRef "@baseboard_fab2_lib.baseboard_fab2(sch_1):fm_slt_cfg0") )
				( member ( signalRef "@baseboard_fab2_lib.baseboard_fab2(sch_1):fm_slt_cfg1") )
				( member ( signalRef "@baseboard_fab2_lib.baseboard_fab2(sch_1):fm_slt_cfg2_r") )
				( member ( signalRef "@baseboard_fab2_lib.baseboard_fab2(sch_1):fm_1gb_lom_disable_n") )
				( member ( signalRef "@baseboard_fab2_lib.baseboard_fab2(sch_1):fm_bb_bmc_mp_gpio") )
				( member ( signalRef "@baseboard_fab2_lib.baseboard_fab2(sch_1):fm_cpu0_thermtrip_latch_lvt3_n") )
				( member ( signalRef "@baseboard_fab2_lib.baseboard_fab2(sch_1):fm_cpu1_thermtrip_latch_lvt3_n") )
				( member ( signalRef "@baseboard_fab2_lib.baseboard_fab2(sch_1):h_cpu0_memdef_memhot_lvt3_n") )
				( member ( signalRef "@baseboard_fab2_lib.baseboard_fab2(sch_1):irq_bmc_pch_nmi_stby_r_n") )
				( member ( signalRef "@baseboard_fab2_lib.baseboard_fab2(sch_1):fm_pvtt_abc_en_r") )
				( member ( signalRef "@baseboard_fab2_lib.baseboard_fab2(sch_1):jtag_mcp_trst_n") )
				( member ( signalRef "@baseboard_fab2_lib.baseboard_fab2(sch_1):fm_bmc_cpu_init_n") )
				( member ( signalRef "@baseboard_fab2_lib.baseboard_fab2(sch_1):fan_pwm_out_sys0") )
				( member ( signalRef "@baseboard_fab2_lib.baseboard_fab2(sch_1):fan_pwm_out_sys1") )
				( member ( signalRef "@baseboard_fab2_lib.baseboard_fab2(sch_1):fm_cpld_bmc_pwrdn_n") )
				( member ( signalRef "@baseboard_fab2_lib.baseboard_fab2(sch_1):fp_id_led_p5v_stby_n") )
				( member ( signalRef "@baseboard_fab2_lib.baseboard_fab2(sch_1):fp_nmi_btn") )
				( member ( signalRef "@baseboard_fab2_lib.baseboard_fab2(sch_1):fp_nmi_btn_out_n") )
				( member ( signalRef "@baseboard_fab2_lib.baseboard_fab2(sch_1):fp_nmi_btn_out_r_n") )
				( member ( signalRef "@baseboard_fab2_lib.baseboard_fab2(sch_1):h_cpu_err0_gtl_r_n") )
				( member ( signalRef "@baseboard_fab2_lib.baseboard_fab2(sch_1):pwrgd_pvccio_cpu0_r") )
				( member ( signalRef "@baseboard_fab2_lib.baseboard_fab2(sch_1):pwrgd_pvsa_cpu0_r") )
				( member ( signalRef "@baseboard_fab2_lib.baseboard_fab2(sch_1):pwrgd_pvsa_cpu1_r") )
				( member ( signalRef "@baseboard_fab2_lib.baseboard_fab2(sch_1):pwrgd_pvtt_abc_cpu0_r") )
				( member ( signalRef "@baseboard_fab2_lib.baseboard_fab2(sch_1):pwrgd_pvtt_def_cpu0_r") )
				( member ( signalRef "@baseboard_fab2_lib.baseboard_fab2(sch_1):pwrgd_pvtt_ghj_cpu1_r") )
				( member ( signalRef "@baseboard_fab2_lib.baseboard_fab2(sch_1):pwrgd_pvtt_klm_cpu1_r") )
				( member ( signalRef "@baseboard_fab2_lib.baseboard_fab2(sch_1):spi_clk_r1") )
				( member ( signalRef "@baseboard_fab2_lib.baseboard_fab2(sch_1):spi_cs0_primary_n") )
				( member ( signalRef "@baseboard_fab2_lib.baseboard_fab2(sch_1):h_cpu1_memklm_memhot_lvt3_n") )
				( member ( signalRef "@baseboard_fab2_lib.baseboard_fab2(sch_1):spi_cs0_primary_r_n") )
				( member ( signalRef "@baseboard_fab2_lib.baseboard_fab2(sch_1):spi_cs0_secondary_n") )
				( member ( signalRef "@baseboard_fab2_lib.baseboard_fab2(sch_1):h_cpu_err0_gtl_n") )
				( member ( signalRef "@baseboard_fab2_lib.baseboard_fab2(sch_1):spi_cs0_secondary_r_n") )
				( member ( signalRef "@baseboard_fab2_lib.baseboard_fab2(sch_1):irq_lvc3_wake_r_n") )
				( member ( signalRef "@baseboard_fab2_lib.baseboard_fab2(sch_1):fm_prsnt_2_6_n") )
				( member ( signalRef "@baseboard_fab2_lib.baseboard_fab2(sch_1):h_cpu_err1_gtl_n") )
				( member ( signalRef "@baseboard_fab2_lib.baseboard_fab2(sch_1):smb_bmc_pmbus_stby_lvc3_sda") )
				( member ( signalRef "@baseboard_fab2_lib.baseboard_fab2(sch_1):spi_miso_r0") )
				( member ( signalRef "@baseboard_fab2_lib.baseboard_fab2(sch_1):spi_miso_r1") )
				( member ( signalRef "@baseboard_fab2_lib.baseboard_fab2(sch_1):irq_lpc_serirq_r") )
				( member ( signalRef "@baseboard_fab2_lib.baseboard_fab2(sch_1):h_pm_sync_gtl_r1") )
				( member ( signalRef "@baseboard_fab2_lib.baseboard_fab2(sch_1):spi_pch_clk") )
				( member ( signalRef "@baseboard_fab2_lib.baseboard_fab2(sch_1):h_cpu1_msmi_g_n") )
				( member ( signalRef "@baseboard_fab2_lib.baseboard_fab2(sch_1):spi_pch_cs0_r_n") )
				( member ( signalRef "@baseboard_fab2_lib.baseboard_fab2(sch_1):smb_bmc_pmbus_stby_lvc3_scl_r") )
				( member ( signalRef "@baseboard_fab2_lib.baseboard_fab2(sch_1):vid_pch_core_pvnn_aux_vid_1") )
				( member ( signalRef "@baseboard_fab2_lib.baseboard_fab2(sch_1):spi_pch_io3_r1") )
				( member ( signalRef "@baseboard_fab2_lib.baseboard_fab2(sch_1):h_pmsync_clk_24m") )
				( member ( signalRef "@baseboard_fab2_lib.baseboard_fab2(sch_1):spi_pch_io3") )
				( member ( signalRef "@baseboard_fab2_lib.baseboard_fab2(sch_1):spi_pch_miso_r") )
				( member ( signalRef "@baseboard_fab2_lib.baseboard_fab2(sch_1):h_pmsync_clk_24m_r") )
				( member ( signalRef "@baseboard_fab2_lib.baseboard_fab2(sch_1):spi_pch_miso") )
				( member ( signalRef "@baseboard_fab2_lib.baseboard_fab2(sch_1):spi_pch_mosi") )
				( member ( signalRef "@baseboard_fab2_lib.baseboard_fab2(sch_1):h_pm_sync_gtl") )
				( member ( signalRef "@baseboard_fab2_lib.baseboard_fab2(sch_1):spi_pch_mosi_r") )
				( member ( signalRef "@baseboard_fab2_lib.baseboard_fab2(sch_1):spi_pch_tpm_cs_r_n") )
				( member ( signalRef "@baseboard_fab2_lib.baseboard_fab2(sch_1):spi_pch_tpm_miso_r") )
				( member ( signalRef "@baseboard_fab2_lib.baseboard_fab2(sch_1):spi_switch_clk") )
				( member ( signalRef "@baseboard_fab2_lib.baseboard_fab2(sch_1):spi_switch_cs0_n") )
				( member ( signalRef "@baseboard_fab2_lib.baseboard_fab2(sch_1):spi_switch_miso") )
				( member ( signalRef "@baseboard_fab2_lib.baseboard_fab2(sch_1):spi_switch_mosi") )
				( member ( signalRef "@baseboard_fab2_lib.baseboard_fab2(sch_1):spi_bios_socket_io3") )
				( member ( signalRef "@baseboard_fab2_lib.baseboard_fab2(sch_1):pwrgd_p12v_r") )
				( member ( signalRef "@baseboard_fab2_lib.baseboard_fab2(sch_1):fm_prsnt_2_3_n") )
				( member ( signalRef "@baseboard_fab2_lib.baseboard_fab2(sch_1):fm_prsnt_2_4_n") )
				( member ( signalRef "@baseboard_fab2_lib.baseboard_fab2(sch_1):fm_prsnt_2_5_n") )
				( member ( signalRef "@baseboard_fab2_lib.baseboard_fab2(sch_1):rmii_bmc_ocp_txd0") )
				( member ( signalRef "@baseboard_fab2_lib.baseboard_fab2(sch_1):h_cpu1_err0_g_n") )
				( member ( signalRef "@baseboard_fab2_lib.baseboard_fab2(sch_1):rmii_bmc_ocp_txd0_r") )
				( member ( signalRef "@baseboard_fab2_lib.baseboard_fab2(sch_1):rmii_bmc_ocp_txd1") )
				( member ( signalRef "@baseboard_fab2_lib.baseboard_fab2(sch_1):h_cpu1_err1_g_n") )
				( member ( signalRef "@baseboard_fab2_lib.baseboard_fab2(sch_1):rmii_bmc_ocp_txd1_r") )
				( member ( signalRef "@baseboard_fab2_lib.baseboard_fab2(sch_1):rmii_bmc_pch_sprngvlle_crsdv") )
				( member ( signalRef "@baseboard_fab2_lib.baseboard_fab2(sch_1):h_pm_sync_gtl_r2") )
				( member ( signalRef "@baseboard_fab2_lib.baseboard_fab2(sch_1):rmii_bmc_pch_sprngvlle_crsdv_r") )
				( member ( signalRef "@baseboard_fab2_lib.baseboard_fab2(sch_1):h_cpu1_ghj_memhot_lvt3_r_n") )
				( member ( signalRef "@baseboard_fab2_lib.baseboard_fab2(sch_1):rmii_bmc_pch_sprngvlle_txd0") )
				( member ( signalRef "@baseboard_fab2_lib.baseboard_fab2(sch_1):rmii_bmc_pch_sprngvlle_txd0_r") )
				( member ( signalRef "@baseboard_fab2_lib.baseboard_fab2(sch_1):rmii_bmc_pch_sprngvlle_txd1") )
				( member ( signalRef "@baseboard_fab2_lib.baseboard_fab2(sch_1):h_cpu1_klm_memhot_lvt3_r_n") )
				( member ( signalRef "@baseboard_fab2_lib.baseboard_fab2(sch_1):rmii_bmc_pch_sprngvlle_txd1_r") )
				( member ( signalRef "@baseboard_fab2_lib.baseboard_fab2(sch_1):h_cpu1_memghj_memhot_lvt3_n") )
				( member ( signalRef "@baseboard_fab2_lib.baseboard_fab2(sch_1):rmii_pch_sprngvlle_arb_in") )
				( member ( signalRef "@baseboard_fab2_lib.baseboard_fab2(sch_1):rmii_pch_sprngvlle_arb_out") )
				( member ( signalRef "@baseboard_fab2_lib.baseboard_fab2(sch_1):h_cpu1_caterr_g_n") )
				( member ( signalRef "@baseboard_fab2_lib.baseboard_fab2(sch_1):rmii_sprngvlle_bmc_pch_rxd0_r") )
				( member ( signalRef "@baseboard_fab2_lib.baseboard_fab2(sch_1):h_cpu0_msmi_g_n") )
				( member ( signalRef "@baseboard_fab2_lib.baseboard_fab2(sch_1):rmii_sprngvlle_bmc_pch_rxd1_r") )
				( member ( signalRef "@baseboard_fab2_lib.baseboard_fab2(sch_1):irq_force_nm_throttle_n") )
				( member ( signalRef "@baseboard_fab2_lib.baseboard_fab2(sch_1):h_pm_sync1_gtl_r") )
				( member ( signalRef "@baseboard_fab2_lib.baseboard_fab2(sch_1):clk_24m_bmc_lpc") )
				( member ( signalRef "@baseboard_fab2_lib.baseboard_fab2(sch_1):clk_24m_bmc_lpc_r") )
				( member ( signalRef "@baseboard_fab2_lib.baseboard_fab2(sch_1):m_ghj_rst_n") )
				( member ( signalRef "@baseboard_fab2_lib.baseboard_fab2(sch_1):xtal_24mhz_in_r") )
				( member ( signalRef "@baseboard_fab2_lib.baseboard_fab2(sch_1):irq_pirqa_spi_tpm_n") )
				( member ( signalRef "@baseboard_fab2_lib.baseboard_fab2(sch_1):xtal_24mhz_out_r") )
				( member ( signalRef "@baseboard_fab2_lib.baseboard_fab2(sch_1):xtal_24mhz_pi7c9x1172_in") )
				( member ( signalRef "@baseboard_fab2_lib.baseboard_fab2(sch_1):irq_spi_tpm_n_r") )
				( member ( signalRef "@baseboard_fab2_lib.baseboard_fab2(sch_1):xtal_24mhz_pi7c9x1172_out") )
				( member ( signalRef "@baseboard_fab2_lib.baseboard_fab2(sch_1):jtag_tck_r") )
				( member ( signalRef "@baseboard_fab2_lib.baseboard_fab2(sch_1):smb_bmc_pmbus_stby_lvc3_sda_r") )
				( member ( signalRef "@baseboard_fab2_lib.baseboard_fab2(sch_1):smb_host_stby_lvc3_scl") )
				( member ( signalRef "@baseboard_fab2_lib.baseboard_fab2(sch_1):smb_host_stby_lvc3_scl_r1") )
				( member ( signalRef "@baseboard_fab2_lib.baseboard_fab2(sch_1):smb_host_stby_lvc3_sda") )
				( member ( signalRef "@baseboard_fab2_lib.baseboard_fab2(sch_1):smb_host_stby_lvc3_sda_r1") )
				( member ( signalRef "@baseboard_fab2_lib.baseboard_fab2(sch_1):smb_vr_scl_pvccio_cpu0") )
				( member ( signalRef "@baseboard_fab2_lib.baseboard_fab2(sch_1):smb_vr_scl_pvccio_cpu1") )
				( member ( signalRef "@baseboard_fab2_lib.baseboard_fab2(sch_1):smb_vr_scl_pvnn_pch") )
				( member ( signalRef "@baseboard_fab2_lib.baseboard_fab2(sch_1):smb_vr_scl_r") )
				( member ( signalRef "@baseboard_fab2_lib.baseboard_fab2(sch_1):smb_vr_scl_r1") )
				( member ( signalRef "@baseboard_fab2_lib.baseboard_fab2(sch_1):smb_vr_scl_vddq_abc") )
				( member ( signalRef "@baseboard_fab2_lib.baseboard_fab2(sch_1):smb_vr_sda_pvccio_cpu0") )
				( member ( signalRef "@baseboard_fab2_lib.baseboard_fab2(sch_1):smb_vr_sda_pvccio_cpu1") )
				( member ( signalRef "@baseboard_fab2_lib.baseboard_fab2(sch_1):smb_vr_sda_pvnn_pch") )
				( member ( signalRef "@baseboard_fab2_lib.baseboard_fab2(sch_1):smb_vr_sda_r") )
				( member ( signalRef "@baseboard_fab2_lib.baseboard_fab2(sch_1):smb_vr_sda_r1") )
				( member ( signalRef "@baseboard_fab2_lib.baseboard_fab2(sch_1):smb_vr_sda_vddq_abc") )
				( member ( signalRef "@baseboard_fab2_lib.baseboard_fab2(sch_1):smb_vr_stby_lvc3_scl") )
				( member ( signalRef "@baseboard_fab2_lib.baseboard_fab2(sch_1):smb_vr_stby_lvc3_scl_r") )
				( member ( signalRef "@baseboard_fab2_lib.baseboard_fab2(sch_1):smb_vr_stby_lvc3_sda") )
				( member ( signalRef "@baseboard_fab2_lib.baseboard_fab2(sch_1):smb_vr_stby_lvc3_sda_r") )
				( member ( signalRef "@baseboard_fab2_lib.baseboard_fab2(sch_1):jtag_tdi_r") )
				( member ( signalRef "@baseboard_fab2_lib.baseboard_fab2(sch_1):smb_bmc_pmbus_stby_lvc3_scl") )
				( member ( signalRef "@baseboard_fab2_lib.baseboard_fab2(sch_1):fm_fast_prochot_and_out_0_n") )
				( member ( signalRef "@baseboard_fab2_lib.baseboard_fab2(sch_1):fm_fast_prochot_throttle_dly_buf_n") )
				( member ( signalRef "@baseboard_fab2_lib.baseboard_fab2(sch_1):fm_fast_prochot_throttle_dly_n") )
				( member ( signalRef "@baseboard_fab2_lib.baseboard_fab2(sch_1):fm_slp_sus_n") )
				( member ( signalRef "@baseboard_fab2_lib.baseboard_fab2(sch_1):fm_ie_disable_n") )
				( member ( signalRef "@baseboard_fab2_lib.baseboard_fab2(sch_1):fm_sol_uart_ch_sel") )
				( member ( signalRef "@baseboard_fab2_lib.baseboard_fab2(sch_1):spi_bios_socket_io2") )
				( member ( signalRef "@baseboard_fab2_lib.baseboard_fab2(sch_1):pu_bios_spi_wp0_n") )
				( member ( signalRef "@baseboard_fab2_lib.baseboard_fab2(sch_1):fm_sys_throttle_lvc3") )
				( member ( signalRef "@baseboard_fab2_lib.baseboard_fab2(sch_1):fm_mp_ps_fail_n") )
				( member ( signalRef "@baseboard_fab2_lib.baseboard_fab2(sch_1):fm_thermtrip_dly") )
				( member ( signalRef "@baseboard_fab2_lib.baseboard_fab2(sch_1):m_def_rst_n") )
				( member ( signalRef "@baseboard_fab2_lib.baseboard_fab2(sch_1):fm_fast_prochot_and_out_1_n") )
				( member ( signalRef "@baseboard_fab2_lib.baseboard_fab2(sch_1):fm_throttle_n") )
				( member ( signalRef "@baseboard_fab2_lib.baseboard_fab2(sch_1):smb_3v3sb_hsc_sda_r") )
				( member ( signalRef "@baseboard_fab2_lib.baseboard_fab2(sch_1):fm_tpm_pres_n") )
				( member ( signalRef "@baseboard_fab2_lib.baseboard_fab2(sch_1):pwrgd_p5v_stby_r") )
				( member ( signalRef "@baseboard_fab2_lib.baseboard_fab2(sch_1):h_cpu_err0_pch_n") )
				( member ( signalRef "@baseboard_fab2_lib.baseboard_fab2(sch_1):smb_3v3sb_hsc_scl_r") )
				( member ( signalRef "@baseboard_fab2_lib.baseboard_fab2(sch_1):fm_oc0_usb_n") )
				( member ( signalRef "@baseboard_fab2_lib.baseboard_fab2(sch_1):fm_uv_adr_trigger_en") )
				( member ( signalRef "@baseboard_fab2_lib.baseboard_fab2(sch_1):pwrgd_pvtt_cpu0") )
				( member ( signalRef "@baseboard_fab2_lib.baseboard_fab2(sch_1):fm_xrc_present_n") )
				( member ( signalRef "@baseboard_fab2_lib.baseboard_fab2(sch_1):fm_xrc_ready_n") )
				( member ( signalRef "@baseboard_fab2_lib.baseboard_fab2(sch_1):fm_10gbe_lom_disable_n") )
				( member ( signalRef "@baseboard_fab2_lib.baseboard_fab2(sch_1):smb_pmbus_bmc_stby_lvc3_sda_r1") )
				( member ( signalRef "@baseboard_fab2_lib.baseboard_fab2(sch_1):smb_pmbus_bmc_stby_lvc3_scl_r1") )
				( member ( signalRef "@baseboard_fab2_lib.baseboard_fab2(sch_1):fm_roma(0)") )
				( member ( signalRef "@baseboard_fab2_lib.baseboard_fab2(sch_1):fm_roma(1)") )
				( member ( signalRef "@baseboard_fab2_lib.baseboard_fab2(sch_1):fm_roma(2)") )
				( member ( signalRef "@baseboard_fab2_lib.baseboard_fab2(sch_1):fm_roma(3)") )
				( member ( signalRef "@baseboard_fab2_lib.baseboard_fab2(sch_1):fm_roma(4)") )
				( member ( signalRef "@baseboard_fab2_lib.baseboard_fab2(sch_1):fm_roma(5)") )
				( member ( signalRef "@baseboard_fab2_lib.baseboard_fab2(sch_1):fm_roma(6)") )
				( member ( signalRef "@baseboard_fab2_lib.baseboard_fab2(sch_1):fm_roma(7)") )
				( member ( signalRef "@baseboard_fab2_lib.baseboard_fab2(sch_1):fm_roma(8)") )
				( member ( signalRef "@baseboard_fab2_lib.baseboard_fab2(sch_1):fm_roma(9)") )
				( member ( signalRef "@baseboard_fab2_lib.baseboard_fab2(sch_1):fm_roma(10)") )
				( member ( signalRef "@baseboard_fab2_lib.baseboard_fab2(sch_1):fm_roma(11)") )
				( member ( signalRef "@baseboard_fab2_lib.baseboard_fab2(sch_1):fm_roma(12)") )
				( member ( signalRef "@baseboard_fab2_lib.baseboard_fab2(sch_1):fm_roma(13)") )
				( member ( signalRef "@baseboard_fab2_lib.baseboard_fab2(sch_1):fm_roma(14)") )
				( member ( signalRef "@baseboard_fab2_lib.baseboard_fab2(sch_1):fm_roma(15)") )
				( member ( signalRef "@baseboard_fab2_lib.baseboard_fab2(sch_1):fm_roma(16)") )
				( member ( signalRef "@baseboard_fab2_lib.baseboard_fab2(sch_1):fm_roma(17)") )
				( member ( signalRef "@baseboard_fab2_lib.baseboard_fab2(sch_1):fm_roma(18)") )
				( member ( signalRef "@baseboard_fab2_lib.baseboard_fab2(sch_1):fm_roma(19)") )
				( member ( signalRef "@baseboard_fab2_lib.baseboard_fab2(sch_1):fm_roma(20)") )
				( member ( signalRef "@baseboard_fab2_lib.baseboard_fab2(sch_1):fm_roma(21)") )
				( member ( signalRef "@baseboard_fab2_lib.baseboard_fab2(sch_1):fm_roma(22)") )
				( member ( signalRef "@baseboard_fab2_lib.baseboard_fab2(sch_1):fm_roma(23)") )
				( member ( signalRef "@baseboard_fab2_lib.baseboard_fab2(sch_1):jtag_bmc_tdi") )
				( member ( signalRef "@baseboard_fab2_lib.baseboard_fab2(sch_1):jtag_bmc_tck") )
				( member ( signalRef "@baseboard_fab2_lib.baseboard_fab2(sch_1):pwrgd_p3v3_r1") )
				( member ( signalRef "@baseboard_fab2_lib.baseboard_fab2(sch_1):pwrgd_p5v") )
				( member ( signalRef "@baseboard_fab2_lib.baseboard_fab2(sch_1):pwrgd_p5v_r") )
				( member ( signalRef "@baseboard_fab2_lib.baseboard_fab2(sch_1):pwrgd_p12v_hsc_dly") )
				( member ( signalRef "@baseboard_fab2_lib.baseboard_fab2(sch_1):pwrgd_p12v_hsc_dly_r") )
				( member ( signalRef "@baseboard_fab2_lib.baseboard_fab2(sch_1):jtag_pch_pld_tms") )
				( member ( signalRef "@baseboard_fab2_lib.baseboard_fab2(sch_1):irq_board_bmc_alert_n") )
				( member ( signalRef "@baseboard_fab2_lib.baseboard_fab2(sch_1):h_cpu1_memghj_memhot_pch_n") )
				( member ( signalRef "@baseboard_fab2_lib.baseboard_fab2(sch_1):xdp_cpu_gtl_tck_r2") )
				( member ( signalRef "@baseboard_fab2_lib.baseboard_fab2(sch_1):fm_jtag_pld_en_debug") )
				( member ( signalRef "@baseboard_fab2_lib.baseboard_fab2(sch_1):jtag_pch_pld_tck") )
				( member ( signalRef "@baseboard_fab2_lib.baseboard_fab2(sch_1):jtag_pch_pld_tdo") )
				( member ( signalRef "@baseboard_fab2_lib.baseboard_fab2(sch_1):fm_modprst_hfi0_cpu0_lvt2_n") )
				( member ( signalRef "@baseboard_fab2_lib.baseboard_fab2(sch_1):jtag_pch_pld_tdi") )
				( member ( signalRef "@baseboard_fab2_lib.baseboard_fab2(sch_1):m_klm_rst_n") )
				( member ( signalRef "@baseboard_fab2_lib.baseboard_fab2(sch_1):fm_oc_detect_n") )
				( member ( signalRef "@baseboard_fab2_lib.baseboard_fab2(sch_1):spi_pch_io2") )
				( member ( signalRef "@baseboard_fab2_lib.baseboard_fab2(sch_1):fm_db1200_pwrgd") )
				( member ( signalRef "@baseboard_fab2_lib.baseboard_fab2(sch_1):pwrgd_pvtt_cpu1") )
				( member ( signalRef "@baseboard_fab2_lib.baseboard_fab2(sch_1):fm_bmc_cpld_gpo") )
				( member ( signalRef "@baseboard_fab2_lib.baseboard_fab2(sch_1):m_bmc_ddr3_ma(13)") )
				( member ( signalRef "@baseboard_fab2_lib.baseboard_fab2(sch_1):m_bmc_ddr3_ma(14)") )
				( member ( signalRef "@baseboard_fab2_lib.baseboard_fab2(sch_1):fm_fast_prochot_throttle_in_n") )
				( member ( signalRef "@baseboard_fab2_lib.baseboard_fab2(sch_1):fm_speaker_pch_n") )
				( member ( signalRef "@baseboard_fab2_lib.baseboard_fab2(sch_1):fp_id_led_xor_r") )
				( member ( signalRef "@baseboard_fab2_lib.baseboard_fab2(sch_1):fm_bmc_fault_led_n") )
				( member ( signalRef "@baseboard_fab2_lib.baseboard_fab2(sch_1):fp_nmi_btn_n") )
				( member ( signalRef "@baseboard_fab2_lib.baseboard_fab2(sch_1):fp_pwr_btn_buf1_n") )
				( member ( signalRef "@baseboard_fab2_lib.baseboard_fab2(sch_1):fp_pwr_id_led_n") )
				( member ( signalRef "@baseboard_fab2_lib.baseboard_fab2(sch_1):fm_modprst_hfi1_cpu0_lvt2_n") )
				( member ( signalRef "@baseboard_fab2_lib.baseboard_fab2(sch_1):led_gbe_p3_1") )
				( member ( signalRef "@baseboard_fab2_lib.baseboard_fab2(sch_1):fp_rst_btn_buf1_n") )
				( member ( signalRef "@baseboard_fab2_lib.baseboard_fab2(sch_1):jtag_tdo_r") )
				( member ( signalRef "@baseboard_fab2_lib.baseboard_fab2(sch_1):jtag_tms_r") )
				( member ( signalRef "@baseboard_fab2_lib.baseboard_fab2(sch_1):smb_ddr_abc_scl_g") )
				( member ( signalRef "@baseboard_fab2_lib.baseboard_fab2(sch_1):smb_ddr_abc_scl_g_r") )
				( member ( signalRef "@baseboard_fab2_lib.baseboard_fab2(sch_1):smb_ddr_abc_sda_g") )
				( member ( signalRef "@baseboard_fab2_lib.baseboard_fab2(sch_1):smb_ddr_abc_sda_g_r") )
				( member ( signalRef "@baseboard_fab2_lib.baseboard_fab2(sch_1):smb_ddr_abc_vpp_scl") )
				( member ( signalRef "@baseboard_fab2_lib.baseboard_fab2(sch_1):smb_ddr_abc_vpp_scl_r") )
				( member ( signalRef "@baseboard_fab2_lib.baseboard_fab2(sch_1):smb_ddr_abc_vpp_sda") )
				( member ( signalRef "@baseboard_fab2_lib.baseboard_fab2(sch_1):smb_ddr_abc_vpp_sda_r") )
				( member ( signalRef "@baseboard_fab2_lib.baseboard_fab2(sch_1):smb_ddr_def_scl_g") )
				( member ( signalRef "@baseboard_fab2_lib.baseboard_fab2(sch_1):smb_ddr_def_scl_g_r") )
				( member ( signalRef "@baseboard_fab2_lib.baseboard_fab2(sch_1):smb_ddr_def_sda_g") )
				( member ( signalRef "@baseboard_fab2_lib.baseboard_fab2(sch_1):smb_ddr_def_sda_g_r") )
				( member ( signalRef "@baseboard_fab2_lib.baseboard_fab2(sch_1):fm_hsc_timer_exp_n") )
				( member ( signalRef "@baseboard_fab2_lib.baseboard_fab2(sch_1):jtag_bmc_tms") )
				( member ( signalRef "@baseboard_fab2_lib.baseboard_fab2(sch_1):fm_intruder_hdr_pch_n") )
				( member ( signalRef "@baseboard_fab2_lib.baseboard_fab2(sch_1):m_abc_rst_n") )
				( member ( signalRef "@baseboard_fab2_lib.baseboard_fab2(sch_1):fm_mated_in_d1_n") )
				( member ( signalRef "@baseboard_fab2_lib.baseboard_fab2(sch_1):fm_mated_in_d2_n") )
				( member ( signalRef "@baseboard_fab2_lib.baseboard_fab2(sch_1):fm_mated_in_n") )
				( member ( signalRef "@baseboard_fab2_lib.baseboard_fab2(sch_1):smb_lan_stby_lvc3_scl_r2") )
				( member ( signalRef "@baseboard_fab2_lib.baseboard_fab2(sch_1):smb_lan_stby_lvc3_sda_r2") )
				( member ( signalRef "@baseboard_fab2_lib.baseboard_fab2(sch_1):fm_mb_slot_id0") )
				( member ( signalRef "@baseboard_fab2_lib.baseboard_fab2(sch_1):fm_mb_slot_id1") )
				( member ( signalRef "@baseboard_fab2_lib.baseboard_fab2(sch_1):fm_mb_slot_id2") )
				( member ( signalRef "@baseboard_fab2_lib.baseboard_fab2(sch_1):vr_pvccio_cpu0_ocset") )
				( member ( signalRef "@baseboard_fab2_lib.baseboard_fab2(sch_1):fm_mezz_prsntb1_n") )
				( member ( signalRef "@baseboard_fab2_lib.baseboard_fab2(sch_1):fm_mezza_prsnt1_n") )
				( member ( signalRef "@baseboard_fab2_lib.baseboard_fab2(sch_1):fm_me_recover_n") )
				( member ( signalRef "@baseboard_fab2_lib.baseboard_fab2(sch_1):h_cpu_err1_pch_n") )
				( member ( signalRef "@baseboard_fab2_lib.baseboard_fab2(sch_1):fm_cpu0_and_cpu1_mcp_pres") )
				( member ( signalRef "@baseboard_fab2_lib.baseboard_fab2(sch_1):smb_hfi0_cpu0_lvc2_sda") )
				( member ( signalRef "@baseboard_fab2_lib.baseboard_fab2(sch_1):fm_m2_ssd_pedet") )
				( member ( signalRef "@baseboard_fab2_lib.baseboard_fab2(sch_1):fm_ocp_mezza_pres_n") )
				( member ( signalRef "@baseboard_fab2_lib.baseboard_fab2(sch_1):fm_oc_detect_en") )
				( member ( signalRef "@baseboard_fab2_lib.baseboard_fab2(sch_1):fm_password_clear_n") )
				( member ( signalRef "@baseboard_fab2_lib.baseboard_fab2(sch_1):fm_pch_lvc1_thermtrip_n") )
				( member ( signalRef "@baseboard_fab2_lib.baseboard_fab2(sch_1):fm_pch_prsnt_n") )
				( member ( signalRef "@baseboard_fab2_lib.baseboard_fab2(sch_1):fm_pch_pwrbtn_n") )
				( member ( signalRef "@baseboard_fab2_lib.baseboard_fab2(sch_1):h_cpu1_memklm_memhot_pch_n") )
				( member ( signalRef "@baseboard_fab2_lib.baseboard_fab2(sch_1):fm_wbg_prsnt_n") )
				( member ( signalRef "@baseboard_fab2_lib.baseboard_fab2(sch_1):jtag_bmc_tdo") )
				( member ( signalRef "@baseboard_fab2_lib.baseboard_fab2(sch_1):rst_hfi0_cpu0_lvt2_n") )
				( member ( signalRef "@baseboard_fab2_lib.baseboard_fab2(sch_1):fm_pld_debug_mode_n") )
				( member ( signalRef "@baseboard_fab2_lib.baseboard_fab2(sch_1):fm_pmbus_alert_buf_en") )
				( member ( signalRef "@baseboard_fab2_lib.baseboard_fab2(sch_1):h_cpu0_memabc_memhot_g_pch_n") )
				( member ( signalRef "@baseboard_fab2_lib.baseboard_fab2(sch_1):smb_hfi1_cpu0_lvc2_sda") )
				( member ( signalRef "@baseboard_fab2_lib.baseboard_fab2(sch_1):fm_post_card_pres_bmc_n") )
				( member ( signalRef "@baseboard_fab2_lib.baseboard_fab2(sch_1):fm_ps_en") )
				( member ( signalRef "@baseboard_fab2_lib.baseboard_fab2(sch_1):fm_adr_mode_sel") )
				( member ( signalRef "@baseboard_fab2_lib.baseboard_fab2(sch_1):fm_pvccin_cpu0_pwr_in_alert_n") )
				( member ( signalRef "@baseboard_fab2_lib.baseboard_fab2(sch_1):fm_pvccin_cpu1_pwr_in_alert_n") )
				( member ( signalRef "@baseboard_fab2_lib.baseboard_fab2(sch_1):fm_pvccio_cpu0_en") )
				( member ( signalRef "@baseboard_fab2_lib.baseboard_fab2(sch_1):fm_pvccio_cpu1_en") )
				( member ( signalRef "@baseboard_fab2_lib.baseboard_fab2(sch_1):clk_24m_25m_bmc_clkin") )
				( member ( signalRef "@baseboard_fab2_lib.baseboard_fab2(sch_1):fm_pvccmcp_cpu1_en") )
				( member ( signalRef "@baseboard_fab2_lib.baseboard_fab2(sch_1):smb_hfi1_cpu0_lvc2_scl") )
				( member ( signalRef "@baseboard_fab2_lib.baseboard_fab2(sch_1):fm_cpld_adr_trigger_n") )
				( member ( signalRef "@baseboard_fab2_lib.baseboard_fab2(sch_1):fm_p3v3_cpld_en") )
				( member ( signalRef "@baseboard_fab2_lib.baseboard_fab2(sch_1):fm_mp_ps_redundant_lost_n") )
				( member ( signalRef "@baseboard_fab2_lib.baseboard_fab2(sch_1):fm_cpu0_cd_pres") )
				( member ( signalRef "@baseboard_fab2_lib.baseboard_fab2(sch_1):fm_p12v_hotswap0_en") )
				( member ( signalRef "@baseboard_fab2_lib.baseboard_fab2(sch_1):fm_p12v_hsc_adr1") )
				( member ( signalRef "@baseboard_fab2_lib.baseboard_fab2(sch_1):fm_p12v_hsc_adr2") )
				( member ( signalRef "@baseboard_fab2_lib.baseboard_fab2(sch_1):fm_p12v_main_sw_en") )
				( member ( signalRef "@baseboard_fab2_lib.baseboard_fab2(sch_1):fm_qat_en_n") )
				( member ( signalRef "@baseboard_fab2_lib.baseboard_fab2(sch_1):smb_hfi0_cpu0_lvc2_scl") )
				( member ( signalRef "@baseboard_fab2_lib.baseboard_fab2(sch_1):fm_slps3_n") )
				( member ( signalRef "@baseboard_fab2_lib.baseboard_fab2(sch_1):fm_slps4_n") )
				( member ( signalRef "@baseboard_fab2_lib.baseboard_fab2(sch_1):spi_pch_io2_r1") )
				( member ( signalRef "@baseboard_fab2_lib.baseboard_fab2(sch_1):rmii_bmc_ocp_txen_r") )
				( member ( signalRef "@baseboard_fab2_lib.baseboard_fab2(sch_1):pwrgd_p12v_main") )
				( member ( signalRef "@baseboard_fab2_lib.baseboard_fab2(sch_1):pd_cpu0_rsvd_test_1") )
				( member ( signalRef "@baseboard_fab2_lib.baseboard_fab2(sch_1):pd_cpu0_rsvd_test_2") )
				( member ( signalRef "@baseboard_fab2_lib.baseboard_fab2(sch_1):tp_cpu0_rsvd_test_4") )
				( member ( signalRef "@baseboard_fab2_lib.baseboard_fab2(sch_1):tp_cpu1_rsvd_test_3") )
				( member ( signalRef "@baseboard_fab2_lib.baseboard_fab2(sch_1):pd_cpu1_rsvd_test_1") )
				( member ( signalRef "@baseboard_fab2_lib.baseboard_fab2(sch_1):pd_cpu1_rsvd_test_2") )
				( member ( signalRef "@baseboard_fab2_lib.baseboard_fab2(sch_1):tp_cpu1_rsvd_test_4") )
				( member ( signalRef "@baseboard_fab2_lib.baseboard_fab2(sch_1):xdp_pch_pwr_debug_n") )
				( member ( signalRef "@baseboard_fab2_lib.baseboard_fab2(sch_1):rst_rsmrst_r_n") )
				( member ( signalRef "@baseboard_fab2_lib.baseboard_fab2(sch_1):fm_pch_pwrbtn_r_n") )
				( member ( signalRef "@baseboard_fab2_lib.baseboard_fab2(sch_1):irq_force_nm_throttle_r_n") )
				( member ( signalRef "@baseboard_fab2_lib.baseboard_fab2(sch_1):rst_bmc_srst_r2_n") )
				( member ( signalRef "@baseboard_fab2_lib.baseboard_fab2(sch_1):smb_host_stby_lvc3_sda_r2") )
				( member ( signalRef "@baseboard_fab2_lib.baseboard_fab2(sch_1):smb_sensor_stby_lvc3_scl_r2") )
				( member ( signalRef "@baseboard_fab2_lib.baseboard_fab2(sch_1):smb_sensor_stby_lvc3_sda_r2") )
				( member ( signalRef "@baseboard_fab2_lib.baseboard_fab2(sch_1):smb_ddr_def_vpp_scl") )
				( member ( signalRef "@baseboard_fab2_lib.baseboard_fab2(sch_1):smb_ddr_def_vpp_scl_r") )
				( member ( signalRef "@baseboard_fab2_lib.baseboard_fab2(sch_1):smb_ddr_def_vpp_sda") )
				( member ( signalRef "@baseboard_fab2_lib.baseboard_fab2(sch_1):smb_ddr_def_vpp_sda_r") )
				( member ( signalRef "@baseboard_fab2_lib.baseboard_fab2(sch_1):smb_ddr_ghj_scl_g") )
				( member ( signalRef "@baseboard_fab2_lib.baseboard_fab2(sch_1):smb_ddr_ghj_scl_g_r") )
				( member ( signalRef "@baseboard_fab2_lib.baseboard_fab2(sch_1):smb_ddr_ghj_sda_g") )
				( member ( signalRef "@baseboard_fab2_lib.baseboard_fab2(sch_1):smb_ddr_ghj_sda_g_r") )
				( member ( signalRef "@baseboard_fab2_lib.baseboard_fab2(sch_1):smb_ddr_ghj_vpp_scl") )
				( member ( signalRef "@baseboard_fab2_lib.baseboard_fab2(sch_1):smb_ddr_ghj_vpp_scl_r") )
				( member ( signalRef "@baseboard_fab2_lib.baseboard_fab2(sch_1):smb_ddr_ghj_vpp_sda") )
				( member ( signalRef "@baseboard_fab2_lib.baseboard_fab2(sch_1):smb_ddr_ghj_vpp_sda_r") )
				( member ( signalRef "@baseboard_fab2_lib.baseboard_fab2(sch_1):smb_ddr_klm_scl_g") )
				( member ( signalRef "@baseboard_fab2_lib.baseboard_fab2(sch_1):smb_ddr_klm_scl_g_r") )
				( member ( signalRef "@baseboard_fab2_lib.baseboard_fab2(sch_1):smb_ddr_klm_sda_g") )
				( member ( signalRef "@baseboard_fab2_lib.baseboard_fab2(sch_1):smb_ddr_klm_sda_g_r") )
				( member ( signalRef "@baseboard_fab2_lib.baseboard_fab2(sch_1):smb_ddr_klm_vpp_scl") )
				( member ( signalRef "@baseboard_fab2_lib.baseboard_fab2(sch_1):smb_ddr_klm_vpp_scl_r") )
				( member ( signalRef "@baseboard_fab2_lib.baseboard_fab2(sch_1):smb_ddr_klm_vpp_sda") )
				( member ( signalRef "@baseboard_fab2_lib.baseboard_fab2(sch_1):smb_ddr_klm_vpp_sda_r") )
				( member ( signalRef "@baseboard_fab2_lib.baseboard_fab2(sch_1):smb_sensor_bmc_stby_lvc3_sda") )
				( member ( signalRef "@baseboard_fab2_lib.baseboard_fab2(sch_1):jtag_mcp_cpu1_tdo") )
				( member ( signalRef "@baseboard_fab2_lib.baseboard_fab2(sch_1):fm_uartsw_lsb_n") )
				( member ( signalRef "@baseboard_fab2_lib.baseboard_fab2(sch_1):fm_uartsw_lsb_r_n") )
				( member ( signalRef "@baseboard_fab2_lib.baseboard_fab2(sch_1):smb_smlink0_stby_lvc3_scl_r1") )
				( member ( signalRef "@baseboard_fab2_lib.baseboard_fab2(sch_1):spi_pch_tpm_mosi_r") )
				( member ( signalRef "@baseboard_fab2_lib.baseboard_fab2(sch_1):smb_smlink0_stby_lvc3_sda") )
				( member ( signalRef "@baseboard_fab2_lib.baseboard_fab2(sch_1):smb_smlink0_stby_lvc3_sda_r1") )
				( member ( signalRef "@baseboard_fab2_lib.baseboard_fab2(sch_1):fm_pi7c9x1172_a0") )
				( member ( signalRef "@baseboard_fab2_lib.baseboard_fab2(sch_1):rst_bmc_sysrst_btn_out_b_n") )
				( member ( signalRef "@baseboard_fab2_lib.baseboard_fab2(sch_1):rst_cd_cpu0_por_n") )
				( member ( signalRef "@baseboard_fab2_lib.baseboard_fab2(sch_1):rst_cd_cpu1_por_n") )
				( member ( signalRef "@baseboard_fab2_lib.baseboard_fab2(sch_1):smb_slotx24_pch_stby_lvc3_sda") )
				( member ( signalRef "@baseboard_fab2_lib.baseboard_fab2(sch_1):fm_uartsw_msb_n") )
				( member ( signalRef "@baseboard_fab2_lib.baseboard_fab2(sch_1):fm_uartsw_msb_r_n") )
				( member ( signalRef "@baseboard_fab2_lib.baseboard_fab2(sch_1):smb_slotx24_bmc_stby_lvc3_sda") )
				( member ( signalRef "@baseboard_fab2_lib.baseboard_fab2(sch_1):h_cpu_err2_gtl_n") )
				( member ( signalRef "@baseboard_fab2_lib.baseboard_fab2(sch_1):h_cpu1_err2_g_n") )
				( member ( signalRef "@baseboard_fab2_lib.baseboard_fab2(sch_1):smb_sensor_stby_lvc3_sda") )
				( member ( signalRef "@baseboard_fab2_lib.baseboard_fab2(sch_1):fm_pe_bmc_wake_n") )
				( member ( signalRef "@baseboard_fab2_lib.baseboard_fab2(sch_1):fm_pe_m2_wake_n") )
				( member ( signalRef "@baseboard_fab2_lib.baseboard_fab2(sch_1):fm_pe_ocp_wake_n") )
				( member ( signalRef "@baseboard_fab2_lib.baseboard_fab2(sch_1):fm_pe_slotx24_wake_n") )
				( member ( signalRef "@baseboard_fab2_lib.baseboard_fab2(sch_1):fm_pe_sprv_wake_n") )
				( member ( signalRef "@baseboard_fab2_lib.baseboard_fab2(sch_1):smb_smlink0_stby_lvc3_scl") )
				( member ( signalRef "@baseboard_fab2_lib.baseboard_fab2(sch_1):h_cpu0_err2_g_n") )
				( member ( signalRef "@baseboard_fab2_lib.baseboard_fab2(sch_1):h_cpu0_fast_wake_n") )
				( member ( signalRef "@baseboard_fab2_lib.baseboard_fab2(sch_1):fm_adc128_a0") )
				( member ( signalRef "@baseboard_fab2_lib.baseboard_fab2(sch_1):fm_adc128_a1") )
				( member ( signalRef "@baseboard_fab2_lib.baseboard_fab2(sch_1):fm_adr_complete") )
				( member ( signalRef "@baseboard_fab2_lib.baseboard_fab2(sch_1):fm_adr_smi_gpio_n") )
				( member ( signalRef "@baseboard_fab2_lib.baseboard_fab2(sch_1):fm_all_wake_n") )
				( member ( signalRef "@baseboard_fab2_lib.baseboard_fab2(sch_1):fm_backup_bios_sel_n") )
				( member ( signalRef "@baseboard_fab2_lib.baseboard_fab2(sch_1):h_cpu_err2_g_r_n") )
				( member ( signalRef "@baseboard_fab2_lib.baseboard_fab2(sch_1):fm_battery_sense_en") )
				( member ( signalRef "@baseboard_fab2_lib.baseboard_fab2(sch_1):fm_beep_led_p") )
				( member ( signalRef "@baseboard_fab2_lib.baseboard_fab2(sch_1):rst_hfi1_cpu0_lvt2_n") )
				( member ( signalRef "@baseboard_fab2_lib.baseboard_fab2(sch_1):h_cpu0_memabc_memhot_g_r_n") )
				( member ( signalRef "@baseboard_fab2_lib.baseboard_fab2(sch_1):h_cpu1_fast_wake_n") )
				( member ( signalRef "@baseboard_fab2_lib.baseboard_fab2(sch_1):tp_gpior5_roma25_vpor7") )
				( member ( signalRef "@baseboard_fab2_lib.baseboard_fab2(sch_1):fm_bios_mrc_debug_msg_dis_n") )
				( member ( signalRef "@baseboard_fab2_lib.baseboard_fab2(sch_1):fm_bios_post_cmplt_n") )
				( member ( signalRef "@baseboard_fab2_lib.baseboard_fab2(sch_1):fm_bios_prefrb2_good") )
				( member ( signalRef "@baseboard_fab2_lib.baseboard_fab2(sch_1):fm_bios_smi_active_n") )
				( member ( signalRef "@baseboard_fab2_lib.baseboard_fab2(sch_1):fm_bios_spi_bmc_ctrl") )
				( member ( signalRef "@baseboard_fab2_lib.baseboard_fab2(sch_1):fm_bmc_heartbeat_n") )
				( member ( signalRef "@baseboard_fab2_lib.baseboard_fab2(sch_1):fm_bmc_onctl_n") )
				( member ( signalRef "@baseboard_fab2_lib.baseboard_fab2(sch_1):fm_bmc_onctl_r_n") )
				( member ( signalRef "@baseboard_fab2_lib.baseboard_fab2(sch_1):fm_dimm_event_cod_n") )
				( member ( signalRef "@baseboard_fab2_lib.baseboard_fab2(sch_1):fm_ocp_mezzb_pres_n") )
				( member ( signalRef "@baseboard_fab2_lib.baseboard_fab2(sch_1):fm_bmc_pwrbtn_out_n") )
				( member ( signalRef "@baseboard_fab2_lib.baseboard_fab2(sch_1):fm_bmc_ready_n") )
				( member ( signalRef "@baseboard_fab2_lib.baseboard_fab2(sch_1):fm_board_rev_id0") )
				( member ( signalRef "@baseboard_fab2_lib.baseboard_fab2(sch_1):fm_board_rev_id1") )
				( member ( signalRef "@baseboard_fab2_lib.baseboard_fab2(sch_1):fm_board_rev_id2") )
				( member ( signalRef "@baseboard_fab2_lib.baseboard_fab2(sch_1):fm_board_sku_id0") )
				( member ( signalRef "@baseboard_fab2_lib.baseboard_fab2(sch_1):fm_board_sku_id1") )
				( member ( signalRef "@baseboard_fab2_lib.baseboard_fab2(sch_1):fm_board_sku_id2") )
				( member ( signalRef "@baseboard_fab2_lib.baseboard_fab2(sch_1):fm_board_sku_id3") )
				( member ( signalRef "@baseboard_fab2_lib.baseboard_fab2(sch_1):fm_board_sku_id4") )
				( member ( signalRef "@baseboard_fab2_lib.baseboard_fab2(sch_1):fm_bios_usb_recovery") )
				( member ( signalRef "@baseboard_fab2_lib.baseboard_fab2(sch_1):fm_cpu_caterr_dly_lvt3_r_n") )
				( member ( signalRef "@baseboard_fab2_lib.baseboard_fab2(sch_1):fm_force_adr_n") )
				( member ( signalRef "@baseboard_fab2_lib.baseboard_fab2(sch_1):h_cpu0_memdef_memhot_g_pch_n") )
				( member ( signalRef "@baseboard_fab2_lib.baseboard_fab2(sch_1):fm_pi7c9x1172_a1") )
				( member ( signalRef "@baseboard_fab2_lib.baseboard_fab2(sch_1):fm_cpu0_pkgid0") )
				( member ( signalRef "@baseboard_fab2_lib.baseboard_fab2(sch_1):fm_cpu0_pkgid1") )
				( member ( signalRef "@baseboard_fab2_lib.baseboard_fab2(sch_1):fm_cpu0_pkgid2") )
				( member ( signalRef "@baseboard_fab2_lib.baseboard_fab2(sch_1):fm_cpu0_proc_id0") )
				( member ( signalRef "@baseboard_fab2_lib.baseboard_fab2(sch_1):smb_slotx24_stby_lvc3_scl_r1") )
				( member ( signalRef "@baseboard_fab2_lib.baseboard_fab2(sch_1):fm_cpu0_proc_id1") )
				( member ( signalRef "@baseboard_fab2_lib.baseboard_fab2(sch_1):smb_slotx24_stby_lvc3_sda_r") )
				( member ( signalRef "@baseboard_fab2_lib.baseboard_fab2(sch_1):smb_slotx24_stby_lvc3_sda_r1") )
				( member ( signalRef "@baseboard_fab2_lib.baseboard_fab2(sch_1):smb_ocp_fru_stby_lvc3_scl") )
				( member ( signalRef "@baseboard_fab2_lib.baseboard_fab2(sch_1):smb_ocp_fru_stby_lvc3_scl_r") )
				( member ( signalRef "@baseboard_fab2_lib.baseboard_fab2(sch_1):smb_ocp_fru_stby_lvc3_sda") )
				( member ( signalRef "@baseboard_fab2_lib.baseboard_fab2(sch_1):smb_ocp_fru_stby_lvc3_sda_r") )
				( member ( signalRef "@baseboard_fab2_lib.baseboard_fab2(sch_1):smb_ocp_lan_stby_lvc3_scl") )
				( member ( signalRef "@baseboard_fab2_lib.baseboard_fab2(sch_1):smb_ocp_lan_stby_lvc3_scl_r") )
				( member ( signalRef "@baseboard_fab2_lib.baseboard_fab2(sch_1):smb_ocp_lan_stby_lvc3_sda") )
				( member ( signalRef "@baseboard_fab2_lib.baseboard_fab2(sch_1):smb_ocp_lan_stby_lvc3_sda_r") )
				( member ( signalRef "@baseboard_fab2_lib.baseboard_fab2(sch_1):h_cpu0_memabc_memhot") )
				( member ( signalRef "@baseboard_fab2_lib.baseboard_fab2(sch_1):h_cpu0_fivr_fault_g") )
				( member ( signalRef "@baseboard_fab2_lib.baseboard_fab2(sch_1):h_cpu1_memklm_memhot_g_n") )
				( member ( signalRef "@baseboard_fab2_lib.baseboard_fab2(sch_1):h_cpu1_memklm_memhot") )
				( member ( signalRef "@baseboard_fab2_lib.baseboard_fab2(sch_1):smb_sensor_pch_stby_lvc3_scl") )
				( member ( signalRef "@baseboard_fab2_lib.baseboard_fab2(sch_1):smb_sensor_pch_stby_lvc3_sda") )
				( member ( signalRef "@baseboard_fab2_lib.baseboard_fab2(sch_1):h_cpu0_memdef_memhot") )
				( member ( signalRef "@baseboard_fab2_lib.baseboard_fab2(sch_1):smb_sensor_stby_lvc3_scl_r1") )
				( member ( signalRef "@baseboard_fab2_lib.baseboard_fab2(sch_1):h_cpu0_memdef_memhot_g_n") )
				( member ( signalRef "@baseboard_fab2_lib.baseboard_fab2(sch_1):smb_sensor_stby_lvc3_sda_r1") )
				( member ( signalRef "@baseboard_fab2_lib.baseboard_fab2(sch_1):smb_sensor_tmp421_1_scl") )
				( member ( signalRef "@baseboard_fab2_lib.baseboard_fab2(sch_1):smb_sensor_tmp421_1_sda") )
				( member ( signalRef "@baseboard_fab2_lib.baseboard_fab2(sch_1):smb_sensor_tmp421_2_scl") )
				( member ( signalRef "@baseboard_fab2_lib.baseboard_fab2(sch_1):smb_sensor_tmp421_2_sda") )
				( member ( signalRef "@baseboard_fab2_lib.baseboard_fab2(sch_1):h_cpu1_thermtrip_g_n") )
				( member ( signalRef "@baseboard_fab2_lib.baseboard_fab2(sch_1):h_cpu1_prochot_g_n") )
				( member ( signalRef "@baseboard_fab2_lib.baseboard_fab2(sch_1):rst_pcie_midplane_n") )
				( member ( signalRef "@baseboard_fab2_lib.baseboard_fab2(sch_1):h_cpu1_memghj_memhot_g_n") )
				( member ( signalRef "@baseboard_fab2_lib.baseboard_fab2(sch_1):fm_cpu0_sktocc_lvt3_n") )
				( member ( signalRef "@baseboard_fab2_lib.baseboard_fab2(sch_1):irq_vm_int_n") )
				( member ( signalRef "@baseboard_fab2_lib.baseboard_fab2(sch_1):smb_smlink0_stby_lvc3_scl_r") )
				( member ( signalRef "@baseboard_fab2_lib.baseboard_fab2(sch_1):smb_cpu1_pe_hp_gtl_r_scl") )
				( member ( signalRef "@baseboard_fab2_lib.baseboard_fab2(sch_1):smb_smlink0_stby_lvc3_sda_r") )
				( member ( signalRef "@baseboard_fab2_lib.baseboard_fab2(sch_1):h_cpu0_thermtrip_g_n") )
				( member ( signalRef "@baseboard_fab2_lib.baseboard_fab2(sch_1):tp_cpu0_rsvd_287") )
				( member ( signalRef "@baseboard_fab2_lib.baseboard_fab2(sch_1):h_cpu1_fivr_fault_g") )
				( member ( signalRef "@baseboard_fab2_lib.baseboard_fab2(sch_1):tp_cpu0_rsvd_298") )
				( member ( signalRef "@baseboard_fab2_lib.baseboard_fab2(sch_1):smb_cpu1_pe_hp_gtl_r_sda") )
				( member ( signalRef "@baseboard_fab2_lib.baseboard_fab2(sch_1):smb_vr_scl_vddq_def") )
				( member ( signalRef "@baseboard_fab2_lib.baseboard_fab2(sch_1):smb_vr_scl_vddq_ghj") )
				( member ( signalRef "@baseboard_fab2_lib.baseboard_fab2(sch_1):smb_vr_scl_vddq_klm") )
				( member ( signalRef "@baseboard_fab2_lib.baseboard_fab2(sch_1):tp_cpu0_rsvd_299") )
				( member ( signalRef "@baseboard_fab2_lib.baseboard_fab2(sch_1):h_cpu1_memghj_memhot") )
				( member ( signalRef "@baseboard_fab2_lib.baseboard_fab2(sch_1):fm_heartbeat_led") )
				( member ( signalRef "@baseboard_fab2_lib.baseboard_fab2(sch_1):smb_vr_sda_vddq_def") )
				( member ( signalRef "@baseboard_fab2_lib.baseboard_fab2(sch_1):smb_vr_sda_vddq_ghj") )
				( member ( signalRef "@baseboard_fab2_lib.baseboard_fab2(sch_1):smb_vr_sda_vddq_klm") )
				( member ( signalRef "@baseboard_fab2_lib.baseboard_fab2(sch_1):smb_vr_stby_lvc3_scl_r1") )
				( member ( signalRef "@baseboard_fab2_lib.baseboard_fab2(sch_1):smb_vr_stby_lvc3_sda_r1") )
				( member ( signalRef "@baseboard_fab2_lib.baseboard_fab2(sch_1):tp_cpu0_rsvd_303") )
				( member ( signalRef "@baseboard_fab2_lib.baseboard_fab2(sch_1):h_cpu0_memabc_memhot_g_n") )
				( member ( signalRef "@baseboard_fab2_lib.baseboard_fab2(sch_1):rmii_bmc_ocp_crsdv") )
				( member ( signalRef "@baseboard_fab2_lib.baseboard_fab2(sch_1):rmii_bmc_ocp_rxd0") )
				( member ( signalRef "@baseboard_fab2_lib.baseboard_fab2(sch_1):rmii_bmc_ocp_rxd1") )
				( member ( signalRef "@baseboard_fab2_lib.baseboard_fab2(sch_1):rmii_bmc_ocp_rxer") )
				( member ( signalRef "@baseboard_fab2_lib.baseboard_fab2(sch_1):tp_cpu0_rsvd_304") )
				( member ( signalRef "@baseboard_fab2_lib.baseboard_fab2(sch_1):h_cpu0_prochot_g_n") )
				( member ( signalRef "@baseboard_fab2_lib.baseboard_fab2(sch_1):rmii_bmc_ocp_txen") )
				( member ( signalRef "@baseboard_fab2_lib.baseboard_fab2(sch_1):tp_cpu1_rsvd_275") )
				( member ( signalRef "@baseboard_fab2_lib.baseboard_fab2(sch_1):irq_lom_alert_n") )
				( member ( signalRef "@baseboard_fab2_lib.baseboard_fab2(sch_1):tp_cpu1_rsvd_282") )
				( member ( signalRef "@baseboard_fab2_lib.baseboard_fab2(sch_1):fm_throttle_r_n") )
				( member ( signalRef "@baseboard_fab2_lib.baseboard_fab2(sch_1):fm_throttle_r1_n") )
				( member ( signalRef "@baseboard_fab2_lib.baseboard_fab2(sch_1):tp_cpu1_rsvd_283") )
				( member ( signalRef "@baseboard_fab2_lib.baseboard_fab2(sch_1):rmii_bmc_pch_sprngvlle_rxer") )
				( member ( signalRef "@baseboard_fab2_lib.baseboard_fab2(sch_1):irq_sml1_pmbus_alert_buf_n") )
				( member ( signalRef "@baseboard_fab2_lib.baseboard_fab2(sch_1):smb_slotx24_stby_lvc3_scl_r2") )
				( member ( signalRef "@baseboard_fab2_lib.baseboard_fab2(sch_1):xdp_cpu1_tdo") )
				( member ( signalRef "@baseboard_fab2_lib.baseboard_fab2(sch_1):rmii_sprngvlle_bmc_pch_rxd0") )
				( member ( signalRef "@baseboard_fab2_lib.baseboard_fab2(sch_1):rmii_sprngvlle_bmc_pch_rxd1") )
				( member ( signalRef "@baseboard_fab2_lib.baseboard_fab2(sch_1):m_bmc_ddr3_dq(0)") )
				( member ( signalRef "@baseboard_fab2_lib.baseboard_fab2(sch_1):m_bmc_ddr3_dq(1)") )
				( member ( signalRef "@baseboard_fab2_lib.baseboard_fab2(sch_1):m_bmc_ddr3_dq(2)") )
				( member ( signalRef "@baseboard_fab2_lib.baseboard_fab2(sch_1):m_bmc_ddr3_dq(3)") )
				( member ( signalRef "@baseboard_fab2_lib.baseboard_fab2(sch_1):m_bmc_ddr3_dq(4)") )
				( member ( signalRef "@baseboard_fab2_lib.baseboard_fab2(sch_1):m_bmc_ddr3_dq(5)") )
				( member ( signalRef "@baseboard_fab2_lib.baseboard_fab2(sch_1):m_bmc_ddr3_dq(6)") )
				( member ( signalRef "@baseboard_fab2_lib.baseboard_fab2(sch_1):m_bmc_ddr3_dq(7)") )
				( member ( signalRef "@baseboard_fab2_lib.baseboard_fab2(sch_1):m_bmc_ddr3_dq(8)") )
				( member ( signalRef "@baseboard_fab2_lib.baseboard_fab2(sch_1):m_bmc_ddr3_dq(9)") )
				( member ( signalRef "@baseboard_fab2_lib.baseboard_fab2(sch_1):m_bmc_ddr3_dq(10)") )
				( member ( signalRef "@baseboard_fab2_lib.baseboard_fab2(sch_1):m_bmc_ddr3_dq(11)") )
				( member ( signalRef "@baseboard_fab2_lib.baseboard_fab2(sch_1):m_bmc_ddr3_dq(12)") )
				( member ( signalRef "@baseboard_fab2_lib.baseboard_fab2(sch_1):m_bmc_ddr3_dq(13)") )
				( member ( signalRef "@baseboard_fab2_lib.baseboard_fab2(sch_1):m_bmc_ddr3_dq(14)") )
				( member ( signalRef "@baseboard_fab2_lib.baseboard_fab2(sch_1):m_bmc_ddr3_dq(15)") )
				( member ( signalRef "@baseboard_fab2_lib.baseboard_fab2(sch_1):m_bmc_ddr3_ma(0)") )
				( member ( signalRef "@baseboard_fab2_lib.baseboard_fab2(sch_1):m_bmc_ddr3_ma(1)") )
				( member ( signalRef "@baseboard_fab2_lib.baseboard_fab2(sch_1):m_bmc_ddr3_ma(2)") )
				( member ( signalRef "@baseboard_fab2_lib.baseboard_fab2(sch_1):m_bmc_ddr3_ma(3)") )
				( member ( signalRef "@baseboard_fab2_lib.baseboard_fab2(sch_1):m_bmc_ddr3_ma(4)") )
				( member ( signalRef "@baseboard_fab2_lib.baseboard_fab2(sch_1):m_bmc_ddr3_ma(5)") )
				( member ( signalRef "@baseboard_fab2_lib.baseboard_fab2(sch_1):fm_cpu1_pkgid2") )
				( member ( signalRef "@baseboard_fab2_lib.baseboard_fab2(sch_1):pwrgd_p12v_hsc") )
				( member ( signalRef "@baseboard_fab2_lib.baseboard_fab2(sch_1):lpc_lad2_io2") )
				( member ( signalRef "@baseboard_fab2_lib.baseboard_fab2(sch_1):pwrgd_sys_pwrok") )
				( member ( signalRef "@baseboard_fab2_lib.baseboard_fab2(sch_1):m_bmc_ddr3_ma(9)") )
				( member ( signalRef "@baseboard_fab2_lib.baseboard_fab2(sch_1):spi_pch_cs0_n") )
				( member ( signalRef "@baseboard_fab2_lib.baseboard_fab2(sch_1):fm_uv_adr_trigger_n") )
				( member ( signalRef "@baseboard_fab2_lib.baseboard_fab2(sch_1):irq_bmc_pch_nmi_stby_n") )
				( member ( signalRef "@baseboard_fab2_lib.baseboard_fab2(sch_1):irq_bmc_pch_smi_lpc_n") )
				( member ( signalRef "@baseboard_fab2_lib.baseboard_fab2(sch_1):m_bmc_ddr3_ma(6)") )
				( member ( signalRef "@baseboard_fab2_lib.baseboard_fab2(sch_1):m_bmc_ddr3_ma(7)") )
				( member ( signalRef "@baseboard_fab2_lib.baseboard_fab2(sch_1):irq_hfi0_cpu0_lvt2_n") )
				( member ( signalRef "@baseboard_fab2_lib.baseboard_fab2(sch_1):irq_cpu0_vrhot") )
				( member ( signalRef "@baseboard_fab2_lib.baseboard_fab2(sch_1):irq_hfi1_cpu0_lvt2_n") )
				( member ( signalRef "@baseboard_fab2_lib.baseboard_fab2(sch_1):irq_cpu1_vrhot") )
				( member ( signalRef "@baseboard_fab2_lib.baseboard_fab2(sch_1):fm_dimm_event_fet") )
				( member ( signalRef "@baseboard_fab2_lib.baseboard_fab2(sch_1):smb_slotx24_stby_lvc3_sda_r2") )
				( member ( signalRef "@baseboard_fab2_lib.baseboard_fab2(sch_1):h_cpu0_memdef_memhot_g_r_n") )
				( member ( signalRef "@baseboard_fab2_lib.baseboard_fab2(sch_1):irq_lpc_serirq_n") )
				( member ( signalRef "@baseboard_fab2_lib.baseboard_fab2(sch_1):irq_lvc3_wake_n") )
				( member ( signalRef "@baseboard_fab2_lib.baseboard_fab2(sch_1):h_cpu0_memdef_memhot_lvt3_k_n") )
				( member ( signalRef "@baseboard_fab2_lib.baseboard_fab2(sch_1):irq_pvccin_cpu0_vrhot_lvc3_n") )
				( member ( signalRef "@baseboard_fab2_lib.baseboard_fab2(sch_1):irq_pvccin_cpu1_vrhot_lvc3_n") )
				( member ( signalRef "@baseboard_fab2_lib.baseboard_fab2(sch_1):irq_cpu0_prochot_g_n") )
				( member ( signalRef "@baseboard_fab2_lib.baseboard_fab2(sch_1):irq_pvddq_abc_vrhot_lvt3_n") )
				( member ( signalRef "@baseboard_fab2_lib.baseboard_fab2(sch_1):irq_pvddq_def_vrhot_lvt3_n") )
				( member ( signalRef "@baseboard_fab2_lib.baseboard_fab2(sch_1):irq_pvddq_ghj_vrhot_lvt3_n") )
				( member ( signalRef "@baseboard_fab2_lib.baseboard_fab2(sch_1):irq_pvddq_klm_vrhot_lvt3_n") )
				( member ( signalRef "@baseboard_fab2_lib.baseboard_fab2(sch_1):h_cpu1_memghj_memhot_lvt3_bmc_n") )
				( member ( signalRef "@baseboard_fab2_lib.baseboard_fab2(sch_1):h_cpu1_memghj_memhot_lvt3_k_n") )
				( member ( signalRef "@baseboard_fab2_lib.baseboard_fab2(sch_1):lpc_lad1_io1_r") )
				( member ( signalRef "@baseboard_fab2_lib.baseboard_fab2(sch_1):smb_springville_stby_lvc3_scl") )
				( member ( signalRef "@baseboard_fab2_lib.baseboard_fab2(sch_1):irq_sml0_alert_n") )
				( member ( signalRef "@baseboard_fab2_lib.baseboard_fab2(sch_1):tp_cpu1_rsvd_298") )
				( member ( signalRef "@baseboard_fab2_lib.baseboard_fab2(sch_1):m_bmc_ddr3_ma(8)") )
				( member ( signalRef "@baseboard_fab2_lib.baseboard_fab2(sch_1):irq_sml1_pmbus_alert_n") )
				( member ( signalRef "@baseboard_fab2_lib.baseboard_fab2(sch_1):irq_cpu1_prochot_g_n") )
				( member ( signalRef "@baseboard_fab2_lib.baseboard_fab2(sch_1):h_cpu1_memklm_memhot_lvt3_bmc_n") )
				( member ( signalRef "@baseboard_fab2_lib.baseboard_fab2(sch_1):h_cpu1_memklm_memhot_lvt3_k_n") )
				( member ( signalRef "@baseboard_fab2_lib.baseboard_fab2(sch_1):fm_cpu1_cd_pres") )
				( member ( signalRef "@baseboard_fab2_lib.baseboard_fab2(sch_1):fm_ocp_mezzc_pres_n") )
				( member ( signalRef "@baseboard_fab2_lib.baseboard_fab2(sch_1):fm_mem_event_func") )
				( member ( signalRef "@baseboard_fab2_lib.baseboard_fab2(sch_1):lpc_lad1_io1") )
				( member ( signalRef "@baseboard_fab2_lib.baseboard_fab2(sch_1):tp_shared_kr_mdio_0") )
				( member ( signalRef "@baseboard_fab2_lib.baseboard_fab2(sch_1):fm_cpu1_pkgid0") )
				( member ( signalRef "@baseboard_fab2_lib.baseboard_fab2(sch_1):xdp_syspwrok") )
				( member ( signalRef "@baseboard_fab2_lib.baseboard_fab2(sch_1):fm_cpu0_or_cpu1_mcp_pres") )
				( member ( signalRef "@baseboard_fab2_lib.baseboard_fab2(sch_1):rst_bmc_srst_r_n") )
				( member ( signalRef "@baseboard_fab2_lib.baseboard_fab2(sch_1):h_cpu0_prochot_g_r_n") )
				( member ( signalRef "@baseboard_fab2_lib.baseboard_fab2(sch_1):h_cpu0_prochot_g_pch_n") )
				( member ( signalRef "@baseboard_fab2_lib.baseboard_fab2(sch_1):tp_cpu1_rsvd_299") )
				( member ( signalRef "@baseboard_fab2_lib.baseboard_fab2(sch_1):smb_springville_stby_lvc3_sda") )
				( member ( signalRef "@baseboard_fab2_lib.baseboard_fab2(sch_1):tp_cpu1_rsvd_303") )
				( member ( signalRef "@baseboard_fab2_lib.baseboard_fab2(sch_1):pwrgd_pvcciomcp_cpu0") )
				( member ( signalRef "@baseboard_fab2_lib.baseboard_fab2(sch_1):tp_cpld1_pt17c") )
				( member ( signalRef "@baseboard_fab2_lib.baseboard_fab2(sch_1):fm_cpu1_pkgid1") )
				( member ( signalRef "@baseboard_fab2_lib.baseboard_fab2(sch_1):xtal_ck_mng_in") )
				( member ( signalRef "@baseboard_fab2_lib.baseboard_fab2(sch_1):xtal_ck_mng_out") )
				( member ( signalRef "@baseboard_fab2_lib.baseboard_fab2(sch_1):xtal_kr_25m_in") )
				( member ( signalRef "@baseboard_fab2_lib.baseboard_fab2(sch_1):xtal_kr_25m_out") )
				( member ( signalRef "@baseboard_fab2_lib.baseboard_fab2(sch_1):tp_cpu1_rsvd_287") )
				( member ( signalRef "@baseboard_fab2_lib.baseboard_fab2(sch_1):h_cpu1_memghj_memhot_g_pch_n") )
				( member ( signalRef "@baseboard_fab2_lib.baseboard_fab2(sch_1):tp_cpu1_rsvd_304") )
				( member ( signalRef "@baseboard_fab2_lib.baseboard_fab2(sch_1):xtal_25mhz_out") )
				( member ( signalRef "@baseboard_fab2_lib.baseboard_fab2(sch_1):lpc_lad2_io2_r") )
				( member ( signalRef "@baseboard_fab2_lib.baseboard_fab2(sch_1):pu_pirom_cpu1_addr0") )
				( member ( signalRef "@baseboard_fab2_lib.baseboard_fab2(sch_1):pd_pirom_cpu0_addr0") )
				( member ( signalRef "@baseboard_fab2_lib.baseboard_fab2(sch_1):h_cpu0_memabc_memhot_lvt3_k_n") )
				( member ( signalRef "@baseboard_fab2_lib.baseboard_fab2(sch_1):h_cpu0_memdef_memhot_lvt3_bmc_n") )
				( member ( signalRef "@baseboard_fab2_lib.baseboard_fab2(sch_1):pd_pirom_cpu0_addr1") )
				( member ( signalRef "@baseboard_fab2_lib.baseboard_fab2(sch_1):pd_pirom_cpu0_addr2") )
				( member ( signalRef "@baseboard_fab2_lib.baseboard_fab2(sch_1):h_cpu0_memabc_memhot_lvt3_bmc_n") )
				( member ( signalRef "@baseboard_fab2_lib.baseboard_fab2(sch_1):pu_m2_clk_req_n") )
				( member ( signalRef "@baseboard_fab2_lib.baseboard_fab2(sch_1):pd_pirom_cpu1_addr1") )
				( member ( signalRef "@baseboard_fab2_lib.baseboard_fab2(sch_1):pd_pirom_cpu1_addr2") )
				( member ( signalRef "@baseboard_fab2_lib.baseboard_fab2(sch_1):smb_pirom_cpu0_scl") )
				( member ( signalRef "@baseboard_fab2_lib.baseboard_fab2(sch_1):smb_pirom_cpu0_sda") )
				( member ( signalRef "@baseboard_fab2_lib.baseboard_fab2(sch_1):fm_cpu1_prochot_lvt3_r_n") )
				( member ( signalRef "@baseboard_fab2_lib.baseboard_fab2(sch_1):h_cpu1_memghj_memhot_g_r_n") )
				( member ( signalRef "@baseboard_fab2_lib.baseboard_fab2(sch_1):h_cpu1_memklm_memhot_g_pch_n") )
				( member ( signalRef "@baseboard_fab2_lib.baseboard_fab2(sch_1):h_cpu1_memklm_memhot_g_r_n") )
				( member ( signalRef "@baseboard_fab2_lib.baseboard_fab2(sch_1):h_cpu1_prochot_g_pch_n") )
				( member ( signalRef "@baseboard_fab2_lib.baseboard_fab2(sch_1):h_cpu1_prochot_g_r_n") )
				( member ( signalRef "@baseboard_fab2_lib.baseboard_fab2(sch_1):smb_pirom_cpu1_scl") )
				( member ( signalRef "@baseboard_fab2_lib.baseboard_fab2(sch_1):svid_clk_pvccio_cpu0") )
				( member ( signalRef "@baseboard_fab2_lib.baseboard_fab2(sch_1):rst_pcie_m2_dev_n") )
				( member ( signalRef "@baseboard_fab2_lib.baseboard_fab2(sch_1):lpc_lad0_io0_r") )
				( member ( signalRef "@baseboard_fab2_lib.baseboard_fab2(sch_1):smb_cpu1_pe_hp_gtl_scl") )
				( member ( signalRef "@baseboard_fab2_lib.baseboard_fab2(sch_1):smb_cpu1_pe_hp_gtl_sda") )
				( member ( signalRef "@baseboard_fab2_lib.baseboard_fab2(sch_1):smb_pirom_cpu1_sda") )
				( member ( signalRef "@baseboard_fab2_lib.baseboard_fab2(sch_1):lpc_lad0_io0") )
				( member ( signalRef "@baseboard_fab2_lib.baseboard_fab2(sch_1):vr_vrrdy_pvccin_cpu0") )
				( member ( signalRef "@baseboard_fab2_lib.baseboard_fab2(sch_1):vr_vrrdy_pvccin_cpu1") )
				( member ( signalRef "@baseboard_fab2_lib.baseboard_fab2(sch_1):pwrgd_pvpp_abc_r") )
				( member ( signalRef "@baseboard_fab2_lib.baseboard_fab2(sch_1):pwrgd_p1v8_pch_stby_r") )
				( member ( signalRef "@baseboard_fab2_lib.baseboard_fab2(sch_1):pwrgd_cpu0_drampwrok_abc_g") )
				( member ( signalRef "@baseboard_fab2_lib.baseboard_fab2(sch_1):vr_pvddq_abc_ph1_ocset") )
				( member ( signalRef "@baseboard_fab2_lib.baseboard_fab2(sch_1):pwrgd_cpu0_drampwrok_def_g") )
				( member ( signalRef "@baseboard_fab2_lib.baseboard_fab2(sch_1):smb_host_stby_lvc3_sda_r") )
				( member ( signalRef "@baseboard_fab2_lib.baseboard_fab2(sch_1):pwrgd_cpu0_g") )
				( member ( signalRef "@baseboard_fab2_lib.baseboard_fab2(sch_1):pwrgd_cpu0_lvc3") )
				( member ( signalRef "@baseboard_fab2_lib.baseboard_fab2(sch_1):m_bmc_ddr3_ma(10)") )
				( member ( signalRef "@baseboard_fab2_lib.baseboard_fab2(sch_1):irq_dimm_save_lvt3") )
				( member ( signalRef "@baseboard_fab2_lib.baseboard_fab2(sch_1):pwrgd_cpu1_drampwrok_ghj_g") )
				( member ( signalRef "@baseboard_fab2_lib.baseboard_fab2(sch_1):m_bmc_ddr3_mras_n") )
				( member ( signalRef "@baseboard_fab2_lib.baseboard_fab2(sch_1):pwrgd_cpu1_drampwrok_klm_g") )
				( member ( signalRef "@baseboard_fab2_lib.baseboard_fab2(sch_1):irq_dimm_save_lvt3_n") )
				( member ( signalRef "@baseboard_fab2_lib.baseboard_fab2(sch_1):pwrgd_cpu1_g") )
				( member ( signalRef "@baseboard_fab2_lib.baseboard_fab2(sch_1):pwrgd_cpu1_lvc3") )
				( member ( signalRef "@baseboard_fab2_lib.baseboard_fab2(sch_1):m_bmc_ddr3_ma(11)") )
				( member ( signalRef "@baseboard_fab2_lib.baseboard_fab2(sch_1):pwrgd_pvpp_klm_r") )
				( member ( signalRef "@baseboard_fab2_lib.baseboard_fab2(sch_1):pwrgd_drampwrgd") )
				( member ( signalRef "@baseboard_fab2_lib.baseboard_fab2(sch_1):pwrgd_dsw_pwrok") )
				( member ( signalRef "@baseboard_fab2_lib.baseboard_fab2(sch_1):m_bmc_ddr3_ma(12)") )
				( member ( signalRef "@baseboard_fab2_lib.baseboard_fab2(sch_1):fm_db_uart_sel4_n") )
				( member ( signalRef "@baseboard_fab2_lib.baseboard_fab2(sch_1):m_bmc_ddr3_mcas_n") )
				( member ( signalRef "@baseboard_fab2_lib.baseboard_fab2(sch_1):fan_tach3") )
				( member ( signalRef "@baseboard_fab2_lib.baseboard_fab2(sch_1):pwrgd_pch_pwrok") )
				( member ( signalRef "@baseboard_fab2_lib.baseboard_fab2(sch_1):m_bmc_ddr3_mcke") )
				( member ( signalRef "@baseboard_fab2_lib.baseboard_fab2(sch_1):smb_host_stby_lvc3_scl_r") )
				( member ( signalRef "@baseboard_fab2_lib.baseboard_fab2(sch_1):lpc_lad3_io3_r") )
				( member ( signalRef "@baseboard_fab2_lib.baseboard_fab2(sch_1):m_bmc_ddr3_mcs_n") )
				( member ( signalRef "@baseboard_fab2_lib.baseboard_fab2(sch_1):m_bmc_ddr3_mdm_0") )
				( member ( signalRef "@baseboard_fab2_lib.baseboard_fab2(sch_1):lpc_lframe_n_cs0_r_n") )
				( member ( signalRef "@baseboard_fab2_lib.baseboard_fab2(sch_1):m_bmc_ddr3_mdm_1") )
				( member ( signalRef "@baseboard_fab2_lib.baseboard_fab2(sch_1):pwrgd_pvccin_cpu0") )
				( member ( signalRef "@baseboard_fab2_lib.baseboard_fab2(sch_1):pwrgd_pvccin_cpu1") )
				( member ( signalRef "@baseboard_fab2_lib.baseboard_fab2(sch_1):m_bmc_ddr3_modt") )
				( member ( signalRef "@baseboard_fab2_lib.baseboard_fab2(sch_1):fm_cpu1_proc_id1") )
				( member ( signalRef "@baseboard_fab2_lib.baseboard_fab2(sch_1):vr_pvddq_abc_ph2_ocset") )
				( member ( signalRef "@baseboard_fab2_lib.baseboard_fab2(sch_1):fm_cpu1_sktocc_lvt3_n") )
				( member ( signalRef "@baseboard_fab2_lib.baseboard_fab2(sch_1):pwrgd_pvddq_abc") )
				( member ( signalRef "@baseboard_fab2_lib.baseboard_fab2(sch_1):pwrgd_pvddq_abc_r") )
				( member ( signalRef "@baseboard_fab2_lib.baseboard_fab2(sch_1):pwrgd_pvddq_def") )
				( member ( signalRef "@baseboard_fab2_lib.baseboard_fab2(sch_1):pwrgd_pvddq_def_r") )
				( member ( signalRef "@baseboard_fab2_lib.baseboard_fab2(sch_1):pwrgd_pvddq_ghj") )
				( member ( signalRef "@baseboard_fab2_lib.baseboard_fab2(sch_1):pwrgd_pvddq_ghj_r") )
				( member ( signalRef "@baseboard_fab2_lib.baseboard_fab2(sch_1):pwrgd_pvddq_klm") )
				( member ( signalRef "@baseboard_fab2_lib.baseboard_fab2(sch_1):pwrgd_pvddq_klm_r") )
				( member ( signalRef "@baseboard_fab2_lib.baseboard_fab2(sch_1):vr_pvddq_def_ph1_ocset") )
				( member ( signalRef "@baseboard_fab2_lib.baseboard_fab2(sch_1):vr_pvccio_cpu1_ocset") )
				( member ( signalRef "@baseboard_fab2_lib.baseboard_fab2(sch_1):fan_tach2_cpu1_d2") )
				( member ( signalRef "@baseboard_fab2_lib.baseboard_fab2(sch_1):lpc_lframe_n_cs0_n") )
				( member ( signalRef "@baseboard_fab2_lib.baseboard_fab2(sch_1):fm_cpu1_proc_id0") )
				( member ( signalRef "@baseboard_fab2_lib.baseboard_fab2(sch_1):vr_pvddq_def_ph2_ocset") )
				( member ( signalRef "@baseboard_fab2_lib.baseboard_fab2(sch_1):pwrgd_pvpp_abc") )
				( member ( signalRef "@baseboard_fab2_lib.baseboard_fab2(sch_1):fan_tach0_cpu0_d2") )
				( member ( signalRef "@baseboard_fab2_lib.baseboard_fab2(sch_1):pwrgd_pvpp_def") )
				( member ( signalRef "@baseboard_fab2_lib.baseboard_fab2(sch_1):fan_tach1") )
				( member ( signalRef "@baseboard_fab2_lib.baseboard_fab2(sch_1):pwrgd_pvpp_ghj") )
				( member ( signalRef "@baseboard_fab2_lib.baseboard_fab2(sch_1):fan_tach2") )
				( member ( signalRef "@baseboard_fab2_lib.baseboard_fab2(sch_1):pwrgd_pvpp_klm") )
				( member ( signalRef "@baseboard_fab2_lib.baseboard_fab2(sch_1):fan_tach2_cpu1_d1") )
				( member ( signalRef "@baseboard_fab2_lib.baseboard_fab2(sch_1):m_bmc_ddr3_mwe_n") )
				( member ( signalRef "@baseboard_fab2_lib.baseboard_fab2(sch_1):fm_db_uart_sel3_n") )
				( member ( signalRef "@baseboard_fab2_lib.baseboard_fab2(sch_1):fm_db_uart_sel1_n") )
				( member ( signalRef "@baseboard_fab2_lib.baseboard_fab2(sch_1):vr_pvddq_ghj_ph1_ocset") )
				( member ( signalRef "@baseboard_fab2_lib.baseboard_fab2(sch_1):pwrgd_pvsa_cpu0") )
				( member ( signalRef "@baseboard_fab2_lib.baseboard_fab2(sch_1):pwrgd_pvsa_cpu1") )
				( member ( signalRef "@baseboard_fab2_lib.baseboard_fab2(sch_1):vr_pvddq_ghj_ph2_ocset") )
				( member ( signalRef "@baseboard_fab2_lib.baseboard_fab2(sch_1):pwrgd_p1v26_bmc_stby_r") )
				( member ( signalRef "@baseboard_fab2_lib.baseboard_fab2(sch_1):vr_pvddq_klm_ph1_ocset") )
				( member ( signalRef "@baseboard_fab2_lib.baseboard_fab2(sch_1):pwrgd_p1v538_bmc_stby_r") )
				( member ( signalRef "@baseboard_fab2_lib.baseboard_fab2(sch_1):vr_pvddq_klm_ph2_ocset") )
				( member ( signalRef "@baseboard_fab2_lib.baseboard_fab2(sch_1):pwrgd_p3v3_stby_r") )
				( member ( signalRef "@baseboard_fab2_lib.baseboard_fab2(sch_1):vr_pvnn_pch_stby_ocset") )
				( member ( signalRef "@baseboard_fab2_lib.baseboard_fab2(sch_1):irq_oc_detect_n") )
				( member ( signalRef "@baseboard_fab2_lib.baseboard_fab2(sch_1):vr_pvsa_cpu0_ocset") )
				( member ( signalRef "@baseboard_fab2_lib.baseboard_fab2(sch_1):svid_clk_pvccio_cpu1") )
				( member ( signalRef "@baseboard_fab2_lib.baseboard_fab2(sch_1):pwrgd_pvnn_p1v05_pch") )
				( member ( signalRef "@baseboard_fab2_lib.baseboard_fab2(sch_1):fan_tach0") )
				( member ( signalRef "@baseboard_fab2_lib.baseboard_fab2(sch_1):h_cpu_bmcinit_r") )
				( member ( signalRef "@baseboard_fab2_lib.baseboard_fab2(sch_1):m_bmc_ddr3_mba_0") )
				( member ( signalRef "@baseboard_fab2_lib.baseboard_fab2(sch_1):tp_jtag_mcp_io8_rsvd") )
				( member ( signalRef "@baseboard_fab2_lib.baseboard_fab2(sch_1):vr_pvsa_cpu1_ocset") )
				( member ( signalRef "@baseboard_fab2_lib.baseboard_fab2(sch_1):vr_pvccin_cpu0_ph1_ocset") )
				( member ( signalRef "@baseboard_fab2_lib.baseboard_fab2(sch_1):lpc_lad3_io3") )
				( member ( signalRef "@baseboard_fab2_lib.baseboard_fab2(sch_1):pwrgd_p1v8_pch_stby") )
				( member ( signalRef "@baseboard_fab2_lib.baseboard_fab2(sch_1):vr_pvccin_cpu0_ph2_ocset") )
				( member ( signalRef "@baseboard_fab2_lib.baseboard_fab2(sch_1):fm_db_present") )
				( member ( signalRef "@baseboard_fab2_lib.baseboard_fab2(sch_1):pwrgd_pvpp_def_r") )
				( member ( signalRef "@baseboard_fab2_lib.baseboard_fab2(sch_1):pwrgd_pvpp_ghj_r") )
				( member ( signalRef "@baseboard_fab2_lib.baseboard_fab2(sch_1):pwrgd_pvnn_pch_r") )
				( member ( signalRef "@baseboard_fab2_lib.baseboard_fab2(sch_1):h_cpu0_fast_wake") )
				( member ( signalRef "@baseboard_fab2_lib.baseboard_fab2(sch_1):pwrgd_p1v26_bmc_stby") )
				( member ( signalRef "@baseboard_fab2_lib.baseboard_fab2(sch_1):vr_pvccin_cpu0_ph3_ocset") )
				( member ( signalRef "@baseboard_fab2_lib.baseboard_fab2(sch_1):pwrgd_p1v538_bmc_stby") )
				( member ( signalRef "@baseboard_fab2_lib.baseboard_fab2(sch_1):fm_db_uart_sel2_n") )
				( member ( signalRef "@baseboard_fab2_lib.baseboard_fab2(sch_1):m_bmc_ddr3_mba_2") )
				( member ( signalRef "@baseboard_fab2_lib.baseboard_fab2(sch_1):pwrgd_p3v3_stby") )
				( member ( signalRef "@baseboard_fab2_lib.baseboard_fab2(sch_1):fan_tach0_cpu0_d1") )
				( member ( signalRef "@baseboard_fab2_lib.baseboard_fab2(sch_1):vr_pvccin_cpu0_ph4_ocset") )
				( member ( signalRef "@baseboard_fab2_lib.baseboard_fab2(sch_1):m_bmc_ddr3_mba_1") )
				( member ( signalRef "@baseboard_fab2_lib.baseboard_fab2(sch_1):pwrgd_p5v_stby") )
				( member ( signalRef "@baseboard_fab2_lib.baseboard_fab2(sch_1):xdp_rst_co_n") )
				( member ( signalRef "@baseboard_fab2_lib.baseboard_fab2(sch_1):xdp_tdi") )
				( member ( signalRef "@baseboard_fab2_lib.baseboard_fab2(sch_1):xdp_tdo") )
				( member ( signalRef "@baseboard_fab2_lib.baseboard_fab2(sch_1):xdp_tms") )
				( member ( signalRef "@baseboard_fab2_lib.baseboard_fab2(sch_1):xdp_trst_n") )
				( member ( signalRef "@baseboard_fab2_lib.baseboard_fab2(sch_1):jtag_tck") )
				( member ( signalRef "@baseboard_fab2_lib.baseboard_fab2(sch_1):jtag_tdi") )
				( member ( signalRef "@baseboard_fab2_lib.baseboard_fab2(sch_1):jtag_tdo") )
				( member ( signalRef "@baseboard_fab2_lib.baseboard_fab2(sch_1):jtag_tms") )
				( member ( signalRef "@baseboard_fab2_lib.baseboard_fab2(sch_1):jtag_trst_n") )
				( member ( signalRef "@baseboard_fab2_lib.baseboard_fab2(sch_1):irq_uv_detect_n") )
				( member ( signalRef "@baseboard_fab2_lib.baseboard_fab2(sch_1):spi_bmc_bt_di_r") )
				( member ( signalRef "@baseboard_fab2_lib.baseboard_fab2(sch_1):spi_bmc_bt_di") )
				( member ( signalRef "@baseboard_fab2_lib.baseboard_fab2(sch_1):pwrgd_p3v3") )
				( member ( signalRef "@baseboard_fab2_lib.baseboard_fab2(sch_1):spi_bmc_bt_cs_r_n") )
				( member ( signalRef "@baseboard_fab2_lib.baseboard_fab2(sch_1):spi_bmc_bt_cs_n") )
				( member ( signalRef "@baseboard_fab2_lib.baseboard_fab2(sch_1):rst_bmc_ddr3_n") )
				( member ( signalRef "@baseboard_fab2_lib.baseboard_fab2(sch_1):rst_bmc_ddr3_r_n") )
				( member ( signalRef "@baseboard_fab2_lib.baseboard_fab2(sch_1):rst_bmc_lvc3_n") )
				( member ( signalRef "@baseboard_fab2_lib.baseboard_fab2(sch_1):smb_lan_stby_lvc3_scl") )
				( member ( signalRef "@baseboard_fab2_lib.baseboard_fab2(sch_1):rst_bmc_sysrst_btn_out_n") )
				( member ( signalRef "@baseboard_fab2_lib.baseboard_fab2(sch_1):fm_disable_fan_n") )
				( member ( signalRef "@baseboard_fab2_lib.baseboard_fab2(sch_1):rst_cpu0_g_n") )
				( member ( signalRef "@baseboard_fab2_lib.baseboard_fab2(sch_1):rst_cpu0_lvc3_n") )
				( member ( signalRef "@baseboard_fab2_lib.baseboard_fab2(sch_1):smb_lan_stby_lvc3_scl_r") )
				( member ( signalRef "@baseboard_fab2_lib.baseboard_fab2(sch_1):rst_cpu1_g_n") )
				( member ( signalRef "@baseboard_fab2_lib.baseboard_fab2(sch_1):rst_cpu1_lvc3_n") )
				( member ( signalRef "@baseboard_fab2_lib.baseboard_fab2(sch_1):smb_lan_stby_lvc3_scl_r1") )
				( member ( signalRef "@baseboard_fab2_lib.baseboard_fab2(sch_1):rst_pcie_riser1_perst_n") )
				( member ( signalRef "@baseboard_fab2_lib.baseboard_fab2(sch_1):fm_db1200_smb_sa1") )
				( member ( signalRef "@baseboard_fab2_lib.baseboard_fab2(sch_1):rst_pcie_cpu_dev0_n") )
				( member ( signalRef "@baseboard_fab2_lib.baseboard_fab2(sch_1):rst_pcie_cpu_dev0_r_n") )
				( member ( signalRef "@baseboard_fab2_lib.baseboard_fab2(sch_1):rst_pcie_cpu_dev1_n") )
				( member ( signalRef "@baseboard_fab2_lib.baseboard_fab2(sch_1):rst_pcie_cpu_dev1_r_n") )
				( member ( signalRef "@baseboard_fab2_lib.baseboard_fab2(sch_1):rst_pcie_cpu_dev2_n") )
				( member ( signalRef "@baseboard_fab2_lib.baseboard_fab2(sch_1):rst_pcie_cpu_dev2_r_n") )
				( member ( signalRef "@baseboard_fab2_lib.baseboard_fab2(sch_1):rst_pcie_cpu_dev3_n") )
				( member ( signalRef "@baseboard_fab2_lib.baseboard_fab2(sch_1):rst_pcie_cpu_dev3_r_n") )
				( member ( signalRef "@baseboard_fab2_lib.baseboard_fab2(sch_1):smb_lan_stby_lvc3_sda") )
				( member ( signalRef "@baseboard_fab2_lib.baseboard_fab2(sch_1):smb_lan_stby_lvc3_sda_r") )
				( member ( signalRef "@baseboard_fab2_lib.baseboard_fab2(sch_1):spi_bmc_bt_clk") )
				( member ( signalRef "@baseboard_fab2_lib.baseboard_fab2(sch_1):rst_pcie_pch_perst_n") )
				( member ( signalRef "@baseboard_fab2_lib.baseboard_fab2(sch_1):rst_pltrst_buf_n") )
				( member ( signalRef "@baseboard_fab2_lib.baseboard_fab2(sch_1):rst_pltrst_n") )
				( member ( signalRef "@baseboard_fab2_lib.baseboard_fab2(sch_1):vr_pvccin_cpu1_ph1_ocset") )
				( member ( signalRef "@baseboard_fab2_lib.baseboard_fab2(sch_1):vr_p1v05_pch_stby_ocset") )
				( member ( signalRef "@baseboard_fab2_lib.baseboard_fab2(sch_1):fm_hbw_bypass_lowbw_n") )
				( member ( signalRef "@baseboard_fab2_lib.baseboard_fab2(sch_1):rst_rsmrst_n") )
				( member ( signalRef "@baseboard_fab2_lib.baseboard_fab2(sch_1):fm_heartbeat_led_a") )
				( member ( signalRef "@baseboard_fab2_lib.baseboard_fab2(sch_1):fm_heartbeat_led_k") )
				( member ( signalRef "@baseboard_fab2_lib.baseboard_fab2(sch_1):rst_rtcrst_n") )
				( member ( signalRef "@baseboard_fab2_lib.baseboard_fab2(sch_1):rst_srtcrst_n") )
				( member ( signalRef "@baseboard_fab2_lib.baseboard_fab2(sch_1):rst_system_btn_n") )
				( member ( signalRef "@baseboard_fab2_lib.baseboard_fab2(sch_1):fm_fast_prochot_en") )
				( member ( signalRef "@baseboard_fab2_lib.baseboard_fab2(sch_1):spi_bmc_bt_clk_r") )
				( member ( signalRef "@baseboard_fab2_lib.baseboard_fab2(sch_1):rst_pltrst_sprv_r_n") )
				( member ( signalRef "@baseboard_fab2_lib.baseboard_fab2(sch_1):fm_dis_adr_dly") )
				( member ( signalRef "@baseboard_fab2_lib.baseboard_fab2(sch_1):pwrgd_p3v3_r") )
				( member ( signalRef "@baseboard_fab2_lib.baseboard_fab2(sch_1):sgpio_bmc_din") )
				( member ( signalRef "@baseboard_fab2_lib.baseboard_fab2(sch_1):sgpio_bmc_din_r") )
				( member ( signalRef "@baseboard_fab2_lib.baseboard_fab2(sch_1):vr_pvccin_cpu0_ph5_ocset") )
				( member ( signalRef "@baseboard_fab2_lib.baseboard_fab2(sch_1):fm_db1200_smb_sa0") )
				( member ( signalRef "@baseboard_fab2_lib.baseboard_fab2(sch_1):spi_pch_tpm_clk_r") )
				( member ( signalRef "@baseboard_fab2_lib.baseboard_fab2(sch_1):irq_bmc_pch_sci_lpc_n") )
				( member ( signalRef "@baseboard_fab2_lib.baseboard_fab2(sch_1):h_cpu0_fast_wake_lvt3_n") )
				( member ( signalRef "@baseboard_fab2_lib.baseboard_fab2(sch_1):irq_hsc_fault_n") )
				( member ( signalRef "@baseboard_fab2_lib.baseboard_fab2(sch_1):fm_enable_fan_power") )
				( member ( signalRef "@baseboard_fab2_lib.baseboard_fab2(sch_1):fm_dual_bios_sel_n") )
				( member ( signalRef "@baseboard_fab2_lib.baseboard_fab2(sch_1):irq_mezz_lan_alert_n") )
				( member ( signalRef "@baseboard_fab2_lib.baseboard_fab2(sch_1):irq_pvccio_cpu0_vrhot_n") )
				( member ( signalRef "@baseboard_fab2_lib.baseboard_fab2(sch_1):irq_pvccio_cpu1_vrhot_n") )
				( member ( signalRef "@baseboard_fab2_lib.baseboard_fab2(sch_1):irq_pvnn_pch_vrhot_n") )
				( member ( signalRef "@baseboard_fab2_lib.baseboard_fab2(sch_1):fm_gbe_lom_disable_n") )
				( member ( signalRef "@baseboard_fab2_lib.baseboard_fab2(sch_1):sgpio_bmc_dout") )
				( member ( signalRef "@baseboard_fab2_lib.baseboard_fab2(sch_1):sgpio_bmc_dout_r") )
				( member ( signalRef "@baseboard_fab2_lib.baseboard_fab2(sch_1):jtag_bmc_trst_n") )
				( member ( signalRef "@baseboard_fab2_lib.baseboard_fab2(sch_1):jtag_pch_gbe_clk") )
				( member ( signalRef "@baseboard_fab2_lib.baseboard_fab2(sch_1):jtag_pch_gbe_tdi") )
				( member ( signalRef "@baseboard_fab2_lib.baseboard_fab2(sch_1):jtag_pch_gbe_tdo") )
				( member ( signalRef "@baseboard_fab2_lib.baseboard_fab2(sch_1):jtag_pch_gbe_tms") )
				( member ( signalRef "@baseboard_fab2_lib.baseboard_fab2(sch_1):jtag_pch_gbe_trst_n") )
				( member ( signalRef "@baseboard_fab2_lib.baseboard_fab2(sch_1):jtag_pld_tck") )
				( member ( signalRef "@baseboard_fab2_lib.baseboard_fab2(sch_1):jtag_pld_tdi") )
				( member ( signalRef "@baseboard_fab2_lib.baseboard_fab2(sch_1):peci_bmc") )
				( member ( signalRef "@baseboard_fab2_lib.baseboard_fab2(sch_1):peci_bmc_r") )
				( member ( signalRef "@baseboard_fab2_lib.baseboard_fab2(sch_1):peci_cpu_g") )
				( member ( signalRef "@baseboard_fab2_lib.baseboard_fab2(sch_1):peci_pch") )
				( member ( signalRef "@baseboard_fab2_lib.baseboard_fab2(sch_1):spi_bmc_bt_do") )
				( member ( signalRef "@baseboard_fab2_lib.baseboard_fab2(sch_1):svid_alert_pvddq_abc") )
				( member ( signalRef "@baseboard_fab2_lib.baseboard_fab2(sch_1):svid_alert_pvddq_def") )
				( member ( signalRef "@baseboard_fab2_lib.baseboard_fab2(sch_1):svid_alert_pvddq_ghj") )
				( member ( signalRef "@baseboard_fab2_lib.baseboard_fab2(sch_1):svid_alert_pvddq_klm") )
				( member ( signalRef "@baseboard_fab2_lib.baseboard_fab2(sch_1):svid_alert0_cpu0_n") )
				( member ( signalRef "@baseboard_fab2_lib.baseboard_fab2(sch_1):svid_alert0_cpu0_r_n") )
				( member ( signalRef "@baseboard_fab2_lib.baseboard_fab2(sch_1):svid_alert0_cpu1_n") )
				( member ( signalRef "@baseboard_fab2_lib.baseboard_fab2(sch_1):svid_alert0_cpu1_r_n") )
				( member ( signalRef "@baseboard_fab2_lib.baseboard_fab2(sch_1):svid_alert1_cpu0_n") )
				( member ( signalRef "@baseboard_fab2_lib.baseboard_fab2(sch_1):svid_alert1_cpu0_r_n") )
				( member ( signalRef "@baseboard_fab2_lib.baseboard_fab2(sch_1):svid_alert1_cpu1_n") )
				( member ( signalRef "@baseboard_fab2_lib.baseboard_fab2(sch_1):svid_alert1_cpu1_r_n") )
				( member ( signalRef "@baseboard_fab2_lib.baseboard_fab2(sch_1):svid_clk_pvddq_abc") )
				( member ( signalRef "@baseboard_fab2_lib.baseboard_fab2(sch_1):svid_clk_pvddq_def") )
				( member ( signalRef "@baseboard_fab2_lib.baseboard_fab2(sch_1):svid_clk_pvddq_ghj") )
				( member ( signalRef "@baseboard_fab2_lib.baseboard_fab2(sch_1):svid_clk_pvddq_klm") )
				( member ( signalRef "@baseboard_fab2_lib.baseboard_fab2(sch_1):svid_clk0_cpu0") )
				( member ( signalRef "@baseboard_fab2_lib.baseboard_fab2(sch_1):svid_clk0_cpu0_r") )
				( member ( signalRef "@baseboard_fab2_lib.baseboard_fab2(sch_1):svid_clk0_cpu1") )
				( member ( signalRef "@baseboard_fab2_lib.baseboard_fab2(sch_1):svid_clk0_cpu1_r") )
				( member ( signalRef "@baseboard_fab2_lib.baseboard_fab2(sch_1):svid_clk1_cpu0") )
				( member ( signalRef "@baseboard_fab2_lib.baseboard_fab2(sch_1):svid_clk1_cpu0_r") )
				( member ( signalRef "@baseboard_fab2_lib.baseboard_fab2(sch_1):svid_clk1_cpu1") )
				( member ( signalRef "@baseboard_fab2_lib.baseboard_fab2(sch_1):svid_clk1_cpu1_r") )
				( member ( signalRef "@baseboard_fab2_lib.baseboard_fab2(sch_1):svid_dio0_cpu0") )
				( member ( signalRef "@baseboard_fab2_lib.baseboard_fab2(sch_1):svid_dio0_cpu0_r") )
				( member ( signalRef "@baseboard_fab2_lib.baseboard_fab2(sch_1):svid_dio0_cpu1") )
				( member ( signalRef "@baseboard_fab2_lib.baseboard_fab2(sch_1):svid_dio0_cpu1_r") )
				( member ( signalRef "@baseboard_fab2_lib.baseboard_fab2(sch_1):svid_dio1_cpu0") )
				( member ( signalRef "@baseboard_fab2_lib.baseboard_fab2(sch_1):svid_dio1_cpu0_r") )
				( member ( signalRef "@baseboard_fab2_lib.baseboard_fab2(sch_1):svid_dio1_cpu1") )
				( member ( signalRef "@baseboard_fab2_lib.baseboard_fab2(sch_1):svid_dio1_cpu1_r") )
				( member ( signalRef "@baseboard_fab2_lib.baseboard_fab2(sch_1):svid_valert_vccin_cpu0") )
				( member ( signalRef "@baseboard_fab2_lib.baseboard_fab2(sch_1):svid_valert_vccin_cpu1") )
				( member ( signalRef "@baseboard_fab2_lib.baseboard_fab2(sch_1):svid_vclk_pvccin_cpu0") )
				( member ( signalRef "@baseboard_fab2_lib.baseboard_fab2(sch_1):svid_vclk_pvccin_cpu1") )
				( member ( signalRef "@baseboard_fab2_lib.baseboard_fab2(sch_1):jtag_mcp_cpu0_tdo") )
				( member ( signalRef "@baseboard_fab2_lib.baseboard_fab2(sch_1):smb_slotx24_stby_lvc3_scl_r") )
				( member ( signalRef "@baseboard_fab2_lib.baseboard_fab2(sch_1):svid_vdio_pvccin_cpu0") )
				( member ( signalRef "@baseboard_fab2_lib.baseboard_fab2(sch_1):svid_vdio_pvccin_cpu1") )
				( member ( signalRef "@baseboard_fab2_lib.baseboard_fab2(sch_1):pwrgd_cpupwrgd") )
				( member ( signalRef "@baseboard_fab2_lib.baseboard_fab2(sch_1):pwrgd_cpupwrgd_gtl") )
				( member ( signalRef "@baseboard_fab2_lib.baseboard_fab2(sch_1):svid_vdio_pvddq_abc") )
				( member ( signalRef "@baseboard_fab2_lib.baseboard_fab2(sch_1):svid_vdio_pvddq_def") )
				( member ( signalRef "@baseboard_fab2_lib.baseboard_fab2(sch_1):svid_vdio_pvddq_ghj") )
				( member ( signalRef "@baseboard_fab2_lib.baseboard_fab2(sch_1):svid_vdio_pvddq_klm") )
				( member ( signalRef "@baseboard_fab2_lib.baseboard_fab2(sch_1):h_pmsync_clk_24m_cpu0") )
				( member ( signalRef "@baseboard_fab2_lib.baseboard_fab2(sch_1):h_pmsync_clk_24m_cpu1") )
				( member ( signalRef "@baseboard_fab2_lib.baseboard_fab2(sch_1):jtag_pld_tms") )
				( member ( signalRef "@baseboard_fab2_lib.baseboard_fab2(sch_1):spi_bmc_bt_do_r") )
				( member ( signalRef "@baseboard_fab2_lib.baseboard_fab2(sch_1):rst_cpu0_lvc3_r1_n") )
				( member ( signalRef "@baseboard_fab2_lib.baseboard_fab2(sch_1):smb_lan_stby_lvc3_sda_r1") )
				( member ( signalRef "@baseboard_fab2_lib.baseboard_fab2(sch_1):clk_48m_usb_bmc") )
				( member ( signalRef "@baseboard_fab2_lib.baseboard_fab2(sch_1):jtag_pld_tdo") )
				( member ( signalRef "@baseboard_fab2_lib.baseboard_fab2(sch_1):xdp_cpu_mbp0_n") )
				( member ( signalRef "@baseboard_fab2_lib.baseboard_fab2(sch_1):xdp_cpu_mbp1_n") )
				( member ( signalRef "@baseboard_fab2_lib.baseboard_fab2(sch_1):xdp_cpu_obsfn_b0_mbp6_n") )
				( member ( signalRef "@baseboard_fab2_lib.baseboard_fab2(sch_1):xdp_cpu_obsfn_b1_mbp7_n") )
				( member ( signalRef "@baseboard_fab2_lib.baseboard_fab2(sch_1):xdp_cpu_prdy_n") )
				( member ( signalRef "@baseboard_fab2_lib.baseboard_fab2(sch_1):xdp_cpu_preq_n") )
				( member ( signalRef "@baseboard_fab2_lib.baseboard_fab2(sch_1):xdp_cpu_pwr_debug_n") )
				( member ( signalRef "@baseboard_fab2_lib.baseboard_fab2(sch_1):spi_bmc_clk") )
				( member ( signalRef "@baseboard_fab2_lib.baseboard_fab2(sch_1):xdp_cpu_tck0") )
				( member ( signalRef "@baseboard_fab2_lib.baseboard_fab2(sch_1):xdp_cpu_tdi") )
				( member ( signalRef "@baseboard_fab2_lib.baseboard_fab2(sch_1):xdp_cpu_tdo") )
				( member ( signalRef "@baseboard_fab2_lib.baseboard_fab2(sch_1):xdp_cpu_tms") )
				( member ( signalRef "@baseboard_fab2_lib.baseboard_fab2(sch_1):xdp_cpu_trst_n") )
				( member ( signalRef "@baseboard_fab2_lib.baseboard_fab2(sch_1):spi_bmc_di") )
				( member ( signalRef "@baseboard_fab2_lib.baseboard_fab2(sch_1):spi_bmc_cs0_n") )
				( member ( signalRef "@baseboard_fab2_lib.baseboard_fab2(sch_1):xdp_cpu0_tdo") )
				( member ( signalRef "@baseboard_fab2_lib.baseboard_fab2(sch_1):spi_clk_r0") )
				( member ( signalRef "@baseboard_fab2_lib.baseboard_fab2(sch_1):rst_cpu1_lvc3_r1_n") )
				( member ( signalRef "@baseboard_fab2_lib.baseboard_fab2(sch_1):spi_bmc_do") )
				( member ( signalRef "@baseboard_fab2_lib.baseboard_fab2(sch_1):xdp_cpu1_tdi") )
				( member ( signalRef "@baseboard_fab2_lib.baseboard_fab2(sch_1):pwrgd_cpupwrgd_r1") )
				( member ( signalRef "@baseboard_fab2_lib.baseboard_fab2(sch_1):xdp_debug_consent_n") )
				( member ( signalRef "@baseboard_fab2_lib.baseboard_fab2(sch_1):xdp_itp_pmode") )
				( member ( signalRef "@baseboard_fab2_lib.baseboard_fab2(sch_1):xdp_obsfn_b0_mbp6_n") )
				( member ( signalRef "@baseboard_fab2_lib.baseboard_fab2(sch_1):xdp_obsfn_b1_mbp7_n") )
				( member ( signalRef "@baseboard_fab2_lib.baseboard_fab2(sch_1):xdp_pch_tck1") )
				( member ( signalRef "@baseboard_fab2_lib.baseboard_fab2(sch_1):xdp_prdy_n") )
				( member ( signalRef "@baseboard_fab2_lib.baseboard_fab2(sch_1):xdp_preq_n") )
				( member ( signalRef "@baseboard_fab2_lib.baseboard_fab2(sch_1):xdp_present_n") )
				( member ( signalRef "@baseboard_fab2_lib.baseboard_fab2(sch_1):xdp_pwrgd_rst_n") )
				( member ( signalRef "@baseboard_fab2_lib.baseboard_fab2(sch_1):xdp_rsmrst_n") )
				( member ( electricalNetRef "@crescent_city_bb_fab1_lib.crescent_city_bb_fab1(sch_1):led_lan_0_n") )
				( member ( electricalNetRef "@crescent_city_bb_fab1_lib.crescent_city_bb_fab1(sch_1):led_lan_1_n") )
				( member ( electricalNetRef "@crescent_city_bb_fab1_lib.crescent_city_bb_fab1(sch_1):led_lan_2_n") )
				( member ( electricalNetRef "@crescent_city_bb_fab1_lib.crescent_city_bb_fab1(sch_1):led_postcode_0") )
				( member ( electricalNetRef "@crescent_city_bb_fab1_lib.crescent_city_bb_fab1(sch_1):led_postcode_1") )
				( member ( electricalNetRef "@crescent_city_bb_fab1_lib.crescent_city_bb_fab1(sch_1):led_postcode_2") )
				( member ( electricalNetRef "@crescent_city_bb_fab1_lib.crescent_city_bb_fab1(sch_1):led_postcode_3") )
				( member ( electricalNetRef "@crescent_city_bb_fab1_lib.crescent_city_bb_fab1(sch_1):led_postcode_4") )
				( member ( electricalNetRef "@crescent_city_bb_fab1_lib.crescent_city_bb_fab1(sch_1):led_postcode_5") )
				( member ( electricalNetRef "@crescent_city_bb_fab1_lib.crescent_city_bb_fab1(sch_1):led_postcode_6") )
				( member ( electricalNetRef "@crescent_city_bb_fab1_lib.crescent_city_bb_fab1(sch_1):led_postcode_7") )
				( member ( electricalNetRef "@crescent_city_bb_fab1_lib.crescent_city_bb_fab1(sch_1):rst_pltrst_sprv_r_n") )
				( member ( electricalNetRef "@crescent_city_bb_fab1_lib.crescent_city_bb_fab1(sch_1):rst_system_btn_buf_n") )
				( member ( electricalNetRef "@crescent_city_bb_fab1_lib.crescent_city_bb_fab1(sch_1):sgpio_bmc_clk") )
				( member ( electricalNetRef "@crescent_city_bb_fab1_lib.crescent_city_bb_fab1(sch_1):sgpio_bmc_din") )
				( member ( electricalNetRef "@crescent_city_bb_fab1_lib.crescent_city_bb_fab1(sch_1):sgpio_bmc_dout") )
				( member ( electricalNetRef "@crescent_city_bb_fab1_lib.crescent_city_bb_fab1(sch_1):sgpio_bmc_ld_n") )
				( member ( electricalNetRef "@crescent_city_bb_fab1_lib.crescent_city_bb_fab1(sch_1):sgpio_pch_sata_clock") )
				( member ( electricalNetRef "@crescent_city_bb_fab1_lib.crescent_city_bb_fab1(sch_1):sgpio_pch_sata_dout0") )
				( member ( electricalNetRef "@crescent_city_bb_fab1_lib.crescent_city_bb_fab1(sch_1):sgpio_pch_sata_load") )
				( member ( electricalNetRef "@crescent_city_bb_fab1_lib.crescent_city_bb_fab1(sch_1):sgpio_pch_ssata_clock") )
				( member ( electricalNetRef "@crescent_city_bb_fab1_lib.crescent_city_bb_fab1(sch_1):sgpio_pch_ssata_dout0") )
				( member ( electricalNetRef "@crescent_city_bb_fab1_lib.crescent_city_bb_fab1(sch_1):sgpio_pch_ssata_load") )
				( member ( electricalNetRef "@crescent_city_bb_fab1_lib.crescent_city_bb_fab1(sch_1):smb_ddr_abc_scl_g") )
				( member ( electricalNetRef "@crescent_city_bb_fab1_lib.crescent_city_bb_fab1(sch_1):smb_ddr_abc_sda_g") )
				( member ( electricalNetRef "@crescent_city_bb_fab1_lib.crescent_city_bb_fab1(sch_1):smb_ddr_abc_vpp_scl") )
				( member ( electricalNetRef "@crescent_city_bb_fab1_lib.crescent_city_bb_fab1(sch_1):smb_ddr_abc_vpp_sda") )
				( member ( electricalNetRef "@crescent_city_bb_fab1_lib.crescent_city_bb_fab1(sch_1):smb_ddr_def_scl_g") )
				( member ( electricalNetRef "@crescent_city_bb_fab1_lib.crescent_city_bb_fab1(sch_1):smb_ddr_def_sda_g") )
				( member ( electricalNetRef "@crescent_city_bb_fab1_lib.crescent_city_bb_fab1(sch_1):smb_ddr_def_vpp_scl") )
				( member ( electricalNetRef "@crescent_city_bb_fab1_lib.crescent_city_bb_fab1(sch_1):smb_ddr_def_vpp_sda") )
				( member ( electricalNetRef "@crescent_city_bb_fab1_lib.crescent_city_bb_fab1(sch_1):smb_ddr_ghj_scl_g") )
				( member ( electricalNetRef "@crescent_city_bb_fab1_lib.crescent_city_bb_fab1(sch_1):smb_ddr_ghj_sda_g") )
				( member ( electricalNetRef "@crescent_city_bb_fab1_lib.crescent_city_bb_fab1(sch_1):smb_ddr_ghj_vpp_scl") )
				( member ( electricalNetRef "@crescent_city_bb_fab1_lib.crescent_city_bb_fab1(sch_1):smb_ddr_ghj_vpp_sda") )
				( member ( electricalNetRef "@crescent_city_bb_fab1_lib.crescent_city_bb_fab1(sch_1):smb_ddr_klm_scl_g") )
				( member ( electricalNetRef "@crescent_city_bb_fab1_lib.crescent_city_bb_fab1(sch_1):smb_ddr_klm_sda_g") )
				( member ( electricalNetRef "@crescent_city_bb_fab1_lib.crescent_city_bb_fab1(sch_1):smb_ddr_klm_vpp_scl") )
				( member ( electricalNetRef "@crescent_city_bb_fab1_lib.crescent_city_bb_fab1(sch_1):smb_ddr_klm_vpp_sda") )
				( member ( electricalNetRef "@crescent_city_bb_fab1_lib.crescent_city_bb_fab1(sch_1):smb_host_stby_lvc3_scl") )
				( member ( electricalNetRef "@crescent_city_bb_fab1_lib.crescent_city_bb_fab1(sch_1):smb_host_stby_lvc3_sda") )
				( member ( electricalNetRef "@crescent_city_bb_fab1_lib.crescent_city_bb_fab1(sch_1):smb_sensor_bmc_stby_lvc3_sda") )
				( member ( electricalNetRef "@crescent_city_bb_fab1_lib.crescent_city_bb_fab1(sch_1):smb_slotx24_bmc_stby_lvc3_sda") )
				( member ( electricalNetRef "@crescent_city_bb_fab1_lib.crescent_city_bb_fab1(sch_1):smb_smlink0_stby_lvc3_scl") )
				( member ( electricalNetRef "@crescent_city_bb_fab1_lib.crescent_city_bb_fab1(sch_1):smb_smlink0_stby_lvc3_sda") )
				( member ( electricalNetRef "@crescent_city_bb_fab1_lib.crescent_city_bb_fab1(sch_1):smb_vr_scl_pvccio_cpu0") )
				( member ( electricalNetRef "@crescent_city_bb_fab1_lib.crescent_city_bb_fab1(sch_1):smb_vr_sda_pvccio_cpu0") )
				( member ( electricalNetRef "@crescent_city_bb_fab1_lib.crescent_city_bb_fab1(sch_1):spi_nic_cs_n") )
				( member ( electricalNetRef "@crescent_city_bb_fab1_lib.crescent_city_bb_fab1(sch_1):spi_nic_miso") )
				( member ( electricalNetRef "@crescent_city_bb_fab1_lib.crescent_city_bb_fab1(sch_1):spi_nic_mosi") )
				( member ( electricalNetRef "@crescent_city_bb_fab1_lib.crescent_city_bb_fab1(sch_1):spi_nic_sclk") )
				( member ( electricalNetRef "@crescent_city_bb_fab1_lib.crescent_city_bb_fab1(sch_1):sp2_bmc_cm_uart_rx") )
				( member ( electricalNetRef "@crescent_city_bb_fab1_lib.crescent_city_bb_fab1(sch_1):sp2_bmc_cm_uart_tx") )
				( member ( electricalNetRef "@crescent_city_bb_fab1_lib.crescent_city_bb_fab1(sch_1):xdp_cpu_prdy_n") )
				( member ( electricalNetRef "@crescent_city_bb_fab1_lib.crescent_city_bb_fab1(sch_1):xdp_cpu_preq_n") )
				( member ( electricalNetRef "@crescent_city_bb_fab1_lib.crescent_city_bb_fab1(sch_1):xdp_cpu_tck0") )
				( member ( electricalNetRef "@crescent_city_bb_fab1_lib.crescent_city_bb_fab1(sch_1):xdp_cpu_tdi") )
				( member ( electricalNetRef "@crescent_city_bb_fab1_lib.crescent_city_bb_fab1(sch_1):xdp_cpu_tms") )
				( member ( electricalNetRef "@crescent_city_bb_fab1_lib.crescent_city_bb_fab1(sch_1):xdp_cpu_trst_n") )
				( member ( electricalNetRef "@crescent_city_bb_fab1_lib.crescent_city_bb_fab1(sch_1):xdp_cpu1_tdi") )
				( member ( electricalNetRef "@crescent_city_bb_fab1_lib.crescent_city_bb_fab1(sch_1):xdp_debug_consent_n") )
				( member ( electricalNetRef "@crescent_city_bb_fab1_lib.crescent_city_bb_fab1(sch_1):xdp_obsfn_b0_mbp6_n") )
				( member ( electricalNetRef "@crescent_city_bb_fab1_lib.crescent_city_bb_fab1(sch_1):xdp_obsfn_b1_mbp7_n") )
				( member ( electricalNetRef "@crescent_city_bb_fab1_lib.crescent_city_bb_fab1(sch_1):xdp_rsmrst_n") )
				( member ( electricalNetRef "@crescent_city_bb_fab1_lib.crescent_city_bb_fab1(sch_1):xtal_pch_48m_in") )
				( member ( electricalNetRef "@crescent_city_bb_fab1_lib.crescent_city_bb_fab1(sch_1):xtal_24mhz_in_r") )
				( member ( electricalNetRef "@crescent_city_bb_fab1_lib.crescent_city_bb_fab1(sch_1):xtal_24mhz_pi7c9x1172_out") )
				( member ( electricalNetRef "@crescent_city_bb_fab1_lib.crescent_city_bb_fab1(sch_1):xtal_25mhz_in_r") )
				( member ( electricalNetRef "@crescent_city_bb_fab1_lib.crescent_city_bb_fab1(sch_1):xtal_25mhz_out_r") )
				( member ( electricalNetRef "@crescent_city_bb_fab1_lib.crescent_city_bb_fab1(sch_1):xtal_33k_rtc1") )
				( member ( electricalNetRef "@crescent_city_bb_fab1_lib.crescent_city_bb_fab1(sch_1):vr_p3v3_stby_en") )
				( member ( electricalNetRef "@crescent_city_bb_fab1_lib.crescent_city_bb_fab1(sch_1):vr_pvddq_abc_vren") )
				( member ( electricalNetRef "@crescent_city_bb_fab1_lib.crescent_city_bb_fab1(sch_1):vr_pvddq_def_vren") )
				( member ( electricalNetRef "@crescent_city_bb_fab1_lib.crescent_city_bb_fab1(sch_1):vr_pvddq_ghj_vren") )
				( member ( electricalNetRef "@crescent_city_bb_fab1_lib.crescent_city_bb_fab1(sch_1):vr_pvddq_klm_vren") )
				( member ( electricalNetRef "@crescent_city_bb_fab1_lib.crescent_city_bb_fab1(sch_1):vr_pvnn_pch_vren") )
				( member ( electricalNetRef "@baseboard_fab2_lib.baseboard_fab2(sch_1):jtag_mcp_cpu0_tdi") )
				( member ( electricalNetRef "@crescent_city_bb_fab1_lib.crescent_city_bb_fab1(sch_1):fan_tach1") )
				( member ( electricalNetRef "@crescent_city_bb_fab1_lib.crescent_city_bb_fab1(sch_1):fan_tach2") )
				( member ( electricalNetRef "@crescent_city_bb_fab1_lib.crescent_city_bb_fab1(sch_1):fan_tach3_r") )
				( member ( electricalNetRef "@crescent_city_bb_fab1_lib.crescent_city_bb_fab1(sch_1):fm_adr_complete_r") )
				( member ( electricalNetRef "@crescent_city_bb_fab1_lib.crescent_city_bb_fab1(sch_1):fm_db_uart_sel0_n") )
				( member ( electricalNetRef "@crescent_city_bb_fab1_lib.crescent_city_bb_fab1(sch_1):fm_pvtt_abc_en_r") )
				( member ( electricalNetRef "@crescent_city_bb_fab1_lib.crescent_city_bb_fab1(sch_1):fm_pvtt_def_en_r") )
				( member ( electricalNetRef "@crescent_city_bb_fab1_lib.crescent_city_bb_fab1(sch_1):fm_pvtt_ghj_en_r") )
				( member ( electricalNetRef "@crescent_city_bb_fab1_lib.crescent_city_bb_fab1(sch_1):fm_pvtt_klm_en_r") )
				( member ( electricalNetRef "@crescent_city_bb_fab1_lib.crescent_city_bb_fab1(sch_1):fan_pwm_out_sys0_r") )
				( member ( electricalNetRef "@crescent_city_bb_fab1_lib.crescent_city_bb_fab1(sch_1):h_cpu_err2_g_r_n") )
				( member ( electricalNetRef "@baseboard_fab2_lib.baseboard_fab2(sch_1):jtag_mcp_cpu1_tdi") )
				( member ( electricalNetRef "@baseboard_fab2_lib.baseboard_fab2(sch_1):vr_pvccio_cpu0_en") )
				( member ( electricalNetRef "@baseboard_fab2_lib.baseboard_fab2(sch_1):jtag_mcp_tck_r") )
				( member ( electricalNetRef "@crescent_city_bb_fab1_lib.crescent_city_bb_fab1(sch_1):smb_cpu1_pe_hp_gtl_r_scl") )
				( member ( electricalNetRef "@crescent_city_bb_fab1_lib.crescent_city_bb_fab1(sch_1):smb_cpu1_pe_hp_gtl_r_sda") )
				( member ( electricalNetRef "@crescent_city_bb_fab1_lib.crescent_city_bb_fab1(sch_1):spi_miso_r0") )
				( member ( electricalNetRef "@crescent_city_bb_fab1_lib.crescent_city_bb_fab1(sch_1):clk_32k_susclk_pld") )
				( member ( electricalNetRef "@crescent_city_bb_fab1_lib.crescent_city_bb_fab1(sch_1):clk_25m_bmc") )
				( member ( electricalNetRef "@crescent_city_bb_fab1_lib.crescent_city_bb_fab1(sch_1):clk_24m_bmc_lpc") )
				( member ( electricalNetRef "@crescent_city_bb_fab1_lib.crescent_city_bb_fab1(sch_1):smb_3v3sb_hsc_sda_r") )
				( member ( electricalNetRef "@crescent_city_bb_fab1_lib.crescent_city_bb_fab1(sch_1):smb_3v3sb_hsc_scl_r") )
				( member ( electricalNetRef "@baseboard_fab2_lib.baseboard_fab2(sch_1):fm_cpu_err0_lvt3_k_n") )
				( member ( electricalNetRef "@crescent_city_bb_fab1_lib.crescent_city_bb_fab1(sch_1):smb_lan_stby_lvc3_sda") )
				( member ( electricalNetRef "@crescent_city_bb_fab1_lib.crescent_city_bb_fab1(sch_1):smb_lan_stby_lvc3_scl") )
				( member ( electricalNetRef "@crescent_city_bb_fab1_lib.crescent_city_bb_fab1(sch_1):jtag_pch_gbe_clk") )
				( member ( electricalNetRef "@crescent_city_bb_fab1_lib.crescent_city_bb_fab1(sch_1):lpc_lad1_io1") )
				( member ( electricalNetRef "@crescent_city_bb_fab1_lib.crescent_city_bb_fab1(sch_1):irq_pvddq_klm_vrhot_lvt3_n") )
				( member ( electricalNetRef "@crescent_city_bb_fab1_lib.crescent_city_bb_fab1(sch_1):irq_bmc_pch_nmi_stby_n") )
				( member ( electricalNetRef "@crescent_city_bb_fab1_lib.crescent_city_bb_fab1(sch_1):fm_thermtrip_dly_r") )
				( member ( electricalNetRef "@crescent_city_bb_fab1_lib.crescent_city_bb_fab1(sch_1):fm_throttle_r_n") )
				( member ( electricalNetRef "@crescent_city_bb_fab1_lib.crescent_city_bb_fab1(sch_1):fm_1gb_lom_disable_n") )
				( member ( electricalNetRef "@crescent_city_bb_fab1_lib.crescent_city_bb_fab1(sch_1):fp_nmi_btn_n") )
				( member ( electricalNetRef "@crescent_city_bb_fab1_lib.crescent_city_bb_fab1(sch_1):irq_sml1_pmbus_alert_n") )
				( member ( electricalNetRef "@crescent_city_bb_fab1_lib.crescent_city_bb_fab1(sch_1):clk_50m_ckmng_bmc_1") )
				( member ( electricalNetRef "@crescent_city_bb_fab1_lib.crescent_city_bb_fab1(sch_1):clk_50m_ckmng_bmc_2") )
				( member ( electricalNetRef "@crescent_city_bb_fab1_lib.crescent_city_bb_fab1(sch_1):clk_50m_ckmng_ocp") )
				( member ( electricalNetRef "@crescent_city_bb_fab1_lib.crescent_city_bb_fab1(sch_1):lpc_lad2_io2") )
				( member ( electricalNetRef "@crescent_city_bb_fab1_lib.crescent_city_bb_fab1(sch_1):h_pm_sync_gtl_r1") )
				( member ( electricalNetRef "@crescent_city_bb_fab1_lib.crescent_city_bb_fab1(sch_1):fm_cpu1_thermtrip_lvt3_n") )
				( member ( electricalNetRef "@crescent_city_bb_fab1_lib.crescent_city_bb_fab1(sch_1):fm_m2_det_lvc3") )
				( member ( electricalNetRef "@crescent_city_bb_fab1_lib.crescent_city_bb_fab1(sch_1):fm_flash_desc_override") )
				( member ( electricalNetRef "@crescent_city_bb_fab1_lib.crescent_city_bb_fab1(sch_1):fm_cpu1_fivr_fault_lvt3") )
				( member ( electricalNetRef "@crescent_city_bb_fab1_lib.crescent_city_bb_fab1(sch_1):fm_pch_pld_data") )
				( member ( electricalNetRef "@crescent_city_bb_fab1_lib.crescent_city_bb_fab1(sch_1):fm_cpu1_fivr_fault_lvt3_n") )
				( member ( electricalNetRef "@baseboard_fab2_lib.baseboard_fab2(sch_1):fm_cpu0_prochot_lvt3_k_n") )
				( member ( electricalNetRef "@crescent_city_bb_fab1_lib.crescent_city_bb_fab1(sch_1):fm_pwr_btn_n") )
				( member ( electricalNetRef "@crescent_city_bb_fab1_lib.crescent_city_bb_fab1(sch_1):fm_pch_sata_raid_key") )
				( member ( electricalNetRef "@crescent_city_bb_fab1_lib.crescent_city_bb_fab1(sch_1):fm_pvpp_pvddq_cpu1_en_ghj") )
				( member ( electricalNetRef "@crescent_city_bb_fab1_lib.crescent_city_bb_fab1(sch_1):fm_ctnr_ps_on") )
				( member ( electricalNetRef "@crescent_city_bb_fab1_lib.crescent_city_bb_fab1(sch_1):fm_pvpp_pvddq_cpu0_en_abc") )
				( member ( electricalNetRef "@crescent_city_bb_fab1_lib.crescent_city_bb_fab1(sch_1):fm_cpu0_thermtrip_lvt3_n") )
				( member ( electricalNetRef "@crescent_city_bb_fab1_lib.crescent_city_bb_fab1(sch_1):fm_all_wake_n") )
				( member ( electricalNetRef "@crescent_city_bb_fab1_lib.crescent_city_bb_fab1(sch_1):fm_adr_smi_gpio_n") )
				( member ( electricalNetRef "@crescent_city_bb_fab1_lib.crescent_city_bb_fab1(sch_1):fm_adr_mode_sel") )
				( member ( electricalNetRef "@crescent_city_bb_fab1_lib.crescent_city_bb_fab1(sch_1):fan_pwm_out_sys1_r") )
				( member ( electricalNetRef "@crescent_city_bb_fab1_lib.crescent_city_bb_fab1(sch_1):fp_rst_btn_r_n") )
				( member ( electricalNetRef "@crescent_city_bb_fab1_lib.crescent_city_bb_fab1(sch_1):fm_bmc_nmi_n") )
				( member ( electricalNetRef "@crescent_city_bb_fab1_lib.crescent_city_bb_fab1(sch_1):fm_bios_top_swap_spkr") )
				( member ( electricalNetRef "@crescent_city_bb_fab1_lib.crescent_city_bb_fab1(sch_1):fm_bmc_enable_n") )
				( member ( electricalNetRef "@crescent_city_bb_fab1_lib.crescent_city_bb_fab1(sch_1):fm_bmc_sys_throttle_r_n") )
				( member ( electricalNetRef "@crescent_city_bb_fab1_lib.crescent_city_bb_fab1(sch_1):fm_bmc_onctl_r_n") )
				( member ( electricalNetRef "@crescent_city_bb_fab1_lib.crescent_city_bb_fab1(sch_1):jtag_pch_gbe_tdi") )
				( member ( electricalNetRef "@crescent_city_bb_fab1_lib.crescent_city_bb_fab1(sch_1):jtag_pch_gbe_tdo") )
				( member ( electricalNetRef "@crescent_city_bb_fab1_lib.crescent_city_bb_fab1(sch_1):irq_pvddq_def_vrhot_lvt3_n") )
				( member ( electricalNetRef "@crescent_city_bb_fab1_lib.crescent_city_bb_fab1(sch_1):clk_50m_ckmng_sprvlle") )
				( member ( electricalNetRef "@crescent_city_bb_fab1_lib.crescent_city_bb_fab1(sch_1):smb_slotx24_bmc_stby_lvc3_scl") )
				( member ( electricalNetRef "@crescent_city_bb_fab1_lib.crescent_city_bb_fab1(sch_1):fm_cpu_caterr_dly_lvt3_n") )
				( member ( electricalNetRef "@crescent_city_bb_fab1_lib.crescent_city_bb_fab1(sch_1):fm_cpu_err2_lvt3_n") )
				( member ( electricalNetRef "@crescent_city_bb_fab1_lib.crescent_city_bb_fab1(sch_1):clk_50m_nic") )
				( member ( electricalNetRef "@crescent_city_bb_fab1_lib.crescent_city_bb_fab1(sch_1):fm_cpu_msmi_lvt3_n") )
				( member ( electricalNetRef "@crescent_city_bb_fab1_lib.crescent_city_bb_fab1(sch_1):smb_sensor_pch_stby_lvc3_scl") )
				( member ( electricalNetRef "@crescent_city_bb_fab1_lib.crescent_city_bb_fab1(sch_1):fm_cpu0_fivr_fault_lvt3") )
				( member ( electricalNetRef "@crescent_city_bb_fab1_lib.crescent_city_bb_fab1(sch_1):fm_cpu0_fivr_fault_lvt3_n") )
				( member ( electricalNetRef "@crescent_city_bb_fab1_lib.crescent_city_bb_fab1(sch_1):a_hsc_low_drain") )
				( member ( electricalNetRef "@crescent_city_bb_fab1_lib.crescent_city_bb_fab1(sch_1):fm_cpld_adr_trigger_n") )
				( member ( electricalNetRef "@crescent_city_bb_fab1_lib.crescent_city_bb_fab1(sch_1):fm_cpu_caterr_lvt3_n") )
				( member ( electricalNetRef "@crescent_city_bb_fab1_lib.crescent_city_bb_fab1(sch_1):jtag_pch_gbe_tms") )
				( member ( electricalNetRef "@crescent_city_bb_fab1_lib.crescent_city_bb_fab1(sch_1):jtag_pch_gbe_trst_n") )
				( member ( electricalNetRef "@crescent_city_bb_fab1_lib.crescent_city_bb_fab1(sch_1):irq_dimm_save_n") )
				( member ( electricalNetRef "@crescent_city_bb_fab1_lib.crescent_city_bb_fab1(sch_1):irq_hsc_fault_r_n") )
				( member ( electricalNetRef "@baseboard_fab2_lib.baseboard_fab2(sch_1):jtag_mcp_tms") )
				( member ( electricalNetRef "@crescent_city_bb_fab1_lib.crescent_city_bb_fab1(sch_1):h_cpu0_caterr_g_n") )
				( member ( electricalNetRef "@crescent_city_bb_fab1_lib.crescent_city_bb_fab1(sch_1):irq_lpc_serirq_n") )
				( member ( electricalNetRef "@crescent_city_bb_fab1_lib.crescent_city_bb_fab1(sch_1):irq_lvc3_wake_n") )
				( member ( electricalNetRef "@crescent_city_bb_fab1_lib.crescent_city_bb_fab1(sch_1):h_cpu0_fast_wake_b_n") )
				( member ( electricalNetRef "@crescent_city_bb_fab1_lib.crescent_city_bb_fab1(sch_1):irq_pirqa_spi_tpm_n") )
				( member ( electricalNetRef "@crescent_city_bb_fab1_lib.crescent_city_bb_fab1(sch_1):fp_pwr_btn_r1_n") )
				( member ( electricalNetRef "@crescent_city_bb_fab1_lib.crescent_city_bb_fab1(sch_1):irq_vm_int_n") )
				( member ( electricalNetRef "@crescent_city_bb_fab1_lib.crescent_city_bb_fab1(sch_1):irq_pvddq_ghj_vrhot_lvt3_n") )
				( member ( electricalNetRef "@crescent_city_bb_fab1_lib.crescent_city_bb_fab1(sch_1):h_cpu0_msmi_g_n") )
				( member ( electricalNetRef "@crescent_city_bb_fab1_lib.crescent_city_bb_fab1(sch_1):irq_pvccin_cpu0_vrhot_lvc3_n") )
				( member ( electricalNetRef "@crescent_city_bb_fab1_lib.crescent_city_bb_fab1(sch_1):irq_pvddq_abc_vrhot_lvt3_n") )
				( member ( electricalNetRef "@baseboard_fab2_lib.baseboard_fab2(sch_1):fm_cpu1_prochot_lvt3_k_n") )
				( member ( electricalNetRef "@crescent_city_bb_fab1_lib.crescent_city_bb_fab1(sch_1):h_pmsync_clk_24m_cpu0") )
				( member ( electricalNetRef "@crescent_city_bb_fab1_lib.crescent_city_bb_fab1(sch_1):fp_nmi_btn_out_n") )
				( member ( electricalNetRef "@crescent_city_bb_fab1_lib.crescent_city_bb_fab1(sch_1):lpc_lad0_io0") )
				( member ( electricalNetRef "@crescent_city_bb_fab1_lib.crescent_city_bb_fab1(sch_1):pwrgd_pvpp_ghj") )
				( member ( electricalNetRef "@crescent_city_bb_fab1_lib.crescent_city_bb_fab1(sch_1):irq_pvccin_cpu1_vrhot_lvc3_n") )
				( member ( electricalNetRef "@crescent_city_bb_fab1_lib.crescent_city_bb_fab1(sch_1):pwrgd_pvpp_def") )
				( member ( electricalNetRef "@crescent_city_bb_fab1_lib.crescent_city_bb_fab1(sch_1):lpc_lframe_n_cs0_n") )
				( member ( electricalNetRef "@crescent_city_bb_fab1_lib.crescent_city_bb_fab1(sch_1):peci_bmc") )
				( member ( electricalNetRef "@crescent_city_bb_fab1_lib.crescent_city_bb_fab1(sch_1):pu_bios_spi_wp0_n") )
				( member ( electricalNetRef "@crescent_city_bb_fab1_lib.crescent_city_bb_fab1(sch_1):pwrgd_pvtt_cpu1") )
				( member ( electricalNetRef "@crescent_city_bb_fab1_lib.crescent_city_bb_fab1(sch_1):pwrgd_pvsa_cpu1") )
				( member ( electricalNetRef "@crescent_city_bb_fab1_lib.crescent_city_bb_fab1(sch_1):pwrgd_pvtt_abc_cpu0_r") )
				( member ( electricalNetRef "@crescent_city_bb_fab1_lib.crescent_city_bb_fab1(sch_1):rmii_bmc_pch_sprngvlle_txen") )
				( member ( electricalNetRef "@crescent_city_bb_fab1_lib.crescent_city_bb_fab1(sch_1):lpc_lad3_io3") )
				( member ( electricalNetRef "@crescent_city_bb_fab1_lib.crescent_city_bb_fab1(sch_1):pwrgd_pvpp_klm") )
				( member ( electricalNetRef "@crescent_city_bb_fab1_lib.crescent_city_bb_fab1(sch_1):rmii_bmc_pch_sprngvlle_rxer") )
				( member ( electricalNetRef "@crescent_city_bb_fab1_lib.crescent_city_bb_fab1(sch_1):rmii_sprngvlle_bmc_pch_rxd1") )
				( member ( electricalNetRef "@crescent_city_bb_fab1_lib.crescent_city_bb_fab1(sch_1):pwrgd_p3v3_stby_r") )
				( member ( electricalNetRef "@crescent_city_bb_fab1_lib.crescent_city_bb_fab1(sch_1):rmii_sprngvlle_bmc_pch_rxd0") )
				( member ( electricalNetRef "@crescent_city_bb_fab1_lib.crescent_city_bb_fab1(sch_1):pwrgd_pvccio_cpu0") )
				( member ( electricalNetRef "@crescent_city_bb_fab1_lib.crescent_city_bb_fab1(sch_1):pwrgd_p3v3_r") )
				( member ( electricalNetRef "@crescent_city_bb_fab1_lib.crescent_city_bb_fab1(sch_1):pwrgd_cpupwrgd") )
				( member ( electricalNetRef "@crescent_city_bb_fab1_lib.crescent_city_bb_fab1(sch_1):pwrgd_pvpp_abc") )
				( member ( electricalNetRef "@crescent_city_bb_fab1_lib.crescent_city_bb_fab1(sch_1):rmii_bmc_pch_sprngvlle_crsdv") )
				( member ( electricalNetRef "@crescent_city_bb_fab1_lib.crescent_city_bb_fab1(sch_1):pwrgd_p5v") )
				( member ( electricalNetRef "@crescent_city_bb_fab1_lib.crescent_city_bb_fab1(sch_1):pwrgd_pvccio_cpu1") )
				( member ( electricalNetRef "@crescent_city_bb_fab1_lib.crescent_city_bb_fab1(sch_1):rmii_bmc_pch_sprngvlle_txd1") )
				( member ( electricalNetRef "@crescent_city_bb_fab1_lib.crescent_city_bb_fab1(sch_1):pwrgd_pvnn_p1v05_pch") )
				( member ( electricalNetRef "@crescent_city_bb_fab1_lib.crescent_city_bb_fab1(sch_1):pwrgd_p1v538_bmc_stby") )
				( member ( electricalNetRef "@crescent_city_bb_fab1_lib.crescent_city_bb_fab1(sch_1):rmii_bmc_ocp_txen") )
				( member ( electricalNetRef "@crescent_city_bb_fab1_lib.crescent_city_bb_fab1(sch_1):rmii_bmc_ocp_txd1") )
				( member ( electricalNetRef "@crescent_city_bb_fab1_lib.crescent_city_bb_fab1(sch_1):pwrgd_p12v_hsc") )
				( member ( electricalNetRef "@crescent_city_bb_fab1_lib.crescent_city_bb_fab1(sch_1):pwrgd_p12v_hsc_dly") )
				( member ( electricalNetRef "@crescent_city_bb_fab1_lib.crescent_city_bb_fab1(sch_1):rmii_bmc_pch_sprngvlle_txd0") )
				( member ( electricalNetRef "@crescent_city_bb_fab1_lib.crescent_city_bb_fab1(sch_1):pwrgd_pvsa_cpu0") )
				( member ( electricalNetRef "@crescent_city_bb_fab1_lib.crescent_city_bb_fab1(sch_1):pwrgd_p1v26_bmc_stby") )
				( member ( electricalNetRef "@crescent_city_bb_fab1_lib.crescent_city_bb_fab1(sch_1):rmii_bmc_ocp_txd0") )
				( member ( electricalNetRef "@crescent_city_bb_fab1_lib.crescent_city_bb_fab1(sch_1):rst_pcie_riser1_perst_n") )
				( member ( electricalNetRef "@crescent_city_bb_fab1_lib.crescent_city_bb_fab1(sch_1):rst_pcie_cpu_dev3_n") )
				( member ( electricalNetRef "@crescent_city_bb_fab1_lib.crescent_city_bb_fab1(sch_1):rst_pcie_cpu_dev2_n") )
				( member ( electricalNetRef "@crescent_city_bb_fab1_lib.crescent_city_bb_fab1(sch_1):rst_bmc_ddr3_n") )
				( member ( electricalNetRef "@crescent_city_bb_fab1_lib.crescent_city_bb_fab1(sch_1):rst_pcie_cpu_dev1_n") )
				( member ( electricalNetRef "@crescent_city_bb_fab1_lib.crescent_city_bb_fab1(sch_1):rst_cpu0_lvc3_n") )
				( member ( electricalNetRef "@crescent_city_bb_fab1_lib.crescent_city_bb_fab1(sch_1):rst_pcie_cpu_dev0_n") )
				( member ( electricalNetRef "@crescent_city_bb_fab1_lib.crescent_city_bb_fab1(sch_1):rst_bmc_lvc3_n") )
				( member ( electricalNetRef "@crescent_city_bb_fab1_lib.crescent_city_bb_fab1(sch_1):rst_cpu1_lvc3_n") )
				( member ( electricalNetRef "@crescent_city_bb_fab1_lib.crescent_city_bb_fab1(sch_1):clk_25m_cpld") )
				( member ( electricalNetRef "@crescent_city_bb_fab1_lib.crescent_city_bb_fab1(sch_1):fm_pch_pwrbtn_n") )
				( member ( electricalNetRef "@crescent_city_bb_fab1_lib.crescent_city_bb_fab1(sch_1):rmii_pch_sprngvlle_arb_in") )
				( member ( electricalNetRef "@crescent_city_bb_fab1_lib.crescent_city_bb_fab1(sch_1):rmii_pch_sprngvlle_arb_out") )
				( member ( electricalNetRef "@baseboard_fab2_lib.baseboard_fab2(sch_1):h_cpu1_memghj_memhot_g_pch_n") )
				( member ( electricalNetRef "@baseboard_fab2_lib.baseboard_fab2(sch_1):h_cpu1_memklm_memhot_g_pch_n") )
				( member ( electricalNetRef "@baseboard_fab2_lib.baseboard_fab2(sch_1):spi_pch_cs0_n") )
				( member ( electricalNetRef "@baseboard_fab2_lib.baseboard_fab2(sch_1):h_cpu0_memdef_memhot_g_pch_n") )
				( member ( electricalNetRef "@baseboard_fab2_lib.baseboard_fab2(sch_1):h_cpu0_memabc_memhot_g_pch_n") )
				( objectStatus "PNCLS_50-OHM_SE" )
			)
			( netClass "@crescent_city_bb_fab1_lib.crescent_city_bb_fab1(sch_1):\PNCLS_85-OHM_DIFF\"
				( memberType ( signal ) )
				( physicalCSetRef "@sapphirecity_baseboard_lib.sapphirecity_baseboard(sch_1):\85_OHMS-DIFF\" )
				( objectFlag fObjectPhysical )
				( member ( diffPairRef "@crescent_city_bb_fab1_lib.crescent_city_bb_fab1(sch_1):\P3E_CPU0_PE3_OCP_RX\(0)") )
				( member ( diffPairRef "@crescent_city_bb_fab1_lib.crescent_city_bb_fab1(sch_1):\P3E_CPU0_PE3_OCP_RX\(1)") )
				( member ( diffPairRef "@crescent_city_bb_fab1_lib.crescent_city_bb_fab1(sch_1):\P3E_CPU0_PE3_OCP_RX\(2)") )
				( member ( diffPairRef "@crescent_city_bb_fab1_lib.crescent_city_bb_fab1(sch_1):\P3E_CPU0_PE3_OCP_RX\(3)") )
				( member ( diffPairRef "@crescent_city_bb_fab1_lib.crescent_city_bb_fab1(sch_1):\P3E_CPU0_PE3_OCP_RX\(6)") )
				( member ( diffPairRef "@crescent_city_bb_fab1_lib.crescent_city_bb_fab1(sch_1):\P3E_CPU0_PE3_OCP_RX\(7)") )
				( member ( diffPairRef "@crescent_city_bb_fab1_lib.crescent_city_bb_fab1(sch_1):\P3E_CPU0_PE3_OCP_RX\(8)") )
				( member ( diffPairRef "@crescent_city_bb_fab1_lib.crescent_city_bb_fab1(sch_1):\P3E_CPU0_PE3_OCP_RX\(9)") )
				( member ( diffPairRef "@crescent_city_bb_fab1_lib.crescent_city_bb_fab1(sch_1):\P3E_CPU0_PE3_OCP_RX\(10)") )
				( member ( diffPairRef "@crescent_city_bb_fab1_lib.crescent_city_bb_fab1(sch_1):\P3E_CPU0_PE3_OCP_RX\(11)") )
				( member ( diffPairRef "@crescent_city_bb_fab1_lib.crescent_city_bb_fab1(sch_1):\P3E_CPU0_PE3_OCP_RX\(12)") )
				( member ( diffPairRef "@crescent_city_bb_fab1_lib.crescent_city_bb_fab1(sch_1):\P3E_CPU0_PE3_OCP_RX\(13)") )
				( member ( diffPairRef "@crescent_city_bb_fab1_lib.crescent_city_bb_fab1(sch_1):\P3E_CPU0_PE3_OCP_RX\(14)") )
				( member ( diffPairRef "@crescent_city_bb_fab1_lib.crescent_city_bb_fab1(sch_1):\P3E_CPU0_PE3_OCP_RX\(15)") )
				( member ( diffPairRef "@crescent_city_bb_fab1_lib.crescent_city_bb_fab1(sch_1):\USB2_PCH_BMC_P4_D\") )
				( member ( diffPairRef "@crescent_city_bb_fab1_lib.crescent_city_bb_fab1(sch_1):\USB2_PCH_BMC_P5_D\") )
				( member ( diffPairRef "@crescent_city_bb_fab1_lib.crescent_city_bb_fab1(sch_1):\DP_P3E_CPU1_PE3_MP_C\(10)") )
				( member ( diffPairRef "@crescent_city_bb_fab1_lib.crescent_city_bb_fab1(sch_1):\DP_USB3_P01_RX\") )
				( member ( diffPairRef "@crescent_city_bb_fab1_lib.crescent_city_bb_fab1(sch_1):\P3E_CPU0_PE3_OCP_RXN\(4)") )
				( member ( diffPairRef "@crescent_city_bb_fab1_lib.crescent_city_bb_fab1(sch_1):\P3E_CPU0_PE3_OCP_RXN\(5)") )
				( member ( diffPairRef "@crescent_city_bb_fab1_lib.crescent_city_bb_fab1(sch_1):\P3E_CPU0_PE1_PCH_RX\(10)") )
				( member ( diffPairRef "@crescent_city_bb_fab1_lib.crescent_city_bb_fab1(sch_1):\P3E_CPU0_PE1_PCH_RX\(11)") )
				( member ( diffPairRef "@crescent_city_bb_fab1_lib.crescent_city_bb_fab1(sch_1):\P3E_CPU0_PE1_PCH_RX\(12)") )
				( member ( diffPairRef "@crescent_city_bb_fab1_lib.crescent_city_bb_fab1(sch_1):\P3E_CPU0_PE1_PCH_RX\(13)") )
				( member ( diffPairRef "@crescent_city_bb_fab1_lib.crescent_city_bb_fab1(sch_1):\P3E_CPU0_PE1_PCH_RX\(14)") )
				( member ( diffPairRef "@crescent_city_bb_fab1_lib.crescent_city_bb_fab1(sch_1):\P3E_CPU0_PE1_PCH_RX\(15)") )
				( member ( diffPairRef "@crescent_city_bb_fab1_lib.crescent_city_bb_fab1(sch_1):\DP_P3E_CPU1_PE3_MP_C\(8)") )
				( member ( diffPairRef "@crescent_city_bb_fab1_lib.crescent_city_bb_fab1(sch_1):\PE_PCH_SPRV_RX_D\") )
				( member ( diffPairRef "@crescent_city_bb_fab1_lib.crescent_city_bb_fab1(sch_1):\DP_5\") )
				( member ( diffPairRef "@crescent_city_bb_fab1_lib.crescent_city_bb_fab1(sch_1):\DP_6\") )
				( member ( diffPairRef "@crescent_city_bb_fab1_lib.crescent_city_bb_fab1(sch_1):\DP_7\") )
				( member ( diffPairRef "@crescent_city_bb_fab1_lib.crescent_city_bb_fab1(sch_1):\DP_8\") )
				( member ( diffPairRef "@crescent_city_bb_fab1_lib.crescent_city_bb_fab1(sch_1):\DP_9\") )
				( member ( diffPairRef "@crescent_city_bb_fab1_lib.crescent_city_bb_fab1(sch_1):\DP_10\") )
				( member ( diffPairRef "@crescent_city_bb_fab1_lib.crescent_city_bb_fab1(sch_1):\DP_11\") )
				( member ( diffPairRef "@crescent_city_bb_fab1_lib.crescent_city_bb_fab1(sch_1):\DP_12\") )
				( member ( diffPairRef "@crescent_city_bb_fab1_lib.crescent_city_bb_fab1(sch_1):\DP_13\") )
				( member ( diffPairRef "@crescent_city_bb_fab1_lib.crescent_city_bb_fab1(sch_1):\DP_15\") )
				( member ( diffPairRef "@crescent_city_bb_fab1_lib.crescent_city_bb_fab1(sch_1):\DP_16\") )
				( member ( diffPairRef "@crescent_city_bb_fab1_lib.crescent_city_bb_fab1(sch_1):\DP_17\") )
				( member ( diffPairRef "@crescent_city_bb_fab1_lib.crescent_city_bb_fab1(sch_1):\DP_18\") )
				( member ( diffPairRef "@crescent_city_bb_fab1_lib.crescent_city_bb_fab1(sch_1):\DP_19\") )
				( member ( diffPairRef "@crescent_city_bb_fab1_lib.crescent_city_bb_fab1(sch_1):\DP_20\") )
				( member ( diffPairRef "@crescent_city_bb_fab1_lib.crescent_city_bb_fab1(sch_1):\DP_21\") )
				( member ( diffPairRef "@crescent_city_bb_fab1_lib.crescent_city_bb_fab1(sch_1):\DP_22\") )
				( member ( diffPairRef "@crescent_city_bb_fab1_lib.crescent_city_bb_fab1(sch_1):\DP_23\") )
				( member ( diffPairRef "@crescent_city_bb_fab1_lib.crescent_city_bb_fab1(sch_1):\DP_24\") )
				( member ( diffPairRef "@crescent_city_bb_fab1_lib.crescent_city_bb_fab1(sch_1):\DP_25\") )
				( member ( diffPairRef "@crescent_city_bb_fab1_lib.crescent_city_bb_fab1(sch_1):\DP_26\") )
				( member ( diffPairRef "@crescent_city_bb_fab1_lib.crescent_city_bb_fab1(sch_1):\DP_27\") )
				( member ( diffPairRef "@crescent_city_bb_fab1_lib.crescent_city_bb_fab1(sch_1):\DP_28\") )
				( member ( diffPairRef "@crescent_city_bb_fab1_lib.crescent_city_bb_fab1(sch_1):\DP_29\") )
				( member ( diffPairRef "@crescent_city_bb_fab1_lib.crescent_city_bb_fab1(sch_1):\DP_30\") )
				( member ( diffPairRef "@crescent_city_bb_fab1_lib.crescent_city_bb_fab1(sch_1):\DP_31\") )
				( member ( diffPairRef "@crescent_city_bb_fab1_lib.crescent_city_bb_fab1(sch_1):\DP_32\") )
				( member ( diffPairRef "@crescent_city_bb_fab1_lib.crescent_city_bb_fab1(sch_1):\DP_33\") )
				( member ( diffPairRef "@crescent_city_bb_fab1_lib.crescent_city_bb_fab1(sch_1):\DP_34\") )
				( member ( diffPairRef "@crescent_city_bb_fab1_lib.crescent_city_bb_fab1(sch_1):\DP_35\") )
				( member ( diffPairRef "@crescent_city_bb_fab1_lib.crescent_city_bb_fab1(sch_1):\DP_36\") )
				( member ( diffPairRef "@crescent_city_bb_fab1_lib.crescent_city_bb_fab1(sch_1):\DP_37\") )
				( member ( diffPairRef "@crescent_city_bb_fab1_lib.crescent_city_bb_fab1(sch_1):\DP_38\") )
				( member ( diffPairRef "@crescent_city_bb_fab1_lib.crescent_city_bb_fab1(sch_1):\DP_39\") )
				( member ( diffPairRef "@crescent_city_bb_fab1_lib.crescent_city_bb_fab1(sch_1):\DP_40\") )
				( member ( diffPairRef "@crescent_city_bb_fab1_lib.crescent_city_bb_fab1(sch_1):\DP_41\") )
				( member ( diffPairRef "@crescent_city_bb_fab1_lib.crescent_city_bb_fab1(sch_1):\DP_42\") )
				( member ( diffPairRef "@crescent_city_bb_fab1_lib.crescent_city_bb_fab1(sch_1):\DP_43\") )
				( member ( diffPairRef "@crescent_city_bb_fab1_lib.crescent_city_bb_fab1(sch_1):\DP_44\") )
				( member ( diffPairRef "@crescent_city_bb_fab1_lib.crescent_city_bb_fab1(sch_1):\DP_45\") )
				( member ( diffPairRef "@crescent_city_bb_fab1_lib.crescent_city_bb_fab1(sch_1):\DP_46\") )
				( member ( diffPairRef "@crescent_city_bb_fab1_lib.crescent_city_bb_fab1(sch_1):\DP_47\") )
				( member ( diffPairRef "@crescent_city_bb_fab1_lib.crescent_city_bb_fab1(sch_1):\DP_48\") )
				( member ( diffPairRef "@crescent_city_bb_fab1_lib.crescent_city_bb_fab1(sch_1):\DP_49\") )
				( member ( diffPairRef "@crescent_city_bb_fab1_lib.crescent_city_bb_fab1(sch_1):\DP_50\") )
				( member ( diffPairRef "@crescent_city_bb_fab1_lib.crescent_city_bb_fab1(sch_1):\DP_51\") )
				( member ( diffPairRef "@crescent_city_bb_fab1_lib.crescent_city_bb_fab1(sch_1):\DP_52\") )
				( member ( diffPairRef "@crescent_city_bb_fab1_lib.crescent_city_bb_fab1(sch_1):\DP_53\") )
				( member ( diffPairRef "@crescent_city_bb_fab1_lib.crescent_city_bb_fab1(sch_1):\DP_54\") )
				( member ( diffPairRef "@crescent_city_bb_fab1_lib.crescent_city_bb_fab1(sch_1):\DP_55\") )
				( member ( diffPairRef "@crescent_city_bb_fab1_lib.crescent_city_bb_fab1(sch_1):\DP_56\") )
				( member ( diffPairRef "@crescent_city_bb_fab1_lib.crescent_city_bb_fab1(sch_1):\P3E_CPU0_PE1_PCH_PCIEUP_RX\(0)") )
				( member ( diffPairRef "@crescent_city_bb_fab1_lib.crescent_city_bb_fab1(sch_1):\P3E_CPU0_PE1_PCH_PCIEUP_RX\(1)") )
				( member ( diffPairRef "@crescent_city_bb_fab1_lib.crescent_city_bb_fab1(sch_1):\P3E_CPU0_PE1_PCH_PCIEUP_RX\(2)") )
				( member ( diffPairRef "@crescent_city_bb_fab1_lib.crescent_city_bb_fab1(sch_1):\P3E_CPU0_PE1_PCH_PCIEUP_RX\(3)") )
				( member ( diffPairRef "@crescent_city_bb_fab1_lib.crescent_city_bb_fab1(sch_1):\P3E_CPU0_PE1_PCH_PCIEUP_RX\(4)") )
				( member ( diffPairRef "@crescent_city_bb_fab1_lib.crescent_city_bb_fab1(sch_1):\P3E_CPU0_PE1_PCH_PCIEUP_RX\(5)") )
				( member ( diffPairRef "@crescent_city_bb_fab1_lib.crescent_city_bb_fab1(sch_1):\P3E_CPU0_PE1_PCH_PCIEUP_RX\(6)") )
				( member ( diffPairRef "@crescent_city_bb_fab1_lib.crescent_city_bb_fab1(sch_1):\P3E_CPU0_PE1_PCH_PCIEUP_RX\(8)") )
				( member ( diffPairRef "@crescent_city_bb_fab1_lib.crescent_city_bb_fab1(sch_1):\P3E_CPU0_PE1_PCH_PCIEUP_RX\(9)") )
				( member ( diffPairRef "@crescent_city_bb_fab1_lib.crescent_city_bb_fab1(sch_1):\DP_USB3_P01_TX\") )
				( member ( diffPairRef "@crescent_city_bb_fab1_lib.crescent_city_bb_fab1(sch_1):\P3E_PCH_M2_SATA6G_RX_D\") )
				( member ( diffPairRef "@crescent_city_bb_fab1_lib.crescent_city_bb_fab1(sch_1):\P3E_PCH_M2_SATA6G_TX_D\") )
				( member ( diffPairRef "@crescent_city_bb_fab1_lib.crescent_city_bb_fab1(sch_1):\DP_57\") )
				( member ( diffPairRef "@crescent_city_bb_fab1_lib.crescent_city_bb_fab1(sch_1):\DP_58\") )
				( member ( diffPairRef "@crescent_city_bb_fab1_lib.crescent_city_bb_fab1(sch_1):\DP_59\") )
				( member ( diffPairRef "@crescent_city_bb_fab1_lib.crescent_city_bb_fab1(sch_1):\DP_60\") )
				( member ( diffPairRef "@crescent_city_bb_fab1_lib.crescent_city_bb_fab1(sch_1):\DP_61\") )
				( member ( diffPairRef "@crescent_city_bb_fab1_lib.crescent_city_bb_fab1(sch_1):\DP_87\") )
				( member ( diffPairRef "@crescent_city_bb_fab1_lib.crescent_city_bb_fab1(sch_1):\DP_86\") )
				( member ( diffPairRef "@crescent_city_bb_fab1_lib.crescent_city_bb_fab1(sch_1):\DP_66\") )
				( member ( diffPairRef "@crescent_city_bb_fab1_lib.crescent_city_bb_fab1(sch_1):\DP_67\") )
				( member ( diffPairRef "@crescent_city_bb_fab1_lib.crescent_city_bb_fab1(sch_1):\DP_68\") )
				( member ( diffPairRef "@crescent_city_bb_fab1_lib.crescent_city_bb_fab1(sch_1):\DP_69\") )
				( member ( diffPairRef "@crescent_city_bb_fab1_lib.crescent_city_bb_fab1(sch_1):\DP_104\") )
				( member ( diffPairRef "@crescent_city_bb_fab1_lib.crescent_city_bb_fab1(sch_1):\DP_73\") )
				( member ( diffPairRef "@crescent_city_bb_fab1_lib.crescent_city_bb_fab1(sch_1):\DP_74\") )
				( member ( diffPairRef "@crescent_city_bb_fab1_lib.crescent_city_bb_fab1(sch_1):\DP_75\") )
				( member ( diffPairRef "@crescent_city_bb_fab1_lib.crescent_city_bb_fab1(sch_1):\DP_76\") )
				( member ( diffPairRef "@crescent_city_bb_fab1_lib.crescent_city_bb_fab1(sch_1):\DP_77\") )
				( member ( diffPairRef "@crescent_city_bb_fab1_lib.crescent_city_bb_fab1(sch_1):\DP_96\") )
				( member ( diffPairRef "@crescent_city_bb_fab1_lib.crescent_city_bb_fab1(sch_1):\DP_97\") )
				( member ( diffPairRef "@crescent_city_bb_fab1_lib.crescent_city_bb_fab1(sch_1):\DP_98\") )
				( member ( diffPairRef "@crescent_city_bb_fab1_lib.crescent_city_bb_fab1(sch_1):\DP_99\") )
				( member ( diffPairRef "@crescent_city_bb_fab1_lib.crescent_city_bb_fab1(sch_1):\DP_100\") )
				( member ( diffPairRef "@crescent_city_bb_fab1_lib.crescent_city_bb_fab1(sch_1):\DP_101\") )
				( member ( diffPairRef "@crescent_city_bb_fab1_lib.crescent_city_bb_fab1(sch_1):\DP_102\") )
				( member ( diffPairRef "@crescent_city_bb_fab1_lib.crescent_city_bb_fab1(sch_1):\DP_103\") )
				( member ( diffPairRef "@crescent_city_bb_fab1_lib.crescent_city_bb_fab1(sch_1):\DP_88\") )
				( member ( diffPairRef "@crescent_city_bb_fab1_lib.crescent_city_bb_fab1(sch_1):\DP_89\") )
				( member ( diffPairRef "@crescent_city_bb_fab1_lib.crescent_city_bb_fab1(sch_1):\DP_90\") )
				( member ( diffPairRef "@crescent_city_bb_fab1_lib.crescent_city_bb_fab1(sch_1):\DP_91\") )
				( member ( diffPairRef "@crescent_city_bb_fab1_lib.crescent_city_bb_fab1(sch_1):\DP_92\") )
				( member ( diffPairRef "@crescent_city_bb_fab1_lib.crescent_city_bb_fab1(sch_1):\DP_93\") )
				( member ( diffPairRef "@crescent_city_bb_fab1_lib.crescent_city_bb_fab1(sch_1):\DP_94\") )
				( member ( diffPairRef "@crescent_city_bb_fab1_lib.crescent_city_bb_fab1(sch_1):\DP_95\") )
				( member ( diffPairRef "@crescent_city_bb_fab1_lib.crescent_city_bb_fab1(sch_1):\DP_82\") )
				( member ( diffPairRef "@crescent_city_bb_fab1_lib.crescent_city_bb_fab1(sch_1):\DP_84\") )
				( member ( diffPairRef "@crescent_city_bb_fab1_lib.crescent_city_bb_fab1(sch_1):\DP_70\") )
				( member ( diffPairRef "@crescent_city_bb_fab1_lib.crescent_city_bb_fab1(sch_1):\DP_80\") )
				( member ( diffPairRef "@crescent_city_bb_fab1_lib.crescent_city_bb_fab1(sch_1):\DP_62\") )
				( member ( diffPairRef "@crescent_city_bb_fab1_lib.crescent_city_bb_fab1(sch_1):\DP_64\") )
				( member ( diffPairRef "@crescent_city_bb_fab1_lib.crescent_city_bb_fab1(sch_1):\DP_83\") )
				( member ( diffPairRef "@crescent_city_bb_fab1_lib.crescent_city_bb_fab1(sch_1):\DP_85\") )
				( member ( diffPairRef "@crescent_city_bb_fab1_lib.crescent_city_bb_fab1(sch_1):\DP_79\") )
				( member ( diffPairRef "@crescent_city_bb_fab1_lib.crescent_city_bb_fab1(sch_1):\DP_81\") )
				( member ( diffPairRef "@crescent_city_bb_fab1_lib.crescent_city_bb_fab1(sch_1):\KTI_CPU0_CPU1_P0P0\(0)") )
				( member ( diffPairRef "@crescent_city_bb_fab1_lib.crescent_city_bb_fab1(sch_1):\KTI_CPU0_CPU1_P0P0\(1)") )
				( member ( diffPairRef "@crescent_city_bb_fab1_lib.crescent_city_bb_fab1(sch_1):\KTI_CPU0_CPU1_P0P0\(2)") )
				( member ( diffPairRef "@crescent_city_bb_fab1_lib.crescent_city_bb_fab1(sch_1):\KTI_CPU0_CPU1_P0P0\(3)") )
				( member ( diffPairRef "@crescent_city_bb_fab1_lib.crescent_city_bb_fab1(sch_1):\KTI_CPU0_CPU1_P0P0\(4)") )
				( member ( diffPairRef "@crescent_city_bb_fab1_lib.crescent_city_bb_fab1(sch_1):\KTI_CPU0_CPU1_P0P0\(5)") )
				( member ( diffPairRef "@crescent_city_bb_fab1_lib.crescent_city_bb_fab1(sch_1):\KTI_CPU0_CPU1_P0P0\(6)") )
				( member ( diffPairRef "@crescent_city_bb_fab1_lib.crescent_city_bb_fab1(sch_1):\KTI_CPU0_CPU1_P0P0\(7)") )
				( member ( diffPairRef "@crescent_city_bb_fab1_lib.crescent_city_bb_fab1(sch_1):\KTI_CPU0_CPU1_P0P0\(8)") )
				( member ( diffPairRef "@crescent_city_bb_fab1_lib.crescent_city_bb_fab1(sch_1):\KTI_CPU0_CPU1_P0P0\(9)") )
				( member ( diffPairRef "@crescent_city_bb_fab1_lib.crescent_city_bb_fab1(sch_1):\KTI_CPU0_CPU1_P0P0\(10)") )
				( member ( diffPairRef "@crescent_city_bb_fab1_lib.crescent_city_bb_fab1(sch_1):\KTI_CPU0_CPU1_P0P0\(11)") )
				( member ( diffPairRef "@crescent_city_bb_fab1_lib.crescent_city_bb_fab1(sch_1):\KTI_CPU0_CPU1_P0P0\(12)") )
				( member ( diffPairRef "@crescent_city_bb_fab1_lib.crescent_city_bb_fab1(sch_1):\KTI_CPU0_CPU1_P0P0\(13)") )
				( member ( diffPairRef "@crescent_city_bb_fab1_lib.crescent_city_bb_fab1(sch_1):\KTI_CPU0_CPU1_P0P0\(14)") )
				( member ( diffPairRef "@crescent_city_bb_fab1_lib.crescent_city_bb_fab1(sch_1):\KTI_CPU0_CPU1_P0P0\(15)") )
				( member ( diffPairRef "@crescent_city_bb_fab1_lib.crescent_city_bb_fab1(sch_1):\KTI_CPU0_CPU1_P0P0\(16)") )
				( member ( diffPairRef "@crescent_city_bb_fab1_lib.crescent_city_bb_fab1(sch_1):\KTI_CPU0_CPU1_P0P0\(17)") )
				( member ( diffPairRef "@crescent_city_bb_fab1_lib.crescent_city_bb_fab1(sch_1):\KTI_CPU0_CPU1_P0P0\(18)") )
				( member ( diffPairRef "@crescent_city_bb_fab1_lib.crescent_city_bb_fab1(sch_1):\KTI_CPU0_CPU1_P0P0\(19)") )
				( member ( diffPairRef "@crescent_city_bb_fab1_lib.crescent_city_bb_fab1(sch_1):\KTI_CPU0_CPU1_P1P1\(0)") )
				( member ( diffPairRef "@crescent_city_bb_fab1_lib.crescent_city_bb_fab1(sch_1):\KTI_CPU0_CPU1_P1P1\(1)") )
				( member ( diffPairRef "@crescent_city_bb_fab1_lib.crescent_city_bb_fab1(sch_1):\KTI_CPU0_CPU1_P1P1\(2)") )
				( member ( diffPairRef "@crescent_city_bb_fab1_lib.crescent_city_bb_fab1(sch_1):\KTI_CPU0_CPU1_P1P1\(3)") )
				( member ( diffPairRef "@crescent_city_bb_fab1_lib.crescent_city_bb_fab1(sch_1):\KTI_CPU0_CPU1_P1P1\(4)") )
				( member ( diffPairRef "@crescent_city_bb_fab1_lib.crescent_city_bb_fab1(sch_1):\KTI_CPU0_CPU1_P1P1\(5)") )
				( member ( diffPairRef "@crescent_city_bb_fab1_lib.crescent_city_bb_fab1(sch_1):\KTI_CPU0_CPU1_P1P1\(6)") )
				( member ( diffPairRef "@crescent_city_bb_fab1_lib.crescent_city_bb_fab1(sch_1):\KTI_CPU0_CPU1_P1P1\(7)") )
				( member ( diffPairRef "@crescent_city_bb_fab1_lib.crescent_city_bb_fab1(sch_1):\KTI_CPU0_CPU1_P1P1\(8)") )
				( member ( diffPairRef "@crescent_city_bb_fab1_lib.crescent_city_bb_fab1(sch_1):\KTI_CPU0_CPU1_P1P1\(9)") )
				( member ( diffPairRef "@crescent_city_bb_fab1_lib.crescent_city_bb_fab1(sch_1):\KTI_CPU0_CPU1_P1P1\(10)") )
				( member ( diffPairRef "@crescent_city_bb_fab1_lib.crescent_city_bb_fab1(sch_1):\KTI_CPU0_CPU1_P1P1\(11)") )
				( member ( diffPairRef "@crescent_city_bb_fab1_lib.crescent_city_bb_fab1(sch_1):\KTI_CPU0_CPU1_P1P1\(12)") )
				( member ( diffPairRef "@crescent_city_bb_fab1_lib.crescent_city_bb_fab1(sch_1):\KTI_CPU0_CPU1_P1P1\(13)") )
				( member ( diffPairRef "@crescent_city_bb_fab1_lib.crescent_city_bb_fab1(sch_1):\KTI_CPU0_CPU1_P1P1\(14)") )
				( member ( diffPairRef "@crescent_city_bb_fab1_lib.crescent_city_bb_fab1(sch_1):\KTI_CPU0_CPU1_P1P1\(15)") )
				( member ( diffPairRef "@crescent_city_bb_fab1_lib.crescent_city_bb_fab1(sch_1):\KTI_CPU0_CPU1_P1P1\(16)") )
				( member ( diffPairRef "@crescent_city_bb_fab1_lib.crescent_city_bb_fab1(sch_1):\KTI_CPU0_CPU1_P1P1\(17)") )
				( member ( diffPairRef "@crescent_city_bb_fab1_lib.crescent_city_bb_fab1(sch_1):\KTI_CPU0_CPU1_P1P1\(18)") )
				( member ( diffPairRef "@crescent_city_bb_fab1_lib.crescent_city_bb_fab1(sch_1):\KTI_CPU0_CPU1_P1P1\(19)") )
				( member ( diffPairRef "@crescent_city_bb_fab1_lib.crescent_city_bb_fab1(sch_1):\KTI_CPU1_CPU0_P0P0\(0)") )
				( member ( diffPairRef "@crescent_city_bb_fab1_lib.crescent_city_bb_fab1(sch_1):\KTI_CPU1_CPU0_P0P0\(1)") )
				( member ( diffPairRef "@crescent_city_bb_fab1_lib.crescent_city_bb_fab1(sch_1):\KTI_CPU1_CPU0_P0P0\(2)") )
				( member ( diffPairRef "@crescent_city_bb_fab1_lib.crescent_city_bb_fab1(sch_1):\KTI_CPU1_CPU0_P0P0\(3)") )
				( member ( diffPairRef "@crescent_city_bb_fab1_lib.crescent_city_bb_fab1(sch_1):\KTI_CPU1_CPU0_P0P0\(4)") )
				( member ( diffPairRef "@crescent_city_bb_fab1_lib.crescent_city_bb_fab1(sch_1):\KTI_CPU1_CPU0_P0P0\(5)") )
				( member ( diffPairRef "@crescent_city_bb_fab1_lib.crescent_city_bb_fab1(sch_1):\KTI_CPU1_CPU0_P0P0\(6)") )
				( member ( diffPairRef "@crescent_city_bb_fab1_lib.crescent_city_bb_fab1(sch_1):\KTI_CPU1_CPU0_P0P0\(7)") )
				( member ( diffPairRef "@crescent_city_bb_fab1_lib.crescent_city_bb_fab1(sch_1):\KTI_CPU1_CPU0_P0P0\(8)") )
				( member ( diffPairRef "@crescent_city_bb_fab1_lib.crescent_city_bb_fab1(sch_1):\KTI_CPU1_CPU0_P0P0\(9)") )
				( member ( diffPairRef "@crescent_city_bb_fab1_lib.crescent_city_bb_fab1(sch_1):\KTI_CPU1_CPU0_P0P0\(10)") )
				( member ( diffPairRef "@crescent_city_bb_fab1_lib.crescent_city_bb_fab1(sch_1):\KTI_CPU1_CPU0_P0P0\(11)") )
				( member ( diffPairRef "@crescent_city_bb_fab1_lib.crescent_city_bb_fab1(sch_1):\KTI_CPU1_CPU0_P0P0\(12)") )
				( member ( diffPairRef "@crescent_city_bb_fab1_lib.crescent_city_bb_fab1(sch_1):\KTI_CPU1_CPU0_P0P0\(13)") )
				( member ( diffPairRef "@crescent_city_bb_fab1_lib.crescent_city_bb_fab1(sch_1):\KTI_CPU1_CPU0_P0P0\(14)") )
				( member ( diffPairRef "@crescent_city_bb_fab1_lib.crescent_city_bb_fab1(sch_1):\KTI_CPU1_CPU0_P0P0\(15)") )
				( member ( diffPairRef "@crescent_city_bb_fab1_lib.crescent_city_bb_fab1(sch_1):\KTI_CPU1_CPU0_P0P0\(16)") )
				( member ( diffPairRef "@crescent_city_bb_fab1_lib.crescent_city_bb_fab1(sch_1):\KTI_CPU1_CPU0_P0P0\(17)") )
				( member ( diffPairRef "@crescent_city_bb_fab1_lib.crescent_city_bb_fab1(sch_1):\KTI_CPU1_CPU0_P0P0\(18)") )
				( member ( diffPairRef "@crescent_city_bb_fab1_lib.crescent_city_bb_fab1(sch_1):\KTI_CPU1_CPU0_P0P0\(19)") )
				( member ( diffPairRef "@crescent_city_bb_fab1_lib.crescent_city_bb_fab1(sch_1):\KTI_CPU1_CPU0_P1P1\(0)") )
				( member ( diffPairRef "@crescent_city_bb_fab1_lib.crescent_city_bb_fab1(sch_1):\KTI_CPU1_CPU0_P1P1\(1)") )
				( member ( diffPairRef "@crescent_city_bb_fab1_lib.crescent_city_bb_fab1(sch_1):\KTI_CPU1_CPU0_P1P1\(2)") )
				( member ( diffPairRef "@crescent_city_bb_fab1_lib.crescent_city_bb_fab1(sch_1):\KTI_CPU1_CPU0_P1P1\(3)") )
				( member ( diffPairRef "@crescent_city_bb_fab1_lib.crescent_city_bb_fab1(sch_1):\KTI_CPU1_CPU0_P1P1\(19)") )
				( member ( diffPairRef "@crescent_city_bb_fab1_lib.crescent_city_bb_fab1(sch_1):\KTI_CPU1_CPU0_P1P1\(18)") )
				( member ( diffPairRef "@crescent_city_bb_fab1_lib.crescent_city_bb_fab1(sch_1):\KTI_CPU1_CPU0_P1P1\(17)") )
				( member ( diffPairRef "@crescent_city_bb_fab1_lib.crescent_city_bb_fab1(sch_1):\KTI_CPU1_CPU0_P1P1\(16)") )
				( member ( diffPairRef "@crescent_city_bb_fab1_lib.crescent_city_bb_fab1(sch_1):\KTI_CPU1_CPU0_P1P1\(15)") )
				( member ( diffPairRef "@crescent_city_bb_fab1_lib.crescent_city_bb_fab1(sch_1):\KTI_CPU1_CPU0_P1P1\(14)") )
				( member ( diffPairRef "@crescent_city_bb_fab1_lib.crescent_city_bb_fab1(sch_1):\KTI_CPU1_CPU0_P1P1\(13)") )
				( member ( diffPairRef "@crescent_city_bb_fab1_lib.crescent_city_bb_fab1(sch_1):\KTI_CPU1_CPU0_P1P1\(12)") )
				( member ( diffPairRef "@crescent_city_bb_fab1_lib.crescent_city_bb_fab1(sch_1):\KTI_CPU1_CPU0_P1P1\(11)") )
				( member ( diffPairRef "@crescent_city_bb_fab1_lib.crescent_city_bb_fab1(sch_1):\KTI_CPU1_CPU0_P1P1\(10)") )
				( member ( diffPairRef "@crescent_city_bb_fab1_lib.crescent_city_bb_fab1(sch_1):\KTI_CPU1_CPU0_P1P1\(9)") )
				( member ( diffPairRef "@crescent_city_bb_fab1_lib.crescent_city_bb_fab1(sch_1):\KTI_CPU1_CPU0_P1P1\(8)") )
				( member ( diffPairRef "@crescent_city_bb_fab1_lib.crescent_city_bb_fab1(sch_1):\KTI_CPU1_CPU0_P1P1\(7)") )
				( member ( diffPairRef "@crescent_city_bb_fab1_lib.crescent_city_bb_fab1(sch_1):\KTI_CPU1_CPU0_P1P1\(6)") )
				( member ( diffPairRef "@crescent_city_bb_fab1_lib.crescent_city_bb_fab1(sch_1):\KTI_CPU1_CPU0_P1P1\(5)") )
				( member ( diffPairRef "@crescent_city_bb_fab1_lib.crescent_city_bb_fab1(sch_1):\KTI_CPU1_CPU0_P1P1\(4)") )
				( member ( diffPairRef "@crescent_city_bb_fab1_lib.crescent_city_bb_fab1(sch_1):\DP_P3E_CPU1_PE3_MP_R\(0)") )
				( member ( diffPairRef "@crescent_city_bb_fab1_lib.crescent_city_bb_fab1(sch_1):\DP_P3E_CPU1_PE3_MP_R\(1)") )
				( member ( diffPairRef "@crescent_city_bb_fab1_lib.crescent_city_bb_fab1(sch_1):\DP_P3E_CPU1_PE3_MP_R\(2)") )
				( member ( diffPairRef "@crescent_city_bb_fab1_lib.crescent_city_bb_fab1(sch_1):\DP_P3E_CPU1_PE3_MP_R\(3)") )
				( member ( diffPairRef "@crescent_city_bb_fab1_lib.crescent_city_bb_fab1(sch_1):\DP_P3E_CPU1_PE3_MP_R\(4)") )
				( member ( diffPairRef "@crescent_city_bb_fab1_lib.crescent_city_bb_fab1(sch_1):\DP_P3E_CPU1_PE3_MP_R\(5)") )
				( member ( diffPairRef "@crescent_city_bb_fab1_lib.crescent_city_bb_fab1(sch_1):\DP_P3E_CPU1_PE3_MP_R\(6)") )
				( member ( diffPairRef "@crescent_city_bb_fab1_lib.crescent_city_bb_fab1(sch_1):\DP_P3E_CPU1_PE3_MP_R\(7)") )
				( member ( diffPairRef "@crescent_city_bb_fab1_lib.crescent_city_bb_fab1(sch_1):\P3E_CPU0_PE2_SS_RX\(0)") )
				( member ( diffPairRef "@crescent_city_bb_fab1_lib.crescent_city_bb_fab1(sch_1):\P3E_CPU0_PE2_SS_RX\(1)") )
				( member ( diffPairRef "@crescent_city_bb_fab1_lib.crescent_city_bb_fab1(sch_1):\P3E_CPU0_PE2_SS_RX\(2)") )
				( member ( diffPairRef "@crescent_city_bb_fab1_lib.crescent_city_bb_fab1(sch_1):\P3E_CPU0_PE2_SS_RX\(3)") )
				( member ( diffPairRef "@crescent_city_bb_fab1_lib.crescent_city_bb_fab1(sch_1):\P3E_CPU0_PE2_SS_RX\(4)") )
				( member ( diffPairRef "@crescent_city_bb_fab1_lib.crescent_city_bb_fab1(sch_1):\P3E_CPU0_PE2_SS_RX\(5)") )
				( member ( diffPairRef "@crescent_city_bb_fab1_lib.crescent_city_bb_fab1(sch_1):\DP_DMI_CPU0_PCH_RX_C\(0)") )
				( member ( diffPairRef "@crescent_city_bb_fab1_lib.crescent_city_bb_fab1(sch_1):\DP_DMI_CPU0_PCH_RX_C\(1)") )
				( member ( diffPairRef "@crescent_city_bb_fab1_lib.crescent_city_bb_fab1(sch_1):\DP_DMI_CPU0_PCH_RX_C\(2)") )
				( member ( diffPairRef "@crescent_city_bb_fab1_lib.crescent_city_bb_fab1(sch_1):\DP_DMI_CPU0_PCH_RX_C\(3)") )
				( member ( diffPairRef "@crescent_city_bb_fab1_lib.crescent_city_bb_fab1(sch_1):\P3E_CPU0_PE2_SS_RX\(6)") )
				( member ( diffPairRef "@crescent_city_bb_fab1_lib.crescent_city_bb_fab1(sch_1):\DP_P2E_SSB_BMC_TX_C\") )
				( member ( diffPairRef "@crescent_city_bb_fab1_lib.crescent_city_bb_fab1(sch_1):\DP_P2E_SSB_BMC_TX\") )
				( member ( diffPairRef "@sapphirecity_baseboard_lib.sapphirecity_baseboard(sch_1):\DMI_CPU0_PCH_TX_C_D\(0)") )
				( member ( diffPairRef "@sapphirecity_baseboard_lib.sapphirecity_baseboard(sch_1):\DMI_CPU0_PCH_TX_C_D\(1)") )
				( member ( diffPairRef "@sapphirecity_baseboard_lib.sapphirecity_baseboard(sch_1):\DMI_CPU0_PCH_TX_C_D\(2)") )
				( member ( diffPairRef "@sapphirecity_baseboard_lib.sapphirecity_baseboard(sch_1):\DMI_CPU0_PCH_TX_C_D\(3)") )
				( member ( diffPairRef "@crescent_city_bb_fab1_lib.crescent_city_bb_fab1(sch_1):\DP_USB2_P02\") )
				( member ( diffPairRef "@crescent_city_bb_fab1_lib.crescent_city_bb_fab1(sch_1):\DP_P2E_SSB_BMC_RX\") )
				( member ( diffPairRef "@crescent_city_bb_fab1_lib.crescent_city_bb_fab1(sch_1):\DP_P2E_SSB_BMC_RX_C\") )
				( member ( diffPairRef "@crescent_city_bb_fab1_lib.crescent_city_bb_fab1(sch_1):\P3E_CPU0_PE2_SS_RX\(7)") )
				( member ( diffPairRef "@crescent_city_bb_fab1_lib.crescent_city_bb_fab1(sch_1):\P3E_CPU0_PE2_SS_RX\(8)") )
				( member ( diffPairRef "@crescent_city_bb_fab1_lib.crescent_city_bb_fab1(sch_1):\P3E_PCH_M2_RX_D\(3)") )
				( member ( diffPairRef "@crescent_city_bb_fab1_lib.crescent_city_bb_fab1(sch_1):\P3E_PCH_M2_RX_D\(2)") )
				( member ( diffPairRef "@crescent_city_bb_fab1_lib.crescent_city_bb_fab1(sch_1):\P3E_PCH_M2_RX_D\(1)") )
				( member ( diffPairRef "@crescent_city_bb_fab1_lib.crescent_city_bb_fab1(sch_1):\P3E_CPU0_PE2_SS_RX\(15)") )
				( member ( diffPairRef "@crescent_city_bb_fab1_lib.crescent_city_bb_fab1(sch_1):\P3E_CPU0_PE2_SS_RX\(14)") )
				( member ( diffPairRef "@crescent_city_bb_fab1_lib.crescent_city_bb_fab1(sch_1):\P3E_CPU0_PE2_SS_RX\(13)") )
				( member ( diffPairRef "@crescent_city_bb_fab1_lib.crescent_city_bb_fab1(sch_1):\P3E_CPU0_PE2_SS_RX\(12)") )
				( member ( diffPairRef "@crescent_city_bb_fab1_lib.crescent_city_bb_fab1(sch_1):\P3E_CPU0_PE2_SS_RX\(11)") )
				( member ( diffPairRef "@crescent_city_bb_fab1_lib.crescent_city_bb_fab1(sch_1):\P3E_CPU0_PE2_SS_RX\(10)") )
				( member ( diffPairRef "@crescent_city_bb_fab1_lib.crescent_city_bb_fab1(sch_1):\P3E_CPU0_PE2_SS_RX\(9)") )
				( member ( diffPairRef "@crescent_city_bb_fab1_lib.crescent_city_bb_fab1(sch_1):\DP_78\") )
				( member ( diffPairRef "@crescent_city_bb_fab1_lib.crescent_city_bb_fab1(sch_1):\DP_P3E_CPU1_PE3_MP_R\(8)") )
				( member ( diffPairRef "@crescent_city_bb_fab1_lib.crescent_city_bb_fab1(sch_1):\DP_P3E_CPU1_PE3_MP_R\(9)") )
				( member ( diffPairRef "@crescent_city_bb_fab1_lib.crescent_city_bb_fab1(sch_1):\DP_P3E_CPU1_PE3_MP_R\(10)") )
				( member ( diffPairRef "@crescent_city_bb_fab1_lib.crescent_city_bb_fab1(sch_1):\DP_P3E_CPU1_PE3_MP_R\(11)") )
				( member ( diffPairRef "@crescent_city_bb_fab1_lib.crescent_city_bb_fab1(sch_1):\DP_P3E_CPU1_PE3_MP_R\(12)") )
				( member ( diffPairRef "@crescent_city_bb_fab1_lib.crescent_city_bb_fab1(sch_1):\DP_P3E_CPU1_PE3_MP_R\(13)") )
				( member ( diffPairRef "@crescent_city_bb_fab1_lib.crescent_city_bb_fab1(sch_1):\DP_P3E_CPU1_PE3_MP_R\(14)") )
				( member ( diffPairRef "@crescent_city_bb_fab1_lib.crescent_city_bb_fab1(sch_1):\DP_P3E_CPU1_PE3_MP_R\(15)") )
				( member ( signalRef "@baseboard_fab2_lib.baseboard_fab2(sch_1):sata6g_pch_pcie_up_sata_rxn(0)") )
				( member ( signalRef "@baseboard_fab2_lib.baseboard_fab2(sch_1):sata6g_pch_pcie_up_sata_rxn(1)") )
				( member ( signalRef "@baseboard_fab2_lib.baseboard_fab2(sch_1):sata6g_pch_pcie_up_sata_rxn(2)") )
				( member ( signalRef "@baseboard_fab2_lib.baseboard_fab2(sch_1):sata6g_pch_pcie_up_sata_rxn(3)") )
				( member ( signalRef "@baseboard_fab2_lib.baseboard_fab2(sch_1):sata6g_pch_pcie_up_sata_rxp(0)") )
				( member ( signalRef "@baseboard_fab2_lib.baseboard_fab2(sch_1):sata6g_pch_pcie_up_sata_rxp(1)") )
				( member ( signalRef "@baseboard_fab2_lib.baseboard_fab2(sch_1):sata6g_pch_pcie_up_sata_rxp(2)") )
				( member ( signalRef "@baseboard_fab2_lib.baseboard_fab2(sch_1):sata6g_pch_pcie_up_sata_rxp(3)") )
				( member ( signalRef "@baseboard_fab2_lib.baseboard_fab2(sch_1):sata6g_p0_rx_c_dn") )
				( member ( signalRef "@baseboard_fab2_lib.baseboard_fab2(sch_1):sata6g_p1_rx_c_dn") )
				( member ( signalRef "@baseboard_fab2_lib.baseboard_fab2(sch_1):sata6g_p1_rx_c_dp") )
				( member ( signalRef "@baseboard_fab2_lib.baseboard_fab2(sch_1):sata6g_p2_rx_c_dn") )
				( member ( signalRef "@baseboard_fab2_lib.baseboard_fab2(sch_1):sata6g_p2_rx_c_dp") )
				( member ( signalRef "@baseboard_fab2_lib.baseboard_fab2(sch_1):sata6g_p3_rx_c_dn") )
				( member ( signalRef "@baseboard_fab2_lib.baseboard_fab2(sch_1):sata6g_p3_rx_c_dp") )
				( member ( signalRef "@baseboard_fab2_lib.baseboard_fab2(sch_1):p3e_cpu1_pe3_mp_txp(10)") )
				( member ( signalRef "@baseboard_fab2_lib.baseboard_fab2(sch_1):p3e_cpu1_pe3_mp_c_txp(10)") )
				( member ( signalRef "@baseboard_fab2_lib.baseboard_fab2(sch_1):p3e_cpu1_pe3_mp_txn(10)") )
				( member ( signalRef "@baseboard_fab2_lib.baseboard_fab2(sch_1):p3e_cpu1_pe3_mp_c_txn(10)") )
				( member ( signalRef "@baseboard_fab2_lib.baseboard_fab2(sch_1):p3e_pch_m2_sata6g_rx_r_dn") )
				( member ( signalRef "@baseboard_fab2_lib.baseboard_fab2(sch_1):p3e_pch_m2_sata6g_rx_r_dp") )
				( member ( signalRef "@baseboard_fab2_lib.baseboard_fab2(sch_1):p3e_pch_m2_sata6g_tx_r_dn") )
				( member ( signalRef "@baseboard_fab2_lib.baseboard_fab2(sch_1):p3e_pch_m2_sata6g_tx_r_dp") )
				( member ( signalRef "@baseboard_fab2_lib.baseboard_fab2(sch_1):p3e_pch_rx_0_dn") )
				( member ( signalRef "@baseboard_fab2_lib.baseboard_fab2(sch_1):p3e_pch_rx_0_dp") )
				( member ( signalRef "@baseboard_fab2_lib.baseboard_fab2(sch_1):p3e_pch_tx_0_dn") )
				( member ( signalRef "@baseboard_fab2_lib.baseboard_fab2(sch_1):p3e_pch_tx_0_dp") )
				( member ( signalRef "@baseboard_fab2_lib.baseboard_fab2(sch_1):sata6g_s0_rx_dn") )
				( member ( signalRef "@baseboard_fab2_lib.baseboard_fab2(sch_1):sata6g_s0_rx_dp") )
				( member ( signalRef "@baseboard_fab2_lib.baseboard_fab2(sch_1):sata6g_s0_tx_dn") )
				( member ( signalRef "@baseboard_fab2_lib.baseboard_fab2(sch_1):sata6g_s0_tx_dp") )
				( member ( signalRef "@baseboard_fab2_lib.baseboard_fab2(sch_1):usb3_p01_c_txn") )
				( member ( signalRef "@baseboard_fab2_lib.baseboard_fab2(sch_1):usb3_p01_c_txp") )
				( member ( signalRef "@baseboard_fab2_lib.baseboard_fab2(sch_1):usb3_p01_fb_rxn") )
				( member ( signalRef "@baseboard_fab2_lib.baseboard_fab2(sch_1):usb3_p01_fb_rxp") )
				( member ( signalRef "@baseboard_fab2_lib.baseboard_fab2(sch_1):usb3_p01_fb_txn") )
				( member ( signalRef "@baseboard_fab2_lib.baseboard_fab2(sch_1):usb3_p01_fb_txp") )
				( member ( signalRef "@baseboard_fab2_lib.baseboard_fab2(sch_1):usb3_p01_rxn") )
				( member ( signalRef "@baseboard_fab2_lib.baseboard_fab2(sch_1):usb3_p01_rxp") )
				( member ( signalRef "@baseboard_fab2_lib.baseboard_fab2(sch_1):usb3_p01_txn") )
				( member ( signalRef "@baseboard_fab2_lib.baseboard_fab2(sch_1):usb3_p01_txp") )
				( member ( signalRef "@baseboard_fab2_lib.baseboard_fab2(sch_1):pe_pch_sprv_rx_c_dn") )
				( member ( signalRef "@baseboard_fab2_lib.baseboard_fab2(sch_1):pe_pch_sprv_rx_c_dp") )
				( member ( signalRef "@baseboard_fab2_lib.baseboard_fab2(sch_1):pe_pch_sprv_rx_dn") )
				( member ( signalRef "@baseboard_fab2_lib.baseboard_fab2(sch_1):pe_pch_sprv_rx_dp") )
				( member ( signalRef "@baseboard_fab2_lib.baseboard_fab2(sch_1):pe_pch_sprv_tx_c_dn") )
				( member ( signalRef "@baseboard_fab2_lib.baseboard_fab2(sch_1):pe_pch_sprv_tx_c_dp") )
				( member ( signalRef "@baseboard_fab2_lib.baseboard_fab2(sch_1):pe_pch_sprv_tx_dn") )
				( member ( signalRef "@baseboard_fab2_lib.baseboard_fab2(sch_1):pe_pch_sprv_tx_dp") )
				( member ( signalRef "@baseboard_fab2_lib.baseboard_fab2(sch_1):p3e_cpu0_pe1_pch_c_txn(8)") )
				( member ( signalRef "@baseboard_fab2_lib.baseboard_fab2(sch_1):p3e_cpu0_pe1_pch_c_txp(8)") )
				( member ( signalRef "@baseboard_fab2_lib.baseboard_fab2(sch_1):p3e_cpu0_pe1_pch_rxn(7)") )
				( member ( signalRef "@baseboard_fab2_lib.baseboard_fab2(sch_1):p3e_cpu0_pe1_pch_rxp(7)") )
				( member ( signalRef "@baseboard_fab2_lib.baseboard_fab2(sch_1):p3e_cpu0_pe1_pch_txn(8)") )
				( member ( signalRef "@baseboard_fab2_lib.baseboard_fab2(sch_1):p3e_cpu0_pe1_pch_txp(8)") )
				( member ( signalRef "@baseboard_fab2_lib.baseboard_fab2(sch_1):p3e_cpu0_pe1_ss_rxn(7)") )
				( member ( signalRef "@baseboard_fab2_lib.baseboard_fab2(sch_1):p3e_cpu0_pe1_ss_rxp(7)") )
				( member ( signalRef "@baseboard_fab2_lib.baseboard_fab2(sch_1):p3e_cpu0_pe1_ss_r_rxn(7)") )
				( member ( signalRef "@baseboard_fab2_lib.baseboard_fab2(sch_1):p3e_cpu0_pe1_ss_r_rxp(7)") )
				( member ( signalRef "@baseboard_fab2_lib.baseboard_fab2(sch_1):p3e_cpu0_pe2_ss_c_txn(15)") )
				( member ( signalRef "@baseboard_fab2_lib.baseboard_fab2(sch_1):p3e_cpu0_pe2_ss_c_txp(15)") )
				( member ( signalRef "@baseboard_fab2_lib.baseboard_fab2(sch_1):p3e_cpu0_pe2_ss_txn(15)") )
				( member ( signalRef "@baseboard_fab2_lib.baseboard_fab2(sch_1):p3e_cpu0_pe2_ss_txp(15)") )
				( member ( signalRef "@baseboard_fab2_lib.baseboard_fab2(sch_1):sata6g_pch_pcie_up_sata_rxn(4)") )
				( member ( signalRef "@baseboard_fab2_lib.baseboard_fab2(sch_1):sata6g_pch_pcie_up_sata_txp(5)") )
				( member ( signalRef "@baseboard_fab2_lib.baseboard_fab2(sch_1):sata6g_pch_pcie_up_sata_txp(6)") )
				( member ( signalRef "@baseboard_fab2_lib.baseboard_fab2(sch_1):sata6g_pch_pcie_up_sata_txp(7)") )
				( member ( signalRef "@baseboard_fab2_lib.baseboard_fab2(sch_1):sata6g_pch_pcie_up_sata_txp(2)") )
				( member ( signalRef "@baseboard_fab2_lib.baseboard_fab2(sch_1):sata6g_pch_pcie_up_sata_txp(3)") )
				( member ( signalRef "@baseboard_fab2_lib.baseboard_fab2(sch_1):sata6g_pch_pcie_up_sata_txp(4)") )
				( member ( signalRef "@baseboard_fab2_lib.baseboard_fab2(sch_1):sata6g_p0_rx_c_dp") )
				( member ( signalRef "@baseboard_fab2_lib.baseboard_fab2(sch_1):sata6g_p1_tx_c_dp") )
				( member ( signalRef "@baseboard_fab2_lib.baseboard_fab2(sch_1):sata6g_p2_tx_c_dn") )
				( member ( signalRef "@baseboard_fab2_lib.baseboard_fab2(sch_1):sata6g_p2_tx_c_dp") )
				( member ( signalRef "@baseboard_fab2_lib.baseboard_fab2(sch_1):sata6g_p3_tx_c_dn") )
				( member ( signalRef "@baseboard_fab2_lib.baseboard_fab2(sch_1):sata6g_p3_tx_c_dp") )
				( member ( signalRef "@baseboard_fab2_lib.baseboard_fab2(sch_1):sata6g_p4_rx_c_dn") )
				( member ( signalRef "@baseboard_fab2_lib.baseboard_fab2(sch_1):sata6g_p4_rx_c_dp") )
				( member ( signalRef "@baseboard_fab2_lib.baseboard_fab2(sch_1):sata6g_p4_tx_c_dn") )
				( member ( signalRef "@baseboard_fab2_lib.baseboard_fab2(sch_1):sata6g_p4_tx_c_dp") )
				( member ( signalRef "@baseboard_fab2_lib.baseboard_fab2(sch_1):sata6g_pch_pcie_up_sata_txp(1)") )
				( member ( signalRef "@baseboard_fab2_lib.baseboard_fab2(sch_1):sata6g_p0_tx_c_dn") )
				( member ( signalRef "@baseboard_fab2_lib.baseboard_fab2(sch_1):sata6g_p0_tx_c_dp") )
				( member ( signalRef "@baseboard_fab2_lib.baseboard_fab2(sch_1):sata6g_p1_tx_c_dn") )
				( member ( signalRef "@baseboard_fab2_lib.baseboard_fab2(sch_1):sata6g_pch_pcie_up_sata_txn(5)") )
				( member ( signalRef "@baseboard_fab2_lib.baseboard_fab2(sch_1):sata6g_pch_pcie_up_sata_txn(4)") )
				( member ( signalRef "@baseboard_fab2_lib.baseboard_fab2(sch_1):sata6g_pch_pcie_up_sata_txn(3)") )
				( member ( signalRef "@baseboard_fab2_lib.baseboard_fab2(sch_1):sata6g_pch_pcie_up_sata_txn(2)") )
				( member ( signalRef "@baseboard_fab2_lib.baseboard_fab2(sch_1):sata6g_pch_pcie_up_sata_txn(1)") )
				( member ( signalRef "@baseboard_fab2_lib.baseboard_fab2(sch_1):sata6g_pch_pcie_up_sata_txp(0)") )
				( member ( signalRef "@baseboard_fab2_lib.baseboard_fab2(sch_1):sata6g_pch_pcie_up_sata_txn(0)") )
				( member ( signalRef "@baseboard_fab2_lib.baseboard_fab2(sch_1):sata6g_pch_pcie_up_sata_rxp(7)") )
				( member ( signalRef "@baseboard_fab2_lib.baseboard_fab2(sch_1):sata6g_pch_pcie_up_sata_rxp(6)") )
				( member ( signalRef "@baseboard_fab2_lib.baseboard_fab2(sch_1):sata6g_pch_pcie_up_sata_txn(7)") )
				( member ( signalRef "@baseboard_fab2_lib.baseboard_fab2(sch_1):sata6g_pch_pcie_up_sata_rxp(5)") )
				( member ( signalRef "@baseboard_fab2_lib.baseboard_fab2(sch_1):sata6g_pch_pcie_up_sata_rxp(4)") )
				( member ( signalRef "@baseboard_fab2_lib.baseboard_fab2(sch_1):sata6g_pch_pcie_up_sata_rxn(7)") )
				( member ( signalRef "@baseboard_fab2_lib.baseboard_fab2(sch_1):sata6g_pch_pcie_up_sata_txn(6)") )
				( member ( signalRef "@baseboard_fab2_lib.baseboard_fab2(sch_1):sata6g_pch_pcie_up_sata_rxn(6)") )
				( member ( signalRef "@baseboard_fab2_lib.baseboard_fab2(sch_1):sata6g_pch_pcie_up_sata_rxn(5)") )
				( member ( signalRef "@baseboard_fab2_lib.baseboard_fab2(sch_1):sata6g_p5_rx_c_dn") )
				( member ( signalRef "@baseboard_fab2_lib.baseboard_fab2(sch_1):sata6g_p5_rx_c_dp") )
				( member ( signalRef "@baseboard_fab2_lib.baseboard_fab2(sch_1):sata6g_p5_tx_c_dn") )
				( member ( signalRef "@baseboard_fab2_lib.baseboard_fab2(sch_1):sata6g_p5_tx_c_dp") )
				( member ( signalRef "@baseboard_fab2_lib.baseboard_fab2(sch_1):sata6g_p6_rx_c_dn") )
				( member ( signalRef "@baseboard_fab2_lib.baseboard_fab2(sch_1):sata6g_p6_rx_c_dp") )
				( member ( signalRef "@baseboard_fab2_lib.baseboard_fab2(sch_1):sata6g_p6_tx_c_dn") )
				( member ( signalRef "@baseboard_fab2_lib.baseboard_fab2(sch_1):sata6g_p6_tx_c_dp") )
				( member ( signalRef "@baseboard_fab2_lib.baseboard_fab2(sch_1):sata6g_p7_rx_c_dn") )
				( member ( signalRef "@baseboard_fab2_lib.baseboard_fab2(sch_1):sata6g_p7_rx_c_dp") )
				( member ( signalRef "@baseboard_fab2_lib.baseboard_fab2(sch_1):sata6g_p7_tx_c_dn") )
				( member ( signalRef "@baseboard_fab2_lib.baseboard_fab2(sch_1):sata6g_p7_tx_c_dp") )
				( member ( signalRef "@baseboard_fab2_lib.baseboard_fab2(sch_1):sata6g_p8_rx_c_dn") )
				( member ( signalRef "@baseboard_fab2_lib.baseboard_fab2(sch_1):sata6g_p8_rx_c_dp") )
				( member ( signalRef "@baseboard_fab2_lib.baseboard_fab2(sch_1):sata6g_p8_tx_c_dn") )
				( member ( signalRef "@baseboard_fab2_lib.baseboard_fab2(sch_1):sata6g_p8_tx_c_dp") )
				( member ( signalRef "@baseboard_fab2_lib.baseboard_fab2(sch_1):sata6g_p9_rx_c_dn") )
				( member ( signalRef "@baseboard_fab2_lib.baseboard_fab2(sch_1):sata6g_p9_rx_c_dp") )
				( member ( signalRef "@baseboard_fab2_lib.baseboard_fab2(sch_1):sata6g_p9_tx_c_dn") )
				( member ( signalRef "@baseboard_fab2_lib.baseboard_fab2(sch_1):sata6g_p9_tx_c_dp") )
				( member ( signalRef "@baseboard_fab2_lib.baseboard_fab2(sch_1):sata6g_p10_rx_c_dn") )
				( member ( signalRef "@baseboard_fab2_lib.baseboard_fab2(sch_1):sata6g_p10_rx_c_dp") )
				( member ( signalRef "@baseboard_fab2_lib.baseboard_fab2(sch_1):sata6g_p10_tx_c_dn") )
				( member ( signalRef "@baseboard_fab2_lib.baseboard_fab2(sch_1):sata6g_p10_tx_c_dp") )
				( member ( signalRef "@baseboard_fab2_lib.baseboard_fab2(sch_1):sata6g_p11_rx_c_dn") )
				( member ( signalRef "@baseboard_fab2_lib.baseboard_fab2(sch_1):sata6g_p11_rx_c_dp") )
				( member ( signalRef "@baseboard_fab2_lib.baseboard_fab2(sch_1):sata6g_p11_tx_c_dn") )
				( member ( signalRef "@baseboard_fab2_lib.baseboard_fab2(sch_1):sata6g_p11_tx_c_dp") )
				( member ( signalRef "@baseboard_fab2_lib.baseboard_fab2(sch_1):sata6g_rx_dn(0)") )
				( member ( signalRef "@baseboard_fab2_lib.baseboard_fab2(sch_1):sata6g_rx_dn(1)") )
				( member ( signalRef "@baseboard_fab2_lib.baseboard_fab2(sch_1):sata6g_rx_dn(2)") )
				( member ( signalRef "@baseboard_fab2_lib.baseboard_fab2(sch_1):sata6g_rx_dn(3)") )
				( member ( signalRef "@baseboard_fab2_lib.baseboard_fab2(sch_1):sata6g_rx_dp(0)") )
				( member ( signalRef "@baseboard_fab2_lib.baseboard_fab2(sch_1):sata6g_rx_dp(1)") )
				( member ( signalRef "@baseboard_fab2_lib.baseboard_fab2(sch_1):sata6g_rx_dp(2)") )
				( member ( signalRef "@baseboard_fab2_lib.baseboard_fab2(sch_1):sata6g_rx_dp(3)") )
				( member ( signalRef "@baseboard_fab2_lib.baseboard_fab2(sch_1):sata6g_s1_rx_c_dn") )
				( member ( signalRef "@baseboard_fab2_lib.baseboard_fab2(sch_1):sata6g_s1_rx_c_dp") )
				( member ( signalRef "@baseboard_fab2_lib.baseboard_fab2(sch_1):sata6g_s1_rx_dn") )
				( member ( signalRef "@baseboard_fab2_lib.baseboard_fab2(sch_1):sata6g_s1_rx_dp") )
				( member ( signalRef "@baseboard_fab2_lib.baseboard_fab2(sch_1):sata6g_s1_tx_c_dn") )
				( member ( signalRef "@baseboard_fab2_lib.baseboard_fab2(sch_1):sata6g_s1_tx_c_dp") )
				( member ( signalRef "@baseboard_fab2_lib.baseboard_fab2(sch_1):sata6g_s1_tx_dn") )
				( member ( signalRef "@baseboard_fab2_lib.baseboard_fab2(sch_1):sata6g_s1_tx_dp") )
				( member ( signalRef "@baseboard_fab2_lib.baseboard_fab2(sch_1):sata6g_tx_dn(0)") )
				( member ( signalRef "@baseboard_fab2_lib.baseboard_fab2(sch_1):sata6g_tx_dn(1)") )
				( member ( signalRef "@baseboard_fab2_lib.baseboard_fab2(sch_1):sata6g_tx_dn(2)") )
				( member ( signalRef "@baseboard_fab2_lib.baseboard_fab2(sch_1):sata6g_tx_dn(3)") )
				( member ( signalRef "@baseboard_fab2_lib.baseboard_fab2(sch_1):sata6g_tx_dp(0)") )
				( member ( signalRef "@baseboard_fab2_lib.baseboard_fab2(sch_1):sata6g_tx_dp(1)") )
				( member ( signalRef "@baseboard_fab2_lib.baseboard_fab2(sch_1):sata6g_tx_dp(2)") )
				( member ( signalRef "@baseboard_fab2_lib.baseboard_fab2(sch_1):sata6g_tx_dp(3)") )
				( member ( signalRef "@baseboard_fab2_lib.baseboard_fab2(sch_1):dmi_cpu0_pch_rx_c_dn(0)") )
				( member ( signalRef "@baseboard_fab2_lib.baseboard_fab2(sch_1):dmi_cpu0_pch_rx_c_dn(1)") )
				( member ( signalRef "@baseboard_fab2_lib.baseboard_fab2(sch_1):dmi_cpu0_pch_rx_c_dn(2)") )
				( member ( signalRef "@baseboard_fab2_lib.baseboard_fab2(sch_1):dmi_cpu0_pch_rx_c_dn(3)") )
				( member ( signalRef "@baseboard_fab2_lib.baseboard_fab2(sch_1):dmi_cpu0_pch_rx_c_dp(0)") )
				( member ( signalRef "@baseboard_fab2_lib.baseboard_fab2(sch_1):dmi_cpu0_pch_rx_c_dp(1)") )
				( member ( signalRef "@baseboard_fab2_lib.baseboard_fab2(sch_1):dmi_cpu0_pch_rx_c_dp(2)") )
				( member ( signalRef "@baseboard_fab2_lib.baseboard_fab2(sch_1):dmi_cpu0_pch_rx_c_dp(3)") )
				( member ( signalRef "@baseboard_fab2_lib.baseboard_fab2(sch_1):dmi_cpu0_pch_rx_dn(0)") )
				( member ( signalRef "@baseboard_fab2_lib.baseboard_fab2(sch_1):dmi_cpu0_pch_rx_dn(1)") )
				( member ( signalRef "@baseboard_fab2_lib.baseboard_fab2(sch_1):dmi_cpu0_pch_rx_dn(2)") )
				( member ( signalRef "@baseboard_fab2_lib.baseboard_fab2(sch_1):dmi_cpu0_pch_rx_dn(3)") )
				( member ( signalRef "@baseboard_fab2_lib.baseboard_fab2(sch_1):dmi_cpu0_pch_rx_dp(0)") )
				( member ( signalRef "@baseboard_fab2_lib.baseboard_fab2(sch_1):dmi_cpu0_pch_rx_dp(1)") )
				( member ( signalRef "@baseboard_fab2_lib.baseboard_fab2(sch_1):dmi_cpu0_pch_rx_dp(2)") )
				( member ( signalRef "@baseboard_fab2_lib.baseboard_fab2(sch_1):dmi_cpu0_pch_rx_dp(3)") )
				( member ( signalRef "@baseboard_fab2_lib.baseboard_fab2(sch_1):l1_z85_ms") )
				( member ( signalRef "@baseboard_fab2_lib.baseboard_fab2(sch_1):l3_z85_sl") )
				( member ( signalRef "@baseboard_fab2_lib.baseboard_fab2(sch_1):l12_z85_sl") )
				( member ( signalRef "@baseboard_fab2_lib.baseboard_fab2(sch_1):l14_z85_ms") )
				( member ( signalRef "@baseboard_fab2_lib.baseboard_fab2(sch_1):l1_z85_thru") )
				( member ( signalRef "@baseboard_fab2_lib.baseboard_fab2(sch_1):l5_z85_sl") )
				( member ( signalRef "@baseboard_fab2_lib.baseboard_fab2(sch_1):l10_z85_sl") )
				( objectStatus "PNCLS_85-OHM_DIFF" )
			)
			( netClass "@sapphirecity_baseboard_lib.sapphirecity_baseboard(sch_1):\V_M_BMC_DDR3_COMP\"
				( memberType ( signal ) )
				( spacingCSetRef "@sapphirecity_baseboard_lib.sapphirecity_baseboard(sch_1):\10MIL\" )
				( sameNetSpacingCSetRef "@crescent_city_bb_fab1_lib.crescent_city_bb_fab1(sch_1):\10MIL\" )
				( objectFlag fObjectSpacing )
				( objectFlag fObjectSameNetSpacing )
				( objectStatus "V_M_BMC_DDR3_COMP" )
			)
			( netClass "@sapphirecity_baseboard_lib.sapphirecity_baseboard(sch_1):\VR_PVDDQ_NPRT\"
				( memberType ( signal ) )
				( objectFlag fObjectSpacing )
				( objectFlag fObjectSameNetSpacing )
				( objectStatus "VR_PVDDQ_NPRT" )
			)
			( netClass "@sapphirecity_baseboard_lib.sapphirecity_baseboard(sch_1):\VR_PVDDQ_JKLM\"
				( memberType ( signal ) )
				( objectFlag fObjectSpacing )
				( objectFlag fObjectSameNetSpacing )
				( objectStatus "VR_PVDDQ_JKLM" )
			)
			( netClass "@sapphirecity_baseboard_lib.sapphirecity_baseboard(sch_1):\VR_PVDDQ_ABCD\"
				( memberType ( signal ) )
				( objectFlag fObjectSpacing )
				( objectFlag fObjectSameNetSpacing )
				( objectStatus "VR_PVDDQ_ABCD" )
			)
			( netClass "@sapphirecity_baseboard_lib.sapphirecity_baseboard(sch_1):\VR_P0V75_AUX\"
				( memberType ( signal ) )
				( objectFlag fObjectSpacing )
				( objectFlag fObjectSameNetSpacing )
				( objectStatus "VR_P0V75_AUX" )
			)
			( netClass "@sapphirecity_baseboard_lib.sapphirecity_baseboard(sch_1):\VR_P2V5_LAN_AUX\"
				( memberType ( signal ) )
				( objectFlag fObjectSpacing )
				( objectFlag fObjectSameNetSpacing )
				( objectStatus "VR_P2V5_LAN_AUX" )
			)
			( netClass "@sapphirecity_baseboard_lib.sapphirecity_baseboard(sch_1):\VR_P1V2_LAN_AUX\"
				( memberType ( signal ) )
				( objectFlag fObjectSpacing )
				( objectFlag fObjectSameNetSpacing )
				( objectStatus "VR_P1V2_LAN_AUX" )
			)
			( netClass "@sapphirecity_baseboard_lib.sapphirecity_baseboard(sch_1):\VR_P0V67_LAN_AUX\"
				( memberType ( signal ) )
				( objectFlag fObjectSpacing )
				( objectFlag fObjectSameNetSpacing )
				( objectStatus "VR_P0V67_LAN_AUX" )
			)
			( netClass "@sapphirecity_baseboard_lib.sapphirecity_baseboard(sch_1):\VR_P0V8_LAN_AUX\"
				( memberType ( signal ) )
				( objectFlag fObjectSpacing )
				( objectFlag fObjectSameNetSpacing )
				( objectStatus "VR_P0V8_LAN_AUX" )
			)
			( netClass "@sapphirecity_baseboard_lib.sapphirecity_baseboard(sch_1):\VR_PVTT_NPRT\"
				( memberType ( signal ) )
				( objectFlag fObjectSpacing )
				( objectFlag fObjectSameNetSpacing )
				( objectStatus "VR_PVTT_NPRT" )
			)
			( netClass "@sapphirecity_baseboard_lib.sapphirecity_baseboard(sch_1):\VR_PVTT_JKLM\"
				( memberType ( signal ) )
				( objectFlag fObjectSpacing )
				( objectFlag fObjectSameNetSpacing )
				( objectStatus "VR_PVTT_JKLM" )
			)
			( netClass "@sapphirecity_baseboard_lib.sapphirecity_baseboard(sch_1):\VR_PVPP_NPRT\"
				( memberType ( signal ) )
				( objectFlag fObjectSpacing )
				( objectFlag fObjectSameNetSpacing )
				( objectStatus "VR_PVPP_NPRT" )
			)
			( netClass "@sapphirecity_baseboard_lib.sapphirecity_baseboard(sch_1):\VR_PVPP_JKLM\"
				( memberType ( signal ) )
				( objectFlag fObjectSpacing )
				( objectFlag fObjectSameNetSpacing )
				( objectStatus "VR_PVPP_JKLM" )
			)
			( netClass "@sapphirecity_baseboard_lib.sapphirecity_baseboard(sch_1):\VR_PVPP_EFGH\"
				( memberType ( signal ) )
				( objectFlag fObjectSpacing )
				( objectFlag fObjectSameNetSpacing )
				( objectStatus "VR_PVPP_EFGH" )
			)
			( netClass "@sapphirecity_baseboard_lib.sapphirecity_baseboard(sch_1):\VR_PVPP_ABCD\"
				( memberType ( signal ) )
				( objectFlag fObjectSpacing )
				( objectFlag fObjectSameNetSpacing )
				( objectStatus "VR_PVPP_ABCD" )
			)
			( netClass "@sapphirecity_baseboard_lib.sapphirecity_baseboard(sch_1):\VR_PVCCIN_CPU3\"
				( memberType ( signal ) )
				( objectFlag fObjectSpacing )
				( objectFlag fObjectSameNetSpacing )
				( objectStatus "VR_PVCCIN_CPU3" )
			)
			( netClass "@sapphirecity_baseboard_lib.sapphirecity_baseboard(sch_1):\VR_PVCCIN_CPU2\"
				( memberType ( signal ) )
				( objectFlag fObjectSpacing )
				( objectFlag fObjectSameNetSpacing )
				( objectStatus "VR_PVCCIN_CPU2" )
			)
			( netClass "@sapphirecity_baseboard_lib.sapphirecity_baseboard(sch_1):\VR_PVCCIN_CPU0\"
				( memberType ( signal ) )
				( objectFlag fObjectSpacing )
				( objectFlag fObjectSameNetSpacing )
				( objectStatus "VR_PVCCIN_CPU0" )
			)
			( netClass "@sapphirecity_baseboard_lib.sapphirecity_baseboard(sch_1):\DDR4_VREF\"
				( memberType ( signal ) )
				( spacingCSetRef "@sapphirecity_baseboard_lib.sapphirecity_baseboard(sch_1):\DDR4_2SPC_DQ/DQS\" )
				( objectFlag fObjectSpacing )
				( objectFlag fObjectSameNetSpacing )
				( objectStatus "DDR4_VREF" )
			)
			( netClass "@sapphirecity_baseboard_lib.sapphirecity_baseboard(sch_1):\P2E_CPU0_LAN_RX\"
				( memberType ( signal ) )
				( spacingCSetRef "@sapphirecity_baseboard_lib.sapphirecity_baseboard(sch_1):\11H_US_AND_5H_SL_VIA+3H_A\" )
				( objectFlag fObjectSpacing )
				( objectFlag fObjectSameNetSpacing )
				( member ( diffPairRef "@crescent_city_bb_fab1_lib.crescent_city_bb_fab1(sch_1):\DP_P2E_SSB_BMC_RX\") )
				( member ( diffPairRef "@crescent_city_bb_fab1_lib.crescent_city_bb_fab1(sch_1):\DP_P2E_SSB_BMC_RX_C\") )
				( member ( signalRef "@baseboard_fab2_lib.baseboard_fab2(sch_1):p2e_ssb_bmc_rx_c_dn") )
				( member ( signalRef "@baseboard_fab2_lib.baseboard_fab2(sch_1):p2e_ssb_bmc_rx_c_dp") )
				( member ( signalRef "@baseboard_fab2_lib.baseboard_fab2(sch_1):p2e_ssb_bmc_rx_dn") )
				( member ( signalRef "@baseboard_fab2_lib.baseboard_fab2(sch_1):p2e_ssb_bmc_rx_dp") )
				( objectStatus "SNCLS_P2E_SSB_BMC_RX" )
			)
			( netClass "@sapphirecity_baseboard_lib.sapphirecity_baseboard(sch_1):\P2E_CPU0_LAN_TX\"
				( memberType ( signal ) )
				( spacingCSetRef "@sapphirecity_baseboard_lib.sapphirecity_baseboard(sch_1):\11H_US_AND_5H_SL_VIA+3H_A\" )
				( objectFlag fObjectSpacing )
				( objectFlag fObjectSameNetSpacing )
				( member ( diffPairRef "@crescent_city_bb_fab1_lib.crescent_city_bb_fab1(sch_1):\DP_P2E_SSB_BMC_TX\") )
				( member ( diffPairRef "@crescent_city_bb_fab1_lib.crescent_city_bb_fab1(sch_1):\DP_P2E_SSB_BMC_TX_C\") )
				( member ( signalRef "@baseboard_fab2_lib.baseboard_fab2(sch_1):p2e_ssb_bmc_tx_c_dn") )
				( member ( signalRef "@baseboard_fab2_lib.baseboard_fab2(sch_1):p2e_ssb_bmc_tx_c_dp") )
				( member ( signalRef "@baseboard_fab2_lib.baseboard_fab2(sch_1):p2e_ssb_bmc_tx_dn") )
				( member ( signalRef "@baseboard_fab2_lib.baseboard_fab2(sch_1):p2e_ssb_bmc_tx_dp") )
				( objectStatus "SNCLS_P2E_SSB_BMC_TX" )
			)
			( netClass "@sapphirecity_baseboard_lib.sapphirecity_baseboard(sch_1):\RGMII_TX\"
				( memberType ( signal ) )
				( spacingCSetRef "@sapphirecity_baseboard_lib.sapphirecity_baseboard(sch_1):\8MIL_SL_10MIL_MS\" )
				( sameNetSpacingCSetRef "@crescent_city_bb_fab1_lib.crescent_city_bb_fab1(sch_1):\20_MIL\" )
				( objectFlag fObjectSpacing )
				( objectFlag fObjectSameNetSpacing )
				( member ( signalRef "@baseboard_fab2_lib.baseboard_fab2(sch_1):rmii_pch_sprngvlle_arb_in") )
				( member ( signalRef "@baseboard_fab2_lib.baseboard_fab2(sch_1):rmii_bmc_pch_sprngvlle_crsdv") )
				( member ( signalRef "@baseboard_fab2_lib.baseboard_fab2(sch_1):rmii_bmc_pch_sprngvlle_crsdv_r") )
				( member ( signalRef "@baseboard_fab2_lib.baseboard_fab2(sch_1):rmii_pch_sprngvlle_arb_out") )
				( member ( signalRef "@baseboard_fab2_lib.baseboard_fab2(sch_1):rmii_bmc_ocp_crsdv") )
				( member ( signalRef "@baseboard_fab2_lib.baseboard_fab2(sch_1):rmii_bmc_ocp_crsdv_r") )
				( member ( signalRef "@baseboard_fab2_lib.baseboard_fab2(sch_1):rmii_pch_sprngvlle_arb_in_r") )
				( member ( signalRef "@baseboard_fab2_lib.baseboard_fab2(sch_1):rmii_pch_sprngvlle_arb_out_r") )
				( member ( signalRef "@baseboard_fab2_lib.baseboard_fab2(sch_1):rmii_bmc_pch_sprngvlle_crsdv_r1") )
				( member ( electricalNetRef "@crescent_city_bb_fab1_lib.crescent_city_bb_fab1(sch_1):rmii_bmc_pch_sprngvlle_crsdv") )
				( member ( electricalNetRef "@crescent_city_bb_fab1_lib.crescent_city_bb_fab1(sch_1):rmii_bmc_pch_sprngvlle_rxer") )
				( member ( electricalNetRef "@crescent_city_bb_fab1_lib.crescent_city_bb_fab1(sch_1):rmii_pch_sprngvlle_arb_in") )
				( member ( electricalNetRef "@crescent_city_bb_fab1_lib.crescent_city_bb_fab1(sch_1):rmii_pch_sprngvlle_arb_out") )
				( objectStatus "SNCLS_RMII" )
			)
			( netClass "@sapphirecity_baseboard_lib.sapphirecity_baseboard(sch_1):\WBG_MISC_PWR\"
				( memberType ( signal ) )
				( objectFlag fObjectSpacing )
				( objectFlag fObjectSameNetSpacing )
				( objectStatus "WBG_MISC_PWR" )
			)
			( netClass "@sapphirecity_baseboard_lib.sapphirecity_baseboard(sch_1):\V_M_BMC_DDR3_CLK\"
				( memberType ( signal ) )
				( spacingCSetRef "@sapphirecity_baseboard_lib.sapphirecity_baseboard(sch_1):\30MIL_VIA_2H+A\" )
				( sameNetSpacingCSetRef "@crescent_city_bb_fab1_lib.crescent_city_bb_fab1(sch_1):\20_MIL\" )
				( objectFlag fObjectSpacing )
				( objectFlag fObjectSameNetSpacing )
				( objectStatus "V_M_BMC_DDR3_CLK" )
			)
			( netClass "@sapphirecity_baseboard_lib.sapphirecity_baseboard(sch_1):\V_M_BMC_DDR3_MA\"
				( memberType ( signal ) )
				( spacingCSetRef "@sapphirecity_baseboard_lib.sapphirecity_baseboard(sch_1):\30MIL_VIA_2H+A\" )
				( sameNetSpacingCSetRef "@crescent_city_bb_fab1_lib.crescent_city_bb_fab1(sch_1):\10MIL\" )
				( objectFlag fObjectSpacing )
				( objectFlag fObjectSameNetSpacing )
				( objectStatus "V_M_BMC_DDR3_MA" )
			)
			( netClass "@sapphirecity_baseboard_lib.sapphirecity_baseboard(sch_1):\V_M_BMC_DDR3_DQ\"
				( memberType ( signal ) )
				( spacingCSetRef "@sapphirecity_baseboard_lib.sapphirecity_baseboard(sch_1):\30MIL_VIA_2H+A\" )
				( sameNetSpacingCSetRef "@crescent_city_bb_fab1_lib.crescent_city_bb_fab1(sch_1):\10MIL\" )
				( objectFlag fObjectSpacing )
				( objectFlag fObjectSameNetSpacing )
				( objectStatus "V_M_BMC_DDR3_DQ" )
			)
			( netClass "@sapphirecity_baseboard_lib.sapphirecity_baseboard(sch_1):\V_M_BMC_DDR3_DQS\"
				( memberType ( signal ) )
				( spacingCSetRef "@sapphirecity_baseboard_lib.sapphirecity_baseboard(sch_1):\30MIL_VIA_2H+A\" )
				( sameNetSpacingCSetRef "@crescent_city_bb_fab1_lib.crescent_city_bb_fab1(sch_1):\20_MIL\" )
				( objectFlag fObjectSpacing )
				( objectFlag fObjectSameNetSpacing )
				( objectStatus "V_M_BMC_DDR3_DQS" )
			)
			( netClass "@sapphirecity_baseboard_lib.sapphirecity_baseboard(sch_1):\XDP_CPU_TCK\"
				( memberType ( signal ) )
				( spacingCSetRef "@sapphirecity_baseboard_lib.sapphirecity_baseboard(sch_1):\8MIL_SL_10MIL_MS\" )
				( objectFlag fObjectSpacing )
				( objectFlag fObjectSameNetSpacing )
				( member ( signalRef "@baseboard_fab2_lib.baseboard_fab2(sch_1):xdp_cpu_prdy_n") )
				( member ( signalRef "@baseboard_fab2_lib.baseboard_fab2(sch_1):xdp_cpu_preq_n") )
				( member ( signalRef "@baseboard_fab2_lib.baseboard_fab2(sch_1):xdp_cpu_tdi") )
				( member ( signalRef "@baseboard_fab2_lib.baseboard_fab2(sch_1):xdp_cpu_tdo") )
				( member ( signalRef "@baseboard_fab2_lib.baseboard_fab2(sch_1):xdp_cpu_tms") )
				( member ( signalRef "@baseboard_fab2_lib.baseboard_fab2(sch_1):xdp_cpu_trst_n") )
				( member ( signalRef "@baseboard_fab2_lib.baseboard_fab2(sch_1):xdp_cpu0_tdo") )
				( member ( signalRef "@baseboard_fab2_lib.baseboard_fab2(sch_1):xdp_cpu1_tdo") )
				( member ( signalRef "@baseboard_fab2_lib.baseboard_fab2(sch_1):xdp_obsfn_b0_mbp6_n") )
				( member ( signalRef "@baseboard_fab2_lib.baseboard_fab2(sch_1):xdp_obsfn_b1_mbp7_n") )
				( member ( signalRef "@baseboard_fab2_lib.baseboard_fab2(sch_1):xdp_pch_tck1") )
				( member ( signalRef "@baseboard_fab2_lib.baseboard_fab2(sch_1):xdp_prdy_n") )
				( member ( signalRef "@baseboard_fab2_lib.baseboard_fab2(sch_1):xdp_preq_n") )
				( member ( signalRef "@baseboard_fab2_lib.baseboard_fab2(sch_1):xdp_tdi") )
				( member ( signalRef "@baseboard_fab2_lib.baseboard_fab2(sch_1):xdp_tdo") )
				( member ( signalRef "@baseboard_fab2_lib.baseboard_fab2(sch_1):xdp_tms") )
				( member ( signalRef "@baseboard_fab2_lib.baseboard_fab2(sch_1):xdp_trst_n") )
				( member ( signalRef "@baseboard_fab2_lib.baseboard_fab2(sch_1):xdp_cpu_obsfn_b0_mbp6_n") )
				( member ( signalRef "@baseboard_fab2_lib.baseboard_fab2(sch_1):xdp_cpu_obsfn_b1_mbp7_n") )
				( member ( signalRef "@baseboard_fab2_lib.baseboard_fab2(sch_1):xdp_cpu_gtl_tck_r2") )
				( member ( signalRef "@baseboard_fab2_lib.baseboard_fab2(sch_1):xdp_cpu_mbp0_n") )
				( member ( signalRef "@baseboard_fab2_lib.baseboard_fab2(sch_1):xdp_cpu_mbp1_n") )
				( member ( signalRef "@baseboard_fab2_lib.baseboard_fab2(sch_1):xdp_cpu_pwr_debug_n") )
				( member ( signalRef "@baseboard_fab2_lib.baseboard_fab2(sch_1):xdp_itp_pmode") )
				( member ( signalRef "@baseboard_fab2_lib.baseboard_fab2(sch_1):xdp_present_n") )
				( member ( signalRef "@baseboard_fab2_lib.baseboard_fab2(sch_1):xdp_pwrgd_rst_n") )
				( member ( signalRef "@baseboard_fab2_lib.baseboard_fab2(sch_1):xdp_rst_co_n") )
				( member ( signalRef "@baseboard_fab2_lib.baseboard_fab2(sch_1):xdp_syspwrok") )
				( member ( signalRef "@baseboard_fab2_lib.baseboard_fab2(sch_1):xdp_cpu1_tdi") )
				( member ( signalRef "@baseboard_fab2_lib.baseboard_fab2(sch_1):xdp_cpu_tck_buf") )
				( member ( signalRef "@baseboard_fab2_lib.baseboard_fab2(sch_1):xdp_pch_pwr_debug_n") )
				( member ( signalRef "@baseboard_fab2_lib.baseboard_fab2(sch_1):xdp_cpu_tck0") )
				( member ( signalRef "@baseboard_fab2_lib.baseboard_fab2(sch_1):xdp_pch_cpu_tck0") )
				( member ( electricalNetRef "@crescent_city_bb_fab1_lib.crescent_city_bb_fab1(sch_1):xdp_cpu_prdy_n") )
				( member ( electricalNetRef "@crescent_city_bb_fab1_lib.crescent_city_bb_fab1(sch_1):xdp_cpu_preq_n") )
				( member ( electricalNetRef "@crescent_city_bb_fab1_lib.crescent_city_bb_fab1(sch_1):xdp_cpu_tck0") )
				( member ( electricalNetRef "@crescent_city_bb_fab1_lib.crescent_city_bb_fab1(sch_1):xdp_cpu_tdi") )
				( member ( electricalNetRef "@crescent_city_bb_fab1_lib.crescent_city_bb_fab1(sch_1):xdp_cpu_tms") )
				( member ( electricalNetRef "@crescent_city_bb_fab1_lib.crescent_city_bb_fab1(sch_1):xdp_cpu_trst_n") )
				( member ( electricalNetRef "@crescent_city_bb_fab1_lib.crescent_city_bb_fab1(sch_1):xdp_cpu1_tdi") )
				( member ( electricalNetRef "@crescent_city_bb_fab1_lib.crescent_city_bb_fab1(sch_1):xdp_obsfn_b0_mbp6_n") )
				( member ( electricalNetRef "@crescent_city_bb_fab1_lib.crescent_city_bb_fab1(sch_1):xdp_obsfn_b1_mbp7_n") )
				( member ( electricalNetRef "@crescent_city_bb_fab1_lib.crescent_city_bb_fab1(sch_1):xdp_rsmrst_n") )
				( objectStatus "SNCLS_XDP_DCI" )
			)
			( netClass "@sapphirecity_baseboard_lib.sapphirecity_baseboard(sch_1):\SATA_RCOMP\"
				( memberType ( signal ) )
				( spacingCSetRef "@sapphirecity_baseboard_lib.sapphirecity_baseboard(sch_1):\30MIL\" )
				( objectFlag fObjectSpacing )
				( objectFlag fObjectSameNetSpacing )
				( objectStatus "SATA_RCOMP" )
			)
			( netClass "@sapphirecity_baseboard_lib.sapphirecity_baseboard(sch_1):\RCOMP\"
				( memberType ( signal ) )
				( spacingCSetRef "@sapphirecity_baseboard_lib.sapphirecity_baseboard(sch_1):\12_MIL\" )
				( objectFlag fObjectSpacing )
				( objectFlag fObjectSameNetSpacing )
				( objectStatus "RCOMP" )
			)
			( netClass "@sapphirecity_baseboard_lib.sapphirecity_baseboard(sch_1):\V_BMC_CONTROL\"
				( memberType ( signal ) )
				( spacingCSetRef "@sapphirecity_baseboard_lib.sapphirecity_baseboard(sch_1):\8MIL\" )
				( sameNetSpacingCSetRef "@crescent_city_bb_fab1_lib.crescent_city_bb_fab1(sch_1):\20_MIL\" )
				( objectFlag fObjectSpacing )
				( objectFlag fObjectSameNetSpacing )
				( objectStatus "V_BMC_CONTROL" )
			)
			( netClass "@sapphirecity_baseboard_lib.sapphirecity_baseboard(sch_1):\EV_CPU_NOA\"
				( memberType ( signal ) )
				( spacingCSetRef "@sapphirecity_baseboard_lib.sapphirecity_baseboard(sch_1):\3H\" )
				( sameNetSpacingCSetRef "@crescent_city_bb_fab1_lib.crescent_city_bb_fab1(sch_1):\18.5_MIL\" )
				( objectFlag fObjectSpacing )
				( objectFlag fObjectSameNetSpacing )
				( objectStatus "EV_CPU_NOA" )
			)
			( netClass "@sapphirecity_baseboard_lib.sapphirecity_baseboard(sch_1):\A_SIG_SE\"
				( memberType ( signal ) )
				( spacingCSetRef "@sapphirecity_baseboard_lib.sapphirecity_baseboard(sch_1):\8_MILS\" )
				( objectFlag fObjectSpacing )
				( objectFlag fObjectSameNetSpacing )
				( member ( signalRef "@baseboard_fab2_lib.baseboard_fab2(sch_1):a_dacrset") )
				( member ( signalRef "@baseboard_fab2_lib.baseboard_fab2(sch_1):a_usb2vres") )
				( member ( signalRef "@baseboard_fab2_lib.baseboard_fab2(sch_1):a_1p8_3p3_rcomp") )
				( member ( signalRef "@baseboard_fab2_lib.baseboard_fab2(sch_1):a_rcomp_3p3") )
				( member ( signalRef "@baseboard_fab2_lib.baseboard_fab2(sch_1):a_pvccrtc_ext_cap") )
				( member ( signalRef "@baseboard_fab2_lib.baseboard_fab2(sch_1):a_usb2_comp") )
				( member ( signalRef "@baseboard_fab2_lib.baseboard_fab2(sch_1):a_cpu0_upi2_rbias") )
				( member ( signalRef "@baseboard_fab2_lib.baseboard_fab2(sch_1):a_cpu0_upi01_rbias") )
				( member ( signalRef "@baseboard_fab2_lib.baseboard_fab2(sch_1):a_cpu0_mcp01_rbias") )
				( member ( signalRef "@baseboard_fab2_lib.baseboard_fab2(sch_1):a_cpu0_pe3_rbias") )
				( member ( signalRef "@baseboard_fab2_lib.baseboard_fab2(sch_1):a_cpu0_pe012_rbias") )
				( member ( signalRef "@baseboard_fab2_lib.baseboard_fab2(sch_1):a_cpu1_upi2_rbias") )
				( member ( signalRef "@baseboard_fab2_lib.baseboard_fab2(sch_1):a_cpu1_upi01_rbias") )
				( member ( signalRef "@baseboard_fab2_lib.baseboard_fab2(sch_1):a_cpu1_mcp01_rbias") )
				( member ( signalRef "@baseboard_fab2_lib.baseboard_fab2(sch_1):a_cpu1_pe3_rbias") )
				( member ( signalRef "@baseboard_fab2_lib.baseboard_fab2(sch_1):a_cpu1_pe012_rbias") )
				( member ( signalRef "@baseboard_fab2_lib.baseboard_fab2(sch_1):a_kr0_rbias") )
				( member ( signalRef "@baseboard_fab2_lib.baseboard_fab2(sch_1):a_kr1_rbias") )
				( member ( signalRef "@baseboard_fab2_lib.baseboard_fab2(sch_1):a_pch_xclk_biasref") )
				( member ( signalRef "@baseboard_fab2_lib.baseboard_fab2(sch_1):a_pcieup_rcomp_n") )
				( member ( signalRef "@baseboard_fab2_lib.baseboard_fab2(sch_1):a_pcieup_rcomp_p") )
				( member ( signalRef "@baseboard_fab2_lib.baseboard_fab2(sch_1):a_pcie_rcomp_n") )
				( member ( signalRef "@baseboard_fab2_lib.baseboard_fab2(sch_1):a_pcie_rcomp_p") )
				( member ( signalRef "@baseboard_fab2_lib.baseboard_fab2(sch_1):a_adm1085_cext") )
				( member ( signalRef "@baseboard_fab2_lib.baseboard_fab2(sch_1):a_cbot") )
				( member ( signalRef "@baseboard_fab2_lib.baseboard_fab2(sch_1):a_ctop") )
				( member ( signalRef "@baseboard_fab2_lib.baseboard_fab2(sch_1):a_hsc_iset") )
				( member ( signalRef "@baseboard_fab2_lib.baseboard_fab2(sch_1):a_hsc_iset_s") )
				( member ( signalRef "@baseboard_fab2_lib.baseboard_fab2(sch_1):a_hsc_iset_s2") )
				( member ( signalRef "@baseboard_fab2_lib.baseboard_fab2(sch_1):a_hsc_istart") )
				( member ( signalRef "@baseboard_fab2_lib.baseboard_fab2(sch_1):a_hsc_pset") )
				( member ( signalRef "@baseboard_fab2_lib.baseboard_fab2(sch_1):a_hsc_vcap") )
				( member ( signalRef "@baseboard_fab2_lib.baseboard_fab2(sch_1):a_hsc_inap") )
				( member ( signalRef "@baseboard_fab2_lib.baseboard_fab2(sch_1):a_usb2_vbus") )
				( member ( electricalNetRef "@crescent_city_bb_fab1_lib.crescent_city_bb_fab1(sch_1):a_cbot") )
				( objectStatus "SNCLS_A_SIG_SE" )
			)
			( netClass "@sapphirecity_baseboard_lib.sapphirecity_baseboard(sch_1):\XTAL\"
				( memberType ( signal ) )
				( spacingCSetRef "@crescent_city_bb_fab1_lib.crescent_city_bb_fab1(sch_1):\45\" )
				( sameNetSpacingCSetRef "@crescent_city_bb_fab1_lib.crescent_city_bb_fab1(sch_1):\15_MILS\" )
				( objectFlag fObjectSpacing )
				( objectFlag fObjectSameNetSpacing )
				( member ( signalRef "@baseboard_fab2_lib.baseboard_fab2(sch_1):xtal_ck_mng_in") )
				( member ( signalRef "@baseboard_fab2_lib.baseboard_fab2(sch_1):xtal_ck_mng_out") )
				( member ( signalRef "@baseboard_fab2_lib.baseboard_fab2(sch_1):xtal_kr_25m_in") )
				( member ( signalRef "@baseboard_fab2_lib.baseboard_fab2(sch_1):xtal_kr_25m_out") )
				( member ( signalRef "@baseboard_fab2_lib.baseboard_fab2(sch_1):xtal_24mhz_in_r") )
				( member ( signalRef "@baseboard_fab2_lib.baseboard_fab2(sch_1):xtal_24mhz_out_r") )
				( member ( signalRef "@baseboard_fab2_lib.baseboard_fab2(sch_1):xtal_24mhz_pi7c9x1172_in") )
				( member ( signalRef "@baseboard_fab2_lib.baseboard_fab2(sch_1):xtal_24mhz_pi7c9x1172_out") )
				( member ( signalRef "@baseboard_fab2_lib.baseboard_fab2(sch_1):xtal_pch_48m_in") )
				( member ( signalRef "@baseboard_fab2_lib.baseboard_fab2(sch_1):xtal_pch_48m_out") )
				( member ( signalRef "@baseboard_fab2_lib.baseboard_fab2(sch_1):xtal_25mhz_in") )
				( member ( signalRef "@baseboard_fab2_lib.baseboard_fab2(sch_1):xtal_25mhz_in_r") )
				( member ( signalRef "@baseboard_fab2_lib.baseboard_fab2(sch_1):xtal_25mhz_out") )
				( member ( signalRef "@baseboard_fab2_lib.baseboard_fab2(sch_1):xtal_25mhz_out_r") )
				( member ( signalRef "@baseboard_fab2_lib.baseboard_fab2(sch_1):xtal_33k_rtc1") )
				( member ( signalRef "@baseboard_fab2_lib.baseboard_fab2(sch_1):xtal_33k_rtc2") )
				( member ( electricalNetRef "@crescent_city_bb_fab1_lib.crescent_city_bb_fab1(sch_1):xtal_pch_48m_in") )
				( member ( electricalNetRef "@crescent_city_bb_fab1_lib.crescent_city_bb_fab1(sch_1):xtal_24mhz_in_r") )
				( member ( electricalNetRef "@crescent_city_bb_fab1_lib.crescent_city_bb_fab1(sch_1):xtal_24mhz_pi7c9x1172_out") )
				( member ( electricalNetRef "@crescent_city_bb_fab1_lib.crescent_city_bb_fab1(sch_1):xtal_25mhz_in_r") )
				( member ( electricalNetRef "@crescent_city_bb_fab1_lib.crescent_city_bb_fab1(sch_1):xtal_25mhz_out_r") )
				( member ( electricalNetRef "@crescent_city_bb_fab1_lib.crescent_city_bb_fab1(sch_1):xtal_33k_rtc1") )
				( objectStatus "SNCLS_XTAL" )
			)
			( netClass "@sapphirecity_baseboard_lib.sapphirecity_baseboard(sch_1):\XPD_PREQ_PRDY\"
				( memberType ( signal ) )
				( spacingCSetRef "@sapphirecity_baseboard_lib.sapphirecity_baseboard(sch_1):\2.5H_SL_3H_MS\" )
				( objectFlag fObjectSpacing )
				( objectFlag fObjectSameNetSpacing )
				( objectStatus "XPD_PREQ_PRDY" )
			)
			( netClass "@sapphirecity_baseboard_lib.sapphirecity_baseboard(sch_1):\VR_PVDDQ_GH\"
				( memberType ( signal ) )
				( objectFlag fObjectSpacing )
				( objectFlag fObjectSameNetSpacing )
				( objectStatus "VR_PVDDQ_GH" )
			)
			( netClass "@sapphirecity_baseboard_lib.sapphirecity_baseboard(sch_1):\VR_PVDDQ_EF\"
				( memberType ( signal ) )
				( objectFlag fObjectSpacing )
				( objectFlag fObjectSameNetSpacing )
				( objectStatus "VR_PVDDQ_EF" )
			)
			( netClass "@sapphirecity_baseboard_lib.sapphirecity_baseboard(sch_1):\VR_P3V3\"
				( memberType ( signal ) )
				( objectFlag fObjectSpacing )
				( objectFlag fObjectSameNetSpacing )
				( objectStatus "VR_P3V3" )
			)
			( netClass "@sapphirecity_baseboard_lib.sapphirecity_baseboard(sch_1):\VR_PVCCIO\"
				( memberType ( signal ) )
				( objectFlag fObjectSpacing )
				( objectFlag fObjectSameNetSpacing )
				( objectStatus "VR_PVCCIO" )
			)
			( netClass "@sapphirecity_baseboard_lib.sapphirecity_baseboard(sch_1):\VR_P1V5_AUX\"
				( memberType ( signal ) )
				( objectFlag fObjectSpacing )
				( objectFlag fObjectSameNetSpacing )
				( objectStatus "VR_P1V5_AUX" )
			)
			( netClass "@sapphirecity_baseboard_lib.sapphirecity_baseboard(sch_1):\VR_P1V8_AUX\"
				( memberType ( signal ) )
				( objectFlag fObjectSpacing )
				( objectFlag fObjectSameNetSpacing )
				( objectStatus "VR_P1V8_AUX" )
			)
			( netClass "@sapphirecity_baseboard_lib.sapphirecity_baseboard(sch_1):\VR_P1V0_AUX\"
				( memberType ( signal ) )
				( objectFlag fObjectSpacing )
				( objectFlag fObjectSameNetSpacing )
				( objectStatus "VR_P1V0_AUX" )
			)
			( netClass "@sapphirecity_baseboard_lib.sapphirecity_baseboard(sch_1):\VR_P5V_AUX\"
				( memberType ( signal ) )
				( objectFlag fObjectSpacing )
				( objectFlag fObjectSameNetSpacing )
				( objectStatus "VR_P5V_AUX" )
			)
			( netClass "@sapphirecity_baseboard_lib.sapphirecity_baseboard(sch_1):\VR_P5V\"
				( memberType ( signal ) )
				( objectFlag fObjectSpacing )
				( objectFlag fObjectSameNetSpacing )
				( objectStatus "VR_P5V" )
			)
			( netClass "@sapphirecity_baseboard_lib.sapphirecity_baseboard(sch_1):\VR_P1V5_PCH\"
				( memberType ( signal ) )
				( objectFlag fObjectSpacing )
				( objectFlag fObjectSameNetSpacing )
				( objectStatus "VR_P1V5_PCH" )
			)
			( netClass "@sapphirecity_baseboard_lib.sapphirecity_baseboard(sch_1):\VR_P1V05_STBY_PCH\"
				( memberType ( signal ) )
				( objectFlag fObjectSpacing )
				( objectFlag fObjectSameNetSpacing )
				( objectStatus "VR_P1V05_STBY_PCH" )
			)
			( netClass "@sapphirecity_baseboard_lib.sapphirecity_baseboard(sch_1):\VR_P1V05_PCH\"
				( memberType ( signal ) )
				( objectFlag fObjectSpacing )
				( objectFlag fObjectSameNetSpacing )
				( objectStatus "VR_P1V05_PCH" )
			)
			( netClass "@sapphirecity_baseboard_lib.sapphirecity_baseboard(sch_1):\VR_P3V3_AUX\"
				( memberType ( signal ) )
				( objectFlag fObjectSpacing )
				( objectFlag fObjectSameNetSpacing )
				( objectStatus "VR_P3V3_AUX" )
			)
			( netClass "@sapphirecity_baseboard_lib.sapphirecity_baseboard(sch_1):\VR_PVTT_GH\"
				( memberType ( signal ) )
				( objectFlag fObjectSpacing )
				( objectFlag fObjectSameNetSpacing )
				( objectStatus "VR_PVTT_GH" )
			)
			( netClass "@sapphirecity_baseboard_lib.sapphirecity_baseboard(sch_1):\VR_PVTT_EF\"
				( memberType ( signal ) )
				( objectFlag fObjectSpacing )
				( objectFlag fObjectSameNetSpacing )
				( objectStatus "VR_PVTT_EF" )
			)
			( netClass "@sapphirecity_baseboard_lib.sapphirecity_baseboard(sch_1):\VR_PVTT_CD\"
				( memberType ( signal ) )
				( objectFlag fObjectSpacing )
				( objectFlag fObjectSameNetSpacing )
				( objectStatus "VR_PVTT_CD" )
			)
			( netClass "@sapphirecity_baseboard_lib.sapphirecity_baseboard(sch_1):\VR_PVTT_AB\"
				( memberType ( signal ) )
				( objectFlag fObjectSpacing )
				( objectFlag fObjectSameNetSpacing )
				( objectStatus "VR_PVTT_AB" )
			)
			( netClass "@sapphirecity_baseboard_lib.sapphirecity_baseboard(sch_1):\VR_PVCCIN_CPU1\"
				( memberType ( signal ) )
				( objectFlag fObjectSpacing )
				( objectFlag fObjectSameNetSpacing )
				( objectStatus "VR_PVCCIN_CPU1" )
			)
			( netClass "@sapphirecity_baseboard_lib.sapphirecity_baseboard(sch_1):\SVID\"
				( memberType ( signal ) )
				( spacingCSetRef "@crescent_city_bb_fab1_lib.crescent_city_bb_fab1(sch_1):\12MILS_US_&_15MILS_SL\" )
				( objectFlag fObjectSpacing )
				( objectFlag fObjectSameNetSpacing )
				( member ( netGroupRef "@crescent_city_bb_fab1_lib.crescent_city_bb_fab1(sch_1):\#SVID_CPU0_0\") )
				( member ( netGroupRef "@crescent_city_bb_fab1_lib.crescent_city_bb_fab1(sch_1):\#SVID_CPU0_1\") )
				( member ( netGroupRef "@crescent_city_bb_fab1_lib.crescent_city_bb_fab1(sch_1):\#SVID_CPU1_0\") )
				( member ( netGroupRef "@crescent_city_bb_fab1_lib.crescent_city_bb_fab1(sch_1):\#SVID_CPU1_1\") )
				( member ( signalRef "@baseboard_fab2_lib.baseboard_fab2(sch_1):svid_alert_pvddq_def") )
				( member ( signalRef "@baseboard_fab2_lib.baseboard_fab2(sch_1):svid_alert_pvddq_ghj") )
				( member ( signalRef "@baseboard_fab2_lib.baseboard_fab2(sch_1):svid_alert_pvddq_klm") )
				( member ( signalRef "@baseboard_fab2_lib.baseboard_fab2(sch_1):svid_clk_pvddq_def") )
				( member ( signalRef "@baseboard_fab2_lib.baseboard_fab2(sch_1):svid_clk_pvddq_ghj") )
				( member ( signalRef "@baseboard_fab2_lib.baseboard_fab2(sch_1):svid_clk_pvddq_klm") )
				( member ( signalRef "@baseboard_fab2_lib.baseboard_fab2(sch_1):svid_vdio_pvddq_def") )
				( member ( signalRef "@baseboard_fab2_lib.baseboard_fab2(sch_1):svid_vdio_pvddq_ghj") )
				( member ( signalRef "@baseboard_fab2_lib.baseboard_fab2(sch_1):svid_vdio_pvddq_klm") )
				( member ( signalRef "@baseboard_fab2_lib.baseboard_fab2(sch_1):svid_alert_pvccio_cpu0") )
				( member ( signalRef "@baseboard_fab2_lib.baseboard_fab2(sch_1):svid_alert_pvccio_cpu1") )
				( member ( signalRef "@baseboard_fab2_lib.baseboard_fab2(sch_1):svid_clk_pvccio_cpu0") )
				( member ( signalRef "@baseboard_fab2_lib.baseboard_fab2(sch_1):svid_clk_pvccio_cpu1") )
				( member ( signalRef "@baseboard_fab2_lib.baseboard_fab2(sch_1):svid_valert_vccin_cpu0") )
				( member ( signalRef "@baseboard_fab2_lib.baseboard_fab2(sch_1):svid_valert_vccin_cpu1") )
				( member ( signalRef "@baseboard_fab2_lib.baseboard_fab2(sch_1):svid_vclk_pvccin_cpu0") )
				( member ( signalRef "@baseboard_fab2_lib.baseboard_fab2(sch_1):svid_vclk_pvccin_cpu1") )
				( member ( signalRef "@baseboard_fab2_lib.baseboard_fab2(sch_1):svid_vdio_pvccin_cpu0") )
				( member ( signalRef "@baseboard_fab2_lib.baseboard_fab2(sch_1):svid_vdio_pvccin_cpu1") )
				( member ( signalRef "@baseboard_fab2_lib.baseboard_fab2(sch_1):svid_vdio_pvccio_cpu0") )
				( member ( signalRef "@baseboard_fab2_lib.baseboard_fab2(sch_1):svid_vdio_pvccio_cpu1") )
				( member ( signalRef "@baseboard_fab2_lib.baseboard_fab2(sch_1):svid_alert_pvddq_abc") )
				( member ( signalRef "@baseboard_fab2_lib.baseboard_fab2(sch_1):svid_alert0_cpu0_n") )
				( member ( signalRef "@baseboard_fab2_lib.baseboard_fab2(sch_1):svid_alert0_cpu0_r_n") )
				( member ( signalRef "@baseboard_fab2_lib.baseboard_fab2(sch_1):svid_alert0_cpu1_n") )
				( member ( signalRef "@baseboard_fab2_lib.baseboard_fab2(sch_1):svid_alert0_cpu1_r_n") )
				( member ( signalRef "@baseboard_fab2_lib.baseboard_fab2(sch_1):svid_alert1_cpu0_n") )
				( member ( signalRef "@baseboard_fab2_lib.baseboard_fab2(sch_1):svid_alert1_cpu0_r_n") )
				( member ( signalRef "@baseboard_fab2_lib.baseboard_fab2(sch_1):svid_alert1_cpu1_n") )
				( member ( signalRef "@baseboard_fab2_lib.baseboard_fab2(sch_1):svid_alert1_cpu1_r_n") )
				( member ( signalRef "@baseboard_fab2_lib.baseboard_fab2(sch_1):svid_clk_pvddq_abc") )
				( member ( signalRef "@baseboard_fab2_lib.baseboard_fab2(sch_1):svid_clk0_cpu0") )
				( member ( signalRef "@baseboard_fab2_lib.baseboard_fab2(sch_1):svid_clk0_cpu0_r") )
				( member ( signalRef "@baseboard_fab2_lib.baseboard_fab2(sch_1):svid_clk0_cpu1") )
				( member ( signalRef "@baseboard_fab2_lib.baseboard_fab2(sch_1):svid_clk0_cpu1_r") )
				( member ( signalRef "@baseboard_fab2_lib.baseboard_fab2(sch_1):svid_clk1_cpu0") )
				( member ( signalRef "@baseboard_fab2_lib.baseboard_fab2(sch_1):svid_clk1_cpu0_r") )
				( member ( signalRef "@baseboard_fab2_lib.baseboard_fab2(sch_1):svid_clk1_cpu1") )
				( member ( signalRef "@baseboard_fab2_lib.baseboard_fab2(sch_1):svid_clk1_cpu1_r") )
				( member ( signalRef "@baseboard_fab2_lib.baseboard_fab2(sch_1):svid_dio0_cpu0") )
				( member ( signalRef "@baseboard_fab2_lib.baseboard_fab2(sch_1):svid_dio0_cpu0_r") )
				( member ( signalRef "@baseboard_fab2_lib.baseboard_fab2(sch_1):svid_dio0_cpu1") )
				( member ( signalRef "@baseboard_fab2_lib.baseboard_fab2(sch_1):svid_dio0_cpu1_r") )
				( member ( signalRef "@baseboard_fab2_lib.baseboard_fab2(sch_1):svid_dio1_cpu0") )
				( member ( signalRef "@baseboard_fab2_lib.baseboard_fab2(sch_1):svid_dio1_cpu0_r") )
				( member ( signalRef "@baseboard_fab2_lib.baseboard_fab2(sch_1):svid_dio1_cpu1") )
				( member ( signalRef "@baseboard_fab2_lib.baseboard_fab2(sch_1):svid_dio1_cpu1_r") )
				( member ( signalRef "@baseboard_fab2_lib.baseboard_fab2(sch_1):svid_vdio_pvddq_abc") )
				( objectStatus "SNCLS_SVID" )
			)
			( netClass "@sapphirecity_baseboard_lib.sapphirecity_baseboard(sch_1):\SPI\"
				( memberType ( signal ) )
				( spacingCSetRef "@sapphirecity_baseboard_lib.sapphirecity_baseboard(sch_1):\8MIL_SL_10MIL_MS\" )
				( sameNetSpacingCSetRef "@crescent_city_bb_fab1_lib.crescent_city_bb_fab1(sch_1):\2.5H_US_AND_2H_SL\" )
				( objectFlag fObjectSpacing )
				( objectFlag fObjectSameNetSpacing )
				( member ( signalRef "@baseboard_fab2_lib.baseboard_fab2(sch_1):spi_bios_socket_io3") )
				( member ( signalRef "@baseboard_fab2_lib.baseboard_fab2(sch_1):spi_bmc_bt_clk") )
				( member ( signalRef "@baseboard_fab2_lib.baseboard_fab2(sch_1):spi_bmc_bt_clk_r") )
				( member ( signalRef "@baseboard_fab2_lib.baseboard_fab2(sch_1):spi_bmc_bt_cs_n") )
				( member ( signalRef "@baseboard_fab2_lib.baseboard_fab2(sch_1):spi_bmc_bt_cs_r_n") )
				( member ( signalRef "@baseboard_fab2_lib.baseboard_fab2(sch_1):spi_bmc_bt_di") )
				( member ( signalRef "@baseboard_fab2_lib.baseboard_fab2(sch_1):spi_bmc_bt_di_r") )
				( member ( signalRef "@baseboard_fab2_lib.baseboard_fab2(sch_1):spi_bmc_bt_do") )
				( member ( signalRef "@baseboard_fab2_lib.baseboard_fab2(sch_1):spi_bmc_bt_do_r") )
				( member ( signalRef "@baseboard_fab2_lib.baseboard_fab2(sch_1):spi_bmc_clk") )
				( member ( signalRef "@baseboard_fab2_lib.baseboard_fab2(sch_1):spi_bmc_cs0_n") )
				( member ( signalRef "@baseboard_fab2_lib.baseboard_fab2(sch_1):spi_bmc_di") )
				( member ( signalRef "@baseboard_fab2_lib.baseboard_fab2(sch_1):spi_bmc_do") )
				( member ( signalRef "@baseboard_fab2_lib.baseboard_fab2(sch_1):spi_clk_r0") )
				( member ( signalRef "@baseboard_fab2_lib.baseboard_fab2(sch_1):spi_clk_r1") )
				( member ( signalRef "@baseboard_fab2_lib.baseboard_fab2(sch_1):spi_cs0_primary_n") )
				( member ( signalRef "@baseboard_fab2_lib.baseboard_fab2(sch_1):spi_cs0_primary_r_n") )
				( member ( signalRef "@baseboard_fab2_lib.baseboard_fab2(sch_1):spi_cs0_secondary_n") )
				( member ( signalRef "@baseboard_fab2_lib.baseboard_fab2(sch_1):spi_cs0_secondary_r_n") )
				( member ( signalRef "@baseboard_fab2_lib.baseboard_fab2(sch_1):spi_miso_r0") )
				( member ( signalRef "@baseboard_fab2_lib.baseboard_fab2(sch_1):spi_miso_r1") )
				( member ( signalRef "@baseboard_fab2_lib.baseboard_fab2(sch_1):spi_pch_clk") )
				( member ( signalRef "@baseboard_fab2_lib.baseboard_fab2(sch_1):spi_pch_cs0_r_n") )
				( member ( signalRef "@baseboard_fab2_lib.baseboard_fab2(sch_1):spi_pch_io3_r1") )
				( member ( signalRef "@baseboard_fab2_lib.baseboard_fab2(sch_1):spi_pch_io3") )
				( member ( signalRef "@baseboard_fab2_lib.baseboard_fab2(sch_1):spi_pch_miso_r") )
				( member ( signalRef "@baseboard_fab2_lib.baseboard_fab2(sch_1):spi_pch_miso") )
				( member ( signalRef "@baseboard_fab2_lib.baseboard_fab2(sch_1):spi_pch_tpm_clk_r") )
				( member ( signalRef "@baseboard_fab2_lib.baseboard_fab2(sch_1):spi_pch_tpm_cs_r_n") )
				( member ( signalRef "@baseboard_fab2_lib.baseboard_fab2(sch_1):spi_pch_tpm_miso_r") )
				( member ( signalRef "@baseboard_fab2_lib.baseboard_fab2(sch_1):spi_switch_clk") )
				( member ( signalRef "@baseboard_fab2_lib.baseboard_fab2(sch_1):spi_switch_cs0_n") )
				( member ( signalRef "@baseboard_fab2_lib.baseboard_fab2(sch_1):spi_switch_miso") )
				( member ( signalRef "@baseboard_fab2_lib.baseboard_fab2(sch_1):spi_switch_mosi") )
				( member ( signalRef "@baseboard_fab2_lib.baseboard_fab2(sch_1):spi_pch_tpm_cs_n") )
				( member ( signalRef "@baseboard_fab2_lib.baseboard_fab2(sch_1):spi_bios_socket_io2") )
				( member ( signalRef "@baseboard_fab2_lib.baseboard_fab2(sch_1):spi_pch_io2_r1") )
				( member ( signalRef "@baseboard_fab2_lib.baseboard_fab2(sch_1):spi_pch_io2") )
				( member ( signalRef "@baseboard_fab2_lib.baseboard_fab2(sch_1):spi_pch_mosi") )
				( member ( signalRef "@baseboard_fab2_lib.baseboard_fab2(sch_1):spi_pch_mosi_r") )
				( member ( signalRef "@baseboard_fab2_lib.baseboard_fab2(sch_1):spi_pch_tpm_mosi_r") )
				( member ( signalRef "@baseboard_fab2_lib.baseboard_fab2(sch_1):spi_nic_cs_n") )
				( member ( signalRef "@baseboard_fab2_lib.baseboard_fab2(sch_1):spi_nic_cs_r_n") )
				( member ( signalRef "@baseboard_fab2_lib.baseboard_fab2(sch_1):spi_nic_miso") )
				( member ( signalRef "@baseboard_fab2_lib.baseboard_fab2(sch_1):spi_nic_miso_r") )
				( member ( signalRef "@baseboard_fab2_lib.baseboard_fab2(sch_1):spi_nic_mosi") )
				( member ( signalRef "@baseboard_fab2_lib.baseboard_fab2(sch_1):spi_nic_mosi_r") )
				( member ( signalRef "@baseboard_fab2_lib.baseboard_fab2(sch_1):spi_nic_sclk") )
				( member ( signalRef "@baseboard_fab2_lib.baseboard_fab2(sch_1):spi_nic_sclk_r") )
				( member ( signalRef "@baseboard_fab2_lib.baseboard_fab2(sch_1):pu_bios_spi_wp0_n") )
				( member ( signalRef "@baseboard_fab2_lib.baseboard_fab2(sch_1):xdp_debug_consent_n") )
				( member ( signalRef "@baseboard_fab2_lib.baseboard_fab2(sch_1):spi_pch_cs0_n") )
				( member ( electricalNetRef "@crescent_city_bb_fab1_lib.crescent_city_bb_fab1(sch_1):pu_bios_spi_wp0_n") )
				( member ( electricalNetRef "@crescent_city_bb_fab1_lib.crescent_city_bb_fab1(sch_1):spi_miso_r0") )
				( member ( electricalNetRef "@crescent_city_bb_fab1_lib.crescent_city_bb_fab1(sch_1):spi_nic_cs_n") )
				( member ( electricalNetRef "@crescent_city_bb_fab1_lib.crescent_city_bb_fab1(sch_1):spi_nic_miso") )
				( member ( electricalNetRef "@crescent_city_bb_fab1_lib.crescent_city_bb_fab1(sch_1):spi_nic_mosi") )
				( member ( electricalNetRef "@crescent_city_bb_fab1_lib.crescent_city_bb_fab1(sch_1):spi_nic_sclk") )
				( member ( electricalNetRef "@crescent_city_bb_fab1_lib.crescent_city_bb_fab1(sch_1):xdp_debug_consent_n") )
				( member ( electricalNetRef "@baseboard_fab2_lib.baseboard_fab2(sch_1):spi_pch_cs0_n") )
				( objectStatus "SNCLS_SPI" )
			)
			( netClass "@sapphirecity_baseboard_lib.sapphirecity_baseboard(sch_1):\SGPIO_SATA\"
				( memberType ( signal ) )
				( spacingCSetRef "@sapphirecity_baseboard_lib.sapphirecity_baseboard(sch_1):\8MIL_SL_7MIL_MS\" )
				( objectFlag fObjectSpacing )
				( objectFlag fObjectSameNetSpacing )
				( member ( signalRef "@baseboard_fab2_lib.baseboard_fab2(sch_1):sgpio_pch_sata_clock") )
				( member ( signalRef "@baseboard_fab2_lib.baseboard_fab2(sch_1):sgpio_pch_sata_clock_r") )
				( member ( signalRef "@baseboard_fab2_lib.baseboard_fab2(sch_1):sgpio_pch_sata_dout0") )
				( member ( signalRef "@baseboard_fab2_lib.baseboard_fab2(sch_1):sgpio_pch_sata_dout0_r") )
				( member ( signalRef "@baseboard_fab2_lib.baseboard_fab2(sch_1):sgpio_pch_sata_load") )
				( member ( signalRef "@baseboard_fab2_lib.baseboard_fab2(sch_1):sgpio_pch_sata_load_r") )
				( member ( electricalNetRef "@crescent_city_bb_fab1_lib.crescent_city_bb_fab1(sch_1):sgpio_pch_sata_clock") )
				( member ( electricalNetRef "@crescent_city_bb_fab1_lib.crescent_city_bb_fab1(sch_1):sgpio_pch_sata_dout0") )
				( member ( electricalNetRef "@crescent_city_bb_fab1_lib.crescent_city_bb_fab1(sch_1):sgpio_pch_sata_load") )
				( objectStatus "SNCLS_SGPIO_SATA" )
			)
			( netClass "@sapphirecity_baseboard_lib.sapphirecity_baseboard(sch_1):\SGPIO\"
				( memberType ( signal ) )
				( spacingCSetRef "@sapphirecity_baseboard_lib.sapphirecity_baseboard(sch_1):\8MIL_SL_7MIL_MS\" )
				( sameNetSpacingCSetRef "@crescent_city_bb_fab1_lib.crescent_city_bb_fab1(sch_1):\2.5H_US_AND_2H_SL\" )
				( objectFlag fObjectSpacing )
				( objectFlag fObjectSameNetSpacing )
				( member ( signalRef "@baseboard_fab2_lib.baseboard_fab2(sch_1):sgpio_bmc_clk") )
				( member ( signalRef "@baseboard_fab2_lib.baseboard_fab2(sch_1):sgpio_bmc_clk_r") )
				( member ( signalRef "@baseboard_fab2_lib.baseboard_fab2(sch_1):sgpio_bmc_din") )
				( member ( signalRef "@baseboard_fab2_lib.baseboard_fab2(sch_1):sgpio_bmc_din_r") )
				( member ( signalRef "@baseboard_fab2_lib.baseboard_fab2(sch_1):sgpio_bmc_dout") )
				( member ( signalRef "@baseboard_fab2_lib.baseboard_fab2(sch_1):sgpio_bmc_dout_r") )
				( member ( signalRef "@baseboard_fab2_lib.baseboard_fab2(sch_1):sgpio_bmc_ld_n") )
				( member ( signalRef "@baseboard_fab2_lib.baseboard_fab2(sch_1):sgpio_bmc_ld_r_n") )
				( member ( electricalNetRef "@crescent_city_bb_fab1_lib.crescent_city_bb_fab1(sch_1):sgpio_bmc_clk") )
				( member ( electricalNetRef "@crescent_city_bb_fab1_lib.crescent_city_bb_fab1(sch_1):sgpio_bmc_din") )
				( member ( electricalNetRef "@crescent_city_bb_fab1_lib.crescent_city_bb_fab1(sch_1):sgpio_bmc_dout") )
				( member ( electricalNetRef "@crescent_city_bb_fab1_lib.crescent_city_bb_fab1(sch_1):sgpio_bmc_ld_n") )
				( objectStatus "SNCLS_SGPIO_BMC" )
			)
			( netClass "@sapphirecity_baseboard_lib.sapphirecity_baseboard(sch_1):\RBIAS\"
				( memberType ( signal ) )
				( spacingCSetRef "@sapphirecity_baseboard_lib.sapphirecity_baseboard(sch_1):\5H_SL_7H_MS_VIA_3H_A\" )
				( objectFlag fObjectSpacing )
				( objectFlag fObjectSameNetSpacing )
				( objectStatus "RBIAS" )
			)
			( netClass "@sapphirecity_baseboard_lib.sapphirecity_baseboard(sch_1):\NOA\"
				( memberType ( signal ) )
				( spacingCSetRef "@sapphirecity_baseboard_lib.sapphirecity_baseboard(sch_1):\15_MILS\" )
				( sameNetSpacingCSetRef "@crescent_city_bb_fab1_lib.crescent_city_bb_fab1(sch_1):\15_MILS\" )
				( objectFlag fObjectSpacing )
				( objectFlag fObjectSameNetSpacing )
				( objectStatus "NOA" )
			)
			( netClass "@sapphirecity_baseboard_lib.sapphirecity_baseboard(sch_1):\RESET_IRQ_PWRGD\"
				( memberType ( signal ) )
				( spacingCSetRef "@sapphirecity_baseboard_lib.sapphirecity_baseboard(sch_1):\8MIL_SL_10MIL_MS\" )
				( objectFlag fObjectSpacing )
				( objectFlag fObjectSameNetSpacing )
				( member ( signalRef "@baseboard_fab2_lib.baseboard_fab2(sch_1):rst_pcie_pch_perst_n") )
				( member ( signalRef "@baseboard_fab2_lib.baseboard_fab2(sch_1):rst_pltrst_buf_n") )
				( member ( signalRef "@baseboard_fab2_lib.baseboard_fab2(sch_1):rst_pltrst_n") )
				( member ( signalRef "@baseboard_fab2_lib.baseboard_fab2(sch_1):rst_rsmrst_n") )
				( member ( signalRef "@baseboard_fab2_lib.baseboard_fab2(sch_1):rst_rtcrst_n") )
				( member ( signalRef "@baseboard_fab2_lib.baseboard_fab2(sch_1):rst_srtcrst_n") )
				( member ( signalRef "@baseboard_fab2_lib.baseboard_fab2(sch_1):rst_system_btn_n") )
				( member ( signalRef "@baseboard_fab2_lib.baseboard_fab2(sch_1):rst_bmc_sysrst_btn_out_b_n") )
				( member ( signalRef "@baseboard_fab2_lib.baseboard_fab2(sch_1):rst_cd_cpu0_por_n") )
				( member ( signalRef "@baseboard_fab2_lib.baseboard_fab2(sch_1):rst_cd_cpu1_por_n") )
				( member ( signalRef "@baseboard_fab2_lib.baseboard_fab2(sch_1):pwrgd_pvcciomcp_cpu1") )
				( member ( signalRef "@baseboard_fab2_lib.baseboard_fab2(sch_1):rst_rsmrst_dly") )
				( member ( signalRef "@baseboard_fab2_lib.baseboard_fab2(sch_1):pwrgd_p3v3_r1") )
				( member ( signalRef "@baseboard_fab2_lib.baseboard_fab2(sch_1):pwrgd_p5v") )
				( member ( signalRef "@baseboard_fab2_lib.baseboard_fab2(sch_1):pwrgd_p5v_r") )
				( member ( signalRef "@baseboard_fab2_lib.baseboard_fab2(sch_1):pwrgd_p12v_hsc_dly") )
				( member ( signalRef "@baseboard_fab2_lib.baseboard_fab2(sch_1):pwrgd_p12v_hsc_dly_r") )
				( member ( signalRef "@baseboard_fab2_lib.baseboard_fab2(sch_1):irq_bmc_pch_sci_lpc_n") )
				( member ( signalRef "@baseboard_fab2_lib.baseboard_fab2(sch_1):irq_board_bmc_alert_n") )
				( member ( signalRef "@baseboard_fab2_lib.baseboard_fab2(sch_1):irq_hsc_fault_n") )
				( member ( signalRef "@baseboard_fab2_lib.baseboard_fab2(sch_1):irq_mezz_lan_alert_n") )
				( member ( signalRef "@baseboard_fab2_lib.baseboard_fab2(sch_1):irq_pvccio_cpu0_vrhot_n") )
				( member ( signalRef "@baseboard_fab2_lib.baseboard_fab2(sch_1):irq_pvccio_cpu1_vrhot_n") )
				( member ( signalRef "@baseboard_fab2_lib.baseboard_fab2(sch_1):irq_pvnn_pch_vrhot_n") )
				( member ( signalRef "@baseboard_fab2_lib.baseboard_fab2(sch_1):vr_vrrdy_pvccin_cpu0") )
				( member ( signalRef "@baseboard_fab2_lib.baseboard_fab2(sch_1):vr_vrrdy_pvccin_cpu1") )
				( member ( signalRef "@baseboard_fab2_lib.baseboard_fab2(sch_1):pwrgd_pvcciomcp_cpu0") )
				( member ( signalRef "@baseboard_fab2_lib.baseboard_fab2(sch_1):pwrgd_pvnn_pch_r") )
				( member ( signalRef "@baseboard_fab2_lib.baseboard_fab2(sch_1):pwrgd_pvnn_p1v05_pch") )
				( member ( signalRef "@baseboard_fab2_lib.baseboard_fab2(sch_1):pwrgd_pvpp_abc_r") )
				( member ( signalRef "@baseboard_fab2_lib.baseboard_fab2(sch_1):pwrgd_pvpp_def_r") )
				( member ( signalRef "@baseboard_fab2_lib.baseboard_fab2(sch_1):pwrgd_pvpp_ghj_r") )
				( member ( signalRef "@baseboard_fab2_lib.baseboard_fab2(sch_1):pwrgd_pvpp_klm_r") )
				( member ( signalRef "@baseboard_fab2_lib.baseboard_fab2(sch_1):pwrgd_p1v8_pch_stby_r") )
				( member ( signalRef "@baseboard_fab2_lib.baseboard_fab2(sch_1):pwrgd_p1v26_bmc_stby_r") )
				( member ( signalRef "@baseboard_fab2_lib.baseboard_fab2(sch_1):pwrgd_p1v538_bmc_stby_r") )
				( member ( signalRef "@baseboard_fab2_lib.baseboard_fab2(sch_1):pwrgd_p3v3_stby_r") )
				( member ( signalRef "@baseboard_fab2_lib.baseboard_fab2(sch_1):pwrgd_p5v_stby_r") )
				( member ( signalRef "@baseboard_fab2_lib.baseboard_fab2(sch_1):rst_hfi0_cpu0_lvt2_n") )
				( member ( signalRef "@baseboard_fab2_lib.baseboard_fab2(sch_1):rst_hfi1_cpu0_lvt2_n") )
				( member ( signalRef "@baseboard_fab2_lib.baseboard_fab2(sch_1):rst_pcie_midplane_n") )
				( member ( signalRef "@baseboard_fab2_lib.baseboard_fab2(sch_1):rst_pcie_m2_dev_n") )
				( member ( signalRef "@baseboard_fab2_lib.baseboard_fab2(sch_1):irq_cpu0_prochot_g_n") )
				( member ( signalRef "@baseboard_fab2_lib.baseboard_fab2(sch_1):irq_cpu1_prochot_g_n") )
				( member ( signalRef "@baseboard_fab2_lib.baseboard_fab2(sch_1):irq_dimm_save_lvt3") )
				( member ( signalRef "@baseboard_fab2_lib.baseboard_fab2(sch_1):irq_dimm_save_lvt3_n") )
				( member ( signalRef "@baseboard_fab2_lib.baseboard_fab2(sch_1):irq_hfi0_cpu0_lvt2_n") )
				( member ( signalRef "@baseboard_fab2_lib.baseboard_fab2(sch_1):irq_hfi1_cpu0_lvt2_n") )
				( member ( signalRef "@baseboard_fab2_lib.baseboard_fab2(sch_1):irq_lom_alert_n") )
				( member ( signalRef "@baseboard_fab2_lib.baseboard_fab2(sch_1):irq_sml1_pmbus_alert_buf_n") )
				( member ( signalRef "@baseboard_fab2_lib.baseboard_fab2(sch_1):irq_vm_int_n") )
				( member ( signalRef "@baseboard_fab2_lib.baseboard_fab2(sch_1):irq_uv_detect_n") )
				( member ( signalRef "@baseboard_fab2_lib.baseboard_fab2(sch_1):irq_hsc_fault_r_n") )
				( member ( signalRef "@baseboard_fab2_lib.baseboard_fab2(sch_1):irq_oc_detect_n") )
				( member ( signalRef "@baseboard_fab2_lib.baseboard_fab2(sch_1):irq_pvccin_cpu0_vrhot_lvc3_r_n") )
				( member ( signalRef "@baseboard_fab2_lib.baseboard_fab2(sch_1):irq_pvccin_cpu1_vrhot_lvc3_r_n") )
				( member ( signalRef "@baseboard_fab2_lib.baseboard_fab2(sch_1):irq_pvddq_abc_vrhot_lvt3_r_n") )
				( member ( signalRef "@baseboard_fab2_lib.baseboard_fab2(sch_1):irq_pvddq_def_vrhot_lvt3_r_n") )
				( member ( signalRef "@baseboard_fab2_lib.baseboard_fab2(sch_1):irq_pvddq_ghj_vrhot_lvt3_r_n") )
				( member ( signalRef "@baseboard_fab2_lib.baseboard_fab2(sch_1):irq_pvddq_klm_vrhot_lvt3_r_n") )
				( member ( signalRef "@baseboard_fab2_lib.baseboard_fab2(sch_1):irq_sml1_pmbus_alert_r_n") )
				( member ( signalRef "@baseboard_fab2_lib.baseboard_fab2(sch_1):irq_vm_int_r_n") )
				( member ( signalRef "@baseboard_fab2_lib.baseboard_fab2(sch_1):pwrgd_pvccio_cpu0_r") )
				( member ( signalRef "@baseboard_fab2_lib.baseboard_fab2(sch_1):pwrgd_pvsa_cpu0_r") )
				( member ( signalRef "@baseboard_fab2_lib.baseboard_fab2(sch_1):pwrgd_pvsa_cpu1_r") )
				( member ( signalRef "@baseboard_fab2_lib.baseboard_fab2(sch_1):pwrgd_pvtt_abc_cpu0_r") )
				( member ( signalRef "@baseboard_fab2_lib.baseboard_fab2(sch_1):pwrgd_pvtt_def_cpu0_r") )
				( member ( signalRef "@baseboard_fab2_lib.baseboard_fab2(sch_1):pwrgd_pvtt_ghj_cpu1_r") )
				( member ( signalRef "@baseboard_fab2_lib.baseboard_fab2(sch_1):pwrgd_pvtt_klm_cpu1_r") )
				( member ( signalRef "@baseboard_fab2_lib.baseboard_fab2(sch_1):pwrgd_p12v_r") )
				( member ( signalRef "@baseboard_fab2_lib.baseboard_fab2(sch_1):pwrgd_pvtt_cpu0") )
				( member ( signalRef "@baseboard_fab2_lib.baseboard_fab2(sch_1):pwrgd_pvtt_cpu1") )
				( member ( signalRef "@baseboard_fab2_lib.baseboard_fab2(sch_1):fm_adr_complete_abc_n") )
				( member ( signalRef "@baseboard_fab2_lib.baseboard_fab2(sch_1):fm_adr_complete_def_n") )
				( member ( signalRef "@baseboard_fab2_lib.baseboard_fab2(sch_1):fm_adr_complete_ghj_n") )
				( member ( signalRef "@baseboard_fab2_lib.baseboard_fab2(sch_1):fm_adr_complete_klm_n") )
				( member ( signalRef "@baseboard_fab2_lib.baseboard_fab2(sch_1):irq_dimm_save_n") )
				( member ( signalRef "@baseboard_fab2_lib.baseboard_fab2(sch_1):irq_bmc_pch_nmi_stby_r_n") )
				( member ( signalRef "@baseboard_fab2_lib.baseboard_fab2(sch_1):irq_lpc_serirq_r") )
				( member ( signalRef "@baseboard_fab2_lib.baseboard_fab2(sch_1):irq_lvc3_wake_r_n") )
				( member ( signalRef "@baseboard_fab2_lib.baseboard_fab2(sch_1):irq_pirqa_spi_tpm_n") )
				( member ( signalRef "@baseboard_fab2_lib.baseboard_fab2(sch_1):pwrgd_pvpp_abc") )
				( member ( signalRef "@baseboard_fab2_lib.baseboard_fab2(sch_1):pwrgd_pvpp_def") )
				( member ( signalRef "@baseboard_fab2_lib.baseboard_fab2(sch_1):pwrgd_pvpp_ghj") )
				( member ( signalRef "@baseboard_fab2_lib.baseboard_fab2(sch_1):pwrgd_pvpp_klm") )
				( member ( signalRef "@baseboard_fab2_lib.baseboard_fab2(sch_1):pwrgd_pvsa_cpu0") )
				( member ( signalRef "@baseboard_fab2_lib.baseboard_fab2(sch_1):pwrgd_pvsa_cpu1") )
				( member ( signalRef "@baseboard_fab2_lib.baseboard_fab2(sch_1):pwrgd_p1v8_pch_stby") )
				( member ( signalRef "@baseboard_fab2_lib.baseboard_fab2(sch_1):pwrgd_p1v26_bmc_stby") )
				( member ( signalRef "@baseboard_fab2_lib.baseboard_fab2(sch_1):pwrgd_p1v538_bmc_stby") )
				( member ( signalRef "@baseboard_fab2_lib.baseboard_fab2(sch_1):pwrgd_p3v3_stby") )
				( member ( signalRef "@baseboard_fab2_lib.baseboard_fab2(sch_1):pwrgd_p5v_stby") )
				( member ( signalRef "@baseboard_fab2_lib.baseboard_fab2(sch_1):pwrgd_p12v_hsc") )
				( member ( signalRef "@baseboard_fab2_lib.baseboard_fab2(sch_1):pwrgd_sys_pwrok") )
				( member ( signalRef "@baseboard_fab2_lib.baseboard_fab2(sch_1):rst_bmc_ddr3_n") )
				( member ( signalRef "@baseboard_fab2_lib.baseboard_fab2(sch_1):rst_bmc_ddr3_r_n") )
				( member ( signalRef "@baseboard_fab2_lib.baseboard_fab2(sch_1):rst_bmc_lvc3_n") )
				( member ( signalRef "@baseboard_fab2_lib.baseboard_fab2(sch_1):rst_bmc_sysrst_btn_out_n") )
				( member ( signalRef "@baseboard_fab2_lib.baseboard_fab2(sch_1):rst_cpu0_g_n") )
				( member ( signalRef "@baseboard_fab2_lib.baseboard_fab2(sch_1):rst_cpu0_lvc3_n") )
				( member ( signalRef "@baseboard_fab2_lib.baseboard_fab2(sch_1):rst_cpu1_g_n") )
				( member ( signalRef "@baseboard_fab2_lib.baseboard_fab2(sch_1):rst_cpu1_lvc3_n") )
				( member ( signalRef "@baseboard_fab2_lib.baseboard_fab2(sch_1):rst_pcie_riser1_perst_n") )
				( member ( signalRef "@baseboard_fab2_lib.baseboard_fab2(sch_1):rst_pcie_cpu_dev0_n") )
				( member ( signalRef "@baseboard_fab2_lib.baseboard_fab2(sch_1):rst_pcie_cpu_dev0_r_n") )
				( member ( signalRef "@baseboard_fab2_lib.baseboard_fab2(sch_1):rst_pcie_cpu_dev1_n") )
				( member ( signalRef "@baseboard_fab2_lib.baseboard_fab2(sch_1):rst_pcie_cpu_dev1_r_n") )
				( member ( signalRef "@baseboard_fab2_lib.baseboard_fab2(sch_1):rst_pcie_cpu_dev2_n") )
				( member ( signalRef "@baseboard_fab2_lib.baseboard_fab2(sch_1):rst_pcie_cpu_dev2_r_n") )
				( member ( signalRef "@baseboard_fab2_lib.baseboard_fab2(sch_1):rst_pcie_cpu_dev3_n") )
				( member ( signalRef "@baseboard_fab2_lib.baseboard_fab2(sch_1):rst_pcie_cpu_dev3_r_n") )
				( member ( signalRef "@baseboard_fab2_lib.baseboard_fab2(sch_1):irq_dimm_save_r_n") )
				( member ( signalRef "@baseboard_fab2_lib.baseboard_fab2(sch_1):pwrgd_pvccio_cpu0") )
				( member ( signalRef "@baseboard_fab2_lib.baseboard_fab2(sch_1):pwrgd_pvccio_cpu1") )
				( member ( signalRef "@baseboard_fab2_lib.baseboard_fab2(sch_1):pwrgd_pvccio_cpu1_r") )
				( member ( signalRef "@baseboard_fab2_lib.baseboard_fab2(sch_1):vr_p3v3_stby_en") )
				( member ( signalRef "@baseboard_fab2_lib.baseboard_fab2(sch_1):rst_pch_sysrst_btn_out_n") )
				( member ( signalRef "@baseboard_fab2_lib.baseboard_fab2(sch_1):rst_pltrst_top_swap") )
				( member ( signalRef "@baseboard_fab2_lib.baseboard_fab2(sch_1):pwrgd_p1v8mcp_cpu1") )
				( member ( signalRef "@baseboard_fab2_lib.baseboard_fab2(sch_1):vr_pvnn_pch_vren") )
				( member ( signalRef "@baseboard_fab2_lib.baseboard_fab2(sch_1):irq_oob_mgmt_riser_alert_n") )
				( member ( signalRef "@baseboard_fab2_lib.baseboard_fab2(sch_1):irq_pch_nic_alert_n") )
				( member ( signalRef "@baseboard_fab2_lib.baseboard_fab2(sch_1):fm_pvtt_abc_en_r") )
				( member ( signalRef "@baseboard_fab2_lib.baseboard_fab2(sch_1):fm_pvtt_def_en_r") )
				( member ( signalRef "@baseboard_fab2_lib.baseboard_fab2(sch_1):fm_pvtt_ghj_en_r") )
				( member ( signalRef "@baseboard_fab2_lib.baseboard_fab2(sch_1):fm_pvtt_klm_en_r") )
				( member ( signalRef "@baseboard_fab2_lib.baseboard_fab2(sch_1):a_hsc_low_drain") )
				( member ( signalRef "@baseboard_fab2_lib.baseboard_fab2(sch_1):rst_pltrst_sprv_r_n") )
				( member ( signalRef "@baseboard_fab2_lib.baseboard_fab2(sch_1):pwrgd_p12v_main") )
				( member ( signalRef "@baseboard_fab2_lib.baseboard_fab2(sch_1):pwrgd_cpu0_g_r") )
				( member ( signalRef "@baseboard_fab2_lib.baseboard_fab2(sch_1):rst_bmc_sysrst_btn_out_b_r_n") )
				( member ( signalRef "@baseboard_fab2_lib.baseboard_fab2(sch_1):rst_rsmrst_r_n") )
				( member ( signalRef "@baseboard_fab2_lib.baseboard_fab2(sch_1):irq_force_nm_throttle_r_n") )
				( member ( signalRef "@baseboard_fab2_lib.baseboard_fab2(sch_1):rst_bmc_srst_r2_n") )
				( member ( signalRef "@baseboard_fab2_lib.baseboard_fab2(sch_1):irq_spi_tpm_n_r") )
				( member ( signalRef "@baseboard_fab2_lib.baseboard_fab2(sch_1):pwrgd_p3v3") )
				( member ( signalRef "@baseboard_fab2_lib.baseboard_fab2(sch_1):pwrgd_p3v3_r") )
				( member ( signalRef "@baseboard_fab2_lib.baseboard_fab2(sch_1):vr_p5v_stby_en") )
				( member ( signalRef "@baseboard_fab2_lib.baseboard_fab2(sch_1):rst_cpu0_lvc3_r1_n") )
				( member ( signalRef "@baseboard_fab2_lib.baseboard_fab2(sch_1):rst_cpu1_lvc3_r1_n") )
				( member ( signalRef "@baseboard_fab2_lib.baseboard_fab2(sch_1):rst_pcie_riser1_perst_r_n") )
				( member ( signalRef "@baseboard_fab2_lib.baseboard_fab2(sch_1):rst_system_btn_buf_n") )
				( member ( signalRef "@baseboard_fab2_lib.baseboard_fab2(sch_1):pwrgd_pvccmcp_cpu0") )
				( member ( signalRef "@baseboard_fab2_lib.baseboard_fab2(sch_1):pwrgd_pvccmcp_cpu1") )
				( member ( signalRef "@baseboard_fab2_lib.baseboard_fab2(sch_1):pwrgd_p1v8mcp_cpu0") )
				( member ( signalRef "@baseboard_fab2_lib.baseboard_fab2(sch_1):pwrgd_p5v_n") )
				( member ( signalRef "@baseboard_fab2_lib.baseboard_fab2(sch_1):pwrgd_p12v_main_r") )
				( member ( signalRef "@baseboard_fab2_lib.baseboard_fab2(sch_1):irq_bmc_pch_nmi_stby_n") )
				( member ( signalRef "@baseboard_fab2_lib.baseboard_fab2(sch_1):irq_bmc_pch_smi_lpc_n") )
				( member ( signalRef "@baseboard_fab2_lib.baseboard_fab2(sch_1):irq_cpu0_vrhot") )
				( member ( signalRef "@baseboard_fab2_lib.baseboard_fab2(sch_1):irq_cpu1_vrhot") )
				( member ( signalRef "@baseboard_fab2_lib.baseboard_fab2(sch_1):irq_lpc_serirq_n") )
				( member ( signalRef "@baseboard_fab2_lib.baseboard_fab2(sch_1):irq_lvc3_wake_n") )
				( member ( signalRef "@baseboard_fab2_lib.baseboard_fab2(sch_1):irq_pvccin_cpu0_vrhot_lvc3_n") )
				( member ( signalRef "@baseboard_fab2_lib.baseboard_fab2(sch_1):irq_pvccin_cpu1_vrhot_lvc3_n") )
				( member ( signalRef "@baseboard_fab2_lib.baseboard_fab2(sch_1):irq_pvddq_abc_vrhot_lvt3_n") )
				( member ( signalRef "@baseboard_fab2_lib.baseboard_fab2(sch_1):irq_pvddq_def_vrhot_lvt3_n") )
				( member ( signalRef "@baseboard_fab2_lib.baseboard_fab2(sch_1):irq_pvddq_ghj_vrhot_lvt3_n") )
				( member ( signalRef "@baseboard_fab2_lib.baseboard_fab2(sch_1):irq_pvddq_klm_vrhot_lvt3_n") )
				( member ( signalRef "@baseboard_fab2_lib.baseboard_fab2(sch_1):irq_sml0_alert_n") )
				( member ( signalRef "@baseboard_fab2_lib.baseboard_fab2(sch_1):irq_sml1_pmbus_alert_n") )
				( member ( signalRef "@baseboard_fab2_lib.baseboard_fab2(sch_1):pwrgd_cpupwrgd") )
				( member ( signalRef "@baseboard_fab2_lib.baseboard_fab2(sch_1):pwrgd_cpupwrgd_gtl") )
				( member ( signalRef "@baseboard_fab2_lib.baseboard_fab2(sch_1):pwrgd_cpupwrgd_r1") )
				( member ( signalRef "@baseboard_fab2_lib.baseboard_fab2(sch_1):pwrgd_cpu0_drampwrok_abc_g") )
				( member ( signalRef "@baseboard_fab2_lib.baseboard_fab2(sch_1):pwrgd_cpu0_drampwrok_def_g") )
				( member ( signalRef "@baseboard_fab2_lib.baseboard_fab2(sch_1):pwrgd_cpu0_g") )
				( member ( signalRef "@baseboard_fab2_lib.baseboard_fab2(sch_1):pwrgd_cpu0_lvc3") )
				( member ( signalRef "@baseboard_fab2_lib.baseboard_fab2(sch_1):pwrgd_cpu1_drampwrok_ghj_g") )
				( member ( signalRef "@baseboard_fab2_lib.baseboard_fab2(sch_1):pwrgd_cpu1_drampwrok_klm_g") )
				( member ( signalRef "@baseboard_fab2_lib.baseboard_fab2(sch_1):pwrgd_cpu1_g") )
				( member ( signalRef "@baseboard_fab2_lib.baseboard_fab2(sch_1):pwrgd_cpu1_lvc3") )
				( member ( signalRef "@baseboard_fab2_lib.baseboard_fab2(sch_1):pwrgd_drampwrgd") )
				( member ( signalRef "@baseboard_fab2_lib.baseboard_fab2(sch_1):pwrgd_dsw_pwrok") )
				( member ( signalRef "@baseboard_fab2_lib.baseboard_fab2(sch_1):pwrgd_pch_pwrok") )
				( member ( signalRef "@baseboard_fab2_lib.baseboard_fab2(sch_1):pwrgd_pvccin_cpu0") )
				( member ( signalRef "@baseboard_fab2_lib.baseboard_fab2(sch_1):pwrgd_pvccin_cpu1") )
				( member ( signalRef "@baseboard_fab2_lib.baseboard_fab2(sch_1):pwrgd_pvddq_abc") )
				( member ( signalRef "@baseboard_fab2_lib.baseboard_fab2(sch_1):pwrgd_pvddq_abc_r") )
				( member ( signalRef "@baseboard_fab2_lib.baseboard_fab2(sch_1):pwrgd_pvddq_def") )
				( member ( signalRef "@baseboard_fab2_lib.baseboard_fab2(sch_1):pwrgd_pvddq_def_r") )
				( member ( signalRef "@baseboard_fab2_lib.baseboard_fab2(sch_1):pwrgd_pvddq_ghj") )
				( member ( signalRef "@baseboard_fab2_lib.baseboard_fab2(sch_1):pwrgd_pvddq_ghj_r") )
				( member ( signalRef "@baseboard_fab2_lib.baseboard_fab2(sch_1):pwrgd_pvddq_klm") )
				( member ( signalRef "@baseboard_fab2_lib.baseboard_fab2(sch_1):pwrgd_pvddq_klm_r") )
				( member ( signalRef "@baseboard_fab2_lib.baseboard_fab2(sch_1):rst_bmc_ddr3_buf_in_n") )
				( member ( electricalNetRef "@crescent_city_bb_fab1_lib.crescent_city_bb_fab1(sch_1):a_hsc_low_drain") )
				( member ( electricalNetRef "@crescent_city_bb_fab1_lib.crescent_city_bb_fab1(sch_1):fm_pvtt_abc_en_r") )
				( member ( electricalNetRef "@crescent_city_bb_fab1_lib.crescent_city_bb_fab1(sch_1):fm_pvtt_def_en_r") )
				( member ( electricalNetRef "@crescent_city_bb_fab1_lib.crescent_city_bb_fab1(sch_1):fm_pvtt_ghj_en_r") )
				( member ( electricalNetRef "@crescent_city_bb_fab1_lib.crescent_city_bb_fab1(sch_1):fm_pvtt_klm_en_r") )
				( member ( electricalNetRef "@crescent_city_bb_fab1_lib.crescent_city_bb_fab1(sch_1):irq_dimm_save_n") )
				( member ( electricalNetRef "@crescent_city_bb_fab1_lib.crescent_city_bb_fab1(sch_1):irq_bmc_pch_nmi_stby_n") )
				( member ( electricalNetRef "@crescent_city_bb_fab1_lib.crescent_city_bb_fab1(sch_1):irq_hsc_fault_r_n") )
				( member ( electricalNetRef "@crescent_city_bb_fab1_lib.crescent_city_bb_fab1(sch_1):irq_lpc_serirq_n") )
				( member ( electricalNetRef "@crescent_city_bb_fab1_lib.crescent_city_bb_fab1(sch_1):irq_lvc3_wake_n") )
				( member ( electricalNetRef "@crescent_city_bb_fab1_lib.crescent_city_bb_fab1(sch_1):irq_pirqa_spi_tpm_n") )
				( member ( electricalNetRef "@crescent_city_bb_fab1_lib.crescent_city_bb_fab1(sch_1):irq_pvccin_cpu0_vrhot_lvc3_n") )
				( member ( electricalNetRef "@crescent_city_bb_fab1_lib.crescent_city_bb_fab1(sch_1):irq_pvccin_cpu1_vrhot_lvc3_n") )
				( member ( electricalNetRef "@crescent_city_bb_fab1_lib.crescent_city_bb_fab1(sch_1):irq_pvddq_abc_vrhot_lvt3_n") )
				( member ( electricalNetRef "@crescent_city_bb_fab1_lib.crescent_city_bb_fab1(sch_1):irq_pvddq_def_vrhot_lvt3_n") )
				( member ( electricalNetRef "@crescent_city_bb_fab1_lib.crescent_city_bb_fab1(sch_1):irq_pvddq_ghj_vrhot_lvt3_n") )
				( member ( electricalNetRef "@crescent_city_bb_fab1_lib.crescent_city_bb_fab1(sch_1):irq_pvddq_klm_vrhot_lvt3_n") )
				( member ( electricalNetRef "@crescent_city_bb_fab1_lib.crescent_city_bb_fab1(sch_1):irq_sml1_pmbus_alert_n") )
				( member ( electricalNetRef "@crescent_city_bb_fab1_lib.crescent_city_bb_fab1(sch_1):irq_vm_int_n") )
				( member ( electricalNetRef "@crescent_city_bb_fab1_lib.crescent_city_bb_fab1(sch_1):pwrgd_cpupwrgd") )
				( member ( electricalNetRef "@crescent_city_bb_fab1_lib.crescent_city_bb_fab1(sch_1):pwrgd_pvccio_cpu0") )
				( member ( electricalNetRef "@crescent_city_bb_fab1_lib.crescent_city_bb_fab1(sch_1):pwrgd_pvccio_cpu1") )
				( member ( electricalNetRef "@crescent_city_bb_fab1_lib.crescent_city_bb_fab1(sch_1):pwrgd_pvnn_p1v05_pch") )
				( member ( electricalNetRef "@crescent_city_bb_fab1_lib.crescent_city_bb_fab1(sch_1):pwrgd_pvpp_abc") )
				( member ( electricalNetRef "@crescent_city_bb_fab1_lib.crescent_city_bb_fab1(sch_1):pwrgd_pvpp_def") )
				( member ( electricalNetRef "@crescent_city_bb_fab1_lib.crescent_city_bb_fab1(sch_1):pwrgd_pvpp_ghj") )
				( member ( electricalNetRef "@crescent_city_bb_fab1_lib.crescent_city_bb_fab1(sch_1):pwrgd_pvpp_klm") )
				( member ( electricalNetRef "@crescent_city_bb_fab1_lib.crescent_city_bb_fab1(sch_1):pwrgd_pvsa_cpu0") )
				( member ( electricalNetRef "@crescent_city_bb_fab1_lib.crescent_city_bb_fab1(sch_1):pwrgd_pvsa_cpu1") )
				( member ( electricalNetRef "@crescent_city_bb_fab1_lib.crescent_city_bb_fab1(sch_1):pwrgd_pvtt_abc_cpu0_r") )
				( member ( electricalNetRef "@crescent_city_bb_fab1_lib.crescent_city_bb_fab1(sch_1):pwrgd_pvtt_cpu1") )
				( member ( electricalNetRef "@crescent_city_bb_fab1_lib.crescent_city_bb_fab1(sch_1):pwrgd_p1v26_bmc_stby") )
				( member ( electricalNetRef "@crescent_city_bb_fab1_lib.crescent_city_bb_fab1(sch_1):pwrgd_p1v538_bmc_stby") )
				( member ( electricalNetRef "@crescent_city_bb_fab1_lib.crescent_city_bb_fab1(sch_1):pwrgd_p3v3_r") )
				( member ( electricalNetRef "@crescent_city_bb_fab1_lib.crescent_city_bb_fab1(sch_1):pwrgd_p3v3_stby_r") )
				( member ( electricalNetRef "@crescent_city_bb_fab1_lib.crescent_city_bb_fab1(sch_1):pwrgd_p5v") )
				( member ( electricalNetRef "@crescent_city_bb_fab1_lib.crescent_city_bb_fab1(sch_1):pwrgd_p12v_hsc") )
				( member ( electricalNetRef "@crescent_city_bb_fab1_lib.crescent_city_bb_fab1(sch_1):pwrgd_p12v_hsc_dly") )
				( member ( electricalNetRef "@crescent_city_bb_fab1_lib.crescent_city_bb_fab1(sch_1):rst_bmc_ddr3_n") )
				( member ( electricalNetRef "@crescent_city_bb_fab1_lib.crescent_city_bb_fab1(sch_1):rst_bmc_lvc3_n") )
				( member ( electricalNetRef "@crescent_city_bb_fab1_lib.crescent_city_bb_fab1(sch_1):rst_cpu0_lvc3_n") )
				( member ( electricalNetRef "@crescent_city_bb_fab1_lib.crescent_city_bb_fab1(sch_1):rst_cpu1_lvc3_n") )
				( member ( electricalNetRef "@crescent_city_bb_fab1_lib.crescent_city_bb_fab1(sch_1):rst_pcie_cpu_dev0_n") )
				( member ( electricalNetRef "@crescent_city_bb_fab1_lib.crescent_city_bb_fab1(sch_1):rst_pcie_cpu_dev1_n") )
				( member ( electricalNetRef "@crescent_city_bb_fab1_lib.crescent_city_bb_fab1(sch_1):rst_pcie_cpu_dev2_n") )
				( member ( electricalNetRef "@crescent_city_bb_fab1_lib.crescent_city_bb_fab1(sch_1):rst_pcie_cpu_dev3_n") )
				( member ( electricalNetRef "@crescent_city_bb_fab1_lib.crescent_city_bb_fab1(sch_1):rst_pcie_riser1_perst_n") )
				( member ( electricalNetRef "@crescent_city_bb_fab1_lib.crescent_city_bb_fab1(sch_1):rst_pltrst_sprv_r_n") )
				( member ( electricalNetRef "@crescent_city_bb_fab1_lib.crescent_city_bb_fab1(sch_1):rst_system_btn_buf_n") )
				( member ( electricalNetRef "@crescent_city_bb_fab1_lib.crescent_city_bb_fab1(sch_1):vr_pvnn_pch_vren") )
				( member ( electricalNetRef "@crescent_city_bb_fab1_lib.crescent_city_bb_fab1(sch_1):vr_p3v3_stby_en") )
				( objectStatus "SNCLS_RST_IRQ_PWRGD" )
			)
			( netClass "@sapphirecity_baseboard_lib.sapphirecity_baseboard(sch_1):\MISC_CPU\"
				( memberType ( signal ) )
				( spacingCSetRef "@sapphirecity_baseboard_lib.sapphirecity_baseboard(sch_1):\8MIL_SL_10MIL_MS\" )
				( sameNetSpacingCSetRef "@crescent_city_bb_fab1_lib.crescent_city_bb_fab1(sch_1):\7H_US_AND_5H_SL\" )
				( objectFlag fObjectSpacing )
				( objectFlag fObjectSameNetSpacing )
				( objectStatus "MISC_CPU" )
			)
			( netClass "@sapphirecity_baseboard_lib.sapphirecity_baseboard(sch_1):\LPC\"
				( memberType ( signal ) )
				( spacingCSetRef "@crescent_city_bb_fab1_lib.crescent_city_bb_fab1(sch_1):\4_MILS\" )
				( sameNetSpacingCSetRef "@crescent_city_bb_fab1_lib.crescent_city_bb_fab1(sch_1):\2.5H_US_AND_2H_SL\" )
				( objectFlag fObjectSpacing )
				( objectFlag fObjectSameNetSpacing )
				( member ( signalRef "@baseboard_fab2_lib.baseboard_fab2(sch_1):lpc_lad0_io0") )
				( member ( signalRef "@baseboard_fab2_lib.baseboard_fab2(sch_1):lpc_lad0_io0_r") )
				( member ( signalRef "@baseboard_fab2_lib.baseboard_fab2(sch_1):lpc_lad1_io1") )
				( member ( signalRef "@baseboard_fab2_lib.baseboard_fab2(sch_1):lpc_lad1_io1_r") )
				( member ( signalRef "@baseboard_fab2_lib.baseboard_fab2(sch_1):lpc_lad2_io2") )
				( member ( signalRef "@baseboard_fab2_lib.baseboard_fab2(sch_1):lpc_lad2_io2_r") )
				( member ( signalRef "@baseboard_fab2_lib.baseboard_fab2(sch_1):lpc_lad3_io3") )
				( member ( signalRef "@baseboard_fab2_lib.baseboard_fab2(sch_1):lpc_lad3_io3_r") )
				( member ( signalRef "@baseboard_fab2_lib.baseboard_fab2(sch_1):lpc_lframe_n_cs0_n") )
				( member ( signalRef "@baseboard_fab2_lib.baseboard_fab2(sch_1):lpc_lframe_n_cs0_r_n") )
				( member ( electricalNetRef "@crescent_city_bb_fab1_lib.crescent_city_bb_fab1(sch_1):lpc_lad0_io0") )
				( member ( electricalNetRef "@crescent_city_bb_fab1_lib.crescent_city_bb_fab1(sch_1):lpc_lad1_io1") )
				( member ( electricalNetRef "@crescent_city_bb_fab1_lib.crescent_city_bb_fab1(sch_1):lpc_lad2_io2") )
				( member ( electricalNetRef "@crescent_city_bb_fab1_lib.crescent_city_bb_fab1(sch_1):lpc_lad3_io3") )
				( member ( electricalNetRef "@crescent_city_bb_fab1_lib.crescent_city_bb_fab1(sch_1):lpc_lframe_n_cs0_n") )
				( objectStatus "SNCLS_LPC" )
			)
			( netClass "@sapphirecity_baseboard_lib.sapphirecity_baseboard(sch_1):\JTAG_XDP\"
				( memberType ( signal ) )
				( spacingCSetRef "@sapphirecity_baseboard_lib.sapphirecity_baseboard(sch_1):\2.5H_US_AND_2H_SL\" )
				( sameNetSpacingCSetRef "@crescent_city_bb_fab1_lib.crescent_city_bb_fab1(sch_1):\2.5H_US_AND_2H_SL\" )
				( objectFlag fObjectSpacing )
				( objectFlag fObjectSameNetSpacing )
				( member ( signalRef "@baseboard_fab2_lib.baseboard_fab2(sch_1):pu_jtag_sprv_tck") )
				( member ( signalRef "@baseboard_fab2_lib.baseboard_fab2(sch_1):pu_jtag_sprv_tdi") )
				( member ( signalRef "@baseboard_fab2_lib.baseboard_fab2(sch_1):pu_jtag_sprv_tdo") )
				( member ( signalRef "@baseboard_fab2_lib.baseboard_fab2(sch_1):pu_jtag_sprv_tms") )
				( member ( signalRef "@baseboard_fab2_lib.baseboard_fab2(sch_1):jtag_mcp_cpu0_tdo") )
				( member ( signalRef "@baseboard_fab2_lib.baseboard_fab2(sch_1):jtag_mcp_cpu1_tdo") )
				( member ( signalRef "@baseboard_fab2_lib.baseboard_fab2(sch_1):jtag_bmc_tck") )
				( member ( signalRef "@baseboard_fab2_lib.baseboard_fab2(sch_1):jtag_bmc_tdi") )
				( member ( signalRef "@baseboard_fab2_lib.baseboard_fab2(sch_1):jtag_bmc_tdo") )
				( member ( signalRef "@baseboard_fab2_lib.baseboard_fab2(sch_1):jtag_bmc_tms") )
				( member ( signalRef "@baseboard_fab2_lib.baseboard_fab2(sch_1):jtag_bmc_trst_n") )
				( member ( signalRef "@baseboard_fab2_lib.baseboard_fab2(sch_1):jtag_pch_gbe_clk") )
				( member ( signalRef "@baseboard_fab2_lib.baseboard_fab2(sch_1):jtag_pch_gbe_tdi") )
				( member ( signalRef "@baseboard_fab2_lib.baseboard_fab2(sch_1):jtag_pch_gbe_tdo") )
				( member ( signalRef "@baseboard_fab2_lib.baseboard_fab2(sch_1):jtag_pch_gbe_tms") )
				( member ( signalRef "@baseboard_fab2_lib.baseboard_fab2(sch_1):jtag_pch_gbe_trst_n") )
				( member ( signalRef "@baseboard_fab2_lib.baseboard_fab2(sch_1):jtag_pch_pld_tck") )
				( member ( signalRef "@baseboard_fab2_lib.baseboard_fab2(sch_1):jtag_pch_pld_tdi") )
				( member ( signalRef "@baseboard_fab2_lib.baseboard_fab2(sch_1):jtag_pch_pld_tdo") )
				( member ( signalRef "@baseboard_fab2_lib.baseboard_fab2(sch_1):jtag_pch_pld_tms") )
				( member ( signalRef "@baseboard_fab2_lib.baseboard_fab2(sch_1):jtag_pld_tck") )
				( member ( signalRef "@baseboard_fab2_lib.baseboard_fab2(sch_1):jtag_pld_tdi") )
				( member ( signalRef "@baseboard_fab2_lib.baseboard_fab2(sch_1):jtag_pld_tdo") )
				( member ( signalRef "@baseboard_fab2_lib.baseboard_fab2(sch_1):jtag_pld_tms") )
				( member ( signalRef "@baseboard_fab2_lib.baseboard_fab2(sch_1):jtag_tck") )
				( member ( signalRef "@baseboard_fab2_lib.baseboard_fab2(sch_1):jtag_tck_r") )
				( member ( signalRef "@baseboard_fab2_lib.baseboard_fab2(sch_1):jtag_tdi") )
				( member ( signalRef "@baseboard_fab2_lib.baseboard_fab2(sch_1):jtag_tdi_r") )
				( member ( signalRef "@baseboard_fab2_lib.baseboard_fab2(sch_1):jtag_tdo") )
				( member ( signalRef "@baseboard_fab2_lib.baseboard_fab2(sch_1):jtag_tdo_r") )
				( member ( signalRef "@baseboard_fab2_lib.baseboard_fab2(sch_1):jtag_tms") )
				( member ( signalRef "@baseboard_fab2_lib.baseboard_fab2(sch_1):jtag_tms_r") )
				( member ( signalRef "@baseboard_fab2_lib.baseboard_fab2(sch_1):jtag_trst_n") )
				( member ( signalRef "@baseboard_fab2_lib.baseboard_fab2(sch_1):jtag_mcp_cpu0_tdi") )
				( member ( signalRef "@baseboard_fab2_lib.baseboard_fab2(sch_1):jtag_mcp_cpu0_tdi_r") )
				( member ( signalRef "@baseboard_fab2_lib.baseboard_fab2(sch_1):jtag_mcp_cpu1_tdi") )
				( member ( signalRef "@baseboard_fab2_lib.baseboard_fab2(sch_1):jtag_mcp_cpu1_tdi_r") )
				( member ( signalRef "@baseboard_fab2_lib.baseboard_fab2(sch_1):jtag_mcp_mux_tdi") )
				( member ( signalRef "@baseboard_fab2_lib.baseboard_fab2(sch_1):jtag_mcp_mux_tdo") )
				( member ( signalRef "@baseboard_fab2_lib.baseboard_fab2(sch_1):jtag_mcp_tck") )
				( member ( signalRef "@baseboard_fab2_lib.baseboard_fab2(sch_1):jtag_mcp_tck_r") )
				( member ( signalRef "@baseboard_fab2_lib.baseboard_fab2(sch_1):jtag_mcp_tms") )
				( member ( signalRef "@baseboard_fab2_lib.baseboard_fab2(sch_1):jtag_mcp_tms_r") )
				( member ( signalRef "@baseboard_fab2_lib.baseboard_fab2(sch_1):jtag_mcp_tms_r1") )
				( member ( signalRef "@baseboard_fab2_lib.baseboard_fab2(sch_1):jtag_mcp_trst_n") )
				( member ( electricalNetRef "@crescent_city_bb_fab1_lib.crescent_city_bb_fab1(sch_1):jtag_pch_gbe_clk") )
				( member ( electricalNetRef "@crescent_city_bb_fab1_lib.crescent_city_bb_fab1(sch_1):jtag_pch_gbe_tdi") )
				( member ( electricalNetRef "@crescent_city_bb_fab1_lib.crescent_city_bb_fab1(sch_1):jtag_pch_gbe_tdo") )
				( member ( electricalNetRef "@crescent_city_bb_fab1_lib.crescent_city_bb_fab1(sch_1):jtag_pch_gbe_tms") )
				( member ( electricalNetRef "@crescent_city_bb_fab1_lib.crescent_city_bb_fab1(sch_1):jtag_pch_gbe_trst_n") )
				( member ( electricalNetRef "@baseboard_fab2_lib.baseboard_fab2(sch_1):jtag_mcp_cpu0_tdi") )
				( member ( electricalNetRef "@baseboard_fab2_lib.baseboard_fab2(sch_1):jtag_mcp_cpu1_tdi") )
				( member ( electricalNetRef "@baseboard_fab2_lib.baseboard_fab2(sch_1):jtag_mcp_tck_r") )
				( member ( electricalNetRef "@baseboard_fab2_lib.baseboard_fab2(sch_1):jtag_mcp_tms") )
				( objectStatus "SNCLS_JTAG_XDP" )
			)
			( netClass "@sapphirecity_baseboard_lib.sapphirecity_baseboard(sch_1):\FAN\"
				( memberType ( signal ) )
				( spacingCSetRef "@sapphirecity_baseboard_lib.sapphirecity_baseboard(sch_1):\8_MILS\" )
				( sameNetSpacingCSetRef "@crescent_city_bb_fab1_lib.crescent_city_bb_fab1(sch_1):\2.2H_US_AND_2H_SL\" )
				( objectFlag fObjectSpacing )
				( objectFlag fObjectSameNetSpacing )
				( member ( signalRef "@baseboard_fab2_lib.baseboard_fab2(sch_1):fan_tach0_cpu0_d1") )
				( member ( signalRef "@baseboard_fab2_lib.baseboard_fab2(sch_1):fan_tach1") )
				( member ( signalRef "@baseboard_fab2_lib.baseboard_fab2(sch_1):fan_tach2_cpu1_d1") )
				( member ( signalRef "@baseboard_fab2_lib.baseboard_fab2(sch_1):fan_tach3") )
				( member ( signalRef "@baseboard_fab2_lib.baseboard_fab2(sch_1):fan_tach0") )
				( member ( signalRef "@baseboard_fab2_lib.baseboard_fab2(sch_1):fan_tach0_cpu0_d2") )
				( member ( signalRef "@baseboard_fab2_lib.baseboard_fab2(sch_1):fan_tach2_cpu1_d2") )
				( member ( signalRef "@baseboard_fab2_lib.baseboard_fab2(sch_1):fan_pwm_out_sys0") )
				( member ( signalRef "@baseboard_fab2_lib.baseboard_fab2(sch_1):fan_pwm_out_sys1") )
				( member ( signalRef "@baseboard_fab2_lib.baseboard_fab2(sch_1):fan_tach2") )
				( member ( signalRef "@baseboard_fab2_lib.baseboard_fab2(sch_1):fan_pwm_out_sys0_r1") )
				( member ( signalRef "@baseboard_fab2_lib.baseboard_fab2(sch_1):fan_tach1_r") )
				( member ( signalRef "@baseboard_fab2_lib.baseboard_fab2(sch_1):fan_tach2_r") )
				( member ( signalRef "@baseboard_fab2_lib.baseboard_fab2(sch_1):fan_tach3_r") )
				( member ( signalRef "@baseboard_fab2_lib.baseboard_fab2(sch_1):fan_tach1_cpu1_d1") )
				( member ( signalRef "@baseboard_fab2_lib.baseboard_fab2(sch_1):fan_tach1_cpu1_d2") )
				( member ( signalRef "@baseboard_fab2_lib.baseboard_fab2(sch_1):fan_tach3_cpu1_d1") )
				( member ( signalRef "@baseboard_fab2_lib.baseboard_fab2(sch_1):fan_tach3_cpu1_d2") )
				( member ( signalRef "@baseboard_fab2_lib.baseboard_fab2(sch_1):fan_pwm_out_sys0_buf") )
				( member ( signalRef "@baseboard_fab2_lib.baseboard_fab2(sch_1):fan_pwm_out_sys0_r") )
				( member ( signalRef "@baseboard_fab2_lib.baseboard_fab2(sch_1):fan_pwm_out_sys1_buf") )
				( member ( signalRef "@baseboard_fab2_lib.baseboard_fab2(sch_1):fan_pwm_out_sys1_r") )
				( member ( signalRef "@baseboard_fab2_lib.baseboard_fab2(sch_1):fan_tach0_r") )
				( member ( electricalNetRef "@crescent_city_bb_fab1_lib.crescent_city_bb_fab1(sch_1):fan_pwm_out_sys0_r") )
				( member ( electricalNetRef "@crescent_city_bb_fab1_lib.crescent_city_bb_fab1(sch_1):fan_pwm_out_sys1_r") )
				( member ( electricalNetRef "@crescent_city_bb_fab1_lib.crescent_city_bb_fab1(sch_1):fan_tach1") )
				( member ( electricalNetRef "@crescent_city_bb_fab1_lib.crescent_city_bb_fab1(sch_1):fan_tach2") )
				( member ( electricalNetRef "@crescent_city_bb_fab1_lib.crescent_city_bb_fab1(sch_1):fan_tach3_r") )
				( objectStatus "SNCLS_FAN" )
			)
			( netClass "@sapphirecity_baseboard_lib.sapphirecity_baseboard(sch_1):\ISENSE\"
				( memberType ( signal ) )
				( spacingCSetRef "@sapphirecity_baseboard_lib.sapphirecity_baseboard(sch_1):\20MIL_VIA_2H+A\" )
				( objectFlag fObjectSpacing )
				( objectFlag fObjectSameNetSpacing )
				( member ( diffPairRef "@crescent_city_bb_fab1_lib.crescent_city_bb_fab1(sch_1):\DP_VSENSE_P1V0_CPU0_R\") )
				( member ( diffPairRef "@crescent_city_bb_fab1_lib.crescent_city_bb_fab1(sch_1):\DP_VSENSE_P1V0_CPU1_R\") )
				( member ( diffPairRef "@crescent_city_bb_fab1_lib.crescent_city_bb_fab1(sch_1):\DP_VSENSE_PVDDQ_ABC\") )
				( member ( diffPairRef "@crescent_city_bb_fab1_lib.crescent_city_bb_fab1(sch_1):\DP_VSENSE_PVDDQ_DEF\") )
				( member ( diffPairRef "@crescent_city_bb_fab1_lib.crescent_city_bb_fab1(sch_1):\DP_VSENSE_PVDDQ_GHI\") )
				( member ( diffPairRef "@crescent_city_bb_fab1_lib.crescent_city_bb_fab1(sch_1):\DP_VSENSE_PVDDQ_KLM\") )
				( member ( diffPairRef "@baseboard_fab2_lib.baseboard_fab2(sch_1):\DP_VSENSE_P1V8MCP_CPU0_SKT\") )
				( member ( diffPairRef "@baseboard_fab2_lib.baseboard_fab2(sch_1):\DP_VSENSE_P1V8MCP_CPU1_SKT\") )
				( member ( diffPairRef "@crescent_city_bb_fab1_lib.crescent_city_bb_fab1(sch_1):\VSENSE_PVSA_CPU0\") )
				( member ( diffPairRef "@crescent_city_bb_fab1_lib.crescent_city_bb_fab1(sch_1):\VSENSE_P1V05_PCH_STBY\") )
				( member ( diffPairRef "@baseboard_fab2_lib.baseboard_fab2(sch_1):\DP_VSENSE_PVCCIN_CPU0\") )
				( member ( diffPairRef "@baseboard_fab2_lib.baseboard_fab2(sch_1):\DP_VSENSE_PVCCIO_CPU0_AVS\") )
				( member ( diffPairRef "@baseboard_fab2_lib.baseboard_fab2(sch_1):\DP_VSENSE_PVNN_PCH_STBY\") )
				( member ( diffPairRef "@baseboard_fab2_lib.baseboard_fab2(sch_1):\DP_VSENSE_PVSA_CPU1_CPU1_SKT\") )
				( member ( diffPairRef "@baseboard_fab2_lib.baseboard_fab2(sch_1):\DP_VSENSE_PVCCIN_CPU1\") )
				( member ( diffPairRef "@baseboard_fab2_lib.baseboard_fab2(sch_1):\DP_VSENSE_PVCCIO_CPU1_SKT\") )
				( member ( diffPairRef "@baseboard_fab2_lib.baseboard_fab2(sch_1):\DP_VSENSE_PVCCMCP_CPU0_SKT\") )
				( member ( diffPairRef "@baseboard_fab2_lib.baseboard_fab2(sch_1):\DP_VSENSE_PVCCMCP_CPU1_SKT\") )
				( member ( diffPairRef "@baseboard_fab2_lib.baseboard_fab2(sch_1):\DP_VSENSE_PVCCIN_CPU0_SKT\") )
				( member ( signalRef "@baseboard_fab2_lib.baseboard_fab2(sch_1):vsense_pvnn_pch_stby_avsn") )
				( member ( signalRef "@baseboard_fab2_lib.baseboard_fab2(sch_1):vsense_pvnn_pch_stby_avsp") )
				( member ( signalRef "@baseboard_fab2_lib.baseboard_fab2(sch_1):vsense_pmax_cpu0") )
				( member ( signalRef "@baseboard_fab2_lib.baseboard_fab2(sch_1):vsense_pmax_cpu1") )
				( member ( signalRef "@baseboard_fab2_lib.baseboard_fab2(sch_1):vsense_vccinr2pmax_cpu0") )
				( member ( signalRef "@baseboard_fab2_lib.baseboard_fab2(sch_1):vsense_vccinr2pmax_cpu1") )
				( member ( signalRef "@baseboard_fab2_lib.baseboard_fab2(sch_1):vsense_rgnd_p3v3_stby") )
				( member ( signalRef "@baseboard_fab2_lib.baseboard_fab2(sch_1):vsense_p12v_adm1085") )
				( member ( signalRef "@baseboard_fab2_lib.baseboard_fab2(sch_1):vsense_p3v3_stby") )
				( member ( signalRef "@baseboard_fab2_lib.baseboard_fab2(sch_1):vsense_vout_p3v3_stby") )
				( member ( electricalNetRef "@crescent_city_bb_fab1_lib.crescent_city_bb_fab1(sch_1):vsense_p3v3_stby") )
				( objectStatus "SNCLS_VSENSE" )
			)
			( netClass "@sapphirecity_baseboard_lib.sapphirecity_baseboard(sch_1):\V_BMC_DDC\"
				( memberType ( signal ) )
				( spacingCSetRef "@sapphirecity_baseboard_lib.sapphirecity_baseboard(sch_1):\10MIL\" )
				( sameNetSpacingCSetRef "@crescent_city_bb_fab1_lib.crescent_city_bb_fab1(sch_1):\20_MIL\" )
				( objectFlag fObjectSpacing )
				( objectFlag fObjectSameNetSpacing )
				( objectStatus "V_BMC_DDC" )
			)
			( netClass "@sapphirecity_baseboard_lib.sapphirecity_baseboard(sch_1):\V_BMC_RSET\"
				( memberType ( signal ) )
				( spacingCSetRef "@sapphirecity_baseboard_lib.sapphirecity_baseboard(sch_1):\20_MILS\" )
				( sameNetSpacingCSetRef "@crescent_city_bb_fab1_lib.crescent_city_bb_fab1(sch_1):\20_MIL\" )
				( objectFlag fObjectSpacing )
				( objectFlag fObjectSameNetSpacing )
				( objectStatus "V_BMC_RSET" )
			)
			( netClass "@sapphirecity_baseboard_lib.sapphirecity_baseboard(sch_1):\V_BMC_SYNC\"
				( memberType ( signal ) )
				( spacingCSetRef "@sapphirecity_baseboard_lib.sapphirecity_baseboard(sch_1):\16MIL\" )
				( sameNetSpacingCSetRef "@crescent_city_bb_fab1_lib.crescent_city_bb_fab1(sch_1):\20_MIL\" )
				( objectFlag fObjectSpacing )
				( objectFlag fObjectSameNetSpacing )
				( objectStatus "V_BMC_SYNC" )
			)
			( netClass "@sapphirecity_baseboard_lib.sapphirecity_baseboard(sch_1):\V_BMC_RGB\"
				( memberType ( signal ) )
				( spacingCSetRef "@sapphirecity_baseboard_lib.sapphirecity_baseboard(sch_1):\30MIL\" )
				( sameNetSpacingCSetRef "@crescent_city_bb_fab1_lib.crescent_city_bb_fab1(sch_1):\20_MIL\" )
				( objectFlag fObjectSpacing )
				( objectFlag fObjectSameNetSpacing )
				( objectStatus "V_BMC_RGB" )
			)
			( netClass "@sapphirecity_baseboard_lib.sapphirecity_baseboard(sch_1):\PE_PCH_BMC\"
				( memberType ( signal ) )
				( spacingCSetRef "@crescent_city_bb_fab1_lib.crescent_city_bb_fab1(sch_1):\9H_US_&_5H_SL_VIA+3H_A\" )
				( objectFlag fObjectSpacing )
				( objectFlag fObjectSameNetSpacing )
				( objectStatus "PE_PCH_BMC" )
			)
			( netClass "@sapphirecity_baseboard_lib.sapphirecity_baseboard(sch_1):\USB2\"
				( memberType ( signal ) )
				( spacingCSetRef "@sapphirecity_baseboard_lib.sapphirecity_baseboard(sch_1):\5H_SL_7H_MS_VIA_3H_A\" )
				( sameNetSpacingCSetRef "@crescent_city_bb_fab1_lib.crescent_city_bb_fab1(sch_1):\7H_US_AND_5H_SL\" )
				( objectFlag fObjectSpacing )
				( objectFlag fObjectSameNetSpacing )
				( member ( diffPairRef "@crescent_city_bb_fab1_lib.crescent_city_bb_fab1(sch_1):\DP_USB2_P02\") )
				( member ( diffPairRef "@crescent_city_bb_fab1_lib.crescent_city_bb_fab1(sch_1):\USB2_PCH_BMC_P4_D\") )
				( member ( diffPairRef "@crescent_city_bb_fab1_lib.crescent_city_bb_fab1(sch_1):\USB2_PCH_BMC_P5_D\") )
				( objectStatus "SNCLS_USB2" )
			)
			( netClass "@sapphirecity_baseboard_lib.sapphirecity_baseboard(sch_1):\CLK_DIFF_100M\"
				( memberType ( signal ) )
				( spacingCSetRef "@sapphirecity_baseboard_lib.sapphirecity_baseboard(sch_1):\7H_US_AND_3H_SL\" )
				( sameNetSpacingCSetRef "@crescent_city_bb_fab1_lib.crescent_city_bb_fab1(sch_1):\24MIL_US&15MIL_SL\" )
				( objectFlag fObjectSpacing )
				( objectFlag fObjectSameNetSpacing )
				( member ( diffPairRef "@crescent_city_bb_fab1_lib.crescent_city_bb_fab1(sch_1):\CLK_100M_AIRMAX8_PE1\") )
				( member ( diffPairRef "@crescent_city_bb_fab1_lib.crescent_city_bb_fab1(sch_1):\DP_CLK_100M_BMC_PE\") )
				( member ( diffPairRef "@sapphirecity_baseboard_lib.sapphirecity_baseboard(sch_1):\CLK_100M_CPU0_BCLK0\") )
				( member ( diffPairRef "@sapphirecity_baseboard_lib.sapphirecity_baseboard(sch_1):\CLK_100M_CPU0_BCLK1\") )
				( member ( diffPairRef "@sapphirecity_baseboard_lib.sapphirecity_baseboard(sch_1):\CLK_100M_CPU0_BCLK2\") )
				( member ( diffPairRef "@crescent_city_bb_fab1_lib.crescent_city_bb_fab1(sch_1):\CLK_100M_CPU0_MCP_CLK2\") )
				( member ( diffPairRef "@sapphirecity_baseboard_lib.sapphirecity_baseboard(sch_1):\CLK_100M_CPU1_BCLK0\") )
				( member ( diffPairRef "@sapphirecity_baseboard_lib.sapphirecity_baseboard(sch_1):\CLK_100M_CPU1_BCLK1\") )
				( member ( diffPairRef "@sapphirecity_baseboard_lib.sapphirecity_baseboard(sch_1):\CLK_100M_CPU1_BCLK2\") )
				( member ( diffPairRef "@crescent_city_bb_fab1_lib.crescent_city_bb_fab1(sch_1):\CLK_100M_CPU1_MCP_CLK2\") )
				( member ( diffPairRef "@crescent_city_bb_fab1_lib.crescent_city_bb_fab1(sch_1):\CLK_100M_DB1200\") )
				( member ( diffPairRef "@crescent_city_bb_fab1_lib.crescent_city_bb_fab1(sch_1):\CLK_100M_MEZZ1\") )
				( member ( diffPairRef "@crescent_city_bb_fab1_lib.crescent_city_bb_fab1(sch_1):\CLK_100M_MEZZ2\") )
				( member ( diffPairRef "@crescent_city_bb_fab1_lib.crescent_city_bb_fab1(sch_1):\DP_CLK_100M_MEZZ3_D\") )
				( member ( diffPairRef "@crescent_city_bb_fab1_lib.crescent_city_bb_fab1(sch_1):\DP_CLK_100M_MEZZ4_D\") )
				( member ( diffPairRef "@crescent_city_bb_fab1_lib.crescent_city_bb_fab1(sch_1):\CLK_100M_M2\") )
				( member ( diffPairRef "@crescent_city_bb_fab1_lib.crescent_city_bb_fab1(sch_1):\CLK_100M_PCH_SLOTX24_S1\") )
				( member ( diffPairRef "@crescent_city_bb_fab1_lib.crescent_city_bb_fab1(sch_1):\CLK_100M_PCH_SLOTX24_S2\") )
				( member ( diffPairRef "@crescent_city_bb_fab1_lib.crescent_city_bb_fab1(sch_1):\CLK_100M_PCH_SLOTX24_S3\") )
				( member ( diffPairRef "@sapphirecity_baseboard_lib.sapphirecity_baseboard(sch_1):\CLK_100M_PCH_XDP\") )
				( member ( diffPairRef "@crescent_city_bb_fab1_lib.crescent_city_bb_fab1(sch_1):\CLK_100M_SPRV_D\") )
				( member ( diffPairRef "@crescent_city_bb_fab1_lib.crescent_city_bb_fab1(sch_1):\DP_CLK_100M_PCH_SLOTX24_S0\") )
				( member ( diffPairRef "@crescent_city_bb_fab1_lib.crescent_city_bb_fab1(sch_1):\DP_CLK_100M_PCH_SLOTX24_S4\") )
				( member ( diffPairRef "@crescent_city_bb_fab1_lib.crescent_city_bb_fab1(sch_1):\DP_CLK_100M_PCH_SLOTX24_S5\") )
				( member ( diffPairRef "@crescent_city_bb_fab1_lib.crescent_city_bb_fab1(sch_1):\CLK_100M_CPU0_MCP_CLK1_R_D\") )
				( member ( diffPairRef "@crescent_city_bb_fab1_lib.crescent_city_bb_fab1(sch_1):\CLK_100M_CPU1_MCP_CLK1_R_D\") )
				( member ( diffPairRef "@crescent_city_bb_fab1_lib.crescent_city_bb_fab1(sch_1):\DP_CLK_156M_OSC_CPU0_HFI\") )
				( member ( diffPairRef "@crescent_city_bb_fab1_lib.crescent_city_bb_fab1(sch_1):\DP_CLK_156M_OSC_CPU1_HFI\") )
				( member ( diffPairRef "@crescent_city_bb_fab1_lib.crescent_city_bb_fab1(sch_1):\CLK_100M_CPU0_PE_REFCLK_R_D\") )
				( member ( diffPairRef "@crescent_city_bb_fab1_lib.crescent_city_bb_fab1(sch_1):\CLK_100M_CPU1_PE_REFCLK_R_D\") )
				( member ( diffPairRef "@baseboard_fab2_lib.baseboard_fab2(sch_1):\DP_CLK_156M_OSC_BRD_CPU0\") )
				( member ( diffPairRef "@baseboard_fab2_lib.baseboard_fab2(sch_1):\DP_CLK_156M_OSC_BRD_CPU1\") )
				( member ( diffPairRef "@baseboard_fab2_lib.baseboard_fab2(sch_1):\DP_CLK_156M_OSC_CPU0_HFI\") )
				( member ( diffPairRef "@baseboard_fab2_lib.baseboard_fab2(sch_1):\DP_CLK_156M_OSC_CPU1_HFI\") )
				( member ( diffPairRef "@baseboard_fab2_lib.baseboard_fab2(sch_1):\DP_CLK_322M_156M_CPU0_OSC_VRM\") )
				( member ( diffPairRef "@baseboard_fab2_lib.baseboard_fab2(sch_1):\DP_CLK_322M_156M_CPU1_OSC_VRM\") )
				( member ( signalRef "@baseboard_fab2_lib.baseboard_fab2(sch_1):clk_100m_cpu0_pe_refclk_dn") )
				( member ( signalRef "@baseboard_fab2_lib.baseboard_fab2(sch_1):clk_100m_cpu0_pe_refclk_dp") )
				( member ( signalRef "@baseboard_fab2_lib.baseboard_fab2(sch_1):clk_100m_cpu0_pe_refclk_r_dn") )
				( member ( signalRef "@baseboard_fab2_lib.baseboard_fab2(sch_1):clk_100m_cpu0_pe_refclk_r_dp") )
				( member ( signalRef "@baseboard_fab2_lib.baseboard_fab2(sch_1):clk_100m_cpu0_rc_refclk0_dn") )
				( member ( signalRef "@baseboard_fab2_lib.baseboard_fab2(sch_1):clk_100m_cpu0_rc_refclk0_dp") )
				( member ( signalRef "@baseboard_fab2_lib.baseboard_fab2(sch_1):clk_100m_cpu0_rc_refclk0_r_dn") )
				( member ( signalRef "@baseboard_fab2_lib.baseboard_fab2(sch_1):clk_100m_cpu0_rc_refclk0_r_dp") )
				( member ( signalRef "@baseboard_fab2_lib.baseboard_fab2(sch_1):clk_100m_cpu1_pe_refclk_dn") )
				( member ( signalRef "@baseboard_fab2_lib.baseboard_fab2(sch_1):clk_100m_cpu1_pe_refclk_dp") )
				( member ( signalRef "@baseboard_fab2_lib.baseboard_fab2(sch_1):clk_100m_cpu1_pe_refclk_r_dn") )
				( member ( signalRef "@baseboard_fab2_lib.baseboard_fab2(sch_1):clk_100m_cpu1_pe_refclk_r_dp") )
				( member ( signalRef "@baseboard_fab2_lib.baseboard_fab2(sch_1):clk_100m_cpu1_rc_refclk0_dn") )
				( member ( signalRef "@baseboard_fab2_lib.baseboard_fab2(sch_1):clk_100m_cpu1_rc_refclk0_dp") )
				( member ( signalRef "@baseboard_fab2_lib.baseboard_fab2(sch_1):clk_100m_cpu1_rc_refclk0_r_dn") )
				( member ( signalRef "@baseboard_fab2_lib.baseboard_fab2(sch_1):clk_100m_cpu1_rc_refclk0_r_dp") )
				( objectStatus "SNCLS_CLK_DIFF_100M" )
			)
			( netClass "@sapphirecity_baseboard_lib.sapphirecity_baseboard(sch_1):\CLK_SE_48_50M\"
				( memberType ( signal ) )
				( spacingCSetRef "@sapphirecity_baseboard_lib.sapphirecity_baseboard(sch_1):\7H_US_AND_3H_SL\" )
				( sameNetSpacingCSetRef "@crescent_city_bb_fab1_lib.crescent_city_bb_fab1(sch_1):\24MIL_US&15MIL_SL\" )
				( objectFlag fObjectSpacing )
				( objectFlag fObjectSameNetSpacing )
				( member ( signalRef "@baseboard_fab2_lib.baseboard_fab2(sch_1):clk_50m_ckmng_bmc_2") )
				( member ( signalRef "@baseboard_fab2_lib.baseboard_fab2(sch_1):clk_50m_ckmng_bmc_2_r") )
				( member ( signalRef "@baseboard_fab2_lib.baseboard_fab2(sch_1):clk_50m_ckmng_sprvlle") )
				( member ( signalRef "@baseboard_fab2_lib.baseboard_fab2(sch_1):clk_50m_ckmng_sprvlle_r") )
				( member ( signalRef "@baseboard_fab2_lib.baseboard_fab2(sch_1):clk_25m_cpld") )
				( member ( signalRef "@baseboard_fab2_lib.baseboard_fab2(sch_1):clk_25m_cpld_r") )
				( member ( signalRef "@baseboard_fab2_lib.baseboard_fab2(sch_1):clk_24m_bmc_lpc") )
				( member ( signalRef "@baseboard_fab2_lib.baseboard_fab2(sch_1):clk_24m_bmc_lpc_r") )
				( member ( signalRef "@baseboard_fab2_lib.baseboard_fab2(sch_1):clk_25m_bmc") )
				( member ( signalRef "@baseboard_fab2_lib.baseboard_fab2(sch_1):clk_25m_bmc_r") )
				( member ( signalRef "@baseboard_fab2_lib.baseboard_fab2(sch_1):clk_32k_susclk_pld") )
				( member ( signalRef "@baseboard_fab2_lib.baseboard_fab2(sch_1):clk_32k_susclk_pld_r") )
				( member ( signalRef "@baseboard_fab2_lib.baseboard_fab2(sch_1):clk_48m_usb_bmc") )
				( member ( signalRef "@baseboard_fab2_lib.baseboard_fab2(sch_1):clk_50m_ckmng_bmc_1") )
				( member ( signalRef "@baseboard_fab2_lib.baseboard_fab2(sch_1):clk_50m_ckmng_bmc_1_r") )
				( member ( signalRef "@baseboard_fab2_lib.baseboard_fab2(sch_1):clk_50m_ckmng_ocp") )
				( member ( signalRef "@baseboard_fab2_lib.baseboard_fab2(sch_1):clk_50m_ckmng_ocp_r") )
				( member ( signalRef "@baseboard_fab2_lib.baseboard_fab2(sch_1):clk_50m_ckmng_pch_10gbe") )
				( member ( signalRef "@baseboard_fab2_lib.baseboard_fab2(sch_1):clk_50m_ckmng_pch_10gbe_r") )
				( member ( signalRef "@baseboard_fab2_lib.baseboard_fab2(sch_1):h_pmsync_clk_24m") )
				( member ( signalRef "@baseboard_fab2_lib.baseboard_fab2(sch_1):h_pmsync_clk_24m_cpu0") )
				( member ( signalRef "@baseboard_fab2_lib.baseboard_fab2(sch_1):h_pmsync_clk_24m_cpu1") )
				( member ( signalRef "@baseboard_fab2_lib.baseboard_fab2(sch_1):h_pmsync_clk_24m_r") )
				( member ( signalRef "@baseboard_fab2_lib.baseboard_fab2(sch_1):clk_24m_bmc_clkin_r") )
				( member ( signalRef "@baseboard_fab2_lib.baseboard_fab2(sch_1):clk_24m_25m_bmc_clkin") )
				( member ( electricalNetRef "@crescent_city_bb_fab1_lib.crescent_city_bb_fab1(sch_1):clk_24m_bmc_lpc") )
				( member ( electricalNetRef "@crescent_city_bb_fab1_lib.crescent_city_bb_fab1(sch_1):clk_25m_bmc") )
				( member ( electricalNetRef "@crescent_city_bb_fab1_lib.crescent_city_bb_fab1(sch_1):clk_32k_susclk_pld") )
				( member ( electricalNetRef "@crescent_city_bb_fab1_lib.crescent_city_bb_fab1(sch_1):clk_50m_ckmng_bmc_1") )
				( member ( electricalNetRef "@crescent_city_bb_fab1_lib.crescent_city_bb_fab1(sch_1):clk_50m_ckmng_bmc_2") )
				( member ( electricalNetRef "@crescent_city_bb_fab1_lib.crescent_city_bb_fab1(sch_1):clk_50m_ckmng_ocp") )
				( member ( electricalNetRef "@crescent_city_bb_fab1_lib.crescent_city_bb_fab1(sch_1):clk_50m_ckmng_sprvlle") )
				( member ( electricalNetRef "@crescent_city_bb_fab1_lib.crescent_city_bb_fab1(sch_1):clk_50m_nic") )
				( member ( electricalNetRef "@crescent_city_bb_fab1_lib.crescent_city_bb_fab1(sch_1):h_pmsync_clk_24m_cpu0") )
				( member ( electricalNetRef "@crescent_city_bb_fab1_lib.crescent_city_bb_fab1(sch_1):clk_25m_cpld") )
				( objectStatus "SNCLS_CLK_SE_25_50M" )
			)
			( netClass "@sapphirecity_baseboard_lib.sapphirecity_baseboard(sch_1):\SATA6G_TX\"
				( memberType ( signal ) )
				( spacingCSetRef "@crescent_city_bb_fab1_lib.crescent_city_bb_fab1(sch_1):\24MIL_US_&_21MIL_SL\" )
				( sameNetSpacingCSetRef "@crescent_city_bb_fab1_lib.crescent_city_bb_fab1(sch_1):\7H_US_AND_5H_SL\" )
				( objectFlag fObjectSpacing )
				( objectFlag fObjectSameNetSpacing )
				( member ( diffPairRef "@crescent_city_bb_fab1_lib.crescent_city_bb_fab1(sch_1):\P3E_PCH_M2_SATA6G_TX_D\") )
				( member ( diffPairRef "@crescent_city_bb_fab1_lib.crescent_city_bb_fab1(sch_1):\DP_87\") )
				( member ( diffPairRef "@crescent_city_bb_fab1_lib.crescent_city_bb_fab1(sch_1):\DP_88\") )
				( member ( diffPairRef "@crescent_city_bb_fab1_lib.crescent_city_bb_fab1(sch_1):\DP_89\") )
				( member ( diffPairRef "@crescent_city_bb_fab1_lib.crescent_city_bb_fab1(sch_1):\DP_90\") )
				( member ( diffPairRef "@crescent_city_bb_fab1_lib.crescent_city_bb_fab1(sch_1):\DP_91\") )
				( member ( diffPairRef "@crescent_city_bb_fab1_lib.crescent_city_bb_fab1(sch_1):\DP_92\") )
				( member ( diffPairRef "@crescent_city_bb_fab1_lib.crescent_city_bb_fab1(sch_1):\DP_93\") )
				( member ( diffPairRef "@crescent_city_bb_fab1_lib.crescent_city_bb_fab1(sch_1):\DP_94\") )
				( member ( diffPairRef "@crescent_city_bb_fab1_lib.crescent_city_bb_fab1(sch_1):\DP_100\") )
				( member ( diffPairRef "@crescent_city_bb_fab1_lib.crescent_city_bb_fab1(sch_1):\DP_101\") )
				( member ( diffPairRef "@crescent_city_bb_fab1_lib.crescent_city_bb_fab1(sch_1):\DP_102\") )
				( member ( diffPairRef "@crescent_city_bb_fab1_lib.crescent_city_bb_fab1(sch_1):\DP_103\") )
				( member ( diffPairRef "@crescent_city_bb_fab1_lib.crescent_city_bb_fab1(sch_1):\DP_104\") )
				( member ( signalRef "@baseboard_fab2_lib.baseboard_fab2(sch_1):sata6g_s0_tx_dn") )
				( member ( signalRef "@baseboard_fab2_lib.baseboard_fab2(sch_1):sata6g_s0_tx_dp") )
				( objectStatus "SNCLS_SATA6G_TX" )
			)
			( netClass "@sapphirecity_baseboard_lib.sapphirecity_baseboard(sch_1):\USB3_RX\"
				( memberType ( signal ) )
				( spacingCSetRef "@crescent_city_bb_fab1_lib.crescent_city_bb_fab1(sch_1):\11H_US_&_7H_SL_VIA+3H_A\" )
				( sameNetSpacingCSetRef "@crescent_city_bb_fab1_lib.crescent_city_bb_fab1(sch_1):\7H_US_AND_5H_SL\" )
				( objectFlag fObjectSpacing )
				( objectFlag fObjectSameNetSpacing )
				( member ( diffPairRef "@crescent_city_bb_fab1_lib.crescent_city_bb_fab1(sch_1):\DP_USB3_P01_RX\") )
				( member ( signalRef "@baseboard_fab2_lib.baseboard_fab2(sch_1):usb3_p01_fb_rxn") )
				( member ( signalRef "@baseboard_fab2_lib.baseboard_fab2(sch_1):usb3_p01_fb_rxp") )
				( member ( signalRef "@baseboard_fab2_lib.baseboard_fab2(sch_1):usb3_p01_rxn") )
				( member ( signalRef "@baseboard_fab2_lib.baseboard_fab2(sch_1):usb3_p01_rxp") )
				( objectStatus "SNCLS_USB3_RX" )
			)
			( netClass "@sapphirecity_baseboard_lib.sapphirecity_baseboard(sch_1):\SATA6G_RX\"
				( memberType ( signal ) )
				( spacingCSetRef "@crescent_city_bb_fab1_lib.crescent_city_bb_fab1(sch_1):\24MIL_US_&_21MIL_SL\" )
				( sameNetSpacingCSetRef "@crescent_city_bb_fab1_lib.crescent_city_bb_fab1(sch_1):\7H_US_AND_5H_SL\" )
				( objectFlag fObjectSpacing )
				( objectFlag fObjectSameNetSpacing )
				( member ( diffPairRef "@crescent_city_bb_fab1_lib.crescent_city_bb_fab1(sch_1):\P3E_PCH_M2_SATA6G_RX_D\") )
				( member ( diffPairRef "@crescent_city_bb_fab1_lib.crescent_city_bb_fab1(sch_1):\DP_79\") )
				( member ( diffPairRef "@crescent_city_bb_fab1_lib.crescent_city_bb_fab1(sch_1):\DP_80\") )
				( member ( diffPairRef "@crescent_city_bb_fab1_lib.crescent_city_bb_fab1(sch_1):\DP_82\") )
				( member ( diffPairRef "@crescent_city_bb_fab1_lib.crescent_city_bb_fab1(sch_1):\DP_85\") )
				( member ( diffPairRef "@crescent_city_bb_fab1_lib.crescent_city_bb_fab1(sch_1):\DP_86\") )
				( member ( diffPairRef "@crescent_city_bb_fab1_lib.crescent_city_bb_fab1(sch_1):\DP_95\") )
				( member ( diffPairRef "@crescent_city_bb_fab1_lib.crescent_city_bb_fab1(sch_1):\DP_96\") )
				( member ( diffPairRef "@crescent_city_bb_fab1_lib.crescent_city_bb_fab1(sch_1):\DP_97\") )
				( member ( diffPairRef "@crescent_city_bb_fab1_lib.crescent_city_bb_fab1(sch_1):\DP_98\") )
				( member ( diffPairRef "@crescent_city_bb_fab1_lib.crescent_city_bb_fab1(sch_1):\DP_99\") )
				( member ( diffPairRef "@crescent_city_bb_fab1_lib.crescent_city_bb_fab1(sch_1):\DP_81\") )
				( member ( diffPairRef "@crescent_city_bb_fab1_lib.crescent_city_bb_fab1(sch_1):\DP_83\") )
				( member ( diffPairRef "@crescent_city_bb_fab1_lib.crescent_city_bb_fab1(sch_1):\DP_84\") )
				( member ( signalRef "@baseboard_fab2_lib.baseboard_fab2(sch_1):sata6g_pch_pcie_up_sata_rxn(0)") )
				( member ( signalRef "@baseboard_fab2_lib.baseboard_fab2(sch_1):sata6g_pch_pcie_up_sata_rxn(1)") )
				( member ( signalRef "@baseboard_fab2_lib.baseboard_fab2(sch_1):sata6g_pch_pcie_up_sata_rxn(2)") )
				( member ( signalRef "@baseboard_fab2_lib.baseboard_fab2(sch_1):sata6g_pch_pcie_up_sata_rxn(3)") )
				( member ( signalRef "@baseboard_fab2_lib.baseboard_fab2(sch_1):sata6g_pch_pcie_up_sata_rxp(0)") )
				( member ( signalRef "@baseboard_fab2_lib.baseboard_fab2(sch_1):sata6g_pch_pcie_up_sata_rxp(1)") )
				( member ( signalRef "@baseboard_fab2_lib.baseboard_fab2(sch_1):sata6g_pch_pcie_up_sata_rxp(2)") )
				( member ( signalRef "@baseboard_fab2_lib.baseboard_fab2(sch_1):sata6g_pch_pcie_up_sata_rxp(3)") )
				( member ( signalRef "@baseboard_fab2_lib.baseboard_fab2(sch_1):sata6g_p0_rx_c_dn") )
				( member ( signalRef "@baseboard_fab2_lib.baseboard_fab2(sch_1):sata6g_p0_rx_c_dp") )
				( member ( signalRef "@baseboard_fab2_lib.baseboard_fab2(sch_1):sata6g_p1_rx_c_dn") )
				( member ( signalRef "@baseboard_fab2_lib.baseboard_fab2(sch_1):sata6g_p1_rx_c_dp") )
				( member ( signalRef "@baseboard_fab2_lib.baseboard_fab2(sch_1):sata6g_p2_rx_c_dn") )
				( member ( signalRef "@baseboard_fab2_lib.baseboard_fab2(sch_1):sata6g_p2_rx_c_dp") )
				( member ( signalRef "@baseboard_fab2_lib.baseboard_fab2(sch_1):sata6g_p3_rx_c_dn") )
				( member ( signalRef "@baseboard_fab2_lib.baseboard_fab2(sch_1):sata6g_p3_rx_c_dp") )
				( member ( electricalNetRef "@crescent_city_bb_fab1_lib.crescent_city_bb_fab1(sch_1):sata6g_p2_rx_c_dp") )
				( objectStatus "SNCLS_SATA6G_RX" )
			)
			( netClass "@sapphirecity_baseboard_lib.sapphirecity_baseboard(sch_1):\DIGITAL_DEBUG\"
				( memberType ( signal ) )
				( spacingCSetRef "@sapphirecity_baseboard_lib.sapphirecity_baseboard(sch_1):\3H\" )
				( sameNetSpacingCSetRef "@crescent_city_bb_fab1_lib.crescent_city_bb_fab1(sch_1):\3H\" )
				( objectFlag fObjectSpacing )
				( objectFlag fObjectSameNetSpacing )
				( objectStatus "DIGITAL_DEBUG" )
			)
			( netClass "@sapphirecity_baseboard_lib.sapphirecity_baseboard(sch_1):\BMC_DDR3_ADR_CMD_CTRL\"
				( memberType ( signal ) )
				( spacingCSetRef "@sapphirecity_baseboard_lib.sapphirecity_baseboard(sch_1):\20_MILS\" )
				( sameNetSpacingCSetRef "@crescent_city_bb_fab1_lib.crescent_city_bb_fab1(sch_1):\20_MILS_US_&_15_MILS_SL\" )
				( objectFlag fObjectSpacing )
				( objectFlag fObjectSameNetSpacing )
				( member ( signalRef "@baseboard_fab2_lib.baseboard_fab2(sch_1):m_bmc_ddr3_ma(0)") )
				( member ( signalRef "@baseboard_fab2_lib.baseboard_fab2(sch_1):m_bmc_ddr3_ma(1)") )
				( member ( signalRef "@baseboard_fab2_lib.baseboard_fab2(sch_1):m_bmc_ddr3_ma(2)") )
				( member ( signalRef "@baseboard_fab2_lib.baseboard_fab2(sch_1):m_bmc_ddr3_ma(3)") )
				( member ( signalRef "@baseboard_fab2_lib.baseboard_fab2(sch_1):m_bmc_ddr3_ma(4)") )
				( member ( signalRef "@baseboard_fab2_lib.baseboard_fab2(sch_1):m_bmc_ddr3_ma(5)") )
				( member ( signalRef "@baseboard_fab2_lib.baseboard_fab2(sch_1):m_bmc_ddr3_ma(6)") )
				( member ( signalRef "@baseboard_fab2_lib.baseboard_fab2(sch_1):m_bmc_ddr3_ma(7)") )
				( member ( signalRef "@baseboard_fab2_lib.baseboard_fab2(sch_1):m_bmc_ddr3_ma(8)") )
				( member ( signalRef "@baseboard_fab2_lib.baseboard_fab2(sch_1):m_bmc_ddr3_ma(9)") )
				( member ( signalRef "@baseboard_fab2_lib.baseboard_fab2(sch_1):m_bmc_ddr3_ma(10)") )
				( member ( signalRef "@baseboard_fab2_lib.baseboard_fab2(sch_1):m_bmc_ddr3_ma(11)") )
				( member ( signalRef "@baseboard_fab2_lib.baseboard_fab2(sch_1):m_bmc_ddr3_ma(12)") )
				( member ( signalRef "@baseboard_fab2_lib.baseboard_fab2(sch_1):m_bmc_ddr3_mba_0") )
				( member ( signalRef "@baseboard_fab2_lib.baseboard_fab2(sch_1):m_bmc_ddr3_mba_1") )
				( member ( signalRef "@baseboard_fab2_lib.baseboard_fab2(sch_1):m_bmc_ddr3_mba_2") )
				( member ( signalRef "@baseboard_fab2_lib.baseboard_fab2(sch_1):m_bmc_ddr3_mcas_n") )
				( member ( signalRef "@baseboard_fab2_lib.baseboard_fab2(sch_1):m_bmc_ddr3_mcke") )
				( member ( signalRef "@baseboard_fab2_lib.baseboard_fab2(sch_1):m_bmc_ddr3_mcs_n") )
				( member ( signalRef "@baseboard_fab2_lib.baseboard_fab2(sch_1):m_bmc_ddr3_modt") )
				( member ( signalRef "@baseboard_fab2_lib.baseboard_fab2(sch_1):m_bmc_ddr3_mras_n") )
				( member ( signalRef "@baseboard_fab2_lib.baseboard_fab2(sch_1):m_bmc_ddr3_mwe_n") )
				( member ( signalRef "@baseboard_fab2_lib.baseboard_fab2(sch_1):m_bmc_ddr3_ma(13)") )
				( member ( signalRef "@baseboard_fab2_lib.baseboard_fab2(sch_1):m_bmc_ddr3_ma(14)") )
				( objectStatus "SNCLS_BMC_DDR3_ADR_CMD_CTRL" )
			)
			( netClass "@sapphirecity_baseboard_lib.sapphirecity_baseboard(sch_1):\BMC_DDR3_CLKDIFF\"
				( memberType ( signal ) )
				( spacingCSetRef "@sapphirecity_baseboard_lib.sapphirecity_baseboard(sch_1):\20_MILS\" )
				( sameNetSpacingCSetRef "@crescent_city_bb_fab1_lib.crescent_city_bb_fab1(sch_1):\20_MILS_US_&_15_MILS_SL\" )
				( objectFlag fObjectSpacing )
				( objectFlag fObjectSameNetSpacing )
				( member ( diffPairRef "@crescent_city_bb_fab1_lib.crescent_city_bb_fab1(sch_1):\M_BMC_DDR3_MCK_\") )
				( objectStatus "SNCLS_BMC_DDR3_CLKDIFF" )
			)
			( netClass "@sapphirecity_baseboard_lib.sapphirecity_baseboard(sch_1):\BMC_DDR3_DQS\"
				( memberType ( signal ) )
				( spacingCSetRef "@sapphirecity_baseboard_lib.sapphirecity_baseboard(sch_1):\20_MILS\" )
				( sameNetSpacingCSetRef "@crescent_city_bb_fab1_lib.crescent_city_bb_fab1(sch_1):\20_MILS_US_&_15_MILS_SL\" )
				( objectFlag fObjectSpacing )
				( objectFlag fObjectSameNetSpacing )
				( member ( diffPairRef "@crescent_city_bb_fab1_lib.crescent_city_bb_fab1(sch_1):\DP_V_M_BMC_DDR3_DQS0\") )
				( member ( diffPairRef "@crescent_city_bb_fab1_lib.crescent_city_bb_fab1(sch_1):\DP_V_M_BMC_DDR3_DQS1\") )
				( objectStatus "SNCLS_BMC_DDR3_DQS" )
			)
			( netClass "@sapphirecity_baseboard_lib.sapphirecity_baseboard(sch_1):\BMC_DDR3_DATA_BYTE2\"
				( memberType ( signal ) )
				( spacingCSetRef "@sapphirecity_baseboard_lib.sapphirecity_baseboard(sch_1):\20_MILS\" )
				( sameNetSpacingCSetRef "@crescent_city_bb_fab1_lib.crescent_city_bb_fab1(sch_1):\20_MILS_US_&_15_MILS_SL\" )
				( objectFlag fObjectSpacing )
				( objectFlag fObjectSameNetSpacing )
				( member ( signalRef "@baseboard_fab2_lib.baseboard_fab2(sch_1):m_bmc_ddr3_dq(8)") )
				( member ( signalRef "@baseboard_fab2_lib.baseboard_fab2(sch_1):m_bmc_ddr3_dq(9)") )
				( member ( signalRef "@baseboard_fab2_lib.baseboard_fab2(sch_1):m_bmc_ddr3_dq(10)") )
				( member ( signalRef "@baseboard_fab2_lib.baseboard_fab2(sch_1):m_bmc_ddr3_dq(11)") )
				( member ( signalRef "@baseboard_fab2_lib.baseboard_fab2(sch_1):m_bmc_ddr3_dq(12)") )
				( member ( signalRef "@baseboard_fab2_lib.baseboard_fab2(sch_1):m_bmc_ddr3_dq(13)") )
				( member ( signalRef "@baseboard_fab2_lib.baseboard_fab2(sch_1):m_bmc_ddr3_dq(14)") )
				( member ( signalRef "@baseboard_fab2_lib.baseboard_fab2(sch_1):m_bmc_ddr3_dq(15)") )
				( member ( signalRef "@baseboard_fab2_lib.baseboard_fab2(sch_1):m_bmc_ddr3_mdm_1") )
				( objectStatus "SNCLS_BMC_DDR3_DATA_BYTE2" )
			)
			( netClass "@sapphirecity_baseboard_lib.sapphirecity_baseboard(sch_1):\BMC_DDR3_DATA_BYTE1\"
				( memberType ( signal ) )
				( spacingCSetRef "@sapphirecity_baseboard_lib.sapphirecity_baseboard(sch_1):\20_MILS\" )
				( sameNetSpacingCSetRef "@crescent_city_bb_fab1_lib.crescent_city_bb_fab1(sch_1):\20_MILS_US_&_15_MILS_SL\" )
				( objectFlag fObjectSpacing )
				( objectFlag fObjectSameNetSpacing )
				( member ( signalRef "@baseboard_fab2_lib.baseboard_fab2(sch_1):m_bmc_ddr3_dq(0)") )
				( member ( signalRef "@baseboard_fab2_lib.baseboard_fab2(sch_1):m_bmc_ddr3_dq(1)") )
				( member ( signalRef "@baseboard_fab2_lib.baseboard_fab2(sch_1):m_bmc_ddr3_dq(2)") )
				( member ( signalRef "@baseboard_fab2_lib.baseboard_fab2(sch_1):m_bmc_ddr3_dq(3)") )
				( member ( signalRef "@baseboard_fab2_lib.baseboard_fab2(sch_1):m_bmc_ddr3_dq(4)") )
				( member ( signalRef "@baseboard_fab2_lib.baseboard_fab2(sch_1):m_bmc_ddr3_dq(5)") )
				( member ( signalRef "@baseboard_fab2_lib.baseboard_fab2(sch_1):m_bmc_ddr3_dq(6)") )
				( member ( signalRef "@baseboard_fab2_lib.baseboard_fab2(sch_1):m_bmc_ddr3_dq(7)") )
				( member ( signalRef "@baseboard_fab2_lib.baseboard_fab2(sch_1):m_bmc_ddr3_mdm_0") )
				( objectStatus "SNCLS_BMC_DDR3_DATA_BYTE1" )
			)
			( netClass "@sapphirecity_baseboard_lib.sapphirecity_baseboard(sch_1):\BMC_DDR3_COMP\"
				( memberType ( signal ) )
				( spacingCSetRef "@sapphirecity_baseboard_lib.sapphirecity_baseboard(sch_1):\20_MILS\" )
				( sameNetSpacingCSetRef "@crescent_city_bb_fab1_lib.crescent_city_bb_fab1(sch_1):\20_MILS_US_&_15_MILS_SL\" )
				( objectFlag fObjectSpacing )
				( objectFlag fObjectSameNetSpacing )
				( objectStatus "SNCLS_BMC_DDR3_VREF" )
			)
			( netClass "@sapphirecity_baseboard_lib.sapphirecity_baseboard(sch_1):\BMC_DDR3_RST\"
				( memberType ( signal ) )
				( spacingCSetRef "@sapphirecity_baseboard_lib.sapphirecity_baseboard(sch_1):\20_MILS\" )
				( sameNetSpacingCSetRef "@crescent_city_bb_fab1_lib.crescent_city_bb_fab1(sch_1):\20_MILS_US_&_15_MILS_SL\" )
				( objectFlag fObjectSpacing )
				( objectFlag fObjectSameNetSpacing )
				( objectStatus "SNCLS_BMC_DDR3_RST" )
			)
			( netClass "@sapphirecity_baseboard_lib.sapphirecity_baseboard(sch_1):\XTAL_EXT\"
				( memberType ( signal ) )
				( spacingCSetRef "@sapphirecity_baseboard_lib.sapphirecity_baseboard(sch_1):\20_MILS\" )
				( sameNetSpacingCSetRef "@crescent_city_bb_fab1_lib.crescent_city_bb_fab1(sch_1):\20_MIL\" )
				( objectFlag fObjectSpacing )
				( objectFlag fObjectSameNetSpacing )
				( objectStatus "XTAL_EXT" )
			)
			( netClass "@sapphirecity_baseboard_lib.sapphirecity_baseboard(sch_1):\WBG_PLLS\"
				( memberType ( signal ) )
				( spacingCSetRef "@sapphirecity_baseboard_lib.sapphirecity_baseboard(sch_1):\10MIL\" )
				( sameNetSpacingCSetRef "@crescent_city_bb_fab1_lib.crescent_city_bb_fab1(sch_1):\10_MILS\" )
				( objectFlag fObjectSpacing )
				( objectFlag fObjectSameNetSpacing )
				( objectStatus "WBG_PLLS" )
			)
			( netClass "@sapphirecity_baseboard_lib.sapphirecity_baseboard(sch_1):\VR_VSENSE\"
				( memberType ( signal ) )
				( objectFlag fObjectSpacing )
				( objectFlag fObjectSameNetSpacing )
				( objectStatus "VR_VSENSE" )
			)
			( netClass "@sapphirecity_baseboard_lib.sapphirecity_baseboard(sch_1):\VR_VCCIN_CPU0\"
				( memberType ( signal ) )
				( objectFlag fObjectSpacing )
				( objectFlag fObjectSameNetSpacing )
				( objectStatus "VR_VCCIN_CPU0" )
			)
			( netClass "@sapphirecity_baseboard_lib.sapphirecity_baseboard(sch_1):\VR_P2V5_AUX\"
				( memberType ( signal ) )
				( objectFlag fObjectSpacing )
				( objectFlag fObjectSameNetSpacing )
				( objectStatus "VR_P2V5_AUX" )
			)
			( netClass "@sapphirecity_baseboard_lib.sapphirecity_baseboard(sch_1):\VR_P1V2_AUX\"
				( memberType ( signal ) )
				( objectFlag fObjectSpacing )
				( objectFlag fObjectSameNetSpacing )
				( objectStatus "VR_P1V2_AUX" )
			)
			( netClass "@sapphirecity_baseboard_lib.sapphirecity_baseboard(sch_1):\VR_P0V95\"
				( memberType ( signal ) )
				( objectFlag fObjectSpacing )
				( objectFlag fObjectSameNetSpacing )
				( objectStatus "VR_P0V95" )
			)
			( netClass "@sapphirecity_baseboard_lib.sapphirecity_baseboard(sch_1):\VR_P0V75\"
				( memberType ( signal ) )
				( objectFlag fObjectSpacing )
				( objectFlag fObjectSameNetSpacing )
				( objectStatus "VR_P0V75" )
			)
			( netClass "@sapphirecity_baseboard_lib.sapphirecity_baseboard(sch_1):\VR_P0V67\"
				( memberType ( signal ) )
				( objectFlag fObjectSpacing )
				( objectFlag fObjectSameNetSpacing )
				( objectStatus "VR_P0V67" )
			)
			( netClass "@sapphirecity_baseboard_lib.sapphirecity_baseboard(sch_1):\VR_P0V8\"
				( memberType ( signal ) )
				( objectFlag fObjectSpacing )
				( objectFlag fObjectSameNetSpacing )
				( objectStatus "VR_P0V8" )
			)
			( netClass "@sapphirecity_baseboard_lib.sapphirecity_baseboard(sch_1):\VR_PVPP_GH\"
				( memberType ( signal ) )
				( objectFlag fObjectSpacing )
				( objectFlag fObjectSameNetSpacing )
				( objectStatus "VR_PVPP_GH" )
			)
			( netClass "@sapphirecity_baseboard_lib.sapphirecity_baseboard(sch_1):\VR_PVPP_EF\"
				( memberType ( signal ) )
				( objectFlag fObjectSpacing )
				( objectFlag fObjectSameNetSpacing )
				( objectStatus "VR_PVPP_EF" )
			)
			( netClass "@sapphirecity_baseboard_lib.sapphirecity_baseboard(sch_1):\VR_PVPP_AB\"
				( memberType ( signal ) )
				( objectFlag fObjectSpacing )
				( objectFlag fObjectSameNetSpacing )
				( objectStatus "VR_PVPP_AB" )
			)
			( netClass "@sapphirecity_baseboard_lib.sapphirecity_baseboard(sch_1):\VR_PVPP\"
				( memberType ( signal ) )
				( objectFlag fObjectSpacing )
				( objectFlag fObjectSameNetSpacing )
				( objectStatus "VR_PVPP" )
			)
			( netClass "@sapphirecity_baseboard_lib.sapphirecity_baseboard(sch_1):\VR_PVDDQ_CD\"
				( memberType ( signal ) )
				( objectFlag fObjectSpacing )
				( objectFlag fObjectSameNetSpacing )
				( objectStatus "VR_PVDDQ_CD" )
			)
			( netClass "@sapphirecity_baseboard_lib.sapphirecity_baseboard(sch_1):\VR_PVDDQ_AB\"
				( memberType ( signal ) )
				( objectFlag fObjectSpacing )
				( objectFlag fObjectSameNetSpacing )
				( objectStatus "VR_PVDDQ_AB" )
			)
			( netClass "@sapphirecity_baseboard_lib.sapphirecity_baseboard(sch_1):\VR_PCH\"
				( memberType ( signal ) )
				( objectFlag fObjectSpacing )
				( objectFlag fObjectSameNetSpacing )
				( objectStatus "VR_PCH" )
			)
			( netClass "@sapphirecity_baseboard_lib.sapphirecity_baseboard(sch_1):\VR_LAN\"
				( memberType ( signal ) )
				( objectFlag fObjectSpacing )
				( objectFlag fObjectSameNetSpacing )
				( objectStatus "VR_LAN" )
			)
			( netClass "@sapphirecity_baseboard_lib.sapphirecity_baseboard(sch_1):\VR_ISENSE\"
				( memberType ( signal ) )
				( spacingCSetRef "@sapphirecity_baseboard_lib.sapphirecity_baseboard(sch_1):\10MIL\" )
				( sameNetSpacingCSetRef "@crescent_city_bb_fab1_lib.crescent_city_bb_fab1(sch_1):\10_MILS\" )
				( objectFlag fObjectSpacing )
				( objectFlag fObjectSameNetSpacing )
				( objectStatus "VR_ISENSE" )
			)
			( netClass "@sapphirecity_baseboard_lib.sapphirecity_baseboard(sch_1):\SPA-B_12V\"
				( memberType ( signal ) )
				( spacingCSetRef "@sapphirecity_baseboard_lib.sapphirecity_baseboard(sch_1):\12_MIL\" )
				( sameNetSpacingCSetRef "@crescent_city_bb_fab1_lib.crescent_city_bb_fab1(sch_1):\12_MILS\" )
				( objectFlag fObjectSpacing )
				( objectFlag fObjectSameNetSpacing )
				( objectStatus "SPA-B_12V" )
			)
			( netClass "@sapphirecity_baseboard_lib.sapphirecity_baseboard(sch_1):\SPA-B_3V\"
				( memberType ( signal ) )
				( spacingCSetRef "@crescent_city_bb_fab1_lib.crescent_city_bb_fab1(sch_1):\DEFAULT\" )
				( sameNetSpacingCSetRef "@crescent_city_bb_fab1_lib.crescent_city_bb_fab1(sch_1):\DEFAULT\" )
				( objectFlag fObjectSpacing )
				( objectFlag fObjectSameNetSpacing )
				( objectStatus "SPA-B_3V" )
			)
			( netClass "@sapphirecity_baseboard_lib.sapphirecity_baseboard(sch_1):\SET2DIL\"
				( memberType ( signal ) )
				( spacingCSetRef "@crescent_city_bb_fab1_lib.crescent_city_bb_fab1(sch_1):\DEFAULT\" )
				( attribute "SN_LINE_TO_LINE_SPACING" "4.00"
					( Origin gBackEnd )
				)
				( objectFlag fObjectSpacing )
				( objectFlag fObjectSameNetSpacing )
				( member ( signalRef "@baseboard_fab2_lib.baseboard_fab2(sch_1):l1_z85_ms") )
				( member ( signalRef "@baseboard_fab2_lib.baseboard_fab2(sch_1):l3_z85_sl") )
				( member ( signalRef "@baseboard_fab2_lib.baseboard_fab2(sch_1):l1_z100_ms") )
				( member ( signalRef "@baseboard_fab2_lib.baseboard_fab2(sch_1):l12_z85_sl") )
				( member ( signalRef "@baseboard_fab2_lib.baseboard_fab2(sch_1):l14_z100_ms") )
				( member ( signalRef "@baseboard_fab2_lib.baseboard_fab2(sch_1):l14_z85_ms") )
				( member ( signalRef "@baseboard_fab2_lib.baseboard_fab2(sch_1):l1_z85_thru") )
				( member ( signalRef "@baseboard_fab2_lib.baseboard_fab2(sch_1):l5_z85_sl") )
				( member ( signalRef "@baseboard_fab2_lib.baseboard_fab2(sch_1):l10_z85_sl") )
				( objectStatus "SET2DIL" )
			)
			( netClass "@sapphirecity_baseboard_lib.sapphirecity_baseboard(sch_1):\DMI_CPU0_PCH_RX\"
				( memberType ( signal ) )
				( spacingCSetRef "@sapphirecity_baseboard_lib.sapphirecity_baseboard(sch_1):\11H_US_AND_5H_SL_VIA+3H_A\" )
				( sameNetSpacingCSetRef "@crescent_city_bb_fab1_lib.crescent_city_bb_fab1(sch_1):\7H_US_AND_5H_SL\" )
				( objectFlag fObjectSpacing )
				( objectFlag fObjectSameNetSpacing )
				( member ( diffPairRef "@crescent_city_bb_fab1_lib.crescent_city_bb_fab1(sch_1):\DP_DMI_CPU0_PCH_RX_C\(0)") )
				( member ( diffPairRef "@crescent_city_bb_fab1_lib.crescent_city_bb_fab1(sch_1):\DP_DMI_CPU0_PCH_RX_C\(1)") )
				( member ( diffPairRef "@crescent_city_bb_fab1_lib.crescent_city_bb_fab1(sch_1):\DP_DMI_CPU0_PCH_RX_C\(2)") )
				( member ( diffPairRef "@crescent_city_bb_fab1_lib.crescent_city_bb_fab1(sch_1):\DP_DMI_CPU0_PCH_RX_C\(3)") )
				( member ( signalRef "@baseboard_fab2_lib.baseboard_fab2(sch_1):dmi_cpu0_pch_rx_c_dn(0)") )
				( member ( signalRef "@baseboard_fab2_lib.baseboard_fab2(sch_1):dmi_cpu0_pch_rx_c_dn(1)") )
				( member ( signalRef "@baseboard_fab2_lib.baseboard_fab2(sch_1):dmi_cpu0_pch_rx_c_dn(2)") )
				( member ( signalRef "@baseboard_fab2_lib.baseboard_fab2(sch_1):dmi_cpu0_pch_rx_c_dn(3)") )
				( member ( signalRef "@baseboard_fab2_lib.baseboard_fab2(sch_1):dmi_cpu0_pch_rx_c_dp(0)") )
				( member ( signalRef "@baseboard_fab2_lib.baseboard_fab2(sch_1):dmi_cpu0_pch_rx_c_dp(1)") )
				( member ( signalRef "@baseboard_fab2_lib.baseboard_fab2(sch_1):dmi_cpu0_pch_rx_c_dp(2)") )
				( member ( signalRef "@baseboard_fab2_lib.baseboard_fab2(sch_1):dmi_cpu0_pch_rx_c_dp(3)") )
				( member ( signalRef "@baseboard_fab2_lib.baseboard_fab2(sch_1):dmi_cpu0_pch_rx_dn(0)") )
				( member ( signalRef "@baseboard_fab2_lib.baseboard_fab2(sch_1):dmi_cpu0_pch_rx_dn(1)") )
				( member ( signalRef "@baseboard_fab2_lib.baseboard_fab2(sch_1):dmi_cpu0_pch_rx_dn(2)") )
				( member ( signalRef "@baseboard_fab2_lib.baseboard_fab2(sch_1):dmi_cpu0_pch_rx_dn(3)") )
				( member ( signalRef "@baseboard_fab2_lib.baseboard_fab2(sch_1):dmi_cpu0_pch_rx_dp(0)") )
				( member ( signalRef "@baseboard_fab2_lib.baseboard_fab2(sch_1):dmi_cpu0_pch_rx_dp(1)") )
				( member ( signalRef "@baseboard_fab2_lib.baseboard_fab2(sch_1):dmi_cpu0_pch_rx_dp(2)") )
				( member ( signalRef "@baseboard_fab2_lib.baseboard_fab2(sch_1):dmi_cpu0_pch_rx_dp(3)") )
				( objectStatus "SNCLS_DMI_CPU0_PCH_RX" )
			)
			( netClass "@sapphirecity_baseboard_lib.sapphirecity_baseboard(sch_1):\DMI_CPU0_PCH_TX\"
				( memberType ( signal ) )
				( spacingCSetRef "@sapphirecity_baseboard_lib.sapphirecity_baseboard(sch_1):\11H_US_AND_5H_SL_VIA+3H_A\" )
				( sameNetSpacingCSetRef "@crescent_city_bb_fab1_lib.crescent_city_bb_fab1(sch_1):\7H_US_AND_5H_SL\" )
				( objectFlag fObjectSpacing )
				( objectFlag fObjectSameNetSpacing )
				( member ( diffPairRef "@sapphirecity_baseboard_lib.sapphirecity_baseboard(sch_1):\DMI_CPU0_PCH_TX_C_D\(0)") )
				( member ( diffPairRef "@sapphirecity_baseboard_lib.sapphirecity_baseboard(sch_1):\DMI_CPU0_PCH_TX_C_D\(1)") )
				( member ( diffPairRef "@sapphirecity_baseboard_lib.sapphirecity_baseboard(sch_1):\DMI_CPU0_PCH_TX_C_D\(2)") )
				( member ( diffPairRef "@sapphirecity_baseboard_lib.sapphirecity_baseboard(sch_1):\DMI_CPU0_PCH_TX_C_D\(3)") )
				( objectStatus "SNCLS_DMI_CPU0_PCH_TX" )
			)
			( netClass "@sapphirecity_baseboard_lib.sapphirecity_baseboard(sch_1):\PE_PCH_BMC_TX\"
				( memberType ( signal ) )
				( spacingCSetRef "@sapphirecity_baseboard_lib.sapphirecity_baseboard(sch_1):\11H_US_AND_5H_SL_VIA+2H_A\" )
				( sameNetSpacingCSetRef "@crescent_city_bb_fab1_lib.crescent_city_bb_fab1(sch_1):\7H_US_AND_5H_SL\" )
				( objectFlag fObjectSpacing )
				( objectFlag fObjectSameNetSpacing )
				( member ( diffPairRef "@crescent_city_bb_fab1_lib.crescent_city_bb_fab1(sch_1):\DP_78\") )
				( member ( signalRef "@baseboard_fab2_lib.baseboard_fab2(sch_1):pe_pch_sprv_tx_c_dn") )
				( member ( signalRef "@baseboard_fab2_lib.baseboard_fab2(sch_1):pe_pch_sprv_tx_c_dp") )
				( member ( signalRef "@baseboard_fab2_lib.baseboard_fab2(sch_1):pe_pch_sprv_tx_dn") )
				( member ( signalRef "@baseboard_fab2_lib.baseboard_fab2(sch_1):pe_pch_sprv_tx_dp") )
				( objectStatus "SNCLS_PE_PCH_SPRV_TX" )
			)
			( netClass "@sapphirecity_baseboard_lib.sapphirecity_baseboard(sch_1):\PE_PCH_BMC_RX\"
				( memberType ( signal ) )
				( spacingCSetRef "@sapphirecity_baseboard_lib.sapphirecity_baseboard(sch_1):\11H_US_AND_5H_SL_VIA+2H_A\" )
				( sameNetSpacingCSetRef "@crescent_city_bb_fab1_lib.crescent_city_bb_fab1(sch_1):\7H_US_AND_5H_SL\" )
				( objectFlag fObjectSpacing )
				( objectFlag fObjectSameNetSpacing )
				( member ( diffPairRef "@crescent_city_bb_fab1_lib.crescent_city_bb_fab1(sch_1):\PE_PCH_SPRV_RX_D\") )
				( member ( signalRef "@baseboard_fab2_lib.baseboard_fab2(sch_1):pe_pch_sprv_rx_c_dn") )
				( member ( signalRef "@baseboard_fab2_lib.baseboard_fab2(sch_1):pe_pch_sprv_rx_c_dp") )
				( member ( signalRef "@baseboard_fab2_lib.baseboard_fab2(sch_1):pe_pch_sprv_rx_dn") )
				( member ( signalRef "@baseboard_fab2_lib.baseboard_fab2(sch_1):pe_pch_sprv_rx_dp") )
				( objectStatus "SNCLS_PE_PCH_SPRV_RX" )
			)
			( netClass "@sapphirecity_baseboard_lib.sapphirecity_baseboard(sch_1):\HOT_PLUG\"
				( memberType ( signal ) )
				( spacingCSetRef "@sapphirecity_baseboard_lib.sapphirecity_baseboard(sch_1):\8_MILS\" )
				( sameNetSpacingCSetRef "@crescent_city_bb_fab1_lib.crescent_city_bb_fab1(sch_1):\8_MILS\" )
				( objectFlag fObjectSpacing )
				( objectFlag fObjectSameNetSpacing )
				( objectStatus "HOT_PLUG" )
			)
			( netClass "@sapphirecity_baseboard_lib.sapphirecity_baseboard(sch_1):\GSX\"
				( memberType ( signal ) )
				( spacingCSetRef "@sapphirecity_baseboard_lib.sapphirecity_baseboard(sch_1):\10MIL\" )
				( sameNetSpacingCSetRef "@crescent_city_bb_fab1_lib.crescent_city_bb_fab1(sch_1):\10_MILS\" )
				( objectFlag fObjectSpacing )
				( objectFlag fObjectSameNetSpacing )
				( objectStatus "GSX" )
			)
			( netClass "@sapphirecity_baseboard_lib.sapphirecity_baseboard(sch_1):\RCOMP_ALL\"
				( memberType ( signal ) )
				( spacingCSetRef "@sapphirecity_baseboard_lib.sapphirecity_baseboard(sch_1):\4H\" )
				( sameNetSpacingCSetRef "@crescent_city_bb_fab1_lib.crescent_city_bb_fab1(sch_1):\4H\" )
				( objectFlag fObjectSpacing )
				( objectFlag fObjectSameNetSpacing )
				( objectStatus "RCOMP_ALL" )
			)
			( netClass "@sapphirecity_baseboard_lib.sapphirecity_baseboard(sch_1):\ANALOG_SIG-DIFF\"
				( memberType ( signal ) )
				( spacingCSetRef "@sapphirecity_baseboard_lib.sapphirecity_baseboard(sch_1):\2.5H_US_AND_2H_SL\" )
				( sameNetSpacingCSetRef "@crescent_city_bb_fab1_lib.crescent_city_bb_fab1(sch_1):\2.5H_US_AND_2H_SL\" )
				( objectFlag fObjectSpacing )
				( objectFlag fObjectSameNetSpacing )
				( objectStatus "ANALOG_SIG-DIFF" )
			)
			( netClass "@sapphirecity_baseboard_lib.sapphirecity_baseboard(sch_1):\DDR_VREFDQRX\"
				( memberType ( signal ) )
				( spacingCSetRef "@sapphirecity_baseboard_lib.sapphirecity_baseboard(sch_1):\20_MILS\" )
				( sameNetSpacingCSetRef "@crescent_city_bb_fab1_lib.crescent_city_bb_fab1(sch_1):\20_MIL\" )
				( objectFlag fObjectSpacing )
				( objectFlag fObjectSameNetSpacing )
				( objectStatus "DDR_VREFDQRX" )
			)
			( netClass "@sapphirecity_baseboard_lib.sapphirecity_baseboard(sch_1):\ANALOG_SIG-SE\"
				( memberType ( signal ) )
				( spacingCSetRef "@sapphirecity_baseboard_lib.sapphirecity_baseboard(sch_1):\2.5H_US_AND_2H_SL\" )
				( sameNetSpacingCSetRef "@crescent_city_bb_fab1_lib.crescent_city_bb_fab1(sch_1):\2.5H_US_AND_2H_SL\" )
				( objectFlag fObjectSpacing )
				( objectFlag fObjectSameNetSpacing )
				( objectStatus "ANALOG_SIG-SE" )
			)
			( netClass "@sapphirecity_baseboard_lib.sapphirecity_baseboard(sch_1):\AGND\"
				( memberType ( signal ) )
				( spacingCSetRef "@crescent_city_bb_fab1_lib.crescent_city_bb_fab1(sch_1):\DEFAULT\" )
				( sameNetSpacingCSetRef "@crescent_city_bb_fab1_lib.crescent_city_bb_fab1(sch_1):\DEFAULT\" )
				( objectFlag fObjectSpacing )
				( objectFlag fObjectSameNetSpacing )
				( objectStatus "AGND" )
			)
			( netClass "@sapphirecity_baseboard_lib.sapphirecity_baseboard(sch_1):\AUDIO_AZALIA\"
				( memberType ( signal ) )
				( spacingCSetRef "@sapphirecity_baseboard_lib.sapphirecity_baseboard(sch_1):\2.5H_US_AND_2H_SL\" )
				( sameNetSpacingCSetRef "@crescent_city_bb_fab1_lib.crescent_city_bb_fab1(sch_1):\2.5H_US_AND_2H_SL\" )
				( objectFlag fObjectSpacing )
				( objectFlag fObjectSameNetSpacing )
				( objectStatus "AUDIO_AZALIA" )
			)
			( netClass "@sapphirecity_baseboard_lib.sapphirecity_baseboard(sch_1):\AVMC\"
				( memberType ( signal ) )
				( spacingCSetRef "@sapphirecity_baseboard_lib.sapphirecity_baseboard(sch_1):\8_MILS\" )
				( sameNetSpacingCSetRef "@crescent_city_bb_fab1_lib.crescent_city_bb_fab1(sch_1):\8_MILS\" )
				( objectFlag fObjectSpacing )
				( objectFlag fObjectSameNetSpacing )
				( objectStatus "AVMC" )
			)
			( netClass "@sapphirecity_baseboard_lib.sapphirecity_baseboard(sch_1):\DDR4_VIEWDIG\"
				( memberType ( signal ) )
				( spacingCSetRef "@sapphirecity_baseboard_lib.sapphirecity_baseboard(sch_1):\4H\" )
				( sameNetSpacingCSetRef "@crescent_city_bb_fab1_lib.crescent_city_bb_fab1(sch_1):\4H\" )
				( objectFlag fObjectSpacing )
				( objectFlag fObjectSameNetSpacing )
				( objectStatus "DDR4_VIEWDIG" )
			)
			( netClass "@sapphirecity_baseboard_lib.sapphirecity_baseboard(sch_1):\SMBUS_ALL\"
				( memberType ( signal ) )
				( spacingCSetRef "@sapphirecity_baseboard_lib.sapphirecity_baseboard(sch_1):\8MIL_SL_10MIL_MS\" )
				( sameNetSpacingCSetRef "@crescent_city_bb_fab1_lib.crescent_city_bb_fab1(sch_1):\2.5H_US_AND_2H_SL\" )
				( objectFlag fObjectSpacing )
				( objectFlag fObjectSameNetSpacing )
				( member ( signalRef "@baseboard_fab2_lib.baseboard_fab2(sch_1):smb_sensor_tmp421_2_scl") )
				( member ( signalRef "@baseboard_fab2_lib.baseboard_fab2(sch_1):smb_sensor_tmp421_2_sda") )
				( member ( signalRef "@baseboard_fab2_lib.baseboard_fab2(sch_1):smb_slotx24_bmc_stby_lvc3_scl") )
				( member ( signalRef "@baseboard_fab2_lib.baseboard_fab2(sch_1):smb_slotx24_bmc_stby_lvc3_sda") )
				( member ( signalRef "@baseboard_fab2_lib.baseboard_fab2(sch_1):smb_slotx24_pch_stby_lvc3_scl") )
				( member ( signalRef "@baseboard_fab2_lib.baseboard_fab2(sch_1):smb_slotx24_pch_stby_lvc3_sda") )
				( member ( signalRef "@baseboard_fab2_lib.baseboard_fab2(sch_1):smb_slotx24_stby_lvc3_scl_r") )
				( member ( signalRef "@baseboard_fab2_lib.baseboard_fab2(sch_1):smb_slotx24_stby_lvc3_scl_r1") )
				( member ( signalRef "@baseboard_fab2_lib.baseboard_fab2(sch_1):smb_slotx24_stby_lvc3_scl_r2") )
				( member ( signalRef "@baseboard_fab2_lib.baseboard_fab2(sch_1):smb_slotx24_stby_lvc3_sda_r") )
				( member ( signalRef "@baseboard_fab2_lib.baseboard_fab2(sch_1):smb_slotx24_stby_lvc3_sda_r1") )
				( member ( signalRef "@baseboard_fab2_lib.baseboard_fab2(sch_1):smb_slotx24_stby_lvc3_sda_r2") )
				( member ( signalRef "@baseboard_fab2_lib.baseboard_fab2(sch_1):smb_smlink0_stby_lvc3_scl") )
				( member ( signalRef "@baseboard_fab2_lib.baseboard_fab2(sch_1):smb_smlink0_stby_lvc3_scl_r") )
				( member ( signalRef "@baseboard_fab2_lib.baseboard_fab2(sch_1):smb_smlink0_stby_lvc3_scl_r1") )
				( member ( signalRef "@baseboard_fab2_lib.baseboard_fab2(sch_1):smb_smlink0_stby_lvc3_sda") )
				( member ( signalRef "@baseboard_fab2_lib.baseboard_fab2(sch_1):smb_smlink0_stby_lvc3_sda_r") )
				( member ( signalRef "@baseboard_fab2_lib.baseboard_fab2(sch_1):smb_smlink0_stby_lvc3_sda_r1") )
				( member ( signalRef "@baseboard_fab2_lib.baseboard_fab2(sch_1):smb_springville_stby_lvc3_scl") )
				( member ( signalRef "@baseboard_fab2_lib.baseboard_fab2(sch_1):smb_springville_stby_lvc3_sda") )
				( member ( signalRef "@baseboard_fab2_lib.baseboard_fab2(sch_1):smb_pch_mezz_lom0_scl") )
				( member ( signalRef "@baseboard_fab2_lib.baseboard_fab2(sch_1):smb_pch_mezz_lom0_sda") )
				( member ( signalRef "@baseboard_fab2_lib.baseboard_fab2(sch_1):smb_pch_mezz_lom1_scl") )
				( member ( signalRef "@baseboard_fab2_lib.baseboard_fab2(sch_1):smb_pch_mezz_lom1_sda") )
				( member ( signalRef "@baseboard_fab2_lib.baseboard_fab2(sch_1):smb_pch_mezz_lom2_scl") )
				( member ( signalRef "@baseboard_fab2_lib.baseboard_fab2(sch_1):smb_pch_mezz_lom2_sda") )
				( member ( signalRef "@baseboard_fab2_lib.baseboard_fab2(sch_1):smb_pch_mezz_lom3_scl") )
				( member ( signalRef "@baseboard_fab2_lib.baseboard_fab2(sch_1):smb_pch_mezz_lom3_sda") )
				( member ( signalRef "@baseboard_fab2_lib.baseboard_fab2(sch_1):smb_pirom_cpu0_scl") )
				( member ( signalRef "@baseboard_fab2_lib.baseboard_fab2(sch_1):smb_pirom_cpu0_sda") )
				( member ( signalRef "@baseboard_fab2_lib.baseboard_fab2(sch_1):smb_pirom_cpu1_scl") )
				( member ( signalRef "@baseboard_fab2_lib.baseboard_fab2(sch_1):smb_pirom_cpu1_sda") )
				( member ( signalRef "@baseboard_fab2_lib.baseboard_fab2(sch_1):smb_hfi0_cpu0_lvc2_scl") )
				( member ( signalRef "@baseboard_fab2_lib.baseboard_fab2(sch_1):smb_hfi0_cpu0_lvc2_sda") )
				( member ( signalRef "@baseboard_fab2_lib.baseboard_fab2(sch_1):smb_hfi1_cpu0_lvc2_scl") )
				( member ( signalRef "@baseboard_fab2_lib.baseboard_fab2(sch_1):smb_hfi1_cpu0_lvc2_sda") )
				( member ( signalRef "@baseboard_fab2_lib.baseboard_fab2(sch_1):smb_vr_scl_pvccio_cpu0") )
				( member ( signalRef "@baseboard_fab2_lib.baseboard_fab2(sch_1):smb_vr_scl_pvccio_cpu1") )
				( member ( signalRef "@baseboard_fab2_lib.baseboard_fab2(sch_1):smb_vr_scl_pvnn_pch") )
				( member ( signalRef "@baseboard_fab2_lib.baseboard_fab2(sch_1):smb_vr_scl_r") )
				( member ( signalRef "@baseboard_fab2_lib.baseboard_fab2(sch_1):smb_vr_scl_r1") )
				( member ( signalRef "@baseboard_fab2_lib.baseboard_fab2(sch_1):smb_vr_scl_vddq_abc") )
				( member ( signalRef "@baseboard_fab2_lib.baseboard_fab2(sch_1):smb_vr_scl_vddq_def") )
				( member ( signalRef "@baseboard_fab2_lib.baseboard_fab2(sch_1):smb_vr_scl_vddq_ghj") )
				( member ( signalRef "@baseboard_fab2_lib.baseboard_fab2(sch_1):smb_vr_scl_vddq_klm") )
				( member ( signalRef "@baseboard_fab2_lib.baseboard_fab2(sch_1):smb_vr_sda_pvccio_cpu0") )
				( member ( signalRef "@baseboard_fab2_lib.baseboard_fab2(sch_1):smb_vr_sda_pvccio_cpu1") )
				( member ( signalRef "@baseboard_fab2_lib.baseboard_fab2(sch_1):smb_vr_sda_pvnn_pch") )
				( member ( signalRef "@baseboard_fab2_lib.baseboard_fab2(sch_1):smb_vr_sda_r") )
				( member ( signalRef "@baseboard_fab2_lib.baseboard_fab2(sch_1):smb_vr_sda_r1") )
				( member ( signalRef "@baseboard_fab2_lib.baseboard_fab2(sch_1):smb_vr_sda_vddq_abc") )
				( member ( signalRef "@baseboard_fab2_lib.baseboard_fab2(sch_1):smb_vr_sda_vddq_def") )
				( member ( signalRef "@baseboard_fab2_lib.baseboard_fab2(sch_1):smb_vr_sda_vddq_ghj") )
				( member ( signalRef "@baseboard_fab2_lib.baseboard_fab2(sch_1):smb_vr_sda_vddq_klm") )
				( member ( signalRef "@baseboard_fab2_lib.baseboard_fab2(sch_1):smb_vr_stby_lvc3_scl") )
				( member ( signalRef "@baseboard_fab2_lib.baseboard_fab2(sch_1):smb_vr_stby_lvc3_scl_r") )
				( member ( signalRef "@baseboard_fab2_lib.baseboard_fab2(sch_1):smb_vr_stby_lvc3_scl_r1") )
				( member ( signalRef "@baseboard_fab2_lib.baseboard_fab2(sch_1):smb_vr_stby_lvc3_sda") )
				( member ( signalRef "@baseboard_fab2_lib.baseboard_fab2(sch_1):smb_vr_stby_lvc3_sda_r") )
				( member ( signalRef "@baseboard_fab2_lib.baseboard_fab2(sch_1):smb_vr_stby_lvc3_sda_r1") )
				( member ( signalRef "@baseboard_fab2_lib.baseboard_fab2(sch_1):smb_pehpcpu1_stby_lvc3_scl") )
				( member ( signalRef "@baseboard_fab2_lib.baseboard_fab2(sch_1):smb_pehpcpu1_stby_lvc3_sda") )
				( member ( signalRef "@baseboard_fab2_lib.baseboard_fab2(sch_1):smb_pehpcpu1_stby_lvc3_r_scl") )
				( member ( signalRef "@baseboard_fab2_lib.baseboard_fab2(sch_1):smb_pehpcpu1_stby_lvc3_r_sda") )
				( member ( signalRef "@baseboard_fab2_lib.baseboard_fab2(sch_1):smb_lan_stby_lvc3_scl") )
				( member ( signalRef "@baseboard_fab2_lib.baseboard_fab2(sch_1):smb_lan_stby_lvc3_scl_r") )
				( member ( signalRef "@baseboard_fab2_lib.baseboard_fab2(sch_1):smb_lan_stby_lvc3_scl_r1") )
				( member ( signalRef "@baseboard_fab2_lib.baseboard_fab2(sch_1):smb_lan_stby_lvc3_scl_r2") )
				( member ( signalRef "@baseboard_fab2_lib.baseboard_fab2(sch_1):smb_lan_stby_lvc3_sda") )
				( member ( signalRef "@baseboard_fab2_lib.baseboard_fab2(sch_1):smb_lan_stby_lvc3_sda_r") )
				( member ( signalRef "@baseboard_fab2_lib.baseboard_fab2(sch_1):smb_lan_stby_lvc3_sda_r1") )
				( member ( signalRef "@baseboard_fab2_lib.baseboard_fab2(sch_1):smb_lan_stby_lvc3_sda_r2") )
				( member ( signalRef "@baseboard_fab2_lib.baseboard_fab2(sch_1):smb_ocp_fru_stby_lvc3_scl") )
				( member ( signalRef "@baseboard_fab2_lib.baseboard_fab2(sch_1):smb_ocp_fru_stby_lvc3_scl_r") )
				( member ( signalRef "@baseboard_fab2_lib.baseboard_fab2(sch_1):smb_ocp_fru_stby_lvc3_sda") )
				( member ( signalRef "@baseboard_fab2_lib.baseboard_fab2(sch_1):smb_ocp_fru_stby_lvc3_sda_r") )
				( member ( signalRef "@baseboard_fab2_lib.baseboard_fab2(sch_1):smb_bmc_pmbus_stby_lvc3_scl") )
				( member ( signalRef "@baseboard_fab2_lib.baseboard_fab2(sch_1):smb_bmc_pmbus_stby_lvc3_scl_r") )
				( member ( signalRef "@baseboard_fab2_lib.baseboard_fab2(sch_1):smb_bmc_pmbus_stby_lvc3_sda") )
				( member ( signalRef "@baseboard_fab2_lib.baseboard_fab2(sch_1):smb_bmc_pmbus_stby_lvc3_sda_r") )
				( member ( signalRef "@baseboard_fab2_lib.baseboard_fab2(sch_1):smb_cpu1_pe_hp_gtl_r_scl") )
				( member ( signalRef "@baseboard_fab2_lib.baseboard_fab2(sch_1):smb_cpu1_pe_hp_gtl_r_sda") )
				( member ( signalRef "@baseboard_fab2_lib.baseboard_fab2(sch_1):smb_cpu1_pe_hp_gtl_scl") )
				( member ( signalRef "@baseboard_fab2_lib.baseboard_fab2(sch_1):smb_cpu1_pe_hp_gtl_sda") )
				( member ( signalRef "@baseboard_fab2_lib.baseboard_fab2(sch_1):smb_pmbus_bmc_stby_lvc3_scl_r1") )
				( member ( signalRef "@baseboard_fab2_lib.baseboard_fab2(sch_1):smb_pmbus_bmc_stby_lvc3_sda_r1") )
				( member ( signalRef "@baseboard_fab2_lib.baseboard_fab2(sch_1):smb_3v3sb_hsc_scl_r") )
				( member ( signalRef "@baseboard_fab2_lib.baseboard_fab2(sch_1):smb_3v3sb_hsc_sda_r") )
				( member ( signalRef "@baseboard_fab2_lib.baseboard_fab2(sch_1):smb_host_stby_lvc3_scl_r2") )
				( member ( signalRef "@baseboard_fab2_lib.baseboard_fab2(sch_1):smb_host_stby_lvc3_sda_r2") )
				( member ( signalRef "@baseboard_fab2_lib.baseboard_fab2(sch_1):smb_sensor_stby_lvc3_scl_r2") )
				( member ( signalRef "@baseboard_fab2_lib.baseboard_fab2(sch_1):smb_sensor_stby_lvc3_sda_r2") )
				( member ( signalRef "@baseboard_fab2_lib.baseboard_fab2(sch_1):smb_host_stby_lvc3_scl") )
				( member ( signalRef "@baseboard_fab2_lib.baseboard_fab2(sch_1):smb_host_stby_lvc3_scl_r") )
				( member ( signalRef "@baseboard_fab2_lib.baseboard_fab2(sch_1):smb_host_stby_lvc3_scl_r1") )
				( member ( signalRef "@baseboard_fab2_lib.baseboard_fab2(sch_1):smb_host_stby_lvc3_sda") )
				( member ( signalRef "@baseboard_fab2_lib.baseboard_fab2(sch_1):smb_host_stby_lvc3_sda_r") )
				( member ( signalRef "@baseboard_fab2_lib.baseboard_fab2(sch_1):smb_host_stby_lvc3_sda_r1") )
				( member ( signalRef "@baseboard_fab2_lib.baseboard_fab2(sch_1):smb_ocp_lan_stby_lvc3_scl") )
				( member ( signalRef "@baseboard_fab2_lib.baseboard_fab2(sch_1):smb_ocp_lan_stby_lvc3_scl_r") )
				( member ( signalRef "@baseboard_fab2_lib.baseboard_fab2(sch_1):smb_ocp_lan_stby_lvc3_sda") )
				( member ( signalRef "@baseboard_fab2_lib.baseboard_fab2(sch_1):smb_ocp_lan_stby_lvc3_sda_r") )
				( member ( signalRef "@baseboard_fab2_lib.baseboard_fab2(sch_1):smb_sensor_bmc_stby_lvc3_scl") )
				( member ( signalRef "@baseboard_fab2_lib.baseboard_fab2(sch_1):smb_sensor_bmc_stby_lvc3_sda") )
				( member ( signalRef "@baseboard_fab2_lib.baseboard_fab2(sch_1):smb_sensor_pch_stby_lvc3_scl") )
				( member ( signalRef "@baseboard_fab2_lib.baseboard_fab2(sch_1):smb_sensor_pch_stby_lvc3_sda") )
				( member ( signalRef "@baseboard_fab2_lib.baseboard_fab2(sch_1):smb_sensor_stby_lvc3_scl") )
				( member ( signalRef "@baseboard_fab2_lib.baseboard_fab2(sch_1):smb_sensor_stby_lvc3_scl_r1") )
				( member ( signalRef "@baseboard_fab2_lib.baseboard_fab2(sch_1):smb_sensor_stby_lvc3_sda") )
				( member ( signalRef "@baseboard_fab2_lib.baseboard_fab2(sch_1):smb_sensor_stby_lvc3_sda_r1") )
				( member ( signalRef "@baseboard_fab2_lib.baseboard_fab2(sch_1):smb_sensor_tmp421_1_scl") )
				( member ( signalRef "@baseboard_fab2_lib.baseboard_fab2(sch_1):smb_sensor_tmp421_1_sda") )
				( member ( electricalNetRef "@crescent_city_bb_fab1_lib.crescent_city_bb_fab1(sch_1):smb_slotx24_bmc_stby_lvc3_scl") )
				( member ( electricalNetRef "@crescent_city_bb_fab1_lib.crescent_city_bb_fab1(sch_1):smb_slotx24_bmc_stby_lvc3_sda") )
				( member ( electricalNetRef "@crescent_city_bb_fab1_lib.crescent_city_bb_fab1(sch_1):smb_smlink0_stby_lvc3_scl") )
				( member ( electricalNetRef "@crescent_city_bb_fab1_lib.crescent_city_bb_fab1(sch_1):smb_smlink0_stby_lvc3_sda") )
				( member ( electricalNetRef "@crescent_city_bb_fab1_lib.crescent_city_bb_fab1(sch_1):smb_vr_scl_pvccio_cpu0") )
				( member ( electricalNetRef "@crescent_city_bb_fab1_lib.crescent_city_bb_fab1(sch_1):smb_vr_sda_pvccio_cpu0") )
				( member ( electricalNetRef "@crescent_city_bb_fab1_lib.crescent_city_bb_fab1(sch_1):smb_3v3sb_hsc_scl_r") )
				( member ( electricalNetRef "@crescent_city_bb_fab1_lib.crescent_city_bb_fab1(sch_1):smb_3v3sb_hsc_sda_r") )
				( member ( electricalNetRef "@crescent_city_bb_fab1_lib.crescent_city_bb_fab1(sch_1):smb_cpu1_pe_hp_gtl_r_scl") )
				( member ( electricalNetRef "@crescent_city_bb_fab1_lib.crescent_city_bb_fab1(sch_1):smb_cpu1_pe_hp_gtl_r_sda") )
				( member ( electricalNetRef "@crescent_city_bb_fab1_lib.crescent_city_bb_fab1(sch_1):smb_host_stby_lvc3_scl") )
				( member ( electricalNetRef "@crescent_city_bb_fab1_lib.crescent_city_bb_fab1(sch_1):smb_host_stby_lvc3_sda") )
				( member ( electricalNetRef "@crescent_city_bb_fab1_lib.crescent_city_bb_fab1(sch_1):smb_lan_stby_lvc3_scl") )
				( member ( electricalNetRef "@crescent_city_bb_fab1_lib.crescent_city_bb_fab1(sch_1):smb_lan_stby_lvc3_sda") )
				( member ( electricalNetRef "@crescent_city_bb_fab1_lib.crescent_city_bb_fab1(sch_1):smb_sensor_bmc_stby_lvc3_sda") )
				( member ( electricalNetRef "@crescent_city_bb_fab1_lib.crescent_city_bb_fab1(sch_1):smb_sensor_pch_stby_lvc3_scl") )
				( objectStatus "SNCLS_SMB_ALL" )
			)
			( netClass "@sapphirecity_baseboard_lib.sapphirecity_baseboard(sch_1):\SMBUS_DDR\"
				( memberType ( signal ) )
				( spacingCSetRef "@sapphirecity_baseboard_lib.sapphirecity_baseboard(sch_1):\8MIL_SL_10MIL_MS\" )
				( sameNetSpacingCSetRef "@crescent_city_bb_fab1_lib.crescent_city_bb_fab1(sch_1):\10_MILS\" )
				( objectFlag fObjectSpacing )
				( objectFlag fObjectSameNetSpacing )
				( member ( signalRef "@baseboard_fab2_lib.baseboard_fab2(sch_1):smb_ddr_abc_scl_g") )
				( member ( signalRef "@baseboard_fab2_lib.baseboard_fab2(sch_1):smb_ddr_abc_scl_g_r") )
				( member ( signalRef "@baseboard_fab2_lib.baseboard_fab2(sch_1):smb_ddr_abc_sda_g") )
				( member ( signalRef "@baseboard_fab2_lib.baseboard_fab2(sch_1):smb_ddr_abc_sda_g_r") )
				( member ( signalRef "@baseboard_fab2_lib.baseboard_fab2(sch_1):smb_ddr_abc_vpp_scl") )
				( member ( signalRef "@baseboard_fab2_lib.baseboard_fab2(sch_1):smb_ddr_abc_vpp_scl_r") )
				( member ( signalRef "@baseboard_fab2_lib.baseboard_fab2(sch_1):smb_ddr_abc_vpp_sda") )
				( member ( signalRef "@baseboard_fab2_lib.baseboard_fab2(sch_1):smb_ddr_abc_vpp_sda_r") )
				( member ( signalRef "@baseboard_fab2_lib.baseboard_fab2(sch_1):smb_ddr_def_scl_g") )
				( member ( signalRef "@baseboard_fab2_lib.baseboard_fab2(sch_1):smb_ddr_def_scl_g_r") )
				( member ( signalRef "@baseboard_fab2_lib.baseboard_fab2(sch_1):smb_ddr_def_sda_g") )
				( member ( signalRef "@baseboard_fab2_lib.baseboard_fab2(sch_1):smb_ddr_def_sda_g_r") )
				( member ( signalRef "@baseboard_fab2_lib.baseboard_fab2(sch_1):smb_ddr_def_vpp_scl") )
				( member ( signalRef "@baseboard_fab2_lib.baseboard_fab2(sch_1):smb_ddr_def_vpp_scl_r") )
				( member ( signalRef "@baseboard_fab2_lib.baseboard_fab2(sch_1):smb_ddr_def_vpp_sda") )
				( member ( signalRef "@baseboard_fab2_lib.baseboard_fab2(sch_1):smb_ddr_def_vpp_sda_r") )
				( member ( signalRef "@baseboard_fab2_lib.baseboard_fab2(sch_1):smb_ddr_ghj_scl_g") )
				( member ( signalRef "@baseboard_fab2_lib.baseboard_fab2(sch_1):smb_ddr_ghj_scl_g_r") )
				( member ( signalRef "@baseboard_fab2_lib.baseboard_fab2(sch_1):smb_ddr_ghj_sda_g") )
				( member ( signalRef "@baseboard_fab2_lib.baseboard_fab2(sch_1):smb_ddr_ghj_sda_g_r") )
				( member ( signalRef "@baseboard_fab2_lib.baseboard_fab2(sch_1):smb_ddr_ghj_vpp_scl") )
				( member ( signalRef "@baseboard_fab2_lib.baseboard_fab2(sch_1):smb_ddr_ghj_vpp_scl_r") )
				( member ( signalRef "@baseboard_fab2_lib.baseboard_fab2(sch_1):smb_ddr_ghj_vpp_sda") )
				( member ( signalRef "@baseboard_fab2_lib.baseboard_fab2(sch_1):smb_ddr_ghj_vpp_sda_r") )
				( member ( signalRef "@baseboard_fab2_lib.baseboard_fab2(sch_1):smb_ddr_klm_scl_g") )
				( member ( signalRef "@baseboard_fab2_lib.baseboard_fab2(sch_1):smb_ddr_klm_scl_g_r") )
				( member ( signalRef "@baseboard_fab2_lib.baseboard_fab2(sch_1):smb_ddr_klm_sda_g") )
				( member ( signalRef "@baseboard_fab2_lib.baseboard_fab2(sch_1):smb_ddr_klm_sda_g_r") )
				( member ( signalRef "@baseboard_fab2_lib.baseboard_fab2(sch_1):smb_ddr_klm_vpp_scl") )
				( member ( signalRef "@baseboard_fab2_lib.baseboard_fab2(sch_1):smb_ddr_klm_vpp_scl_r") )
				( member ( signalRef "@baseboard_fab2_lib.baseboard_fab2(sch_1):smb_ddr_klm_vpp_sda") )
				( member ( signalRef "@baseboard_fab2_lib.baseboard_fab2(sch_1):smb_ddr_klm_vpp_sda_r") )
				( member ( electricalNetRef "@crescent_city_bb_fab1_lib.crescent_city_bb_fab1(sch_1):smb_ddr_abc_scl_g") )
				( member ( electricalNetRef "@crescent_city_bb_fab1_lib.crescent_city_bb_fab1(sch_1):smb_ddr_abc_sda_g") )
				( member ( electricalNetRef "@crescent_city_bb_fab1_lib.crescent_city_bb_fab1(sch_1):smb_ddr_abc_vpp_scl") )
				( member ( electricalNetRef "@crescent_city_bb_fab1_lib.crescent_city_bb_fab1(sch_1):smb_ddr_abc_vpp_sda") )
				( member ( electricalNetRef "@crescent_city_bb_fab1_lib.crescent_city_bb_fab1(sch_1):smb_ddr_def_scl_g") )
				( member ( electricalNetRef "@crescent_city_bb_fab1_lib.crescent_city_bb_fab1(sch_1):smb_ddr_def_sda_g") )
				( member ( electricalNetRef "@crescent_city_bb_fab1_lib.crescent_city_bb_fab1(sch_1):smb_ddr_def_vpp_scl") )
				( member ( electricalNetRef "@crescent_city_bb_fab1_lib.crescent_city_bb_fab1(sch_1):smb_ddr_def_vpp_sda") )
				( member ( electricalNetRef "@crescent_city_bb_fab1_lib.crescent_city_bb_fab1(sch_1):smb_ddr_ghj_scl_g") )
				( member ( electricalNetRef "@crescent_city_bb_fab1_lib.crescent_city_bb_fab1(sch_1):smb_ddr_ghj_sda_g") )
				( member ( electricalNetRef "@crescent_city_bb_fab1_lib.crescent_city_bb_fab1(sch_1):smb_ddr_ghj_vpp_scl") )
				( member ( electricalNetRef "@crescent_city_bb_fab1_lib.crescent_city_bb_fab1(sch_1):smb_ddr_ghj_vpp_sda") )
				( member ( electricalNetRef "@crescent_city_bb_fab1_lib.crescent_city_bb_fab1(sch_1):smb_ddr_klm_scl_g") )
				( member ( electricalNetRef "@crescent_city_bb_fab1_lib.crescent_city_bb_fab1(sch_1):smb_ddr_klm_sda_g") )
				( member ( electricalNetRef "@crescent_city_bb_fab1_lib.crescent_city_bb_fab1(sch_1):smb_ddr_klm_vpp_scl") )
				( member ( electricalNetRef "@crescent_city_bb_fab1_lib.crescent_city_bb_fab1(sch_1):smb_ddr_klm_vpp_sda") )
				( objectStatus "SNCLS_SMB_DDR" )
			)
			( netGroup "@crescent_city_bb_fab1_lib.crescent_city_bb_fab1(sch_1):\NG_KTI_CPU1_CPU0_P1P1_0-1\"
				( memberType ( signal ) )
				( electricalCSetRef "@crescent_city_bb_fab1_lib.crescent_city_bb_fab1(sch_1):\KTI_CPU1_CPU0_P1P1\" )
				( member ( diffPairRef "@crescent_city_bb_fab1_lib.crescent_city_bb_fab1(sch_1):\KTI_CPU1_CPU0_P1P1\(0)") )
				( member ( diffPairRef "@crescent_city_bb_fab1_lib.crescent_city_bb_fab1(sch_1):\KTI_CPU1_CPU0_P1P1\(1)") )
				( objectStatus "NG_KTI_CPU1_CPU0_P1P1_0-1" )
			)
			( netGroup "@crescent_city_bb_fab1_lib.crescent_city_bb_fab1(sch_1):\NG_KTI_CPU1_CPU0_P1P1_2-3\"
				( memberType ( signal ) )
				( electricalCSetRef "@crescent_city_bb_fab1_lib.crescent_city_bb_fab1(sch_1):\KTI_CPU1_CPU0_P1P1\" )
				( member ( diffPairRef "@crescent_city_bb_fab1_lib.crescent_city_bb_fab1(sch_1):\KTI_CPU1_CPU0_P1P1\(2)") )
				( member ( diffPairRef "@crescent_city_bb_fab1_lib.crescent_city_bb_fab1(sch_1):\KTI_CPU1_CPU0_P1P1\(3)") )
				( objectStatus "NG_KTI_CPU1_CPU0_P1P1_2-3" )
			)
			( netGroup "@crescent_city_bb_fab1_lib.crescent_city_bb_fab1(sch_1):\NG_KTI_CPU1_CPU0_P1P1_4-5\"
				( memberType ( signal ) )
				( electricalCSetRef "@crescent_city_bb_fab1_lib.crescent_city_bb_fab1(sch_1):\KTI_CPU1_CPU0_P1P1\" )
				( member ( diffPairRef "@crescent_city_bb_fab1_lib.crescent_city_bb_fab1(sch_1):\KTI_CPU1_CPU0_P1P1\(4)") )
				( member ( diffPairRef "@crescent_city_bb_fab1_lib.crescent_city_bb_fab1(sch_1):\KTI_CPU1_CPU0_P1P1\(5)") )
				( objectStatus "NG_KTI_CPU1_CPU0_P1P1_4-5" )
			)
			( netGroup "@crescent_city_bb_fab1_lib.crescent_city_bb_fab1(sch_1):\NG_KTI_CPU1_CPU0_P1P1_6-7\"
				( memberType ( signal ) )
				( electricalCSetRef "@crescent_city_bb_fab1_lib.crescent_city_bb_fab1(sch_1):\KTI_CPU1_CPU0_P1P1\" )
				( member ( diffPairRef "@crescent_city_bb_fab1_lib.crescent_city_bb_fab1(sch_1):\KTI_CPU1_CPU0_P1P1\(6)") )
				( member ( diffPairRef "@crescent_city_bb_fab1_lib.crescent_city_bb_fab1(sch_1):\KTI_CPU1_CPU0_P1P1\(7)") )
				( objectStatus "NG_KTI_CPU1_CPU0_P1P1_6-7" )
			)
			( netGroup "@crescent_city_bb_fab1_lib.crescent_city_bb_fab1(sch_1):\NG_KTI_CPU1_CPU0_P1P1_8-9\"
				( memberType ( signal ) )
				( electricalCSetRef "@crescent_city_bb_fab1_lib.crescent_city_bb_fab1(sch_1):\KTI_CPU1_CPU0_P1P1\" )
				( member ( diffPairRef "@crescent_city_bb_fab1_lib.crescent_city_bb_fab1(sch_1):\KTI_CPU1_CPU0_P1P1\(8)") )
				( member ( diffPairRef "@crescent_city_bb_fab1_lib.crescent_city_bb_fab1(sch_1):\KTI_CPU1_CPU0_P1P1\(9)") )
				( objectStatus "NG_KTI_CPU1_CPU0_P1P1_8-9" )
			)
			( netGroup "@crescent_city_bb_fab1_lib.crescent_city_bb_fab1(sch_1):\NG_KTI_CPU1_CPU0_P1P1_10-11\"
				( memberType ( signal ) )
				( electricalCSetRef "@crescent_city_bb_fab1_lib.crescent_city_bb_fab1(sch_1):\KTI_CPU1_CPU0_P1P1\" )
				( member ( diffPairRef "@crescent_city_bb_fab1_lib.crescent_city_bb_fab1(sch_1):\KTI_CPU1_CPU0_P1P1\(10)") )
				( member ( diffPairRef "@crescent_city_bb_fab1_lib.crescent_city_bb_fab1(sch_1):\KTI_CPU1_CPU0_P1P1\(11)") )
				( objectStatus "NG_KTI_CPU1_CPU0_P1P1_10-11" )
			)
			( netGroup "@crescent_city_bb_fab1_lib.crescent_city_bb_fab1(sch_1):\NG_KTI_CPU1_CPU0_P1P1_12-13\"
				( memberType ( signal ) )
				( electricalCSetRef "@crescent_city_bb_fab1_lib.crescent_city_bb_fab1(sch_1):\KTI_CPU1_CPU0_P1P1\" )
				( member ( diffPairRef "@crescent_city_bb_fab1_lib.crescent_city_bb_fab1(sch_1):\KTI_CPU1_CPU0_P1P1\(12)") )
				( member ( diffPairRef "@crescent_city_bb_fab1_lib.crescent_city_bb_fab1(sch_1):\KTI_CPU1_CPU0_P1P1\(13)") )
				( objectStatus "NG_KTI_CPU1_CPU0_P1P1_12-13" )
			)
			( netGroup "@crescent_city_bb_fab1_lib.crescent_city_bb_fab1(sch_1):\NG_KTI_CPU1_CPU0_P1P1_14-15\"
				( memberType ( signal ) )
				( electricalCSetRef "@crescent_city_bb_fab1_lib.crescent_city_bb_fab1(sch_1):\KTI_CPU1_CPU0_P1P1\" )
				( member ( diffPairRef "@crescent_city_bb_fab1_lib.crescent_city_bb_fab1(sch_1):\KTI_CPU1_CPU0_P1P1\(14)") )
				( member ( diffPairRef "@crescent_city_bb_fab1_lib.crescent_city_bb_fab1(sch_1):\KTI_CPU1_CPU0_P1P1\(15)") )
				( objectStatus "NG_KTI_CPU1_CPU0_P1P1_14-15" )
			)
			( netGroup "@crescent_city_bb_fab1_lib.crescent_city_bb_fab1(sch_1):\NG_KTI_CPU1_CPU0_P1P1_16-17\"
				( memberType ( signal ) )
				( electricalCSetRef "@crescent_city_bb_fab1_lib.crescent_city_bb_fab1(sch_1):\KTI_CPU1_CPU0_P1P1\" )
				( member ( diffPairRef "@crescent_city_bb_fab1_lib.crescent_city_bb_fab1(sch_1):\KTI_CPU1_CPU0_P1P1\(16)") )
				( member ( diffPairRef "@crescent_city_bb_fab1_lib.crescent_city_bb_fab1(sch_1):\KTI_CPU1_CPU0_P1P1\(17)") )
				( objectStatus "NG_KTI_CPU1_CPU0_P1P1_16-17" )
			)
			( netGroup "@crescent_city_bb_fab1_lib.crescent_city_bb_fab1(sch_1):\NG_KTI_CPU1_CPU0_P1P1_18-19\"
				( memberType ( signal ) )
				( electricalCSetRef "@crescent_city_bb_fab1_lib.crescent_city_bb_fab1(sch_1):\KTI_CPU1_CPU0_P1P1\" )
				( member ( diffPairRef "@crescent_city_bb_fab1_lib.crescent_city_bb_fab1(sch_1):\KTI_CPU1_CPU0_P1P1\(18)") )
				( member ( diffPairRef "@crescent_city_bb_fab1_lib.crescent_city_bb_fab1(sch_1):\KTI_CPU1_CPU0_P1P1\(19)") )
				( objectStatus "NG_KTI_CPU1_CPU0_P1P1_18-19" )
			)
			( netGroup "@crescent_city_bb_fab1_lib.crescent_city_bb_fab1(sch_1):\NG_KTI_CPU1_CPU0_P0P0_0-1\"
				( memberType ( signal ) )
				( electricalCSetRef "@crescent_city_bb_fab1_lib.crescent_city_bb_fab1(sch_1):\KTI_CPU1_CPU0_P0P0\" )
				( member ( diffPairRef "@crescent_city_bb_fab1_lib.crescent_city_bb_fab1(sch_1):\KTI_CPU1_CPU0_P0P0\(0)") )
				( member ( diffPairRef "@crescent_city_bb_fab1_lib.crescent_city_bb_fab1(sch_1):\KTI_CPU1_CPU0_P0P0\(1)") )
				( objectStatus "NG_KTI_CPU1_CPU0_P0P0_0-1" )
			)
			( netGroup "@crescent_city_bb_fab1_lib.crescent_city_bb_fab1(sch_1):\NG_KTI_CPU1_CPU0_P0P0_2-3\"
				( memberType ( signal ) )
				( electricalCSetRef "@crescent_city_bb_fab1_lib.crescent_city_bb_fab1(sch_1):\KTI_CPU1_CPU0_P0P0\" )
				( member ( diffPairRef "@crescent_city_bb_fab1_lib.crescent_city_bb_fab1(sch_1):\KTI_CPU1_CPU0_P0P0\(2)") )
				( member ( diffPairRef "@crescent_city_bb_fab1_lib.crescent_city_bb_fab1(sch_1):\KTI_CPU1_CPU0_P0P0\(3)") )
				( objectStatus "NG_KTI_CPU1_CPU0_P0P0_2-3" )
			)
			( netGroup "@crescent_city_bb_fab1_lib.crescent_city_bb_fab1(sch_1):\NG_KTI_CPU1_CPU0_P0P0_4-5\"
				( memberType ( signal ) )
				( electricalCSetRef "@crescent_city_bb_fab1_lib.crescent_city_bb_fab1(sch_1):\KTI_CPU1_CPU0_P0P0\" )
				( member ( diffPairRef "@crescent_city_bb_fab1_lib.crescent_city_bb_fab1(sch_1):\KTI_CPU1_CPU0_P0P0\(4)") )
				( member ( diffPairRef "@crescent_city_bb_fab1_lib.crescent_city_bb_fab1(sch_1):\KTI_CPU1_CPU0_P0P0\(5)") )
				( objectStatus "NG_KTI_CPU1_CPU0_P0P0_4-5" )
			)
			( netGroup "@crescent_city_bb_fab1_lib.crescent_city_bb_fab1(sch_1):\NG_KTI_CPU1_CPU0_P0P0_6-7\"
				( memberType ( signal ) )
				( electricalCSetRef "@crescent_city_bb_fab1_lib.crescent_city_bb_fab1(sch_1):\KTI_CPU1_CPU0_P0P0\" )
				( member ( diffPairRef "@crescent_city_bb_fab1_lib.crescent_city_bb_fab1(sch_1):\KTI_CPU1_CPU0_P0P0\(6)") )
				( member ( diffPairRef "@crescent_city_bb_fab1_lib.crescent_city_bb_fab1(sch_1):\KTI_CPU1_CPU0_P0P0\(7)") )
				( objectStatus "NG_KTI_CPU1_CPU0_P0P0_6-7" )
			)
			( netGroup "@crescent_city_bb_fab1_lib.crescent_city_bb_fab1(sch_1):\NG_KTI_CPU1_CPU0_P0P0_8-9\"
				( memberType ( signal ) )
				( electricalCSetRef "@crescent_city_bb_fab1_lib.crescent_city_bb_fab1(sch_1):\KTI_CPU1_CPU0_P0P0\" )
				( member ( diffPairRef "@crescent_city_bb_fab1_lib.crescent_city_bb_fab1(sch_1):\KTI_CPU1_CPU0_P0P0\(8)") )
				( member ( diffPairRef "@crescent_city_bb_fab1_lib.crescent_city_bb_fab1(sch_1):\KTI_CPU1_CPU0_P0P0\(9)") )
				( objectStatus "NG_KTI_CPU1_CPU0_P0P0_8-9" )
			)
			( netGroup "@crescent_city_bb_fab1_lib.crescent_city_bb_fab1(sch_1):\NG_KTI_CPU1_CPU0_P0P0_10-11\"
				( memberType ( signal ) )
				( electricalCSetRef "@crescent_city_bb_fab1_lib.crescent_city_bb_fab1(sch_1):\KTI_CPU1_CPU0_P0P0\" )
				( member ( diffPairRef "@crescent_city_bb_fab1_lib.crescent_city_bb_fab1(sch_1):\KTI_CPU1_CPU0_P0P0\(10)") )
				( member ( diffPairRef "@crescent_city_bb_fab1_lib.crescent_city_bb_fab1(sch_1):\KTI_CPU1_CPU0_P0P0\(11)") )
				( objectStatus "NG_KTI_CPU1_CPU0_P0P0_10-11" )
			)
			( netGroup "@crescent_city_bb_fab1_lib.crescent_city_bb_fab1(sch_1):\NG_KTI_CPU1_CPU0_P0P0_12-13\"
				( memberType ( signal ) )
				( electricalCSetRef "@crescent_city_bb_fab1_lib.crescent_city_bb_fab1(sch_1):\KTI_CPU1_CPU0_P0P0\" )
				( member ( diffPairRef "@crescent_city_bb_fab1_lib.crescent_city_bb_fab1(sch_1):\KTI_CPU1_CPU0_P0P0\(12)") )
				( member ( diffPairRef "@crescent_city_bb_fab1_lib.crescent_city_bb_fab1(sch_1):\KTI_CPU1_CPU0_P0P0\(13)") )
				( objectStatus "NG_KTI_CPU1_CPU0_P0P0_12-13" )
			)
			( netGroup "@crescent_city_bb_fab1_lib.crescent_city_bb_fab1(sch_1):\NG_KTI_CPU1_CPU0_P0P0_14-15\"
				( memberType ( signal ) )
				( electricalCSetRef "@crescent_city_bb_fab1_lib.crescent_city_bb_fab1(sch_1):\KTI_CPU1_CPU0_P0P0\" )
				( member ( diffPairRef "@crescent_city_bb_fab1_lib.crescent_city_bb_fab1(sch_1):\KTI_CPU1_CPU0_P0P0\(14)") )
				( member ( diffPairRef "@crescent_city_bb_fab1_lib.crescent_city_bb_fab1(sch_1):\KTI_CPU1_CPU0_P0P0\(15)") )
				( objectStatus "NG_KTI_CPU1_CPU0_P0P0_14-15" )
			)
			( netGroup "@crescent_city_bb_fab1_lib.crescent_city_bb_fab1(sch_1):\NG_KTI_CPU1_CPU0_P0P0_16-17\"
				( memberType ( signal ) )
				( electricalCSetRef "@crescent_city_bb_fab1_lib.crescent_city_bb_fab1(sch_1):\KTI_CPU1_CPU0_P0P0\" )
				( member ( diffPairRef "@crescent_city_bb_fab1_lib.crescent_city_bb_fab1(sch_1):\KTI_CPU1_CPU0_P0P0\(16)") )
				( member ( diffPairRef "@crescent_city_bb_fab1_lib.crescent_city_bb_fab1(sch_1):\KTI_CPU1_CPU0_P0P0\(17)") )
				( objectStatus "NG_KTI_CPU1_CPU0_P0P0_16-17" )
			)
			( netGroup "@crescent_city_bb_fab1_lib.crescent_city_bb_fab1(sch_1):\NG_KTI_CPU1_CPU0_P0P0_18-19\"
				( memberType ( signal ) )
				( electricalCSetRef "@crescent_city_bb_fab1_lib.crescent_city_bb_fab1(sch_1):\KTI_CPU1_CPU0_P0P0\" )
				( member ( diffPairRef "@crescent_city_bb_fab1_lib.crescent_city_bb_fab1(sch_1):\KTI_CPU1_CPU0_P0P0\(18)") )
				( member ( diffPairRef "@crescent_city_bb_fab1_lib.crescent_city_bb_fab1(sch_1):\KTI_CPU1_CPU0_P0P0\(19)") )
				( objectStatus "NG_KTI_CPU1_CPU0_P0P0_18-19" )
			)
			( netGroup "@crescent_city_bb_fab1_lib.crescent_city_bb_fab1(sch_1):\NG_KTI_CPU0_CPU1_P1P1_0-1\"
				( memberType ( signal ) )
				( electricalCSetRef "@crescent_city_bb_fab1_lib.crescent_city_bb_fab1(sch_1):\KTI_CPU0_CPU1_P1P1\" )
				( member ( diffPairRef "@crescent_city_bb_fab1_lib.crescent_city_bb_fab1(sch_1):\KTI_CPU0_CPU1_P1P1\(0)") )
				( member ( diffPairRef "@crescent_city_bb_fab1_lib.crescent_city_bb_fab1(sch_1):\KTI_CPU0_CPU1_P1P1\(1)") )
				( objectStatus "NG_KTI_CPU0_CPU1_P1P1_0-1" )
			)
			( netGroup "@crescent_city_bb_fab1_lib.crescent_city_bb_fab1(sch_1):\NG_KTI_CPU0_CPU1_P1P1_2-3\"
				( memberType ( signal ) )
				( electricalCSetRef "@crescent_city_bb_fab1_lib.crescent_city_bb_fab1(sch_1):\KTI_CPU0_CPU1_P1P1\" )
				( member ( diffPairRef "@crescent_city_bb_fab1_lib.crescent_city_bb_fab1(sch_1):\KTI_CPU0_CPU1_P1P1\(2)") )
				( member ( diffPairRef "@crescent_city_bb_fab1_lib.crescent_city_bb_fab1(sch_1):\KTI_CPU0_CPU1_P1P1\(3)") )
				( objectStatus "NG_KTI_CPU0_CPU1_P1P1_2-3" )
			)
			( netGroup "@crescent_city_bb_fab1_lib.crescent_city_bb_fab1(sch_1):\NG_KTI_CPU0_CPU1_P1P1_4-5\"
				( memberType ( signal ) )
				( electricalCSetRef "@crescent_city_bb_fab1_lib.crescent_city_bb_fab1(sch_1):\KTI_CPU0_CPU1_P1P1\" )
				( member ( diffPairRef "@crescent_city_bb_fab1_lib.crescent_city_bb_fab1(sch_1):\KTI_CPU0_CPU1_P1P1\(4)") )
				( member ( diffPairRef "@crescent_city_bb_fab1_lib.crescent_city_bb_fab1(sch_1):\KTI_CPU0_CPU1_P1P1\(5)") )
				( objectStatus "NG_KTI_CPU0_CPU1_P1P1_4-5" )
			)
			( netGroup "@crescent_city_bb_fab1_lib.crescent_city_bb_fab1(sch_1):\NG_KTI_CPU0_CPU1_P1P1_6-7\"
				( memberType ( signal ) )
				( electricalCSetRef "@crescent_city_bb_fab1_lib.crescent_city_bb_fab1(sch_1):\KTI_CPU0_CPU1_P1P1\" )
				( member ( diffPairRef "@crescent_city_bb_fab1_lib.crescent_city_bb_fab1(sch_1):\KTI_CPU0_CPU1_P1P1\(6)") )
				( member ( diffPairRef "@crescent_city_bb_fab1_lib.crescent_city_bb_fab1(sch_1):\KTI_CPU0_CPU1_P1P1\(7)") )
				( objectStatus "NG_KTI_CPU0_CPU1_P1P1_6-7" )
			)
			( netGroup "@crescent_city_bb_fab1_lib.crescent_city_bb_fab1(sch_1):\NG_KTI_CPU0_CPU1_P1P1_8-9\"
				( memberType ( signal ) )
				( electricalCSetRef "@crescent_city_bb_fab1_lib.crescent_city_bb_fab1(sch_1):\KTI_CPU0_CPU1_P1P1\" )
				( member ( diffPairRef "@crescent_city_bb_fab1_lib.crescent_city_bb_fab1(sch_1):\KTI_CPU0_CPU1_P1P1\(8)") )
				( member ( diffPairRef "@crescent_city_bb_fab1_lib.crescent_city_bb_fab1(sch_1):\KTI_CPU0_CPU1_P1P1\(9)") )
				( objectStatus "NG_KTI_CPU0_CPU1_P1P1_8-9" )
			)
			( netGroup "@crescent_city_bb_fab1_lib.crescent_city_bb_fab1(sch_1):\NG_KTI_CPU0_CPU1_P1P1_10-11\"
				( memberType ( signal ) )
				( electricalCSetRef "@crescent_city_bb_fab1_lib.crescent_city_bb_fab1(sch_1):\KTI_CPU0_CPU1_P1P1\" )
				( member ( diffPairRef "@crescent_city_bb_fab1_lib.crescent_city_bb_fab1(sch_1):\KTI_CPU0_CPU1_P1P1\(10)") )
				( member ( diffPairRef "@crescent_city_bb_fab1_lib.crescent_city_bb_fab1(sch_1):\KTI_CPU0_CPU1_P1P1\(11)") )
				( objectStatus "NG_KTI_CPU0_CPU1_P1P1_10-11" )
			)
			( netGroup "@crescent_city_bb_fab1_lib.crescent_city_bb_fab1(sch_1):\NG_KTI_CPU0_CPU1_P1P1_12-13\"
				( memberType ( signal ) )
				( electricalCSetRef "@crescent_city_bb_fab1_lib.crescent_city_bb_fab1(sch_1):\KTI_CPU0_CPU1_P1P1\" )
				( member ( diffPairRef "@crescent_city_bb_fab1_lib.crescent_city_bb_fab1(sch_1):\KTI_CPU0_CPU1_P1P1\(12)") )
				( member ( diffPairRef "@crescent_city_bb_fab1_lib.crescent_city_bb_fab1(sch_1):\KTI_CPU0_CPU1_P1P1\(13)") )
				( objectStatus "NG_KTI_CPU0_CPU1_P1P1_12-13" )
			)
			( netGroup "@crescent_city_bb_fab1_lib.crescent_city_bb_fab1(sch_1):\NG_KTI_CPU0_CPU1_P1P1_14-15\"
				( memberType ( signal ) )
				( electricalCSetRef "@crescent_city_bb_fab1_lib.crescent_city_bb_fab1(sch_1):\KTI_CPU0_CPU1_P1P1\" )
				( member ( diffPairRef "@crescent_city_bb_fab1_lib.crescent_city_bb_fab1(sch_1):\KTI_CPU0_CPU1_P1P1\(14)") )
				( member ( diffPairRef "@crescent_city_bb_fab1_lib.crescent_city_bb_fab1(sch_1):\KTI_CPU0_CPU1_P1P1\(15)") )
				( objectStatus "NG_KTI_CPU0_CPU1_P1P1_14-15" )
			)
			( netGroup "@crescent_city_bb_fab1_lib.crescent_city_bb_fab1(sch_1):\NG_KTI_CPU0_CPU1_P1P1_16-17\"
				( memberType ( signal ) )
				( electricalCSetRef "@crescent_city_bb_fab1_lib.crescent_city_bb_fab1(sch_1):\KTI_CPU0_CPU1_P1P1\" )
				( member ( diffPairRef "@crescent_city_bb_fab1_lib.crescent_city_bb_fab1(sch_1):\KTI_CPU0_CPU1_P1P1\(16)") )
				( member ( diffPairRef "@crescent_city_bb_fab1_lib.crescent_city_bb_fab1(sch_1):\KTI_CPU0_CPU1_P1P1\(17)") )
				( objectStatus "NG_KTI_CPU0_CPU1_P1P1_16-17" )
			)
			( netGroup "@crescent_city_bb_fab1_lib.crescent_city_bb_fab1(sch_1):\NG_KTI_CPU0_CPU1_P1P1_18-19\"
				( memberType ( signal ) )
				( electricalCSetRef "@crescent_city_bb_fab1_lib.crescent_city_bb_fab1(sch_1):\KTI_CPU0_CPU1_P1P1\" )
				( member ( diffPairRef "@crescent_city_bb_fab1_lib.crescent_city_bb_fab1(sch_1):\KTI_CPU0_CPU1_P1P1\(18)") )
				( member ( diffPairRef "@crescent_city_bb_fab1_lib.crescent_city_bb_fab1(sch_1):\KTI_CPU0_CPU1_P1P1\(19)") )
				( objectStatus "NG_KTI_CPU0_CPU1_P1P1_18-19" )
			)
			( netGroup "@crescent_city_bb_fab1_lib.crescent_city_bb_fab1(sch_1):\NG_KTI_CPU0_CPU1_P0P0_0-1\"
				( memberType ( signal ) )
				( electricalCSetRef "@crescent_city_bb_fab1_lib.crescent_city_bb_fab1(sch_1):\KTI\" )
				( member ( diffPairRef "@crescent_city_bb_fab1_lib.crescent_city_bb_fab1(sch_1):\KTI_CPU0_CPU1_P0P0\(0)") )
				( member ( diffPairRef "@crescent_city_bb_fab1_lib.crescent_city_bb_fab1(sch_1):\KTI_CPU0_CPU1_P0P0\(1)") )
				( objectStatus "NG_KTI_CPU0_CPU1_P0P0_0-1" )
			)
			( netGroup "@crescent_city_bb_fab1_lib.crescent_city_bb_fab1(sch_1):\NG_KTI_CPU0_CPU1_P0P0_2-3\"
				( memberType ( signal ) )
				( electricalCSetRef "@crescent_city_bb_fab1_lib.crescent_city_bb_fab1(sch_1):\KTI\" )
				( member ( diffPairRef "@crescent_city_bb_fab1_lib.crescent_city_bb_fab1(sch_1):\KTI_CPU0_CPU1_P0P0\(2)") )
				( member ( diffPairRef "@crescent_city_bb_fab1_lib.crescent_city_bb_fab1(sch_1):\KTI_CPU0_CPU1_P0P0\(3)") )
				( objectStatus "NG_KTI_CPU0_CPU1_P0P0_2-3" )
			)
			( netGroup "@crescent_city_bb_fab1_lib.crescent_city_bb_fab1(sch_1):\NG_KTI_CPU0_CPU1_P0P0_4-5\"
				( memberType ( signal ) )
				( electricalCSetRef "@crescent_city_bb_fab1_lib.crescent_city_bb_fab1(sch_1):\KTI\" )
				( member ( diffPairRef "@crescent_city_bb_fab1_lib.crescent_city_bb_fab1(sch_1):\KTI_CPU0_CPU1_P0P0\(4)") )
				( member ( diffPairRef "@crescent_city_bb_fab1_lib.crescent_city_bb_fab1(sch_1):\KTI_CPU0_CPU1_P0P0\(5)") )
				( objectStatus "NG_KTI_CPU0_CPU1_P0P0_4-5" )
			)
			( netGroup "@crescent_city_bb_fab1_lib.crescent_city_bb_fab1(sch_1):\NG_KTI_CPU0_CPU1_P0P0_6-7\"
				( memberType ( signal ) )
				( electricalCSetRef "@crescent_city_bb_fab1_lib.crescent_city_bb_fab1(sch_1):\KTI\" )
				( member ( diffPairRef "@crescent_city_bb_fab1_lib.crescent_city_bb_fab1(sch_1):\KTI_CPU0_CPU1_P0P0\(6)") )
				( member ( diffPairRef "@crescent_city_bb_fab1_lib.crescent_city_bb_fab1(sch_1):\KTI_CPU0_CPU1_P0P0\(7)") )
				( objectStatus "NG_KTI_CPU0_CPU1_P0P0_6-7" )
			)
			( netGroup "@crescent_city_bb_fab1_lib.crescent_city_bb_fab1(sch_1):\NG_KTI_CPU0_CPU1_P0P0_8-9\"
				( memberType ( signal ) )
				( electricalCSetRef "@crescent_city_bb_fab1_lib.crescent_city_bb_fab1(sch_1):\KTI\" )
				( member ( diffPairRef "@crescent_city_bb_fab1_lib.crescent_city_bb_fab1(sch_1):\KTI_CPU0_CPU1_P0P0\(8)") )
				( member ( diffPairRef "@crescent_city_bb_fab1_lib.crescent_city_bb_fab1(sch_1):\KTI_CPU0_CPU1_P0P0\(9)") )
				( objectStatus "NG_KTI_CPU0_CPU1_P0P0_8-9" )
			)
			( netGroup "@crescent_city_bb_fab1_lib.crescent_city_bb_fab1(sch_1):\NG_KTI_CPU0_CPU1_P0P0_10-11\"
				( memberType ( signal ) )
				( electricalCSetRef "@crescent_city_bb_fab1_lib.crescent_city_bb_fab1(sch_1):\KTI\" )
				( member ( diffPairRef "@crescent_city_bb_fab1_lib.crescent_city_bb_fab1(sch_1):\KTI_CPU0_CPU1_P0P0\(10)") )
				( member ( diffPairRef "@crescent_city_bb_fab1_lib.crescent_city_bb_fab1(sch_1):\KTI_CPU0_CPU1_P0P0\(11)") )
				( objectStatus "NG_KTI_CPU0_CPU1_P0P0_10-11" )
			)
			( netGroup "@crescent_city_bb_fab1_lib.crescent_city_bb_fab1(sch_1):\NG_KTI_CPU0_CPU1_P0P0_12-13\"
				( memberType ( signal ) )
				( electricalCSetRef "@crescent_city_bb_fab1_lib.crescent_city_bb_fab1(sch_1):\KTI\" )
				( member ( diffPairRef "@crescent_city_bb_fab1_lib.crescent_city_bb_fab1(sch_1):\KTI_CPU0_CPU1_P0P0\(12)") )
				( member ( diffPairRef "@crescent_city_bb_fab1_lib.crescent_city_bb_fab1(sch_1):\KTI_CPU0_CPU1_P0P0\(13)") )
				( objectStatus "NG_KTI_CPU0_CPU1_P0P0_12-13" )
			)
			( netGroup "@crescent_city_bb_fab1_lib.crescent_city_bb_fab1(sch_1):\NG_KTI_CPU0_CPU1_P0P0_14-15\"
				( memberType ( signal ) )
				( electricalCSetRef "@crescent_city_bb_fab1_lib.crescent_city_bb_fab1(sch_1):\KTI\" )
				( member ( diffPairRef "@crescent_city_bb_fab1_lib.crescent_city_bb_fab1(sch_1):\KTI_CPU0_CPU1_P0P0\(14)") )
				( member ( diffPairRef "@crescent_city_bb_fab1_lib.crescent_city_bb_fab1(sch_1):\KTI_CPU0_CPU1_P0P0\(15)") )
				( objectStatus "NG_KTI_CPU0_CPU1_P0P0_14-15" )
			)
			( netGroup "@crescent_city_bb_fab1_lib.crescent_city_bb_fab1(sch_1):\NG_KTI_CPU0_CPU1_P0P0_16-17\"
				( memberType ( signal ) )
				( electricalCSetRef "@crescent_city_bb_fab1_lib.crescent_city_bb_fab1(sch_1):\KTI\" )
				( member ( diffPairRef "@crescent_city_bb_fab1_lib.crescent_city_bb_fab1(sch_1):\KTI_CPU0_CPU1_P0P0\(16)") )
				( member ( diffPairRef "@crescent_city_bb_fab1_lib.crescent_city_bb_fab1(sch_1):\KTI_CPU0_CPU1_P0P0\(17)") )
				( objectStatus "NG_KTI_CPU0_CPU1_P0P0_16-17" )
			)
			( netGroup "@crescent_city_bb_fab1_lib.crescent_city_bb_fab1(sch_1):\NG_KTI_CPU0_CPU1_P0P0_18-19\"
				( memberType ( signal ) )
				( electricalCSetRef "@crescent_city_bb_fab1_lib.crescent_city_bb_fab1(sch_1):\KTI\" )
				( member ( diffPairRef "@crescent_city_bb_fab1_lib.crescent_city_bb_fab1(sch_1):\KTI_CPU0_CPU1_P0P0\(18)") )
				( member ( diffPairRef "@crescent_city_bb_fab1_lib.crescent_city_bb_fab1(sch_1):\KTI_CPU0_CPU1_P0P0\(19)") )
				( objectStatus "NG_KTI_CPU0_CPU1_P0P0_18-19" )
			)
			( netGroup "@crescent_city_bb_fab1_lib.crescent_city_bb_fab1(sch_1):\NG_DDR_M_DLL_1\"
				( memberType ( signal ) )
				( electricalCSetRef "@crescent_city_bb_fab1_lib.crescent_city_bb_fab1(sch_1):\DDR_M_CMD_DLL1-13\" )
				( member ( signalRef "@baseboard_fab2_lib.baseboard_fab2(sch_1):m_m_c(2)") )
				( member ( signalRef "@baseboard_fab2_lib.baseboard_fab2(sch_1):m_m_ma(17)") )
				( objectStatus "NG_DDR_M_DLL_1" )
			)
			( netGroup "@crescent_city_bb_fab1_lib.crescent_city_bb_fab1(sch_1):\NG_DDR_M_DLL_2\"
				( memberType ( signal ) )
				( electricalCSetRef "@crescent_city_bb_fab1_lib.crescent_city_bb_fab1(sch_1):\DDR_M_CMD_DLL1-13\" )
				( member ( signalRef "@baseboard_fab2_lib.baseboard_fab2(sch_1):m_m_ma(13)") )
				( member ( signalRef "@baseboard_fab2_lib.baseboard_fab2(sch_1):m_m_ma(15)") )
				( objectStatus "NG_DDR_M_DLL_2" )
			)
			( netGroup "@crescent_city_bb_fab1_lib.crescent_city_bb_fab1(sch_1):\NG_DDR_M_DLL_3\"
				( memberType ( signal ) )
				( electricalCSetRef "@crescent_city_bb_fab1_lib.crescent_city_bb_fab1(sch_1):\DDR_M_CMD_DLL1-13\" )
				( member ( signalRef "@baseboard_fab2_lib.baseboard_fab2(sch_1):m_m_ma(14)") )
				( member ( signalRef "@baseboard_fab2_lib.baseboard_fab2(sch_1):m_m_ma(16)") )
				( objectStatus "NG_DDR_M_DLL_3" )
			)
			( netGroup "@crescent_city_bb_fab1_lib.crescent_city_bb_fab1(sch_1):\NG_DDR_M_DLL_4\"
				( memberType ( signal ) )
				( electricalCSetRef "@crescent_city_bb_fab1_lib.crescent_city_bb_fab1(sch_1):\DDR_M_CMD_DLL1-13\" )
				( member ( signalRef "@baseboard_fab2_lib.baseboard_fab2(sch_1):m_m_ba(1)") )
				( member ( signalRef "@baseboard_fab2_lib.baseboard_fab2(sch_1):m_m_ma(10)") )
				( objectStatus "NG_DDR_M_DLL_4" )
			)
			( netGroup "@crescent_city_bb_fab1_lib.crescent_city_bb_fab1(sch_1):\NG_DDR_M_DLL_5\"
				( memberType ( signal ) )
				( electricalCSetRef "@crescent_city_bb_fab1_lib.crescent_city_bb_fab1(sch_1):\DDR_M_CMD_DLL1-13\" )
				( member ( signalRef "@baseboard_fab2_lib.baseboard_fab2(sch_1):m_m_ba(0)") )
				( member ( signalRef "@baseboard_fab2_lib.baseboard_fab2(sch_1):m_m_ma(0)") )
				( objectStatus "NG_DDR_M_DLL_5" )
			)
			( netGroup "@crescent_city_bb_fab1_lib.crescent_city_bb_fab1(sch_1):\NG_DDR_M_DLL_6\"
				( memberType ( signal ) )
				( electricalCSetRef "@crescent_city_bb_fab1_lib.crescent_city_bb_fab1(sch_1):\DDR_M_CMD_DLL1-13\" )
				( member ( signalRef "@baseboard_fab2_lib.baseboard_fab2(sch_1):m_m_par") )
				( objectStatus "NG_DDR_M_DLL_6" )
			)
			( netGroup "@crescent_city_bb_fab1_lib.crescent_city_bb_fab1(sch_1):\NG_DDR_M_DLL_7\"
				( memberType ( signal ) )
				( electricalCSetRef "@crescent_city_bb_fab1_lib.crescent_city_bb_fab1(sch_1):\DDR_M_CMD_DLL1-13\" )
				( member ( signalRef "@baseboard_fab2_lib.baseboard_fab2(sch_1):m_m_ma(1)") )
				( member ( signalRef "@baseboard_fab2_lib.baseboard_fab2(sch_1):m_m_ma(3)") )
				( objectStatus "NG_DDR_M_DLL_7" )
			)
			( netGroup "@crescent_city_bb_fab1_lib.crescent_city_bb_fab1(sch_1):\NG_DDR_M_DLL_8\"
				( memberType ( signal ) )
				( electricalCSetRef "@crescent_city_bb_fab1_lib.crescent_city_bb_fab1(sch_1):\DDR_M_CMD_DLL1-13\" )
				( member ( signalRef "@baseboard_fab2_lib.baseboard_fab2(sch_1):m_m_ma(2)") )
				( member ( signalRef "@baseboard_fab2_lib.baseboard_fab2(sch_1):m_m_ma(4)") )
				( objectStatus "NG_DDR_M_DLL_8" )
			)
			( netGroup "@crescent_city_bb_fab1_lib.crescent_city_bb_fab1(sch_1):\NG_DDR_M_DLL_9\"
				( memberType ( signal ) )
				( electricalCSetRef "@crescent_city_bb_fab1_lib.crescent_city_bb_fab1(sch_1):\DDR_M_CMD_DLL1-13\" )
				( member ( signalRef "@baseboard_fab2_lib.baseboard_fab2(sch_1):m_m_ma(5)") )
				( member ( signalRef "@baseboard_fab2_lib.baseboard_fab2(sch_1):m_m_ma(6)") )
				( objectStatus "NG_DDR_M_DLL_9" )
			)
			( netGroup "@crescent_city_bb_fab1_lib.crescent_city_bb_fab1(sch_1):\NG_DDR_M_DLL_10\"
				( memberType ( signal ) )
				( electricalCSetRef "@crescent_city_bb_fab1_lib.crescent_city_bb_fab1(sch_1):\DDR_M_CMD_DLL1-13\" )
				( member ( signalRef "@baseboard_fab2_lib.baseboard_fab2(sch_1):m_m_ma(7)") )
				( member ( signalRef "@baseboard_fab2_lib.baseboard_fab2(sch_1):m_m_ma(8)") )
				( objectStatus "NG_DDR_M_DLL_10" )
			)
			( netGroup "@crescent_city_bb_fab1_lib.crescent_city_bb_fab1(sch_1):\NG_DDR_M_DLL_11\"
				( memberType ( signal ) )
				( electricalCSetRef "@crescent_city_bb_fab1_lib.crescent_city_bb_fab1(sch_1):\DDR_M_CMD_DLL1-13\" )
				( member ( signalRef "@baseboard_fab2_lib.baseboard_fab2(sch_1):m_m_ma(9)") )
				( member ( signalRef "@baseboard_fab2_lib.baseboard_fab2(sch_1):m_m_ma(12)") )
				( objectStatus "NG_DDR_M_DLL_11" )
			)
			( netGroup "@crescent_city_bb_fab1_lib.crescent_city_bb_fab1(sch_1):\NG_DDR_M_DLL_12\"
				( memberType ( signal ) )
				( electricalCSetRef "@crescent_city_bb_fab1_lib.crescent_city_bb_fab1(sch_1):\DDR_M_CMD_DLL1-13\" )
				( member ( signalRef "@baseboard_fab2_lib.baseboard_fab2(sch_1):m_m_bg(1)") )
				( member ( signalRef "@baseboard_fab2_lib.baseboard_fab2(sch_1):m_m_ma(11)") )
				( objectStatus "NG_DDR_M_DLL_12" )
			)
			( netGroup "@crescent_city_bb_fab1_lib.crescent_city_bb_fab1(sch_1):\NG_DDR_M_DLL_13\"
				( memberType ( signal ) )
				( electricalCSetRef "@crescent_city_bb_fab1_lib.crescent_city_bb_fab1(sch_1):\DDR_M_CMD_DLL1-13\" )
				( member ( signalRef "@baseboard_fab2_lib.baseboard_fab2(sch_1):m_m_act_n") )
				( member ( signalRef "@baseboard_fab2_lib.baseboard_fab2(sch_1):m_m_bg(0)") )
				( objectStatus "NG_DDR_M_DLL_13" )
			)
			( netGroup "@crescent_city_bb_fab1_lib.crescent_city_bb_fab1(sch_1):\NG_DDR_M_DLL_14\"
				( memberType ( signal ) )
				( electricalCSetRef "@crescent_city_bb_fab1_lib.crescent_city_bb_fab1(sch_1):\DDR_CTRL_DLL14-19\" )
				( member ( signalRef "@baseboard_fab2_lib.baseboard_fab2(sch_1):m_m_cs_n(0)") )
				( member ( signalRef "@baseboard_fab2_lib.baseboard_fab2(sch_1):m_m_odt(0)") )
				( objectStatus "NG_DDR_M_DLL_14" )
			)
			( netGroup "@crescent_city_bb_fab1_lib.crescent_city_bb_fab1(sch_1):\NG_DDR_M_DLL_15\"
				( memberType ( signal ) )
				( electricalCSetRef "@crescent_city_bb_fab1_lib.crescent_city_bb_fab1(sch_1):\DDR_CTRL_DLL14-19\" )
				( member ( signalRef "@baseboard_fab2_lib.baseboard_fab2(sch_1):m_m_cke(0)") )
				( objectStatus "NG_DDR_M_DLL_15" )
			)
			( netGroup "@crescent_city_bb_fab1_lib.crescent_city_bb_fab1(sch_1):\NG_DDR_M_DLL_16\"
				( memberType ( signal ) )
				( electricalCSetRef "@crescent_city_bb_fab1_lib.crescent_city_bb_fab1(sch_1):\DDR_CTRL_DLL14-19\" )
				( member ( signalRef "@baseboard_fab2_lib.baseboard_fab2(sch_1):m_m_cs_n(2)") )
				( objectStatus "NG_DDR_M_DLL_16" )
			)
			( netGroup "@crescent_city_bb_fab1_lib.crescent_city_bb_fab1(sch_1):\NG_DDR_M_DLL_17\"
				( memberType ( signal ) )
				( electricalCSetRef "@crescent_city_bb_fab1_lib.crescent_city_bb_fab1(sch_1):\DDR_CTRL_DLL14-19\" )
				( member ( signalRef "@baseboard_fab2_lib.baseboard_fab2(sch_1):m_m_cs_n(3)") )
				( objectStatus "NG_DDR_M_DLL_17" )
			)
			( netGroup "@crescent_city_bb_fab1_lib.crescent_city_bb_fab1(sch_1):\NG_DDR_M_DLL_18\"
				( memberType ( signal ) )
				( electricalCSetRef "@crescent_city_bb_fab1_lib.crescent_city_bb_fab1(sch_1):\DDR_CTRL_DLL14-19\" )
				( member ( signalRef "@baseboard_fab2_lib.baseboard_fab2(sch_1):m_m_cs_n(1)") )
				( member ( signalRef "@baseboard_fab2_lib.baseboard_fab2(sch_1):m_m_odt(1)") )
				( objectStatus "NG_DDR_M_DLL_18" )
			)
			( netGroup "@crescent_city_bb_fab1_lib.crescent_city_bb_fab1(sch_1):\NG_DDR_M_DLL_19\"
				( memberType ( signal ) )
				( electricalCSetRef "@crescent_city_bb_fab1_lib.crescent_city_bb_fab1(sch_1):\DDR_CTRL_DLL14-19\" )
				( member ( signalRef "@baseboard_fab2_lib.baseboard_fab2(sch_1):m_m_cke(1)") )
				( objectStatus "NG_DDR_M_DLL_19" )
			)
			( netGroup "@crescent_city_bb_fab1_lib.crescent_city_bb_fab1(sch_1):\NG_DDR_M_DLL_20\"
				( memberType ( signal ) )
				( electricalCSetRef "@crescent_city_bb_fab1_lib.crescent_city_bb_fab1(sch_1):\DDR_CTRL_DLL20-14\" )
				( member ( signalRef "@baseboard_fab2_lib.baseboard_fab2(sch_1):m_m_cs_n(4)") )
				( member ( signalRef "@baseboard_fab2_lib.baseboard_fab2(sch_1):m_m_odt(2)") )
				( objectStatus "NG_DDR_M_DLL_20" )
			)
			( netGroup "@crescent_city_bb_fab1_lib.crescent_city_bb_fab1(sch_1):\NG_DDR_M_DLL_21\"
				( memberType ( signal ) )
				( electricalCSetRef "@crescent_city_bb_fab1_lib.crescent_city_bb_fab1(sch_1):\DDR_CTRL_DLL20-14\" )
				( member ( signalRef "@baseboard_fab2_lib.baseboard_fab2(sch_1):m_m_cke(2)") )
				( objectStatus "NG_DDR_M_DLL_21" )
			)
			( netGroup "@crescent_city_bb_fab1_lib.crescent_city_bb_fab1(sch_1):\NG_DDR_M_DLL_22\"
				( memberType ( signal ) )
				( electricalCSetRef "@crescent_city_bb_fab1_lib.crescent_city_bb_fab1(sch_1):\DDR_CTRL_DLL20-14\" )
				( member ( signalRef "@baseboard_fab2_lib.baseboard_fab2(sch_1):m_m_cs_n(6)") )
				( member ( signalRef "@baseboard_fab2_lib.baseboard_fab2(sch_1):m_m_cs_n(7)") )
				( objectStatus "NG_DDR_M_DLL_22" )
			)
			( netGroup "@crescent_city_bb_fab1_lib.crescent_city_bb_fab1(sch_1):\NG_DDR_M_DLL_23\"
				( memberType ( signal ) )
				( electricalCSetRef "@crescent_city_bb_fab1_lib.crescent_city_bb_fab1(sch_1):\DDR_CTRL_DLL20-14\" )
				( member ( signalRef "@baseboard_fab2_lib.baseboard_fab2(sch_1):m_m_cs_n(5)") )
				( member ( signalRef "@baseboard_fab2_lib.baseboard_fab2(sch_1):m_m_odt(3)") )
				( objectStatus "NG_DDR_M_DLL_23" )
			)
			( netGroup "@crescent_city_bb_fab1_lib.crescent_city_bb_fab1(sch_1):\NG_DDR_M_DLL_24\"
				( memberType ( signal ) )
				( electricalCSetRef "@crescent_city_bb_fab1_lib.crescent_city_bb_fab1(sch_1):\DDR_CTRL_DLL20-14\" )
				( member ( signalRef "@baseboard_fab2_lib.baseboard_fab2(sch_1):m_m_cke(3)") )
				( objectStatus "NG_DDR_M_DLL_24" )
			)
			( netGroup "@crescent_city_bb_fab1_lib.crescent_city_bb_fab1(sch_1):\NG_DDR_L_DLL_1\"
				( memberType ( signal ) )
				( electricalCSetRef "@crescent_city_bb_fab1_lib.crescent_city_bb_fab1(sch_1):\DDR_L_CMD_DLL1-13\" )
				( member ( signalRef "@baseboard_fab2_lib.baseboard_fab2(sch_1):m_l_c(2)") )
				( member ( signalRef "@baseboard_fab2_lib.baseboard_fab2(sch_1):m_l_ma(17)") )
				( objectStatus "NG_DDR_L_DLL_1" )
			)
			( netGroup "@crescent_city_bb_fab1_lib.crescent_city_bb_fab1(sch_1):\NG_DDR_L_DLL_2\"
				( memberType ( signal ) )
				( electricalCSetRef "@crescent_city_bb_fab1_lib.crescent_city_bb_fab1(sch_1):\DDR_L_CMD_DLL1-13\" )
				( member ( signalRef "@baseboard_fab2_lib.baseboard_fab2(sch_1):m_l_ma(13)") )
				( member ( signalRef "@baseboard_fab2_lib.baseboard_fab2(sch_1):m_l_ma(15)") )
				( objectStatus "NG_DDR_L_DLL_2" )
			)
			( netGroup "@crescent_city_bb_fab1_lib.crescent_city_bb_fab1(sch_1):\NG_DDR_L_DLL_3\"
				( memberType ( signal ) )
				( electricalCSetRef "@crescent_city_bb_fab1_lib.crescent_city_bb_fab1(sch_1):\DDR_L_CMD_DLL1-13\" )
				( member ( signalRef "@baseboard_fab2_lib.baseboard_fab2(sch_1):m_l_ma(14)") )
				( member ( signalRef "@baseboard_fab2_lib.baseboard_fab2(sch_1):m_l_ma(16)") )
				( objectStatus "NG_DDR_L_DLL_3" )
			)
			( netGroup "@crescent_city_bb_fab1_lib.crescent_city_bb_fab1(sch_1):\NG_DDR_L_DLL_4\"
				( memberType ( signal ) )
				( electricalCSetRef "@crescent_city_bb_fab1_lib.crescent_city_bb_fab1(sch_1):\DDR_L_CMD_DLL1-13\" )
				( member ( signalRef "@baseboard_fab2_lib.baseboard_fab2(sch_1):m_l_ba(1)") )
				( member ( signalRef "@baseboard_fab2_lib.baseboard_fab2(sch_1):m_l_ma(10)") )
				( objectStatus "NG_DDR_L_DLL_4" )
			)
			( netGroup "@crescent_city_bb_fab1_lib.crescent_city_bb_fab1(sch_1):\NG_DDR_L_DLL_5\"
				( memberType ( signal ) )
				( electricalCSetRef "@crescent_city_bb_fab1_lib.crescent_city_bb_fab1(sch_1):\DDR_L_CMD_DLL1-13\" )
				( member ( signalRef "@baseboard_fab2_lib.baseboard_fab2(sch_1):m_l_ba(0)") )
				( member ( signalRef "@baseboard_fab2_lib.baseboard_fab2(sch_1):m_l_ma(0)") )
				( objectStatus "NG_DDR_L_DLL_5" )
			)
			( netGroup "@crescent_city_bb_fab1_lib.crescent_city_bb_fab1(sch_1):\NG_DDR_L_DLL_6\"
				( memberType ( signal ) )
				( electricalCSetRef "@crescent_city_bb_fab1_lib.crescent_city_bb_fab1(sch_1):\DDR_L_CMD_DLL1-13\" )
				( member ( signalRef "@baseboard_fab2_lib.baseboard_fab2(sch_1):m_l_par") )
				( objectStatus "NG_DDR_L_DLL_6" )
			)
			( netGroup "@crescent_city_bb_fab1_lib.crescent_city_bb_fab1(sch_1):\NG_DDR_L_DLL_7\"
				( memberType ( signal ) )
				( electricalCSetRef "@crescent_city_bb_fab1_lib.crescent_city_bb_fab1(sch_1):\DDR_L_CMD_DLL1-13\" )
				( member ( signalRef "@baseboard_fab2_lib.baseboard_fab2(sch_1):m_l_ma(1)") )
				( member ( signalRef "@baseboard_fab2_lib.baseboard_fab2(sch_1):m_l_ma(3)") )
				( objectStatus "NG_DDR_L_DLL_7" )
			)
			( netGroup "@crescent_city_bb_fab1_lib.crescent_city_bb_fab1(sch_1):\NG_DDR_L_DLL_8\"
				( memberType ( signal ) )
				( electricalCSetRef "@crescent_city_bb_fab1_lib.crescent_city_bb_fab1(sch_1):\DDR_L_CMD_DLL1-13\" )
				( member ( signalRef "@baseboard_fab2_lib.baseboard_fab2(sch_1):m_l_ma(2)") )
				( member ( signalRef "@baseboard_fab2_lib.baseboard_fab2(sch_1):m_l_ma(4)") )
				( objectStatus "NG_DDR_L_DLL_8" )
			)
			( netGroup "@crescent_city_bb_fab1_lib.crescent_city_bb_fab1(sch_1):\NG_DDR_L_DLL_9\"
				( memberType ( signal ) )
				( electricalCSetRef "@crescent_city_bb_fab1_lib.crescent_city_bb_fab1(sch_1):\DDR_L_CMD_DLL1-13\" )
				( member ( signalRef "@baseboard_fab2_lib.baseboard_fab2(sch_1):m_l_ma(5)") )
				( member ( signalRef "@baseboard_fab2_lib.baseboard_fab2(sch_1):m_l_ma(6)") )
				( objectStatus "NG_DDR_L_DLL_9" )
			)
			( netGroup "@crescent_city_bb_fab1_lib.crescent_city_bb_fab1(sch_1):\NG_DDR_L_DLL_10\"
				( memberType ( signal ) )
				( electricalCSetRef "@crescent_city_bb_fab1_lib.crescent_city_bb_fab1(sch_1):\DDR_L_CMD_DLL1-13\" )
				( member ( signalRef "@baseboard_fab2_lib.baseboard_fab2(sch_1):m_l_ma(7)") )
				( member ( signalRef "@baseboard_fab2_lib.baseboard_fab2(sch_1):m_l_ma(8)") )
				( objectStatus "NG_DDR_L_DLL_10" )
			)
			( netGroup "@crescent_city_bb_fab1_lib.crescent_city_bb_fab1(sch_1):\NG_DDR_L_DLL_11\"
				( memberType ( signal ) )
				( electricalCSetRef "@crescent_city_bb_fab1_lib.crescent_city_bb_fab1(sch_1):\DDR_L_CMD_DLL1-13\" )
				( member ( signalRef "@baseboard_fab2_lib.baseboard_fab2(sch_1):m_l_ma(9)") )
				( member ( signalRef "@baseboard_fab2_lib.baseboard_fab2(sch_1):m_l_ma(12)") )
				( objectStatus "NG_DDR_L_DLL_11" )
			)
			( netGroup "@crescent_city_bb_fab1_lib.crescent_city_bb_fab1(sch_1):\NG_DDR_L_DLL_12\"
				( memberType ( signal ) )
				( electricalCSetRef "@crescent_city_bb_fab1_lib.crescent_city_bb_fab1(sch_1):\DDR_L_CMD_DLL1-13\" )
				( member ( signalRef "@baseboard_fab2_lib.baseboard_fab2(sch_1):m_l_bg(1)") )
				( member ( signalRef "@baseboard_fab2_lib.baseboard_fab2(sch_1):m_l_ma(11)") )
				( objectStatus "NG_DDR_L_DLL_12" )
			)
			( netGroup "@crescent_city_bb_fab1_lib.crescent_city_bb_fab1(sch_1):\NG_DDR_L_DLL_13\"
				( memberType ( signal ) )
				( electricalCSetRef "@crescent_city_bb_fab1_lib.crescent_city_bb_fab1(sch_1):\DDR_L_CMD_DLL1-13\" )
				( member ( signalRef "@baseboard_fab2_lib.baseboard_fab2(sch_1):m_l_act_n") )
				( member ( signalRef "@baseboard_fab2_lib.baseboard_fab2(sch_1):m_l_bg(0)") )
				( objectStatus "NG_DDR_L_DLL_13" )
			)
			( netGroup "@crescent_city_bb_fab1_lib.crescent_city_bb_fab1(sch_1):\NG_DDR_L_DLL_14\"
				( memberType ( signal ) )
				( electricalCSetRef "@crescent_city_bb_fab1_lib.crescent_city_bb_fab1(sch_1):\DDR_CTRL_DLL14-19\" )
				( member ( signalRef "@baseboard_fab2_lib.baseboard_fab2(sch_1):m_l_cs_n(0)") )
				( member ( signalRef "@baseboard_fab2_lib.baseboard_fab2(sch_1):m_l_odt(0)") )
				( objectStatus "NG_DDR_L_DLL_14" )
			)
			( netGroup "@crescent_city_bb_fab1_lib.crescent_city_bb_fab1(sch_1):\NG_DDR_L_DLL_15\"
				( memberType ( signal ) )
				( electricalCSetRef "@crescent_city_bb_fab1_lib.crescent_city_bb_fab1(sch_1):\DDR_CTRL_DLL14-19\" )
				( member ( signalRef "@baseboard_fab2_lib.baseboard_fab2(sch_1):m_l_cke(0)") )
				( objectStatus "NG_DDR_L_DLL_15" )
			)
			( netGroup "@crescent_city_bb_fab1_lib.crescent_city_bb_fab1(sch_1):\NG_DDR_L_DLL_16\"
				( memberType ( signal ) )
				( electricalCSetRef "@crescent_city_bb_fab1_lib.crescent_city_bb_fab1(sch_1):\DDR_CTRL_DLL14-19\" )
				( member ( signalRef "@baseboard_fab2_lib.baseboard_fab2(sch_1):m_l_cs_n(2)") )
				( objectStatus "NG_DDR_L_DLL_16" )
			)
			( netGroup "@crescent_city_bb_fab1_lib.crescent_city_bb_fab1(sch_1):\NG_DDR_L_DLL_17\"
				( memberType ( signal ) )
				( electricalCSetRef "@crescent_city_bb_fab1_lib.crescent_city_bb_fab1(sch_1):\DDR_CTRL_DLL14-19\" )
				( member ( signalRef "@baseboard_fab2_lib.baseboard_fab2(sch_1):m_l_cs_n(3)") )
				( objectStatus "NG_DDR_L_DLL_17" )
			)
			( netGroup "@crescent_city_bb_fab1_lib.crescent_city_bb_fab1(sch_1):\NG_DDR_L_DLL_18\"
				( memberType ( signal ) )
				( electricalCSetRef "@crescent_city_bb_fab1_lib.crescent_city_bb_fab1(sch_1):\DDR_CTRL_DLL14-19\" )
				( member ( signalRef "@baseboard_fab2_lib.baseboard_fab2(sch_1):m_l_cs_n(1)") )
				( member ( signalRef "@baseboard_fab2_lib.baseboard_fab2(sch_1):m_l_odt(1)") )
				( objectStatus "NG_DDR_L_DLL_18" )
			)
			( netGroup "@crescent_city_bb_fab1_lib.crescent_city_bb_fab1(sch_1):\NG_DDR_L_DLL_19\"
				( memberType ( signal ) )
				( electricalCSetRef "@crescent_city_bb_fab1_lib.crescent_city_bb_fab1(sch_1):\DDR_CTRL_DLL14-19\" )
				( member ( signalRef "@baseboard_fab2_lib.baseboard_fab2(sch_1):m_l_cke(1)") )
				( objectStatus "NG_DDR_L_DLL_19" )
			)
			( netGroup "@crescent_city_bb_fab1_lib.crescent_city_bb_fab1(sch_1):\NG_DDR_L_DLL_20\"
				( memberType ( signal ) )
				( electricalCSetRef "@crescent_city_bb_fab1_lib.crescent_city_bb_fab1(sch_1):\DDR_CTRL_DLL20-14\" )
				( member ( signalRef "@baseboard_fab2_lib.baseboard_fab2(sch_1):m_l_cs_n(4)") )
				( member ( signalRef "@baseboard_fab2_lib.baseboard_fab2(sch_1):m_l_odt(2)") )
				( objectStatus "NG_DDR_L_DLL_20" )
			)
			( netGroup "@crescent_city_bb_fab1_lib.crescent_city_bb_fab1(sch_1):\NG_DDR_L_DLL_21\"
				( memberType ( signal ) )
				( electricalCSetRef "@crescent_city_bb_fab1_lib.crescent_city_bb_fab1(sch_1):\DDR_CTRL_DLL20-14\" )
				( member ( signalRef "@baseboard_fab2_lib.baseboard_fab2(sch_1):m_l_cke(2)") )
				( objectStatus "NG_DDR_L_DLL_21" )
			)
			( netGroup "@crescent_city_bb_fab1_lib.crescent_city_bb_fab1(sch_1):\NG_DDR_L_DLL_22\"
				( memberType ( signal ) )
				( electricalCSetRef "@crescent_city_bb_fab1_lib.crescent_city_bb_fab1(sch_1):\DDR_CTRL_DLL20-14\" )
				( member ( signalRef "@baseboard_fab2_lib.baseboard_fab2(sch_1):m_l_cs_n(6)") )
				( member ( signalRef "@baseboard_fab2_lib.baseboard_fab2(sch_1):m_l_cs_n(7)") )
				( objectStatus "NG_DDR_L_DLL_22" )
			)
			( netGroup "@crescent_city_bb_fab1_lib.crescent_city_bb_fab1(sch_1):\NG_DDR_L_DLL_23\"
				( memberType ( signal ) )
				( electricalCSetRef "@crescent_city_bb_fab1_lib.crescent_city_bb_fab1(sch_1):\DDR_CTRL_DLL20-14\" )
				( member ( signalRef "@baseboard_fab2_lib.baseboard_fab2(sch_1):m_l_cs_n(5)") )
				( member ( signalRef "@baseboard_fab2_lib.baseboard_fab2(sch_1):m_l_odt(3)") )
				( objectStatus "NG_DDR_L_DLL_23" )
			)
			( netGroup "@crescent_city_bb_fab1_lib.crescent_city_bb_fab1(sch_1):\NG_DDR_L_DLL_24\"
				( memberType ( signal ) )
				( electricalCSetRef "@crescent_city_bb_fab1_lib.crescent_city_bb_fab1(sch_1):\DDR_CTRL_DLL20-14\" )
				( member ( signalRef "@baseboard_fab2_lib.baseboard_fab2(sch_1):m_l_cke(3)") )
				( objectStatus "NG_DDR_L_DLL_24" )
			)
			( netGroup "@crescent_city_bb_fab1_lib.crescent_city_bb_fab1(sch_1):\NG_DDR_K_DLL_1\"
				( memberType ( signal ) )
				( electricalCSetRef "@crescent_city_bb_fab1_lib.crescent_city_bb_fab1(sch_1):\DDR_K_CMD_DLL1-13\" )
				( member ( signalRef "@baseboard_fab2_lib.baseboard_fab2(sch_1):m_k_c(2)") )
				( member ( signalRef "@baseboard_fab2_lib.baseboard_fab2(sch_1):m_k_ma(17)") )
				( objectStatus "NG_DDR_K_DLL_1" )
			)
			( netGroup "@crescent_city_bb_fab1_lib.crescent_city_bb_fab1(sch_1):\NG_DDR_K_DLL_2\"
				( memberType ( signal ) )
				( electricalCSetRef "@crescent_city_bb_fab1_lib.crescent_city_bb_fab1(sch_1):\DDR_K_CMD_DLL1-13\" )
				( member ( signalRef "@baseboard_fab2_lib.baseboard_fab2(sch_1):m_k_ma(13)") )
				( member ( signalRef "@baseboard_fab2_lib.baseboard_fab2(sch_1):m_k_ma(15)") )
				( objectStatus "NG_DDR_K_DLL_2" )
			)
			( netGroup "@crescent_city_bb_fab1_lib.crescent_city_bb_fab1(sch_1):\NG_DDR_K_DLL_3\"
				( memberType ( signal ) )
				( electricalCSetRef "@crescent_city_bb_fab1_lib.crescent_city_bb_fab1(sch_1):\DDR_K_CMD_DLL1-13\" )
				( member ( signalRef "@baseboard_fab2_lib.baseboard_fab2(sch_1):m_k_ma(14)") )
				( member ( signalRef "@baseboard_fab2_lib.baseboard_fab2(sch_1):m_k_ma(16)") )
				( objectStatus "NG_DDR_K_DLL_3" )
			)
			( netGroup "@crescent_city_bb_fab1_lib.crescent_city_bb_fab1(sch_1):\NG_DDR_K_DLL_4\"
				( memberType ( signal ) )
				( electricalCSetRef "@crescent_city_bb_fab1_lib.crescent_city_bb_fab1(sch_1):\DDR_K_CMD_DLL1-13\" )
				( member ( signalRef "@baseboard_fab2_lib.baseboard_fab2(sch_1):m_k_ba(1)") )
				( member ( signalRef "@baseboard_fab2_lib.baseboard_fab2(sch_1):m_k_ma(10)") )
				( objectStatus "NG_DDR_K_DLL_4" )
			)
			( netGroup "@crescent_city_bb_fab1_lib.crescent_city_bb_fab1(sch_1):\NG_DDR_K_DLL_5\"
				( memberType ( signal ) )
				( electricalCSetRef "@crescent_city_bb_fab1_lib.crescent_city_bb_fab1(sch_1):\DDR_K_CMD_DLL1-13\" )
				( member ( signalRef "@baseboard_fab2_lib.baseboard_fab2(sch_1):m_k_ba(0)") )
				( member ( signalRef "@baseboard_fab2_lib.baseboard_fab2(sch_1):m_k_ma(0)") )
				( objectStatus "NG_DDR_K_DLL_5" )
			)
			( netGroup "@crescent_city_bb_fab1_lib.crescent_city_bb_fab1(sch_1):\NG_DDR_K_DLL_6\"
				( memberType ( signal ) )
				( electricalCSetRef "@crescent_city_bb_fab1_lib.crescent_city_bb_fab1(sch_1):\DDR_K_CMD_DLL1-13\" )
				( member ( signalRef "@baseboard_fab2_lib.baseboard_fab2(sch_1):m_k_par") )
				( objectStatus "NG_DDR_K_DLL_6" )
			)
			( netGroup "@crescent_city_bb_fab1_lib.crescent_city_bb_fab1(sch_1):\NG_DDR_K_DLL_7\"
				( memberType ( signal ) )
				( electricalCSetRef "@crescent_city_bb_fab1_lib.crescent_city_bb_fab1(sch_1):\DDR_K_CMD_DLL1-13\" )
				( member ( signalRef "@baseboard_fab2_lib.baseboard_fab2(sch_1):m_k_ma(1)") )
				( member ( signalRef "@baseboard_fab2_lib.baseboard_fab2(sch_1):m_k_ma(3)") )
				( objectStatus "NG_DDR_K_DLL_7" )
			)
			( netGroup "@crescent_city_bb_fab1_lib.crescent_city_bb_fab1(sch_1):\NG_DDR_K_DLL_8\"
				( memberType ( signal ) )
				( electricalCSetRef "@crescent_city_bb_fab1_lib.crescent_city_bb_fab1(sch_1):\DDR_K_CMD_DLL1-13\" )
				( member ( signalRef "@baseboard_fab2_lib.baseboard_fab2(sch_1):m_k_ma(2)") )
				( member ( signalRef "@baseboard_fab2_lib.baseboard_fab2(sch_1):m_k_ma(4)") )
				( objectStatus "NG_DDR_K_DLL_8" )
			)
			( netGroup "@crescent_city_bb_fab1_lib.crescent_city_bb_fab1(sch_1):\NG_DDR_K_DLL_9\"
				( memberType ( signal ) )
				( electricalCSetRef "@crescent_city_bb_fab1_lib.crescent_city_bb_fab1(sch_1):\DDR_K_CMD_DLL1-13\" )
				( member ( signalRef "@baseboard_fab2_lib.baseboard_fab2(sch_1):m_k_ma(5)") )
				( member ( signalRef "@baseboard_fab2_lib.baseboard_fab2(sch_1):m_k_ma(6)") )
				( objectStatus "NG_DDR_K_DLL_9" )
			)
			( netGroup "@crescent_city_bb_fab1_lib.crescent_city_bb_fab1(sch_1):\NG_DDR_K_DLL_10\"
				( memberType ( signal ) )
				( electricalCSetRef "@crescent_city_bb_fab1_lib.crescent_city_bb_fab1(sch_1):\DDR_K_CMD_DLL1-13\" )
				( member ( signalRef "@baseboard_fab2_lib.baseboard_fab2(sch_1):m_k_ma(7)") )
				( member ( signalRef "@baseboard_fab2_lib.baseboard_fab2(sch_1):m_k_ma(8)") )
				( objectStatus "NG_DDR_K_DLL_10" )
			)
			( netGroup "@crescent_city_bb_fab1_lib.crescent_city_bb_fab1(sch_1):\NG_DDR_K_DLL_11\"
				( memberType ( signal ) )
				( electricalCSetRef "@crescent_city_bb_fab1_lib.crescent_city_bb_fab1(sch_1):\DDR_K_CMD_DLL1-13\" )
				( member ( signalRef "@baseboard_fab2_lib.baseboard_fab2(sch_1):m_k_ma(9)") )
				( member ( signalRef "@baseboard_fab2_lib.baseboard_fab2(sch_1):m_k_ma(12)") )
				( objectStatus "NG_DDR_K_DLL_11" )
			)
			( netGroup "@crescent_city_bb_fab1_lib.crescent_city_bb_fab1(sch_1):\NG_DDR_K_DLL_12\"
				( memberType ( signal ) )
				( electricalCSetRef "@crescent_city_bb_fab1_lib.crescent_city_bb_fab1(sch_1):\DDR_K_CMD_DLL1-13\" )
				( member ( signalRef "@baseboard_fab2_lib.baseboard_fab2(sch_1):m_k_bg(1)") )
				( member ( signalRef "@baseboard_fab2_lib.baseboard_fab2(sch_1):m_k_ma(11)") )
				( objectStatus "NG_DDR_K_DLL_12" )
			)
			( netGroup "@crescent_city_bb_fab1_lib.crescent_city_bb_fab1(sch_1):\NG_DDR_K_DLL_13\"
				( memberType ( signal ) )
				( electricalCSetRef "@crescent_city_bb_fab1_lib.crescent_city_bb_fab1(sch_1):\DDR_K_CMD_DLL1-13\" )
				( member ( signalRef "@baseboard_fab2_lib.baseboard_fab2(sch_1):m_k_act_n") )
				( member ( signalRef "@baseboard_fab2_lib.baseboard_fab2(sch_1):m_k_bg(0)") )
				( objectStatus "NG_DDR_K_DLL_13" )
			)
			( netGroup "@crescent_city_bb_fab1_lib.crescent_city_bb_fab1(sch_1):\NG_DDR_K_DLL_14\"
				( memberType ( signal ) )
				( electricalCSetRef "@crescent_city_bb_fab1_lib.crescent_city_bb_fab1(sch_1):\DDR_CTRL_DLL14-19\" )
				( member ( signalRef "@baseboard_fab2_lib.baseboard_fab2(sch_1):m_k_cs_n(0)") )
				( member ( signalRef "@baseboard_fab2_lib.baseboard_fab2(sch_1):m_k_odt(0)") )
				( objectStatus "NG_DDR_K_DLL_14" )
			)
			( netGroup "@crescent_city_bb_fab1_lib.crescent_city_bb_fab1(sch_1):\NG_DDR_K_DLL_15\"
				( memberType ( signal ) )
				( electricalCSetRef "@crescent_city_bb_fab1_lib.crescent_city_bb_fab1(sch_1):\DDR_CTRL_DLL14-19\" )
				( member ( signalRef "@baseboard_fab2_lib.baseboard_fab2(sch_1):m_k_cke(0)") )
				( objectStatus "NG_DDR_K_DLL_15" )
			)
			( netGroup "@crescent_city_bb_fab1_lib.crescent_city_bb_fab1(sch_1):\NG_DDR_K_DLL_16\"
				( memberType ( signal ) )
				( electricalCSetRef "@crescent_city_bb_fab1_lib.crescent_city_bb_fab1(sch_1):\DDR_CTRL_DLL14-19\" )
				( member ( signalRef "@baseboard_fab2_lib.baseboard_fab2(sch_1):m_k_cs_n(2)") )
				( objectStatus "NG_DDR_K_DLL_16" )
			)
			( netGroup "@crescent_city_bb_fab1_lib.crescent_city_bb_fab1(sch_1):\NG_DDR_K_DLL_17\"
				( memberType ( signal ) )
				( electricalCSetRef "@crescent_city_bb_fab1_lib.crescent_city_bb_fab1(sch_1):\DDR_CTRL_DLL14-19\" )
				( member ( signalRef "@baseboard_fab2_lib.baseboard_fab2(sch_1):m_k_cs_n(3)") )
				( objectStatus "NG_DDR_K_DLL_17" )
			)
			( netGroup "@crescent_city_bb_fab1_lib.crescent_city_bb_fab1(sch_1):\NG_DDR_K_DLL_18\"
				( memberType ( signal ) )
				( electricalCSetRef "@crescent_city_bb_fab1_lib.crescent_city_bb_fab1(sch_1):\DDR_CTRL_DLL14-19\" )
				( member ( signalRef "@baseboard_fab2_lib.baseboard_fab2(sch_1):m_k_cs_n(1)") )
				( member ( signalRef "@baseboard_fab2_lib.baseboard_fab2(sch_1):m_k_odt(1)") )
				( objectStatus "NG_DDR_K_DLL_18" )
			)
			( netGroup "@crescent_city_bb_fab1_lib.crescent_city_bb_fab1(sch_1):\NG_DDR_K_DLL_19\"
				( memberType ( signal ) )
				( electricalCSetRef "@crescent_city_bb_fab1_lib.crescent_city_bb_fab1(sch_1):\DDR_CTRL_DLL14-19\" )
				( member ( signalRef "@baseboard_fab2_lib.baseboard_fab2(sch_1):m_k_cke(1)") )
				( objectStatus "NG_DDR_K_DLL_19" )
			)
			( netGroup "@crescent_city_bb_fab1_lib.crescent_city_bb_fab1(sch_1):\NG_DDR_K_DLL_20\"
				( memberType ( signal ) )
				( electricalCSetRef "@crescent_city_bb_fab1_lib.crescent_city_bb_fab1(sch_1):\DDR_CTRL_DLL20-14\" )
				( member ( signalRef "@baseboard_fab2_lib.baseboard_fab2(sch_1):m_k_cs_n(4)") )
				( member ( signalRef "@baseboard_fab2_lib.baseboard_fab2(sch_1):m_k_odt(2)") )
				( objectStatus "NG_DDR_K_DLL_20" )
			)
			( netGroup "@crescent_city_bb_fab1_lib.crescent_city_bb_fab1(sch_1):\NG_DDR_K_DLL_21\"
				( memberType ( signal ) )
				( electricalCSetRef "@crescent_city_bb_fab1_lib.crescent_city_bb_fab1(sch_1):\DDR_CTRL_DLL20-14\" )
				( member ( signalRef "@baseboard_fab2_lib.baseboard_fab2(sch_1):m_k_cke(2)") )
				( objectStatus "NG_DDR_K_DLL_21" )
			)
			( netGroup "@crescent_city_bb_fab1_lib.crescent_city_bb_fab1(sch_1):\NG_DDR_K_DLL_22\"
				( memberType ( signal ) )
				( electricalCSetRef "@crescent_city_bb_fab1_lib.crescent_city_bb_fab1(sch_1):\DDR_CTRL_DLL20-14\" )
				( member ( signalRef "@baseboard_fab2_lib.baseboard_fab2(sch_1):m_k_cs_n(6)") )
				( member ( signalRef "@baseboard_fab2_lib.baseboard_fab2(sch_1):m_k_cs_n(7)") )
				( objectStatus "NG_DDR_K_DLL_22" )
			)
			( netGroup "@crescent_city_bb_fab1_lib.crescent_city_bb_fab1(sch_1):\NG_DDR_K_DLL_23\"
				( memberType ( signal ) )
				( electricalCSetRef "@crescent_city_bb_fab1_lib.crescent_city_bb_fab1(sch_1):\DDR_CTRL_DLL20-14\" )
				( member ( signalRef "@baseboard_fab2_lib.baseboard_fab2(sch_1):m_k_cs_n(5)") )
				( member ( signalRef "@baseboard_fab2_lib.baseboard_fab2(sch_1):m_k_odt(3)") )
				( objectStatus "NG_DDR_K_DLL_23" )
			)
			( netGroup "@crescent_city_bb_fab1_lib.crescent_city_bb_fab1(sch_1):\NG_DDR_K_DLL_24\"
				( memberType ( signal ) )
				( electricalCSetRef "@crescent_city_bb_fab1_lib.crescent_city_bb_fab1(sch_1):\DDR_CTRL_DLL20-14\" )
				( member ( signalRef "@baseboard_fab2_lib.baseboard_fab2(sch_1):m_k_cke(3)") )
				( objectStatus "NG_DDR_K_DLL_24" )
			)
			( netGroup "@crescent_city_bb_fab1_lib.crescent_city_bb_fab1(sch_1):\NG_DDR_J_DLL_1\"
				( memberType ( signal ) )
				( electricalCSetRef "@crescent_city_bb_fab1_lib.crescent_city_bb_fab1(sch_1):\DDR_J_CMD_DLL1-13\" )
				( member ( signalRef "@baseboard_fab2_lib.baseboard_fab2(sch_1):m_j_c(2)") )
				( member ( signalRef "@baseboard_fab2_lib.baseboard_fab2(sch_1):m_j_ma(17)") )
				( objectStatus "NG_DDR_J_DLL_1" )
			)
			( netGroup "@crescent_city_bb_fab1_lib.crescent_city_bb_fab1(sch_1):\NG_DDR_J_DLL_2\"
				( memberType ( signal ) )
				( electricalCSetRef "@crescent_city_bb_fab1_lib.crescent_city_bb_fab1(sch_1):\DDR_J_CMD_DLL1-13\" )
				( member ( signalRef "@baseboard_fab2_lib.baseboard_fab2(sch_1):m_j_ma(13)") )
				( member ( signalRef "@baseboard_fab2_lib.baseboard_fab2(sch_1):m_j_ma(15)") )
				( objectStatus "NG_DDR_J_DLL_2" )
			)
			( netGroup "@crescent_city_bb_fab1_lib.crescent_city_bb_fab1(sch_1):\NG_DDR_J_DLL_3\"
				( memberType ( signal ) )
				( electricalCSetRef "@crescent_city_bb_fab1_lib.crescent_city_bb_fab1(sch_1):\DDR_J_CMD_DLL1-13\" )
				( member ( signalRef "@baseboard_fab2_lib.baseboard_fab2(sch_1):m_j_ma(14)") )
				( member ( signalRef "@baseboard_fab2_lib.baseboard_fab2(sch_1):m_j_ma(16)") )
				( objectStatus "NG_DDR_J_DLL_3" )
			)
			( netGroup "@crescent_city_bb_fab1_lib.crescent_city_bb_fab1(sch_1):\NG_DDR_J_DLL_4\"
				( memberType ( signal ) )
				( electricalCSetRef "@crescent_city_bb_fab1_lib.crescent_city_bb_fab1(sch_1):\DDR_J_CMD_DLL1-13\" )
				( member ( signalRef "@baseboard_fab2_lib.baseboard_fab2(sch_1):m_j_ba(1)") )
				( member ( signalRef "@baseboard_fab2_lib.baseboard_fab2(sch_1):m_j_ma(10)") )
				( objectStatus "NG_DDR_J_DLL_4" )
			)
			( netGroup "@crescent_city_bb_fab1_lib.crescent_city_bb_fab1(sch_1):\NG_DDR_J_DLL_5\"
				( memberType ( signal ) )
				( electricalCSetRef "@crescent_city_bb_fab1_lib.crescent_city_bb_fab1(sch_1):\DDR_J_CMD_DLL1-13\" )
				( member ( signalRef "@baseboard_fab2_lib.baseboard_fab2(sch_1):m_j_ba(0)") )
				( member ( signalRef "@baseboard_fab2_lib.baseboard_fab2(sch_1):m_j_ma(0)") )
				( objectStatus "NG_DDR_J_DLL_5" )
			)
			( netGroup "@crescent_city_bb_fab1_lib.crescent_city_bb_fab1(sch_1):\NG_DDR_J_DLL_6\"
				( memberType ( signal ) )
				( electricalCSetRef "@crescent_city_bb_fab1_lib.crescent_city_bb_fab1(sch_1):\DDR_J_CMD_DLL1-13\" )
				( member ( signalRef "@baseboard_fab2_lib.baseboard_fab2(sch_1):m_j_par") )
				( objectStatus "NG_DDR_J_DLL_6" )
			)
			( netGroup "@crescent_city_bb_fab1_lib.crescent_city_bb_fab1(sch_1):\NG_DDR_J_DLL_7\"
				( memberType ( signal ) )
				( electricalCSetRef "@crescent_city_bb_fab1_lib.crescent_city_bb_fab1(sch_1):\DDR_J_CMD_DLL1-13\" )
				( member ( signalRef "@baseboard_fab2_lib.baseboard_fab2(sch_1):m_j_ma(1)") )
				( member ( signalRef "@baseboard_fab2_lib.baseboard_fab2(sch_1):m_j_ma(3)") )
				( objectStatus "NG_DDR_J_DLL_7" )
			)
			( netGroup "@crescent_city_bb_fab1_lib.crescent_city_bb_fab1(sch_1):\NG_DDR_J_DLL_8\"
				( memberType ( signal ) )
				( electricalCSetRef "@crescent_city_bb_fab1_lib.crescent_city_bb_fab1(sch_1):\DDR_J_CMD_DLL1-13\" )
				( member ( signalRef "@baseboard_fab2_lib.baseboard_fab2(sch_1):m_j_ma(2)") )
				( member ( signalRef "@baseboard_fab2_lib.baseboard_fab2(sch_1):m_j_ma(4)") )
				( objectStatus "NG_DDR_J_DLL_8" )
			)
			( netGroup "@crescent_city_bb_fab1_lib.crescent_city_bb_fab1(sch_1):\NG_DDR_J_DLL_9\"
				( memberType ( signal ) )
				( electricalCSetRef "@crescent_city_bb_fab1_lib.crescent_city_bb_fab1(sch_1):\DDR_J_CMD_DLL1-13\" )
				( member ( signalRef "@baseboard_fab2_lib.baseboard_fab2(sch_1):m_j_ma(5)") )
				( member ( signalRef "@baseboard_fab2_lib.baseboard_fab2(sch_1):m_j_ma(6)") )
				( objectStatus "NG_DDR_J_DLL_9" )
			)
			( netGroup "@crescent_city_bb_fab1_lib.crescent_city_bb_fab1(sch_1):\NG_DDR_J_DLL_10\"
				( memberType ( signal ) )
				( electricalCSetRef "@crescent_city_bb_fab1_lib.crescent_city_bb_fab1(sch_1):\DDR_J_CMD_DLL1-13\" )
				( member ( signalRef "@baseboard_fab2_lib.baseboard_fab2(sch_1):m_j_ma(7)") )
				( member ( signalRef "@baseboard_fab2_lib.baseboard_fab2(sch_1):m_j_ma(8)") )
				( objectStatus "NG_DDR_J_DLL_10" )
			)
			( netGroup "@crescent_city_bb_fab1_lib.crescent_city_bb_fab1(sch_1):\NG_DDR_J_DLL_11\"
				( memberType ( signal ) )
				( electricalCSetRef "@crescent_city_bb_fab1_lib.crescent_city_bb_fab1(sch_1):\DDR_J_CMD_DLL1-13\" )
				( member ( signalRef "@baseboard_fab2_lib.baseboard_fab2(sch_1):m_j_ma(9)") )
				( member ( signalRef "@baseboard_fab2_lib.baseboard_fab2(sch_1):m_j_ma(12)") )
				( objectStatus "NG_DDR_J_DLL_11" )
			)
			( netGroup "@crescent_city_bb_fab1_lib.crescent_city_bb_fab1(sch_1):\NG_DDR_J_DLL_12\"
				( memberType ( signal ) )
				( electricalCSetRef "@crescent_city_bb_fab1_lib.crescent_city_bb_fab1(sch_1):\DDR_J_CMD_DLL1-13\" )
				( member ( signalRef "@baseboard_fab2_lib.baseboard_fab2(sch_1):m_j_bg(1)") )
				( member ( signalRef "@baseboard_fab2_lib.baseboard_fab2(sch_1):m_j_ma(11)") )
				( objectStatus "NG_DDR_J_DLL_12" )
			)
			( netGroup "@crescent_city_bb_fab1_lib.crescent_city_bb_fab1(sch_1):\NG_DDR_J_DLL_13\"
				( memberType ( signal ) )
				( electricalCSetRef "@crescent_city_bb_fab1_lib.crescent_city_bb_fab1(sch_1):\DDR_J_CMD_DLL1-13\" )
				( member ( signalRef "@baseboard_fab2_lib.baseboard_fab2(sch_1):m_j_act_n") )
				( member ( signalRef "@baseboard_fab2_lib.baseboard_fab2(sch_1):m_j_bg(0)") )
				( objectStatus "NG_DDR_J_DLL_13" )
			)
			( netGroup "@crescent_city_bb_fab1_lib.crescent_city_bb_fab1(sch_1):\NG_DDR_J_DLL_14\"
				( memberType ( signal ) )
				( electricalCSetRef "@crescent_city_bb_fab1_lib.crescent_city_bb_fab1(sch_1):\DDR_CTRL_DLL14-19\" )
				( member ( signalRef "@baseboard_fab2_lib.baseboard_fab2(sch_1):m_j_cs_n(0)") )
				( member ( signalRef "@baseboard_fab2_lib.baseboard_fab2(sch_1):m_j_odt(0)") )
				( objectStatus "NG_DDR_J_DLL_14" )
			)
			( netGroup "@crescent_city_bb_fab1_lib.crescent_city_bb_fab1(sch_1):\NG_DDR_J_DLL_15\"
				( memberType ( signal ) )
				( electricalCSetRef "@crescent_city_bb_fab1_lib.crescent_city_bb_fab1(sch_1):\DDR_CTRL_DLL14-19\" )
				( member ( signalRef "@baseboard_fab2_lib.baseboard_fab2(sch_1):m_j_cke(0)") )
				( objectStatus "NG_DDR_J_DLL_15" )
			)
			( netGroup "@crescent_city_bb_fab1_lib.crescent_city_bb_fab1(sch_1):\NG_DDR_J_DLL_16\"
				( memberType ( signal ) )
				( electricalCSetRef "@crescent_city_bb_fab1_lib.crescent_city_bb_fab1(sch_1):\DDR_CTRL_DLL14-19\" )
				( member ( signalRef "@baseboard_fab2_lib.baseboard_fab2(sch_1):m_j_cs_n(2)") )
				( objectStatus "NG_DDR_J_DLL_16" )
			)
			( netGroup "@crescent_city_bb_fab1_lib.crescent_city_bb_fab1(sch_1):\NG_DDR_J_DLL_17\"
				( memberType ( signal ) )
				( electricalCSetRef "@crescent_city_bb_fab1_lib.crescent_city_bb_fab1(sch_1):\DDR_CTRL_DLL14-19\" )
				( member ( signalRef "@baseboard_fab2_lib.baseboard_fab2(sch_1):m_j_cs_n(3)") )
				( objectStatus "NG_DDR_J_DLL_17" )
			)
			( netGroup "@crescent_city_bb_fab1_lib.crescent_city_bb_fab1(sch_1):\NG_DDR_J_DLL_18\"
				( memberType ( signal ) )
				( electricalCSetRef "@crescent_city_bb_fab1_lib.crescent_city_bb_fab1(sch_1):\DDR_CTRL_DLL14-19\" )
				( member ( signalRef "@baseboard_fab2_lib.baseboard_fab2(sch_1):m_j_cs_n(1)") )
				( member ( signalRef "@baseboard_fab2_lib.baseboard_fab2(sch_1):m_j_odt(1)") )
				( objectStatus "NG_DDR_J_DLL_18" )
			)
			( netGroup "@crescent_city_bb_fab1_lib.crescent_city_bb_fab1(sch_1):\NG_DDR_J_DLL_19\"
				( memberType ( signal ) )
				( electricalCSetRef "@crescent_city_bb_fab1_lib.crescent_city_bb_fab1(sch_1):\DDR_CTRL_DLL14-19\" )
				( member ( signalRef "@baseboard_fab2_lib.baseboard_fab2(sch_1):m_j_cke(1)") )
				( objectStatus "NG_DDR_J_DLL_19" )
			)
			( netGroup "@crescent_city_bb_fab1_lib.crescent_city_bb_fab1(sch_1):\NG_DDR_J_DLL_20\"
				( memberType ( signal ) )
				( electricalCSetRef "@crescent_city_bb_fab1_lib.crescent_city_bb_fab1(sch_1):\DDR_CTRL_DLL20-14\" )
				( member ( signalRef "@baseboard_fab2_lib.baseboard_fab2(sch_1):m_j_cs_n(4)") )
				( member ( signalRef "@baseboard_fab2_lib.baseboard_fab2(sch_1):m_j_odt(2)") )
				( objectStatus "NG_DDR_J_DLL_20" )
			)
			( netGroup "@crescent_city_bb_fab1_lib.crescent_city_bb_fab1(sch_1):\NG_DDR_J_DLL_21\"
				( memberType ( signal ) )
				( electricalCSetRef "@crescent_city_bb_fab1_lib.crescent_city_bb_fab1(sch_1):\DDR_CTRL_DLL20-14\" )
				( member ( signalRef "@baseboard_fab2_lib.baseboard_fab2(sch_1):m_j_cke(2)") )
				( objectStatus "NG_DDR_J_DLL_21" )
			)
			( netGroup "@crescent_city_bb_fab1_lib.crescent_city_bb_fab1(sch_1):\NG_DDR_J_DLL_22\"
				( memberType ( signal ) )
				( electricalCSetRef "@crescent_city_bb_fab1_lib.crescent_city_bb_fab1(sch_1):\DDR_CTRL_DLL20-14\" )
				( member ( signalRef "@baseboard_fab2_lib.baseboard_fab2(sch_1):m_j_cs_n(6)") )
				( member ( signalRef "@baseboard_fab2_lib.baseboard_fab2(sch_1):m_j_cs_n(7)") )
				( objectStatus "NG_DDR_J_DLL_22" )
			)
			( netGroup "@crescent_city_bb_fab1_lib.crescent_city_bb_fab1(sch_1):\NG_DDR_J_DLL_23\"
				( memberType ( signal ) )
				( electricalCSetRef "@crescent_city_bb_fab1_lib.crescent_city_bb_fab1(sch_1):\DDR_CTRL_DLL20-14\" )
				( member ( signalRef "@baseboard_fab2_lib.baseboard_fab2(sch_1):m_j_cs_n(5)") )
				( member ( signalRef "@baseboard_fab2_lib.baseboard_fab2(sch_1):m_j_odt(3)") )
				( objectStatus "NG_DDR_J_DLL_23" )
			)
			( netGroup "@crescent_city_bb_fab1_lib.crescent_city_bb_fab1(sch_1):\NG_DDR_J_DLL_24\"
				( memberType ( signal ) )
				( electricalCSetRef "@crescent_city_bb_fab1_lib.crescent_city_bb_fab1(sch_1):\DDR_CTRL_DLL20-14\" )
				( member ( signalRef "@baseboard_fab2_lib.baseboard_fab2(sch_1):m_j_cke(3)") )
				( objectStatus "NG_DDR_J_DLL_24" )
			)
			( netGroup "@crescent_city_bb_fab1_lib.crescent_city_bb_fab1(sch_1):\NG_DDR_H_DLL_1\"
				( memberType ( signal ) )
				( electricalCSetRef "@crescent_city_bb_fab1_lib.crescent_city_bb_fab1(sch_1):\DDR_H_CMD_DLL1-13\" )
				( member ( signalRef "@baseboard_fab2_lib.baseboard_fab2(sch_1):m_h_c(2)") )
				( member ( signalRef "@baseboard_fab2_lib.baseboard_fab2(sch_1):m_h_ma(17)") )
				( objectStatus "NG_DDR_H_DLL_1" )
			)
			( netGroup "@crescent_city_bb_fab1_lib.crescent_city_bb_fab1(sch_1):\NG_DDR_H_DLL_2\"
				( memberType ( signal ) )
				( electricalCSetRef "@crescent_city_bb_fab1_lib.crescent_city_bb_fab1(sch_1):\DDR_H_CMD_DLL1-13\" )
				( member ( signalRef "@baseboard_fab2_lib.baseboard_fab2(sch_1):m_h_ma(13)") )
				( member ( signalRef "@baseboard_fab2_lib.baseboard_fab2(sch_1):m_h_ma(14)") )
				( objectStatus "NG_DDR_H_DLL_2" )
			)
			( netGroup "@crescent_city_bb_fab1_lib.crescent_city_bb_fab1(sch_1):\NG_DDR_H_DLL_3\"
				( memberType ( signal ) )
				( electricalCSetRef "@crescent_city_bb_fab1_lib.crescent_city_bb_fab1(sch_1):\DDR_H_CMD_DLL1-13\" )
				( member ( signalRef "@baseboard_fab2_lib.baseboard_fab2(sch_1):m_h_ma(15)") )
				( member ( signalRef "@baseboard_fab2_lib.baseboard_fab2(sch_1):m_h_ma(16)") )
				( objectStatus "NG_DDR_H_DLL_3" )
			)
			( netGroup "@crescent_city_bb_fab1_lib.crescent_city_bb_fab1(sch_1):\NG_DDR_H_DLL_4\"
				( memberType ( signal ) )
				( electricalCSetRef "@crescent_city_bb_fab1_lib.crescent_city_bb_fab1(sch_1):\DDR_H_CMD_DLL1-13\" )
				( member ( signalRef "@baseboard_fab2_lib.baseboard_fab2(sch_1):m_h_ba(1)") )
				( member ( signalRef "@baseboard_fab2_lib.baseboard_fab2(sch_1):m_h_ma(10)") )
				( objectStatus "NG_DDR_H_DLL_4" )
			)
			( netGroup "@crescent_city_bb_fab1_lib.crescent_city_bb_fab1(sch_1):\NG_DDR_H_DLL_5\"
				( memberType ( signal ) )
				( electricalCSetRef "@crescent_city_bb_fab1_lib.crescent_city_bb_fab1(sch_1):\DDR_H_CMD_DLL1-13\" )
				( member ( signalRef "@baseboard_fab2_lib.baseboard_fab2(sch_1):m_h_ba(0)") )
				( member ( signalRef "@baseboard_fab2_lib.baseboard_fab2(sch_1):m_h_ma(0)") )
				( objectStatus "NG_DDR_H_DLL_5" )
			)
			( netGroup "@crescent_city_bb_fab1_lib.crescent_city_bb_fab1(sch_1):\NG_DDR_H_DLL_6\"
				( memberType ( signal ) )
				( electricalCSetRef "@crescent_city_bb_fab1_lib.crescent_city_bb_fab1(sch_1):\DDR_H_CMD_DLL1-13\" )
				( member ( signalRef "@baseboard_fab2_lib.baseboard_fab2(sch_1):m_h_par") )
				( objectStatus "NG_DDR_H_DLL_6" )
			)
			( netGroup "@crescent_city_bb_fab1_lib.crescent_city_bb_fab1(sch_1):\NG_DDR_H_DLL_7\"
				( memberType ( signal ) )
				( electricalCSetRef "@crescent_city_bb_fab1_lib.crescent_city_bb_fab1(sch_1):\DDR_H_CMD_DLL1-13\" )
				( member ( signalRef "@baseboard_fab2_lib.baseboard_fab2(sch_1):m_h_ma(1)") )
				( member ( signalRef "@baseboard_fab2_lib.baseboard_fab2(sch_1):m_h_ma(3)") )
				( objectStatus "NG_DDR_H_DLL_7" )
			)
			( netGroup "@crescent_city_bb_fab1_lib.crescent_city_bb_fab1(sch_1):\NG_DDR_H_DLL_8\"
				( memberType ( signal ) )
				( electricalCSetRef "@crescent_city_bb_fab1_lib.crescent_city_bb_fab1(sch_1):\DDR_H_CMD_DLL1-13\" )
				( member ( signalRef "@baseboard_fab2_lib.baseboard_fab2(sch_1):m_h_ma(2)") )
				( member ( signalRef "@baseboard_fab2_lib.baseboard_fab2(sch_1):m_h_ma(4)") )
				( objectStatus "NG_DDR_H_DLL_8" )
			)
			( netGroup "@crescent_city_bb_fab1_lib.crescent_city_bb_fab1(sch_1):\NG_DDR_H_DLL_9\"
				( memberType ( signal ) )
				( electricalCSetRef "@crescent_city_bb_fab1_lib.crescent_city_bb_fab1(sch_1):\DDR_H_CMD_DLL1-13\" )
				( member ( signalRef "@baseboard_fab2_lib.baseboard_fab2(sch_1):m_h_ma(5)") )
				( member ( signalRef "@baseboard_fab2_lib.baseboard_fab2(sch_1):m_h_ma(6)") )
				( objectStatus "NG_DDR_H_DLL_9" )
			)
			( netGroup "@crescent_city_bb_fab1_lib.crescent_city_bb_fab1(sch_1):\NG_DDR_H_DLL_10\"
				( memberType ( signal ) )
				( electricalCSetRef "@crescent_city_bb_fab1_lib.crescent_city_bb_fab1(sch_1):\DDR_H_CMD_DLL1-13\" )
				( member ( signalRef "@baseboard_fab2_lib.baseboard_fab2(sch_1):m_h_ma(7)") )
				( member ( signalRef "@baseboard_fab2_lib.baseboard_fab2(sch_1):m_h_ma(8)") )
				( objectStatus "NG_DDR_H_DLL_10" )
			)
			( netGroup "@crescent_city_bb_fab1_lib.crescent_city_bb_fab1(sch_1):\NG_DDR_H_DLL_11\"
				( memberType ( signal ) )
				( electricalCSetRef "@crescent_city_bb_fab1_lib.crescent_city_bb_fab1(sch_1):\DDR_H_CMD_DLL1-13\" )
				( member ( signalRef "@baseboard_fab2_lib.baseboard_fab2(sch_1):m_h_ma(9)") )
				( member ( signalRef "@baseboard_fab2_lib.baseboard_fab2(sch_1):m_h_ma(12)") )
				( objectStatus "NG_DDR_H_DLL_11" )
			)
			( netGroup "@crescent_city_bb_fab1_lib.crescent_city_bb_fab1(sch_1):\NG_DDR_H_DLL_12\"
				( memberType ( signal ) )
				( electricalCSetRef "@crescent_city_bb_fab1_lib.crescent_city_bb_fab1(sch_1):\DDR_H_CMD_DLL1-13\" )
				( member ( signalRef "@baseboard_fab2_lib.baseboard_fab2(sch_1):m_h_bg(1)") )
				( member ( signalRef "@baseboard_fab2_lib.baseboard_fab2(sch_1):m_h_ma(11)") )
				( objectStatus "NG_DDR_H_DLL_12" )
			)
			( netGroup "@crescent_city_bb_fab1_lib.crescent_city_bb_fab1(sch_1):\NG_DDR_H_DLL_13\"
				( memberType ( signal ) )
				( electricalCSetRef "@crescent_city_bb_fab1_lib.crescent_city_bb_fab1(sch_1):\DDR_H_CMD_DLL1-13\" )
				( member ( signalRef "@baseboard_fab2_lib.baseboard_fab2(sch_1):m_h_act_n") )
				( member ( signalRef "@baseboard_fab2_lib.baseboard_fab2(sch_1):m_h_bg(0)") )
				( objectStatus "NG_DDR_H_DLL_13" )
			)
			( netGroup "@crescent_city_bb_fab1_lib.crescent_city_bb_fab1(sch_1):\NG_DDR_H_DLL_14\"
				( memberType ( signal ) )
				( electricalCSetRef "@crescent_city_bb_fab1_lib.crescent_city_bb_fab1(sch_1):\DDR_CTRL_DLL14-19\" )
				( member ( signalRef "@baseboard_fab2_lib.baseboard_fab2(sch_1):m_h_cs_n(0)") )
				( member ( signalRef "@baseboard_fab2_lib.baseboard_fab2(sch_1):m_h_odt(0)") )
				( objectStatus "NG_DDR_H_DLL_14" )
			)
			( netGroup "@crescent_city_bb_fab1_lib.crescent_city_bb_fab1(sch_1):\NG_DDR_H_DLL_15\"
				( memberType ( signal ) )
				( electricalCSetRef "@crescent_city_bb_fab1_lib.crescent_city_bb_fab1(sch_1):\DDR_CTRL_DLL14-19\" )
				( member ( signalRef "@baseboard_fab2_lib.baseboard_fab2(sch_1):m_h_cke(0)") )
				( objectStatus "NG_DDR_H_DLL_15" )
			)
			( netGroup "@crescent_city_bb_fab1_lib.crescent_city_bb_fab1(sch_1):\NG_DDR_H_DLL_16\"
				( memberType ( signal ) )
				( electricalCSetRef "@crescent_city_bb_fab1_lib.crescent_city_bb_fab1(sch_1):\DDR_CTRL_DLL14-19\" )
				( member ( signalRef "@baseboard_fab2_lib.baseboard_fab2(sch_1):m_h_cs_n(2)") )
				( objectStatus "NG_DDR_H_DLL_16" )
			)
			( netGroup "@crescent_city_bb_fab1_lib.crescent_city_bb_fab1(sch_1):\NG_DDR_H_DLL_17\"
				( memberType ( signal ) )
				( electricalCSetRef "@crescent_city_bb_fab1_lib.crescent_city_bb_fab1(sch_1):\DDR_CTRL_DLL14-19\" )
				( member ( signalRef "@baseboard_fab2_lib.baseboard_fab2(sch_1):m_h_cs_n(3)") )
				( objectStatus "NG_DDR_H_DLL_17" )
			)
			( netGroup "@crescent_city_bb_fab1_lib.crescent_city_bb_fab1(sch_1):\NG_DDR_H_DLL_18\"
				( memberType ( signal ) )
				( electricalCSetRef "@crescent_city_bb_fab1_lib.crescent_city_bb_fab1(sch_1):\DDR_CTRL_DLL14-19\" )
				( member ( signalRef "@baseboard_fab2_lib.baseboard_fab2(sch_1):m_h_cs_n(1)") )
				( member ( signalRef "@baseboard_fab2_lib.baseboard_fab2(sch_1):m_h_odt(1)") )
				( objectStatus "NG_DDR_H_DLL_18" )
			)
			( netGroup "@crescent_city_bb_fab1_lib.crescent_city_bb_fab1(sch_1):\NG_DDR_H_DLL_19\"
				( memberType ( signal ) )
				( electricalCSetRef "@crescent_city_bb_fab1_lib.crescent_city_bb_fab1(sch_1):\DDR_CTRL_DLL14-19\" )
				( member ( signalRef "@baseboard_fab2_lib.baseboard_fab2(sch_1):m_h_cke(1)") )
				( objectStatus "NG_DDR_H_DLL_19" )
			)
			( netGroup "@crescent_city_bb_fab1_lib.crescent_city_bb_fab1(sch_1):\NG_DDR_H_DLL_20\"
				( memberType ( signal ) )
				( electricalCSetRef "@crescent_city_bb_fab1_lib.crescent_city_bb_fab1(sch_1):\DDR_CTRL_DLL20-14\" )
				( member ( signalRef "@baseboard_fab2_lib.baseboard_fab2(sch_1):m_h_cs_n(4)") )
				( member ( signalRef "@baseboard_fab2_lib.baseboard_fab2(sch_1):m_h_odt(2)") )
				( objectStatus "NG_DDR_H_DLL_20" )
			)
			( netGroup "@crescent_city_bb_fab1_lib.crescent_city_bb_fab1(sch_1):\NG_DDR_H_DLL_21\"
				( memberType ( signal ) )
				( electricalCSetRef "@crescent_city_bb_fab1_lib.crescent_city_bb_fab1(sch_1):\DDR_CTRL_DLL20-14\" )
				( member ( signalRef "@baseboard_fab2_lib.baseboard_fab2(sch_1):m_h_cke(2)") )
				( objectStatus "NG_DDR_H_DLL_21" )
			)
			( netGroup "@crescent_city_bb_fab1_lib.crescent_city_bb_fab1(sch_1):\NG_DDR_H_DLL_22\"
				( memberType ( signal ) )
				( electricalCSetRef "@crescent_city_bb_fab1_lib.crescent_city_bb_fab1(sch_1):\DDR_CTRL_DLL20-14\" )
				( member ( signalRef "@baseboard_fab2_lib.baseboard_fab2(sch_1):m_h_cs_n(6)") )
				( member ( signalRef "@baseboard_fab2_lib.baseboard_fab2(sch_1):m_h_cs_n(7)") )
				( objectStatus "NG_DDR_H_DLL_22" )
			)
			( netGroup "@crescent_city_bb_fab1_lib.crescent_city_bb_fab1(sch_1):\NG_DDR_H_DLL_23\"
				( memberType ( signal ) )
				( electricalCSetRef "@crescent_city_bb_fab1_lib.crescent_city_bb_fab1(sch_1):\DDR_CTRL_DLL20-14\" )
				( member ( signalRef "@baseboard_fab2_lib.baseboard_fab2(sch_1):m_h_cs_n(5)") )
				( member ( signalRef "@baseboard_fab2_lib.baseboard_fab2(sch_1):m_h_odt(3)") )
				( objectStatus "NG_DDR_H_DLL_23" )
			)
			( netGroup "@crescent_city_bb_fab1_lib.crescent_city_bb_fab1(sch_1):\NG_DDR_H_DLL_24\"
				( memberType ( signal ) )
				( electricalCSetRef "@crescent_city_bb_fab1_lib.crescent_city_bb_fab1(sch_1):\DDR_CTRL_DLL20-14\" )
				( member ( signalRef "@baseboard_fab2_lib.baseboard_fab2(sch_1):m_h_cke(3)") )
				( objectStatus "NG_DDR_H_DLL_24" )
			)
			( netGroup "@crescent_city_bb_fab1_lib.crescent_city_bb_fab1(sch_1):\NG_DDR_G_DLL_1\"
				( memberType ( signal ) )
				( electricalCSetRef "@crescent_city_bb_fab1_lib.crescent_city_bb_fab1(sch_1):\DDR_G_CMD_DLL1-13\" )
				( member ( signalRef "@baseboard_fab2_lib.baseboard_fab2(sch_1):m_g_c(2)") )
				( member ( signalRef "@baseboard_fab2_lib.baseboard_fab2(sch_1):m_g_ma(17)") )
				( objectStatus "NG_DDR_G_DLL_1" )
			)
			( netGroup "@crescent_city_bb_fab1_lib.crescent_city_bb_fab1(sch_1):\NG_DDR_G_DLL_2\"
				( memberType ( signal ) )
				( electricalCSetRef "@crescent_city_bb_fab1_lib.crescent_city_bb_fab1(sch_1):\DDR_G_CMD_DLL1-13\" )
				( member ( signalRef "@baseboard_fab2_lib.baseboard_fab2(sch_1):m_g_ma(13)") )
				( member ( signalRef "@baseboard_fab2_lib.baseboard_fab2(sch_1):m_g_ma(15)") )
				( objectStatus "NG_DDR_G_DLL_2" )
			)
			( netGroup "@crescent_city_bb_fab1_lib.crescent_city_bb_fab1(sch_1):\NG_DDR_G_DLL_3\"
				( memberType ( signal ) )
				( electricalCSetRef "@crescent_city_bb_fab1_lib.crescent_city_bb_fab1(sch_1):\DDR_G_CMD_DLL1-13\" )
				( member ( signalRef "@baseboard_fab2_lib.baseboard_fab2(sch_1):m_g_ma(14)") )
				( member ( signalRef "@baseboard_fab2_lib.baseboard_fab2(sch_1):m_g_ma(16)") )
				( objectStatus "NG_DDR_G_DLL_3" )
			)
			( netGroup "@crescent_city_bb_fab1_lib.crescent_city_bb_fab1(sch_1):\NG_DDR_G_DLL_4\"
				( memberType ( signal ) )
				( electricalCSetRef "@crescent_city_bb_fab1_lib.crescent_city_bb_fab1(sch_1):\DDR_G_CMD_DLL1-13\" )
				( member ( signalRef "@baseboard_fab2_lib.baseboard_fab2(sch_1):m_g_ba(1)") )
				( member ( signalRef "@baseboard_fab2_lib.baseboard_fab2(sch_1):m_g_ma(10)") )
				( objectStatus "NG_DDR_G_DLL_4" )
			)
			( netGroup "@crescent_city_bb_fab1_lib.crescent_city_bb_fab1(sch_1):\NG_DDR_G_DLL_5\"
				( memberType ( signal ) )
				( electricalCSetRef "@crescent_city_bb_fab1_lib.crescent_city_bb_fab1(sch_1):\DDR_G_CMD_DLL1-13\" )
				( member ( signalRef "@baseboard_fab2_lib.baseboard_fab2(sch_1):m_g_ba(0)") )
				( member ( signalRef "@baseboard_fab2_lib.baseboard_fab2(sch_1):m_g_ma(0)") )
				( objectStatus "NG_DDR_G_DLL_5" )
			)
			( netGroup "@crescent_city_bb_fab1_lib.crescent_city_bb_fab1(sch_1):\NG_DDR_G_DLL_6\"
				( memberType ( signal ) )
				( electricalCSetRef "@crescent_city_bb_fab1_lib.crescent_city_bb_fab1(sch_1):\DDR_G_CMD_DLL1-13\" )
				( member ( signalRef "@baseboard_fab2_lib.baseboard_fab2(sch_1):m_g_par") )
				( objectStatus "NG_DDR_G_DLL_6" )
			)
			( netGroup "@crescent_city_bb_fab1_lib.crescent_city_bb_fab1(sch_1):\NG_DDR_G_DLL_7\"
				( memberType ( signal ) )
				( electricalCSetRef "@crescent_city_bb_fab1_lib.crescent_city_bb_fab1(sch_1):\DDR_G_CMD_DLL1-13\" )
				( member ( signalRef "@baseboard_fab2_lib.baseboard_fab2(sch_1):m_g_ma(1)") )
				( member ( signalRef "@baseboard_fab2_lib.baseboard_fab2(sch_1):m_g_ma(3)") )
				( objectStatus "NG_DDR_G_DLL_7" )
			)
			( netGroup "@crescent_city_bb_fab1_lib.crescent_city_bb_fab1(sch_1):\NG_DDR_G_DLL_8\"
				( memberType ( signal ) )
				( electricalCSetRef "@crescent_city_bb_fab1_lib.crescent_city_bb_fab1(sch_1):\DDR_G_CMD_DLL1-13\" )
				( member ( signalRef "@baseboard_fab2_lib.baseboard_fab2(sch_1):m_g_ma(2)") )
				( member ( signalRef "@baseboard_fab2_lib.baseboard_fab2(sch_1):m_g_ma(4)") )
				( objectStatus "NG_DDR_G_DLL_8" )
			)
			( netGroup "@crescent_city_bb_fab1_lib.crescent_city_bb_fab1(sch_1):\NG_DDR_G_DLL_9\"
				( memberType ( signal ) )
				( electricalCSetRef "@crescent_city_bb_fab1_lib.crescent_city_bb_fab1(sch_1):\DDR_G_CMD_DLL1-13\" )
				( member ( signalRef "@baseboard_fab2_lib.baseboard_fab2(sch_1):m_g_ma(5)") )
				( member ( signalRef "@baseboard_fab2_lib.baseboard_fab2(sch_1):m_g_ma(6)") )
				( objectStatus "NG_DDR_G_DLL_9" )
			)
			( netGroup "@crescent_city_bb_fab1_lib.crescent_city_bb_fab1(sch_1):\NG_DDR_G_DLL_10\"
				( memberType ( signal ) )
				( electricalCSetRef "@crescent_city_bb_fab1_lib.crescent_city_bb_fab1(sch_1):\DDR_G_CMD_DLL1-13\" )
				( member ( signalRef "@baseboard_fab2_lib.baseboard_fab2(sch_1):m_g_ma(7)") )
				( member ( signalRef "@baseboard_fab2_lib.baseboard_fab2(sch_1):m_g_ma(8)") )
				( objectStatus "NG_DDR_G_DLL_10" )
			)
			( netGroup "@crescent_city_bb_fab1_lib.crescent_city_bb_fab1(sch_1):\NG_DDR_G_DLL_11\"
				( memberType ( signal ) )
				( electricalCSetRef "@crescent_city_bb_fab1_lib.crescent_city_bb_fab1(sch_1):\DDR_G_CMD_DLL1-13\" )
				( member ( signalRef "@baseboard_fab2_lib.baseboard_fab2(sch_1):m_g_ma(9)") )
				( member ( signalRef "@baseboard_fab2_lib.baseboard_fab2(sch_1):m_g_ma(12)") )
				( objectStatus "NG_DDR_G_DLL_11" )
			)
			( netGroup "@crescent_city_bb_fab1_lib.crescent_city_bb_fab1(sch_1):\NG_DDR_G_DLL_12\"
				( memberType ( signal ) )
				( electricalCSetRef "@crescent_city_bb_fab1_lib.crescent_city_bb_fab1(sch_1):\DDR_G_CMD_DLL1-13\" )
				( member ( signalRef "@baseboard_fab2_lib.baseboard_fab2(sch_1):m_g_bg(1)") )
				( member ( signalRef "@baseboard_fab2_lib.baseboard_fab2(sch_1):m_g_ma(11)") )
				( objectStatus "NG_DDR_G_DLL_12" )
			)
			( netGroup "@crescent_city_bb_fab1_lib.crescent_city_bb_fab1(sch_1):\NG_DDR_G_DLL_13\"
				( memberType ( signal ) )
				( electricalCSetRef "@crescent_city_bb_fab1_lib.crescent_city_bb_fab1(sch_1):\DDR_G_CMD_DLL1-13\" )
				( member ( signalRef "@baseboard_fab2_lib.baseboard_fab2(sch_1):m_g_act_n") )
				( member ( signalRef "@baseboard_fab2_lib.baseboard_fab2(sch_1):m_g_bg(0)") )
				( objectStatus "NG_DDR_G_DLL_13" )
			)
			( netGroup "@crescent_city_bb_fab1_lib.crescent_city_bb_fab1(sch_1):\NG_DDR_G_DLL_14\"
				( memberType ( signal ) )
				( electricalCSetRef "@crescent_city_bb_fab1_lib.crescent_city_bb_fab1(sch_1):\DDR_CTRL_DLL14-19\" )
				( member ( signalRef "@baseboard_fab2_lib.baseboard_fab2(sch_1):m_g_cs_n(0)") )
				( member ( signalRef "@baseboard_fab2_lib.baseboard_fab2(sch_1):m_g_odt(0)") )
				( objectStatus "NG_DDR_G_DLL_14" )
			)
			( netGroup "@crescent_city_bb_fab1_lib.crescent_city_bb_fab1(sch_1):\NG_DDR_G_DLL_15\"
				( memberType ( signal ) )
				( electricalCSetRef "@crescent_city_bb_fab1_lib.crescent_city_bb_fab1(sch_1):\DDR_CTRL_DLL14-19\" )
				( member ( signalRef "@baseboard_fab2_lib.baseboard_fab2(sch_1):m_g_cke(0)") )
				( objectStatus "NG_DDR_G_DLL_15" )
			)
			( netGroup "@crescent_city_bb_fab1_lib.crescent_city_bb_fab1(sch_1):\NG_DDR_G_DLL_16\"
				( memberType ( signal ) )
				( electricalCSetRef "@crescent_city_bb_fab1_lib.crescent_city_bb_fab1(sch_1):\DDR_CTRL_DLL14-19\" )
				( member ( signalRef "@baseboard_fab2_lib.baseboard_fab2(sch_1):m_g_cs_n(2)") )
				( objectStatus "NG_DDR_G_DLL_16" )
			)
			( netGroup "@crescent_city_bb_fab1_lib.crescent_city_bb_fab1(sch_1):\NG_DDR_G_DLL_17\"
				( memberType ( signal ) )
				( electricalCSetRef "@crescent_city_bb_fab1_lib.crescent_city_bb_fab1(sch_1):\DDR_CTRL_DLL14-19\" )
				( member ( signalRef "@baseboard_fab2_lib.baseboard_fab2(sch_1):m_g_cs_n(3)") )
				( objectStatus "NG_DDR_G_DLL_17" )
			)
			( netGroup "@crescent_city_bb_fab1_lib.crescent_city_bb_fab1(sch_1):\NG_DDR_G_DLL_18\"
				( memberType ( signal ) )
				( electricalCSetRef "@crescent_city_bb_fab1_lib.crescent_city_bb_fab1(sch_1):\DDR_CTRL_DLL14-19\" )
				( member ( signalRef "@baseboard_fab2_lib.baseboard_fab2(sch_1):m_g_cs_n(1)") )
				( member ( signalRef "@baseboard_fab2_lib.baseboard_fab2(sch_1):m_g_odt(1)") )
				( objectStatus "NG_DDR_G_DLL_18" )
			)
			( netGroup "@crescent_city_bb_fab1_lib.crescent_city_bb_fab1(sch_1):\NG_DDR_G_DLL_19\"
				( memberType ( signal ) )
				( electricalCSetRef "@crescent_city_bb_fab1_lib.crescent_city_bb_fab1(sch_1):\DDR_CTRL_DLL14-19\" )
				( member ( signalRef "@baseboard_fab2_lib.baseboard_fab2(sch_1):m_g_cke(1)") )
				( objectStatus "NG_DDR_G_DLL_19" )
			)
			( netGroup "@crescent_city_bb_fab1_lib.crescent_city_bb_fab1(sch_1):\NG_DDR_G_DLL_20\"
				( memberType ( signal ) )
				( electricalCSetRef "@crescent_city_bb_fab1_lib.crescent_city_bb_fab1(sch_1):\DDR_CTRL_DLL20-14\" )
				( member ( signalRef "@baseboard_fab2_lib.baseboard_fab2(sch_1):m_g_cs_n(4)") )
				( member ( signalRef "@baseboard_fab2_lib.baseboard_fab2(sch_1):m_g_odt(2)") )
				( objectStatus "NG_DDR_G_DLL_20" )
			)
			( netGroup "@crescent_city_bb_fab1_lib.crescent_city_bb_fab1(sch_1):\NG_DDR_G_DLL_21\"
				( memberType ( signal ) )
				( electricalCSetRef "@crescent_city_bb_fab1_lib.crescent_city_bb_fab1(sch_1):\DDR_CTRL_DLL20-14\" )
				( member ( signalRef "@baseboard_fab2_lib.baseboard_fab2(sch_1):m_g_cke(2)") )
				( objectStatus "NG_DDR_G_DLL_21" )
			)
			( netGroup "@crescent_city_bb_fab1_lib.crescent_city_bb_fab1(sch_1):\NG_DDR_G_DLL_22\"
				( memberType ( signal ) )
				( electricalCSetRef "@crescent_city_bb_fab1_lib.crescent_city_bb_fab1(sch_1):\DDR_CTRL_DLL20-14\" )
				( member ( signalRef "@baseboard_fab2_lib.baseboard_fab2(sch_1):m_g_cs_n(6)") )
				( member ( signalRef "@baseboard_fab2_lib.baseboard_fab2(sch_1):m_g_cs_n(7)") )
				( objectStatus "NG_DDR_G_DLL_22" )
			)
			( netGroup "@crescent_city_bb_fab1_lib.crescent_city_bb_fab1(sch_1):\NG_DDR_G_DLL_23\"
				( memberType ( signal ) )
				( electricalCSetRef "@crescent_city_bb_fab1_lib.crescent_city_bb_fab1(sch_1):\DDR_CTRL_DLL20-14\" )
				( member ( signalRef "@baseboard_fab2_lib.baseboard_fab2(sch_1):m_g_cs_n(5)") )
				( member ( signalRef "@baseboard_fab2_lib.baseboard_fab2(sch_1):m_g_odt(3)") )
				( objectStatus "NG_DDR_G_DLL_23" )
			)
			( netGroup "@crescent_city_bb_fab1_lib.crescent_city_bb_fab1(sch_1):\NG_DDR_G_DLL_24\"
				( memberType ( signal ) )
				( electricalCSetRef "@crescent_city_bb_fab1_lib.crescent_city_bb_fab1(sch_1):\DDR_CTRL_DLL20-14\" )
				( member ( signalRef "@baseboard_fab2_lib.baseboard_fab2(sch_1):m_g_cke(3)") )
				( objectStatus "NG_DDR_G_DLL_24" )
			)
			( netGroup "@crescent_city_bb_fab1_lib.crescent_city_bb_fab1(sch_1):\NG_DDR_F_DLL_1\"
				( memberType ( signal ) )
				( electricalCSetRef "@crescent_city_bb_fab1_lib.crescent_city_bb_fab1(sch_1):\DDR_F_CMD_DLL1-13\" )
				( member ( signalRef "@baseboard_fab2_lib.baseboard_fab2(sch_1):m_f_c(2)") )
				( member ( signalRef "@baseboard_fab2_lib.baseboard_fab2(sch_1):m_f_ma(17)") )
				( objectStatus "NG_DDR_F_DLL_1" )
			)
			( netGroup "@crescent_city_bb_fab1_lib.crescent_city_bb_fab1(sch_1):\NG_DDR_F_DLL_2\"
				( memberType ( signal ) )
				( electricalCSetRef "@crescent_city_bb_fab1_lib.crescent_city_bb_fab1(sch_1):\DDR_F_CMD_DLL1-13\" )
				( member ( signalRef "@baseboard_fab2_lib.baseboard_fab2(sch_1):m_f_ma(13)") )
				( member ( signalRef "@baseboard_fab2_lib.baseboard_fab2(sch_1):m_f_ma(15)") )
				( objectStatus "NG_DDR_F_DLL_2" )
			)
			( netGroup "@crescent_city_bb_fab1_lib.crescent_city_bb_fab1(sch_1):\NG_DDR_F_DLL_3\"
				( memberType ( signal ) )
				( electricalCSetRef "@crescent_city_bb_fab1_lib.crescent_city_bb_fab1(sch_1):\DDR_F_CMD_DLL1-13\" )
				( member ( signalRef "@baseboard_fab2_lib.baseboard_fab2(sch_1):m_f_ma(14)") )
				( member ( signalRef "@baseboard_fab2_lib.baseboard_fab2(sch_1):m_f_ma(16)") )
				( objectStatus "NG_DDR_F_DLL_3" )
			)
			( netGroup "@crescent_city_bb_fab1_lib.crescent_city_bb_fab1(sch_1):\NG_DDR_F_DLL_4\"
				( memberType ( signal ) )
				( electricalCSetRef "@crescent_city_bb_fab1_lib.crescent_city_bb_fab1(sch_1):\DDR_F_CMD_DLL1-13\" )
				( member ( signalRef "@baseboard_fab2_lib.baseboard_fab2(sch_1):m_f_ba(1)") )
				( member ( signalRef "@baseboard_fab2_lib.baseboard_fab2(sch_1):m_f_ma(10)") )
				( objectStatus "NG_DDR_F_DLL_4" )
			)
			( netGroup "@crescent_city_bb_fab1_lib.crescent_city_bb_fab1(sch_1):\NG_DDR_F_DLL_5\"
				( memberType ( signal ) )
				( electricalCSetRef "@crescent_city_bb_fab1_lib.crescent_city_bb_fab1(sch_1):\DDR_F_CMD_DLL1-13\" )
				( member ( signalRef "@baseboard_fab2_lib.baseboard_fab2(sch_1):m_f_ba(0)") )
				( member ( signalRef "@baseboard_fab2_lib.baseboard_fab2(sch_1):m_f_ma(0)") )
				( objectStatus "NG_DDR_F_DLL_5" )
			)
			( netGroup "@crescent_city_bb_fab1_lib.crescent_city_bb_fab1(sch_1):\NG_DDR_F_DLL_6\"
				( memberType ( signal ) )
				( electricalCSetRef "@crescent_city_bb_fab1_lib.crescent_city_bb_fab1(sch_1):\DDR_F_CMD_DLL1-13\" )
				( member ( signalRef "@baseboard_fab2_lib.baseboard_fab2(sch_1):m_f_par") )
				( objectStatus "NG_DDR_F_DLL_6" )
			)
			( netGroup "@crescent_city_bb_fab1_lib.crescent_city_bb_fab1(sch_1):\NG_DDR_F_DLL_7\"
				( memberType ( signal ) )
				( electricalCSetRef "@crescent_city_bb_fab1_lib.crescent_city_bb_fab1(sch_1):\DDR_F_CMD_DLL1-13\" )
				( member ( signalRef "@baseboard_fab2_lib.baseboard_fab2(sch_1):m_f_ma(1)") )
				( member ( signalRef "@baseboard_fab2_lib.baseboard_fab2(sch_1):m_f_ma(3)") )
				( objectStatus "NG_DDR_F_DLL_7" )
			)
			( netGroup "@crescent_city_bb_fab1_lib.crescent_city_bb_fab1(sch_1):\NG_DDR_F_DLL_8\"
				( memberType ( signal ) )
				( electricalCSetRef "@crescent_city_bb_fab1_lib.crescent_city_bb_fab1(sch_1):\DDR_F_CMD_DLL1-13\" )
				( member ( signalRef "@baseboard_fab2_lib.baseboard_fab2(sch_1):m_f_ma(2)") )
				( member ( signalRef "@baseboard_fab2_lib.baseboard_fab2(sch_1):m_f_ma(4)") )
				( objectStatus "NG_DDR_F_DLL_8" )
			)
			( netGroup "@crescent_city_bb_fab1_lib.crescent_city_bb_fab1(sch_1):\NG_DDR_F_DLL_9\"
				( memberType ( signal ) )
				( electricalCSetRef "@crescent_city_bb_fab1_lib.crescent_city_bb_fab1(sch_1):\DDR_F_CMD_DLL1-13\" )
				( member ( signalRef "@baseboard_fab2_lib.baseboard_fab2(sch_1):m_f_ma(5)") )
				( member ( signalRef "@baseboard_fab2_lib.baseboard_fab2(sch_1):m_f_ma(6)") )
				( objectStatus "NG_DDR_F_DLL_9" )
			)
			( netGroup "@crescent_city_bb_fab1_lib.crescent_city_bb_fab1(sch_1):\NG_DDR_F_DLL_10\"
				( memberType ( signal ) )
				( electricalCSetRef "@crescent_city_bb_fab1_lib.crescent_city_bb_fab1(sch_1):\DDR_F_CMD_DLL1-13\" )
				( member ( signalRef "@baseboard_fab2_lib.baseboard_fab2(sch_1):m_f_ma(7)") )
				( member ( signalRef "@baseboard_fab2_lib.baseboard_fab2(sch_1):m_f_ma(8)") )
				( objectStatus "NG_DDR_F_DLL_10" )
			)
			( netGroup "@crescent_city_bb_fab1_lib.crescent_city_bb_fab1(sch_1):\NG_DDR_F_DLL_11\"
				( memberType ( signal ) )
				( electricalCSetRef "@crescent_city_bb_fab1_lib.crescent_city_bb_fab1(sch_1):\DDR_F_CMD_DLL1-13\" )
				( member ( signalRef "@baseboard_fab2_lib.baseboard_fab2(sch_1):m_f_ma(9)") )
				( member ( signalRef "@baseboard_fab2_lib.baseboard_fab2(sch_1):m_f_ma(12)") )
				( objectStatus "NG_DDR_F_DLL_11" )
			)
			( netGroup "@crescent_city_bb_fab1_lib.crescent_city_bb_fab1(sch_1):\NG_DDR_F_DLL_12\"
				( memberType ( signal ) )
				( electricalCSetRef "@crescent_city_bb_fab1_lib.crescent_city_bb_fab1(sch_1):\DDR_F_CMD_DLL1-13\" )
				( member ( signalRef "@baseboard_fab2_lib.baseboard_fab2(sch_1):m_f_bg(1)") )
				( member ( signalRef "@baseboard_fab2_lib.baseboard_fab2(sch_1):m_f_ma(11)") )
				( objectStatus "NG_DDR_F_DLL_12" )
			)
			( netGroup "@crescent_city_bb_fab1_lib.crescent_city_bb_fab1(sch_1):\NG_DDR_F_DLL_13\"
				( memberType ( signal ) )
				( electricalCSetRef "@crescent_city_bb_fab1_lib.crescent_city_bb_fab1(sch_1):\DDR_F_CMD_DLL1-13\" )
				( member ( signalRef "@baseboard_fab2_lib.baseboard_fab2(sch_1):m_f_act_n") )
				( member ( signalRef "@baseboard_fab2_lib.baseboard_fab2(sch_1):m_f_bg(0)") )
				( objectStatus "NG_DDR_F_DLL_13" )
			)
			( netGroup "@crescent_city_bb_fab1_lib.crescent_city_bb_fab1(sch_1):\NG_DDR_F_DLL_14\"
				( memberType ( signal ) )
				( electricalCSetRef "@crescent_city_bb_fab1_lib.crescent_city_bb_fab1(sch_1):\DDR_CTRL_DLL14-19\" )
				( member ( signalRef "@baseboard_fab2_lib.baseboard_fab2(sch_1):m_f_cs_n(0)") )
				( member ( signalRef "@baseboard_fab2_lib.baseboard_fab2(sch_1):m_f_odt(0)") )
				( objectStatus "NG_DDR_F_DLL_14" )
			)
			( netGroup "@crescent_city_bb_fab1_lib.crescent_city_bb_fab1(sch_1):\NG_DDR_F_DLL_15\"
				( memberType ( signal ) )
				( electricalCSetRef "@crescent_city_bb_fab1_lib.crescent_city_bb_fab1(sch_1):\DDR_CTRL_DLL14-19\" )
				( member ( signalRef "@baseboard_fab2_lib.baseboard_fab2(sch_1):m_f_cke(0)") )
				( objectStatus "NG_DDR_F_DLL_15" )
			)
			( netGroup "@crescent_city_bb_fab1_lib.crescent_city_bb_fab1(sch_1):\NG_DDR_F_DLL_16\"
				( memberType ( signal ) )
				( electricalCSetRef "@crescent_city_bb_fab1_lib.crescent_city_bb_fab1(sch_1):\DDR_CTRL_DLL14-19\" )
				( member ( signalRef "@baseboard_fab2_lib.baseboard_fab2(sch_1):m_f_cs_n(2)") )
				( objectStatus "NG_DDR_F_DLL_16" )
			)
			( netGroup "@crescent_city_bb_fab1_lib.crescent_city_bb_fab1(sch_1):\NG_DDR_F_DLL_17\"
				( memberType ( signal ) )
				( electricalCSetRef "@crescent_city_bb_fab1_lib.crescent_city_bb_fab1(sch_1):\DDR_CTRL_DLL14-19\" )
				( member ( signalRef "@baseboard_fab2_lib.baseboard_fab2(sch_1):m_f_cs_n(3)") )
				( objectStatus "NG_DDR_F_DLL_17" )
			)
			( netGroup "@crescent_city_bb_fab1_lib.crescent_city_bb_fab1(sch_1):\NG_DDR_F_DLL_18\"
				( memberType ( signal ) )
				( electricalCSetRef "@crescent_city_bb_fab1_lib.crescent_city_bb_fab1(sch_1):\DDR_CTRL_DLL14-19\" )
				( member ( signalRef "@baseboard_fab2_lib.baseboard_fab2(sch_1):m_f_cs_n(1)") )
				( member ( signalRef "@baseboard_fab2_lib.baseboard_fab2(sch_1):m_f_odt(1)") )
				( objectStatus "NG_DDR_F_DLL_18" )
			)
			( netGroup "@crescent_city_bb_fab1_lib.crescent_city_bb_fab1(sch_1):\NG_DDR_F_DLL_19\"
				( memberType ( signal ) )
				( electricalCSetRef "@crescent_city_bb_fab1_lib.crescent_city_bb_fab1(sch_1):\DDR_CTRL_DLL14-19\" )
				( member ( signalRef "@baseboard_fab2_lib.baseboard_fab2(sch_1):m_f_cke(1)") )
				( objectStatus "NG_DDR_F_DLL_19" )
			)
			( netGroup "@crescent_city_bb_fab1_lib.crescent_city_bb_fab1(sch_1):\NG_DDR_F_DLL_20\"
				( memberType ( signal ) )
				( electricalCSetRef "@crescent_city_bb_fab1_lib.crescent_city_bb_fab1(sch_1):\DDR_CTRL_DLL20-14\" )
				( member ( signalRef "@baseboard_fab2_lib.baseboard_fab2(sch_1):m_f_cs_n(4)") )
				( member ( signalRef "@baseboard_fab2_lib.baseboard_fab2(sch_1):m_f_odt(2)") )
				( objectStatus "NG_DDR_F_DLL_20" )
			)
			( netGroup "@crescent_city_bb_fab1_lib.crescent_city_bb_fab1(sch_1):\NG_DDR_F_DLL_21\"
				( memberType ( signal ) )
				( electricalCSetRef "@crescent_city_bb_fab1_lib.crescent_city_bb_fab1(sch_1):\DDR_CTRL_DLL20-14\" )
				( member ( signalRef "@baseboard_fab2_lib.baseboard_fab2(sch_1):m_f_cke(2)") )
				( objectStatus "NG_DDR_F_DLL_21" )
			)
			( netGroup "@crescent_city_bb_fab1_lib.crescent_city_bb_fab1(sch_1):\NG_DDR_F_DLL_22\"
				( memberType ( signal ) )
				( electricalCSetRef "@crescent_city_bb_fab1_lib.crescent_city_bb_fab1(sch_1):\DDR_CTRL_DLL20-14\" )
				( member ( signalRef "@baseboard_fab2_lib.baseboard_fab2(sch_1):m_f_cs_n(6)") )
				( member ( signalRef "@baseboard_fab2_lib.baseboard_fab2(sch_1):m_f_cs_n(7)") )
				( objectStatus "NG_DDR_F_DLL_22" )
			)
			( netGroup "@crescent_city_bb_fab1_lib.crescent_city_bb_fab1(sch_1):\NG_DDR_F_DLL_23\"
				( memberType ( signal ) )
				( electricalCSetRef "@crescent_city_bb_fab1_lib.crescent_city_bb_fab1(sch_1):\DDR_CTRL_DLL20-14\" )
				( member ( signalRef "@baseboard_fab2_lib.baseboard_fab2(sch_1):m_f_cs_n(5)") )
				( member ( signalRef "@baseboard_fab2_lib.baseboard_fab2(sch_1):m_f_odt(3)") )
				( objectStatus "NG_DDR_F_DLL_23" )
			)
			( netGroup "@crescent_city_bb_fab1_lib.crescent_city_bb_fab1(sch_1):\NG_DDR_F_DLL_24\"
				( memberType ( signal ) )
				( electricalCSetRef "@crescent_city_bb_fab1_lib.crescent_city_bb_fab1(sch_1):\DDR_CTRL_DLL20-14\" )
				( member ( signalRef "@baseboard_fab2_lib.baseboard_fab2(sch_1):m_f_cke(3)") )
				( objectStatus "NG_DDR_F_DLL_24" )
			)
			( netGroup "@crescent_city_bb_fab1_lib.crescent_city_bb_fab1(sch_1):\NG_DDR_E_DLL_1\"
				( memberType ( signal ) )
				( electricalCSetRef "@crescent_city_bb_fab1_lib.crescent_city_bb_fab1(sch_1):\DDR_E_CMD_DLL1-13\" )
				( member ( signalRef "@baseboard_fab2_lib.baseboard_fab2(sch_1):m_e_c(2)") )
				( member ( signalRef "@baseboard_fab2_lib.baseboard_fab2(sch_1):m_e_ma(17)") )
				( objectStatus "NG_DDR_E_DLL_1" )
			)
			( netGroup "@crescent_city_bb_fab1_lib.crescent_city_bb_fab1(sch_1):\NG_DDR_E_DLL_2\"
				( memberType ( signal ) )
				( electricalCSetRef "@crescent_city_bb_fab1_lib.crescent_city_bb_fab1(sch_1):\DDR_E_CMD_DLL1-13\" )
				( member ( signalRef "@baseboard_fab2_lib.baseboard_fab2(sch_1):m_e_ma(13)") )
				( member ( signalRef "@baseboard_fab2_lib.baseboard_fab2(sch_1):m_e_ma(15)") )
				( objectStatus "NG_DDR_E_DLL_2" )
			)
			( netGroup "@crescent_city_bb_fab1_lib.crescent_city_bb_fab1(sch_1):\NG_DDR_E_DLL_3\"
				( memberType ( signal ) )
				( electricalCSetRef "@crescent_city_bb_fab1_lib.crescent_city_bb_fab1(sch_1):\DDR_E_CMD_DLL1-13\" )
				( member ( signalRef "@baseboard_fab2_lib.baseboard_fab2(sch_1):m_e_ma(14)") )
				( member ( signalRef "@baseboard_fab2_lib.baseboard_fab2(sch_1):m_e_ma(16)") )
				( objectStatus "NG_DDR_E_DLL_3" )
			)
			( netGroup "@crescent_city_bb_fab1_lib.crescent_city_bb_fab1(sch_1):\NG_DDR_E_DLL_4\"
				( memberType ( signal ) )
				( electricalCSetRef "@crescent_city_bb_fab1_lib.crescent_city_bb_fab1(sch_1):\DDR_E_CMD_DLL1-13\" )
				( member ( signalRef "@baseboard_fab2_lib.baseboard_fab2(sch_1):m_e_ba(1)") )
				( member ( signalRef "@baseboard_fab2_lib.baseboard_fab2(sch_1):m_e_ma(10)") )
				( objectStatus "NG_DDR_E_DLL_4" )
			)
			( netGroup "@crescent_city_bb_fab1_lib.crescent_city_bb_fab1(sch_1):\NG_DDR_E_DLL_5\"
				( memberType ( signal ) )
				( electricalCSetRef "@crescent_city_bb_fab1_lib.crescent_city_bb_fab1(sch_1):\DDR_E_CMD_DLL1-13\" )
				( member ( signalRef "@baseboard_fab2_lib.baseboard_fab2(sch_1):m_e_ba(0)") )
				( member ( signalRef "@baseboard_fab2_lib.baseboard_fab2(sch_1):m_e_ma(0)") )
				( objectStatus "NG_DDR_E_DLL_5" )
			)
			( netGroup "@crescent_city_bb_fab1_lib.crescent_city_bb_fab1(sch_1):\NG_DDR_E_DLL_6\"
				( memberType ( signal ) )
				( electricalCSetRef "@crescent_city_bb_fab1_lib.crescent_city_bb_fab1(sch_1):\DDR_E_CMD_DLL1-13\" )
				( member ( signalRef "@baseboard_fab2_lib.baseboard_fab2(sch_1):m_e_par") )
				( objectStatus "NG_DDR_E_DLL_6" )
			)
			( netGroup "@crescent_city_bb_fab1_lib.crescent_city_bb_fab1(sch_1):\NG_DDR_E_DLL_7\"
				( memberType ( signal ) )
				( electricalCSetRef "@crescent_city_bb_fab1_lib.crescent_city_bb_fab1(sch_1):\DDR_E_CMD_DLL1-13\" )
				( member ( signalRef "@baseboard_fab2_lib.baseboard_fab2(sch_1):m_e_ma(1)") )
				( member ( signalRef "@baseboard_fab2_lib.baseboard_fab2(sch_1):m_e_ma(3)") )
				( objectStatus "NG_DDR_E_DLL_7" )
			)
			( netGroup "@crescent_city_bb_fab1_lib.crescent_city_bb_fab1(sch_1):\NG_DDR_E_DLL_8\"
				( memberType ( signal ) )
				( electricalCSetRef "@crescent_city_bb_fab1_lib.crescent_city_bb_fab1(sch_1):\DDR_E_CMD_DLL1-13\" )
				( member ( signalRef "@baseboard_fab2_lib.baseboard_fab2(sch_1):m_e_ma(2)") )
				( member ( signalRef "@baseboard_fab2_lib.baseboard_fab2(sch_1):m_e_ma(4)") )
				( objectStatus "NG_DDR_E_DLL_8" )
			)
			( netGroup "@crescent_city_bb_fab1_lib.crescent_city_bb_fab1(sch_1):\NG_DDR_E_DLL_9\"
				( memberType ( signal ) )
				( electricalCSetRef "@crescent_city_bb_fab1_lib.crescent_city_bb_fab1(sch_1):\DDR_E_CMD_DLL1-13\" )
				( member ( signalRef "@baseboard_fab2_lib.baseboard_fab2(sch_1):m_e_ma(5)") )
				( member ( signalRef "@baseboard_fab2_lib.baseboard_fab2(sch_1):m_e_ma(6)") )
				( objectStatus "NG_DDR_E_DLL_9" )
			)
			( netGroup "@crescent_city_bb_fab1_lib.crescent_city_bb_fab1(sch_1):\NG_DDR_E_DLL_10\"
				( memberType ( signal ) )
				( electricalCSetRef "@crescent_city_bb_fab1_lib.crescent_city_bb_fab1(sch_1):\DDR_E_CMD_DLL1-13\" )
				( member ( signalRef "@baseboard_fab2_lib.baseboard_fab2(sch_1):m_e_ma(7)") )
				( member ( signalRef "@baseboard_fab2_lib.baseboard_fab2(sch_1):m_e_ma(8)") )
				( objectStatus "NG_DDR_E_DLL_10" )
			)
			( netGroup "@crescent_city_bb_fab1_lib.crescent_city_bb_fab1(sch_1):\NG_DDR_E_DLL_11\"
				( memberType ( signal ) )
				( electricalCSetRef "@crescent_city_bb_fab1_lib.crescent_city_bb_fab1(sch_1):\DDR_E_CMD_DLL1-13\" )
				( member ( signalRef "@baseboard_fab2_lib.baseboard_fab2(sch_1):m_e_ma(9)") )
				( member ( signalRef "@baseboard_fab2_lib.baseboard_fab2(sch_1):m_e_ma(12)") )
				( objectStatus "NG_DDR_E_DLL_11" )
			)
			( netGroup "@crescent_city_bb_fab1_lib.crescent_city_bb_fab1(sch_1):\NG_DDR_E_DLL_12\"
				( memberType ( signal ) )
				( electricalCSetRef "@crescent_city_bb_fab1_lib.crescent_city_bb_fab1(sch_1):\DDR_E_CMD_DLL1-13\" )
				( member ( signalRef "@baseboard_fab2_lib.baseboard_fab2(sch_1):m_e_bg(1)") )
				( member ( signalRef "@baseboard_fab2_lib.baseboard_fab2(sch_1):m_e_ma(11)") )
				( objectStatus "NG_DDR_E_DLL_12" )
			)
			( netGroup "@crescent_city_bb_fab1_lib.crescent_city_bb_fab1(sch_1):\NG_DDR_E_DLL_13\"
				( memberType ( signal ) )
				( electricalCSetRef "@crescent_city_bb_fab1_lib.crescent_city_bb_fab1(sch_1):\DDR_E_CMD_DLL1-13\" )
				( member ( signalRef "@baseboard_fab2_lib.baseboard_fab2(sch_1):m_e_act_n") )
				( member ( signalRef "@baseboard_fab2_lib.baseboard_fab2(sch_1):m_e_bg(0)") )
				( objectStatus "NG_DDR_E_DLL_13" )
			)
			( netGroup "@crescent_city_bb_fab1_lib.crescent_city_bb_fab1(sch_1):\NG_DDR_E_DLL_14\"
				( memberType ( signal ) )
				( electricalCSetRef "@crescent_city_bb_fab1_lib.crescent_city_bb_fab1(sch_1):\DDR_CTRL_DLL14-19\" )
				( member ( signalRef "@baseboard_fab2_lib.baseboard_fab2(sch_1):m_e_cs_n(0)") )
				( member ( signalRef "@baseboard_fab2_lib.baseboard_fab2(sch_1):m_e_odt(0)") )
				( objectStatus "NG_DDR_E_DLL_14" )
			)
			( netGroup "@crescent_city_bb_fab1_lib.crescent_city_bb_fab1(sch_1):\NG_DDR_E_DLL_15\"
				( memberType ( signal ) )
				( electricalCSetRef "@crescent_city_bb_fab1_lib.crescent_city_bb_fab1(sch_1):\DDR_CTRL_DLL14-19\" )
				( member ( signalRef "@baseboard_fab2_lib.baseboard_fab2(sch_1):m_e_cke(0)") )
				( objectStatus "NG_DDR_E_DLL_15" )
			)
			( netGroup "@crescent_city_bb_fab1_lib.crescent_city_bb_fab1(sch_1):\NG_DDR_E_DLL_16\"
				( memberType ( signal ) )
				( electricalCSetRef "@crescent_city_bb_fab1_lib.crescent_city_bb_fab1(sch_1):\DDR_CTRL_DLL14-19\" )
				( member ( signalRef "@baseboard_fab2_lib.baseboard_fab2(sch_1):m_e_cs_n(2)") )
				( objectStatus "NG_DDR_E_DLL_16" )
			)
			( netGroup "@crescent_city_bb_fab1_lib.crescent_city_bb_fab1(sch_1):\NG_DDR_E_DLL_17\"
				( memberType ( signal ) )
				( electricalCSetRef "@crescent_city_bb_fab1_lib.crescent_city_bb_fab1(sch_1):\DDR_CTRL_DLL14-19\" )
				( member ( signalRef "@baseboard_fab2_lib.baseboard_fab2(sch_1):m_e_cs_n(3)") )
				( objectStatus "NG_DDR_E_DLL_17" )
			)
			( netGroup "@crescent_city_bb_fab1_lib.crescent_city_bb_fab1(sch_1):\NG_DDR_E_DLL_18\"
				( memberType ( signal ) )
				( electricalCSetRef "@crescent_city_bb_fab1_lib.crescent_city_bb_fab1(sch_1):\DDR_CTRL_DLL14-19\" )
				( member ( signalRef "@baseboard_fab2_lib.baseboard_fab2(sch_1):m_e_cs_n(1)") )
				( member ( signalRef "@baseboard_fab2_lib.baseboard_fab2(sch_1):m_e_odt(1)") )
				( objectStatus "NG_DDR_E_DLL_18" )
			)
			( netGroup "@crescent_city_bb_fab1_lib.crescent_city_bb_fab1(sch_1):\NG_DDR_E_DLL_19\"
				( memberType ( signal ) )
				( electricalCSetRef "@crescent_city_bb_fab1_lib.crescent_city_bb_fab1(sch_1):\DDR_CTRL_DLL14-19\" )
				( member ( signalRef "@baseboard_fab2_lib.baseboard_fab2(sch_1):m_e_cke(1)") )
				( objectStatus "NG_DDR_E_DLL_19" )
			)
			( netGroup "@crescent_city_bb_fab1_lib.crescent_city_bb_fab1(sch_1):\NG_DDR_E_DLL_20\"
				( memberType ( signal ) )
				( electricalCSetRef "@crescent_city_bb_fab1_lib.crescent_city_bb_fab1(sch_1):\DDR_CTRL_DLL20-14\" )
				( member ( signalRef "@baseboard_fab2_lib.baseboard_fab2(sch_1):m_e_cs_n(4)") )
				( member ( signalRef "@baseboard_fab2_lib.baseboard_fab2(sch_1):m_e_odt(2)") )
				( objectStatus "NG_DDR_E_DLL_20" )
			)
			( netGroup "@crescent_city_bb_fab1_lib.crescent_city_bb_fab1(sch_1):\NG_DDR_E_DLL_21\"
				( memberType ( signal ) )
				( electricalCSetRef "@crescent_city_bb_fab1_lib.crescent_city_bb_fab1(sch_1):\DDR_CTRL_DLL20-14\" )
				( member ( signalRef "@baseboard_fab2_lib.baseboard_fab2(sch_1):m_e_cke(2)") )
				( objectStatus "NG_DDR_E_DLL_21" )
			)
			( netGroup "@crescent_city_bb_fab1_lib.crescent_city_bb_fab1(sch_1):\NG_DDR_E_DLL_22\"
				( memberType ( signal ) )
				( electricalCSetRef "@crescent_city_bb_fab1_lib.crescent_city_bb_fab1(sch_1):\DDR_CTRL_DLL20-14\" )
				( member ( signalRef "@baseboard_fab2_lib.baseboard_fab2(sch_1):m_e_cs_n(6)") )
				( member ( signalRef "@baseboard_fab2_lib.baseboard_fab2(sch_1):m_e_cs_n(7)") )
				( objectStatus "NG_DDR_E_DLL_22" )
			)
			( netGroup "@crescent_city_bb_fab1_lib.crescent_city_bb_fab1(sch_1):\NG_DDR_E_DLL_23\"
				( memberType ( signal ) )
				( electricalCSetRef "@crescent_city_bb_fab1_lib.crescent_city_bb_fab1(sch_1):\DDR_CTRL_DLL20-14\" )
				( member ( signalRef "@baseboard_fab2_lib.baseboard_fab2(sch_1):m_e_cs_n(5)") )
				( member ( signalRef "@baseboard_fab2_lib.baseboard_fab2(sch_1):m_e_odt(3)") )
				( objectStatus "NG_DDR_E_DLL_23" )
			)
			( netGroup "@crescent_city_bb_fab1_lib.crescent_city_bb_fab1(sch_1):\NG_DDR_E_DLL_24\"
				( memberType ( signal ) )
				( electricalCSetRef "@crescent_city_bb_fab1_lib.crescent_city_bb_fab1(sch_1):\DDR_CTRL_DLL20-14\" )
				( member ( signalRef "@baseboard_fab2_lib.baseboard_fab2(sch_1):m_e_cke(3)") )
				( objectStatus "NG_DDR_E_DLL_24" )
			)
			( netGroup "@crescent_city_bb_fab1_lib.crescent_city_bb_fab1(sch_1):\NG_DDR_D_DLL_1\"
				( memberType ( signal ) )
				( electricalCSetRef "@crescent_city_bb_fab1_lib.crescent_city_bb_fab1(sch_1):\DDR_D_CMD_DLL1-13\" )
				( member ( signalRef "@baseboard_fab2_lib.baseboard_fab2(sch_1):m_d_ma(17)") )
				( member ( signalRef "@baseboard_fab2_lib.baseboard_fab2(sch_1):m_d_c(2)") )
				( objectStatus "NG_DDR_D_DLL_1" )
			)
			( netGroup "@crescent_city_bb_fab1_lib.crescent_city_bb_fab1(sch_1):\NG_DDR_D_DLL_2\"
				( memberType ( signal ) )
				( electricalCSetRef "@crescent_city_bb_fab1_lib.crescent_city_bb_fab1(sch_1):\DDR_D_CMD_DLL1-13\" )
				( member ( signalRef "@baseboard_fab2_lib.baseboard_fab2(sch_1):m_d_ma(13)") )
				( member ( signalRef "@baseboard_fab2_lib.baseboard_fab2(sch_1):m_d_ma(15)") )
				( objectStatus "NG_DDR_D_DLL_2" )
			)
			( netGroup "@crescent_city_bb_fab1_lib.crescent_city_bb_fab1(sch_1):\NG_DDR_D_DLL_3\"
				( memberType ( signal ) )
				( electricalCSetRef "@crescent_city_bb_fab1_lib.crescent_city_bb_fab1(sch_1):\DDR_D_CMD_DLL1-13\" )
				( member ( signalRef "@baseboard_fab2_lib.baseboard_fab2(sch_1):m_d_ma(14)") )
				( member ( signalRef "@baseboard_fab2_lib.baseboard_fab2(sch_1):m_d_ma(16)") )
				( objectStatus "NG_DDR_D_DLL_3" )
			)
			( netGroup "@crescent_city_bb_fab1_lib.crescent_city_bb_fab1(sch_1):\NG_DDR_D_DLL_4\"
				( memberType ( signal ) )
				( electricalCSetRef "@crescent_city_bb_fab1_lib.crescent_city_bb_fab1(sch_1):\DDR_D_CMD_DLL1-13\" )
				( member ( signalRef "@baseboard_fab2_lib.baseboard_fab2(sch_1):m_d_ba(1)") )
				( member ( signalRef "@baseboard_fab2_lib.baseboard_fab2(sch_1):m_d_ma(10)") )
				( objectStatus "NG_DDR_D_DLL_4" )
			)
			( netGroup "@crescent_city_bb_fab1_lib.crescent_city_bb_fab1(sch_1):\NG_DDR_D_DLL_5\"
				( memberType ( signal ) )
				( electricalCSetRef "@crescent_city_bb_fab1_lib.crescent_city_bb_fab1(sch_1):\DDR_D_CMD_DLL1-13\" )
				( member ( signalRef "@baseboard_fab2_lib.baseboard_fab2(sch_1):m_d_ba(0)") )
				( member ( signalRef "@baseboard_fab2_lib.baseboard_fab2(sch_1):m_d_ma(0)") )
				( objectStatus "NG_DDR_D_DLL_5" )
			)
			( netGroup "@crescent_city_bb_fab1_lib.crescent_city_bb_fab1(sch_1):\NG_DDR_D_DLL_6\"
				( memberType ( signal ) )
				( electricalCSetRef "@crescent_city_bb_fab1_lib.crescent_city_bb_fab1(sch_1):\DDR_D_CMD_DLL1-13\" )
				( member ( signalRef "@baseboard_fab2_lib.baseboard_fab2(sch_1):m_d_par") )
				( objectStatus "NG_DDR_D_DLL_6" )
			)
			( netGroup "@crescent_city_bb_fab1_lib.crescent_city_bb_fab1(sch_1):\NG_DDR_D_DLL_7\"
				( memberType ( signal ) )
				( electricalCSetRef "@crescent_city_bb_fab1_lib.crescent_city_bb_fab1(sch_1):\DDR_D_CMD_DLL1-13\" )
				( member ( signalRef "@baseboard_fab2_lib.baseboard_fab2(sch_1):m_d_ma(1)") )
				( member ( signalRef "@baseboard_fab2_lib.baseboard_fab2(sch_1):m_d_ma(3)") )
				( objectStatus "NG_DDR_D_DLL_7" )
			)
			( netGroup "@crescent_city_bb_fab1_lib.crescent_city_bb_fab1(sch_1):\NG_DDR_D_DLL_8\"
				( memberType ( signal ) )
				( electricalCSetRef "@crescent_city_bb_fab1_lib.crescent_city_bb_fab1(sch_1):\DDR_D_CMD_DLL1-13\" )
				( member ( signalRef "@baseboard_fab2_lib.baseboard_fab2(sch_1):m_d_ma(2)") )
				( member ( signalRef "@baseboard_fab2_lib.baseboard_fab2(sch_1):m_d_ma(4)") )
				( objectStatus "NG_DDR_D_DLL_8" )
			)
			( netGroup "@crescent_city_bb_fab1_lib.crescent_city_bb_fab1(sch_1):\NG_DDR_D_DLL_9\"
				( memberType ( signal ) )
				( electricalCSetRef "@crescent_city_bb_fab1_lib.crescent_city_bb_fab1(sch_1):\DDR_D_CMD_DLL1-13\" )
				( member ( signalRef "@baseboard_fab2_lib.baseboard_fab2(sch_1):m_d_ma(5)") )
				( member ( signalRef "@baseboard_fab2_lib.baseboard_fab2(sch_1):m_d_ma(6)") )
				( objectStatus "NG_DDR_D_DLL_9" )
			)
			( netGroup "@crescent_city_bb_fab1_lib.crescent_city_bb_fab1(sch_1):\NG_DDR_D_DLL_10\"
				( memberType ( signal ) )
				( electricalCSetRef "@crescent_city_bb_fab1_lib.crescent_city_bb_fab1(sch_1):\DDR_D_CMD_DLL1-13\" )
				( member ( signalRef "@baseboard_fab2_lib.baseboard_fab2(sch_1):m_d_ma(7)") )
				( member ( signalRef "@baseboard_fab2_lib.baseboard_fab2(sch_1):m_d_ma(8)") )
				( objectStatus "NG_DDR_D_DLL_10" )
			)
			( netGroup "@crescent_city_bb_fab1_lib.crescent_city_bb_fab1(sch_1):\NG_DDR_D_DLL_11\"
				( memberType ( signal ) )
				( electricalCSetRef "@crescent_city_bb_fab1_lib.crescent_city_bb_fab1(sch_1):\DDR_D_CMD_DLL1-13\" )
				( member ( signalRef "@baseboard_fab2_lib.baseboard_fab2(sch_1):m_d_ma(9)") )
				( member ( signalRef "@baseboard_fab2_lib.baseboard_fab2(sch_1):m_d_ma(12)") )
				( objectStatus "NG_DDR_D_DLL_11" )
			)
			( netGroup "@crescent_city_bb_fab1_lib.crescent_city_bb_fab1(sch_1):\NG_DDR_D_DLL_12\"
				( memberType ( signal ) )
				( electricalCSetRef "@crescent_city_bb_fab1_lib.crescent_city_bb_fab1(sch_1):\DDR_D_CMD_DLL1-13\" )
				( member ( signalRef "@baseboard_fab2_lib.baseboard_fab2(sch_1):m_d_bg(1)") )
				( member ( signalRef "@baseboard_fab2_lib.baseboard_fab2(sch_1):m_d_ma(11)") )
				( objectStatus "NG_DDR_D_DLL_12" )
			)
			( netGroup "@crescent_city_bb_fab1_lib.crescent_city_bb_fab1(sch_1):\NG_DDR_D_DLL_13\"
				( memberType ( signal ) )
				( electricalCSetRef "@crescent_city_bb_fab1_lib.crescent_city_bb_fab1(sch_1):\DDR_D_CMD_DLL1-13\" )
				( member ( signalRef "@baseboard_fab2_lib.baseboard_fab2(sch_1):m_d_act_n") )
				( member ( signalRef "@baseboard_fab2_lib.baseboard_fab2(sch_1):m_d_bg(0)") )
				( objectStatus "NG_DDR_D_DLL_13" )
			)
			( netGroup "@crescent_city_bb_fab1_lib.crescent_city_bb_fab1(sch_1):\NG_DDR_D_DLL_14\"
				( memberType ( signal ) )
				( electricalCSetRef "@crescent_city_bb_fab1_lib.crescent_city_bb_fab1(sch_1):\DDR_CTRL_DLL14-19\" )
				( member ( signalRef "@baseboard_fab2_lib.baseboard_fab2(sch_1):m_d_cs_n(0)") )
				( member ( signalRef "@baseboard_fab2_lib.baseboard_fab2(sch_1):m_d_odt(0)") )
				( objectStatus "NG_DDR_D_DLL_14" )
			)
			( netGroup "@crescent_city_bb_fab1_lib.crescent_city_bb_fab1(sch_1):\NG_DDR_D_DLL_15\"
				( memberType ( signal ) )
				( electricalCSetRef "@crescent_city_bb_fab1_lib.crescent_city_bb_fab1(sch_1):\DDR_CTRL_DLL14-19\" )
				( member ( signalRef "@baseboard_fab2_lib.baseboard_fab2(sch_1):m_d_cke(0)") )
				( objectStatus "NG_DDR_D_DLL_15" )
			)
			( netGroup "@crescent_city_bb_fab1_lib.crescent_city_bb_fab1(sch_1):\NG_DDR_D_DLL_16\"
				( memberType ( signal ) )
				( electricalCSetRef "@crescent_city_bb_fab1_lib.crescent_city_bb_fab1(sch_1):\DDR_CTRL_DLL14-19\" )
				( member ( signalRef "@baseboard_fab2_lib.baseboard_fab2(sch_1):m_d_cs_n(2)") )
				( objectStatus "NG_DDR_D_DLL_16" )
			)
			( netGroup "@crescent_city_bb_fab1_lib.crescent_city_bb_fab1(sch_1):\NG_DDR_D_DLL_17\"
				( memberType ( signal ) )
				( electricalCSetRef "@crescent_city_bb_fab1_lib.crescent_city_bb_fab1(sch_1):\DDR_CTRL_DLL14-19\" )
				( member ( signalRef "@baseboard_fab2_lib.baseboard_fab2(sch_1):m_d_cs_n(3)") )
				( objectStatus "NG_DDR_D_DLL_17" )
			)
			( netGroup "@crescent_city_bb_fab1_lib.crescent_city_bb_fab1(sch_1):\NG_DDR_D_DLL_18\"
				( memberType ( signal ) )
				( electricalCSetRef "@crescent_city_bb_fab1_lib.crescent_city_bb_fab1(sch_1):\DDR_CTRL_DLL14-19\" )
				( member ( signalRef "@baseboard_fab2_lib.baseboard_fab2(sch_1):m_d_cs_n(1)") )
				( member ( signalRef "@baseboard_fab2_lib.baseboard_fab2(sch_1):m_d_odt(1)") )
				( objectStatus "NG_DDR_D_DLL_18" )
			)
			( netGroup "@crescent_city_bb_fab1_lib.crescent_city_bb_fab1(sch_1):\NG_DDR_D_DLL_19\"
				( memberType ( signal ) )
				( electricalCSetRef "@crescent_city_bb_fab1_lib.crescent_city_bb_fab1(sch_1):\DDR_CTRL_DLL14-19\" )
				( member ( signalRef "@baseboard_fab2_lib.baseboard_fab2(sch_1):m_d_cke(1)") )
				( objectStatus "NG_DDR_D_DLL_19" )
			)
			( netGroup "@crescent_city_bb_fab1_lib.crescent_city_bb_fab1(sch_1):\NG_DDR_D_DLL_20\"
				( memberType ( signal ) )
				( electricalCSetRef "@crescent_city_bb_fab1_lib.crescent_city_bb_fab1(sch_1):\DDR_CTRL_DLL20-14\" )
				( member ( signalRef "@baseboard_fab2_lib.baseboard_fab2(sch_1):m_d_cs_n(4)") )
				( member ( signalRef "@baseboard_fab2_lib.baseboard_fab2(sch_1):m_d_odt(2)") )
				( objectStatus "NG_DDR_D_DLL_20" )
			)
			( netGroup "@crescent_city_bb_fab1_lib.crescent_city_bb_fab1(sch_1):\NG_DDR_D_DLL_21\"
				( memberType ( signal ) )
				( electricalCSetRef "@crescent_city_bb_fab1_lib.crescent_city_bb_fab1(sch_1):\DDR_CTRL_DLL20-14\" )
				( member ( signalRef "@baseboard_fab2_lib.baseboard_fab2(sch_1):m_d_cke(2)") )
				( objectStatus "NG_DDR_D_DLL_21" )
			)
			( netGroup "@crescent_city_bb_fab1_lib.crescent_city_bb_fab1(sch_1):\NG_DDR_D_DLL_22\"
				( memberType ( signal ) )
				( electricalCSetRef "@crescent_city_bb_fab1_lib.crescent_city_bb_fab1(sch_1):\DDR_CTRL_DLL20-14\" )
				( member ( signalRef "@baseboard_fab2_lib.baseboard_fab2(sch_1):m_d_cs_n(6)") )
				( member ( signalRef "@baseboard_fab2_lib.baseboard_fab2(sch_1):m_d_cs_n(7)") )
				( objectStatus "NG_DDR_D_DLL_22" )
			)
			( netGroup "@crescent_city_bb_fab1_lib.crescent_city_bb_fab1(sch_1):\NG_DDR_D_DLL_23\"
				( memberType ( signal ) )
				( electricalCSetRef "@crescent_city_bb_fab1_lib.crescent_city_bb_fab1(sch_1):\DDR_CTRL_DLL20-14\" )
				( member ( signalRef "@baseboard_fab2_lib.baseboard_fab2(sch_1):m_d_cs_n(5)") )
				( member ( signalRef "@baseboard_fab2_lib.baseboard_fab2(sch_1):m_d_odt(3)") )
				( objectStatus "NG_DDR_D_DLL_23" )
			)
			( netGroup "@crescent_city_bb_fab1_lib.crescent_city_bb_fab1(sch_1):\NG_DDR_D_DLL_24\"
				( memberType ( signal ) )
				( electricalCSetRef "@crescent_city_bb_fab1_lib.crescent_city_bb_fab1(sch_1):\DDR_CTRL_DLL20-14\" )
				( member ( signalRef "@baseboard_fab2_lib.baseboard_fab2(sch_1):m_d_cke(3)") )
				( objectStatus "NG_DDR_D_DLL_24" )
			)
			( netGroup "@crescent_city_bb_fab1_lib.crescent_city_bb_fab1(sch_1):\NG_DDR_C_DLL_1\"
				( memberType ( signal ) )
				( electricalCSetRef "@crescent_city_bb_fab1_lib.crescent_city_bb_fab1(sch_1):\DDR_C_CMD_DLL1-13\" )
				( member ( signalRef "@baseboard_fab2_lib.baseboard_fab2(sch_1):m_c_c(2)") )
				( member ( signalRef "@baseboard_fab2_lib.baseboard_fab2(sch_1):m_c_ma(17)") )
				( objectStatus "NG_DDR_C_DLL_1" )
			)
			( netGroup "@crescent_city_bb_fab1_lib.crescent_city_bb_fab1(sch_1):\NG_DDR_C_DLL_2\"
				( memberType ( signal ) )
				( electricalCSetRef "@crescent_city_bb_fab1_lib.crescent_city_bb_fab1(sch_1):\DDR_C_CMD_DLL1-13\" )
				( member ( signalRef "@baseboard_fab2_lib.baseboard_fab2(sch_1):m_c_ma(13)") )
				( member ( signalRef "@baseboard_fab2_lib.baseboard_fab2(sch_1):m_c_ma(15)") )
				( objectStatus "NG_DDR_C_DLL_2" )
			)
			( netGroup "@crescent_city_bb_fab1_lib.crescent_city_bb_fab1(sch_1):\NG_DDR_C_DLL_3\"
				( memberType ( signal ) )
				( electricalCSetRef "@crescent_city_bb_fab1_lib.crescent_city_bb_fab1(sch_1):\DDR_C_CMD_DLL1-13\" )
				( member ( signalRef "@baseboard_fab2_lib.baseboard_fab2(sch_1):m_c_ma(14)") )
				( member ( signalRef "@baseboard_fab2_lib.baseboard_fab2(sch_1):m_c_ma(16)") )
				( objectStatus "NG_DDR_C_DLL_3" )
			)
			( netGroup "@crescent_city_bb_fab1_lib.crescent_city_bb_fab1(sch_1):\NG_DDR_C_DLL_4\"
				( memberType ( signal ) )
				( electricalCSetRef "@crescent_city_bb_fab1_lib.crescent_city_bb_fab1(sch_1):\DDR_C_CMD_DLL1-13\" )
				( member ( signalRef "@baseboard_fab2_lib.baseboard_fab2(sch_1):m_c_ba(1)") )
				( member ( signalRef "@baseboard_fab2_lib.baseboard_fab2(sch_1):m_c_ma(10)") )
				( objectStatus "NG_DDR_C_DLL_4" )
			)
			( netGroup "@crescent_city_bb_fab1_lib.crescent_city_bb_fab1(sch_1):\NG_DDR_C_DLL_5\"
				( memberType ( signal ) )
				( electricalCSetRef "@crescent_city_bb_fab1_lib.crescent_city_bb_fab1(sch_1):\DDR_C_CMD_DLL1-13\" )
				( member ( signalRef "@baseboard_fab2_lib.baseboard_fab2(sch_1):m_c_ba(0)") )
				( member ( signalRef "@baseboard_fab2_lib.baseboard_fab2(sch_1):m_c_ma(0)") )
				( objectStatus "NG_DDR_C_DLL_5" )
			)
			( netGroup "@crescent_city_bb_fab1_lib.crescent_city_bb_fab1(sch_1):\NG_DDR_C_DLL_6\"
				( memberType ( signal ) )
				( electricalCSetRef "@crescent_city_bb_fab1_lib.crescent_city_bb_fab1(sch_1):\DDR_C_CMD_DLL1-13\" )
				( member ( signalRef "@baseboard_fab2_lib.baseboard_fab2(sch_1):m_c_par") )
				( objectStatus "NG_DDR_C_DLL_6" )
			)
			( netGroup "@crescent_city_bb_fab1_lib.crescent_city_bb_fab1(sch_1):\NG_DDR_C_DLL_7\"
				( memberType ( signal ) )
				( electricalCSetRef "@crescent_city_bb_fab1_lib.crescent_city_bb_fab1(sch_1):\DDR_C_CMD_DLL1-13\" )
				( member ( signalRef "@baseboard_fab2_lib.baseboard_fab2(sch_1):m_c_ma(1)") )
				( member ( signalRef "@baseboard_fab2_lib.baseboard_fab2(sch_1):m_c_ma(3)") )
				( objectStatus "NG_DDR_C_DLL_7" )
			)
			( netGroup "@crescent_city_bb_fab1_lib.crescent_city_bb_fab1(sch_1):\NG_DDR_C_DLL_8\"
				( memberType ( signal ) )
				( electricalCSetRef "@crescent_city_bb_fab1_lib.crescent_city_bb_fab1(sch_1):\DDR_C_CMD_DLL1-13\" )
				( member ( signalRef "@baseboard_fab2_lib.baseboard_fab2(sch_1):m_c_ma(2)") )
				( member ( signalRef "@baseboard_fab2_lib.baseboard_fab2(sch_1):m_c_ma(4)") )
				( objectStatus "NG_DDR_C_DLL_8" )
			)
			( netGroup "@crescent_city_bb_fab1_lib.crescent_city_bb_fab1(sch_1):\NG_DDR_C_DLL_9\"
				( memberType ( signal ) )
				( electricalCSetRef "@crescent_city_bb_fab1_lib.crescent_city_bb_fab1(sch_1):\DDR_C_CMD_DLL1-13\" )
				( member ( signalRef "@baseboard_fab2_lib.baseboard_fab2(sch_1):m_c_ma(5)") )
				( member ( signalRef "@baseboard_fab2_lib.baseboard_fab2(sch_1):m_c_ma(6)") )
				( objectStatus "NG_DDR_C_DLL_9" )
			)
			( netGroup "@crescent_city_bb_fab1_lib.crescent_city_bb_fab1(sch_1):\NG_DDR_C_DLL_10\"
				( memberType ( signal ) )
				( electricalCSetRef "@crescent_city_bb_fab1_lib.crescent_city_bb_fab1(sch_1):\DDR_C_CMD_DLL1-13\" )
				( member ( signalRef "@baseboard_fab2_lib.baseboard_fab2(sch_1):m_c_ma(7)") )
				( member ( signalRef "@baseboard_fab2_lib.baseboard_fab2(sch_1):m_c_ma(8)") )
				( objectStatus "NG_DDR_C_DLL_10" )
			)
			( netGroup "@crescent_city_bb_fab1_lib.crescent_city_bb_fab1(sch_1):\NG_DDR_C_DLL_11\"
				( memberType ( signal ) )
				( electricalCSetRef "@crescent_city_bb_fab1_lib.crescent_city_bb_fab1(sch_1):\DDR_C_CMD_DLL1-13\" )
				( member ( signalRef "@baseboard_fab2_lib.baseboard_fab2(sch_1):m_c_ma(9)") )
				( member ( signalRef "@baseboard_fab2_lib.baseboard_fab2(sch_1):m_c_ma(12)") )
				( objectStatus "NG_DDR_C_DLL_11" )
			)
			( netGroup "@crescent_city_bb_fab1_lib.crescent_city_bb_fab1(sch_1):\NG_DDR_C_DLL_12\"
				( memberType ( signal ) )
				( electricalCSetRef "@crescent_city_bb_fab1_lib.crescent_city_bb_fab1(sch_1):\DDR_C_CMD_DLL1-13\" )
				( member ( signalRef "@baseboard_fab2_lib.baseboard_fab2(sch_1):m_c_bg(1)") )
				( member ( signalRef "@baseboard_fab2_lib.baseboard_fab2(sch_1):m_c_ma(11)") )
				( objectStatus "NG_DDR_C_DLL_12" )
			)
			( netGroup "@crescent_city_bb_fab1_lib.crescent_city_bb_fab1(sch_1):\NG_DDR_C_DLL_13\"
				( memberType ( signal ) )
				( electricalCSetRef "@crescent_city_bb_fab1_lib.crescent_city_bb_fab1(sch_1):\DDR_C_CMD_DLL1-13\" )
				( member ( signalRef "@baseboard_fab2_lib.baseboard_fab2(sch_1):m_c_act_n") )
				( member ( signalRef "@baseboard_fab2_lib.baseboard_fab2(sch_1):m_c_bg(0)") )
				( objectStatus "NG_DDR_C_DLL_13" )
			)
			( netGroup "@crescent_city_bb_fab1_lib.crescent_city_bb_fab1(sch_1):\NG_DDR_C_DLL_14\"
				( memberType ( signal ) )
				( electricalCSetRef "@crescent_city_bb_fab1_lib.crescent_city_bb_fab1(sch_1):\DDR_CTRL_DLL14-19\" )
				( member ( signalRef "@baseboard_fab2_lib.baseboard_fab2(sch_1):m_c_cs_n(0)") )
				( member ( signalRef "@baseboard_fab2_lib.baseboard_fab2(sch_1):m_c_odt(0)") )
				( objectStatus "NG_DDR_C_DLL_14" )
			)
			( netGroup "@crescent_city_bb_fab1_lib.crescent_city_bb_fab1(sch_1):\NG_DDR_C_DLL_15\"
				( memberType ( signal ) )
				( electricalCSetRef "@crescent_city_bb_fab1_lib.crescent_city_bb_fab1(sch_1):\DDR_CTRL_DLL14-19\" )
				( member ( signalRef "@baseboard_fab2_lib.baseboard_fab2(sch_1):m_c_cke(0)") )
				( objectStatus "NG_DDR_C_DLL_15" )
			)
			( netGroup "@crescent_city_bb_fab1_lib.crescent_city_bb_fab1(sch_1):\NG_DDR_C_DLL_16\"
				( memberType ( signal ) )
				( electricalCSetRef "@crescent_city_bb_fab1_lib.crescent_city_bb_fab1(sch_1):\DDR_CTRL_DLL14-19\" )
				( member ( signalRef "@baseboard_fab2_lib.baseboard_fab2(sch_1):m_c_cs_n(2)") )
				( objectStatus "NG_DDR_C_DLL_16" )
			)
			( netGroup "@crescent_city_bb_fab1_lib.crescent_city_bb_fab1(sch_1):\NG_DDR_C_DLL_17\"
				( memberType ( signal ) )
				( electricalCSetRef "@crescent_city_bb_fab1_lib.crescent_city_bb_fab1(sch_1):\DDR_CTRL_DLL14-19\" )
				( member ( signalRef "@baseboard_fab2_lib.baseboard_fab2(sch_1):m_c_cs_n(3)") )
				( objectStatus "NG_DDR_C_DLL_17" )
			)
			( netGroup "@crescent_city_bb_fab1_lib.crescent_city_bb_fab1(sch_1):\NG_DDR_C_DLL_18\"
				( memberType ( signal ) )
				( electricalCSetRef "@crescent_city_bb_fab1_lib.crescent_city_bb_fab1(sch_1):\DDR_CTRL_DLL14-19\" )
				( member ( signalRef "@baseboard_fab2_lib.baseboard_fab2(sch_1):m_c_cs_n(1)") )
				( member ( signalRef "@baseboard_fab2_lib.baseboard_fab2(sch_1):m_c_odt(1)") )
				( objectStatus "NG_DDR_C_DLL_18" )
			)
			( netGroup "@crescent_city_bb_fab1_lib.crescent_city_bb_fab1(sch_1):\NG_DDR_C_DLL_19\"
				( memberType ( signal ) )
				( electricalCSetRef "@crescent_city_bb_fab1_lib.crescent_city_bb_fab1(sch_1):\DDR_CTRL_DLL14-19\" )
				( member ( signalRef "@baseboard_fab2_lib.baseboard_fab2(sch_1):m_c_cke(1)") )
				( objectStatus "NG_DDR_C_DLL_19" )
			)
			( netGroup "@crescent_city_bb_fab1_lib.crescent_city_bb_fab1(sch_1):\NG_DDR_C_DLL_20\"
				( memberType ( signal ) )
				( electricalCSetRef "@crescent_city_bb_fab1_lib.crescent_city_bb_fab1(sch_1):\DDR_CTRL_DLL20-14\" )
				( member ( signalRef "@baseboard_fab2_lib.baseboard_fab2(sch_1):m_c_cs_n(4)") )
				( member ( signalRef "@baseboard_fab2_lib.baseboard_fab2(sch_1):m_c_odt(2)") )
				( objectStatus "NG_DDR_C_DLL_20" )
			)
			( netGroup "@crescent_city_bb_fab1_lib.crescent_city_bb_fab1(sch_1):\NG_DDR_C_DLL_21\"
				( memberType ( signal ) )
				( electricalCSetRef "@crescent_city_bb_fab1_lib.crescent_city_bb_fab1(sch_1):\DDR_CTRL_DLL20-14\" )
				( member ( signalRef "@baseboard_fab2_lib.baseboard_fab2(sch_1):m_c_cke(2)") )
				( objectStatus "NG_DDR_C_DLL_21" )
			)
			( netGroup "@crescent_city_bb_fab1_lib.crescent_city_bb_fab1(sch_1):\NG_DDR_C_DLL_22\"
				( memberType ( signal ) )
				( electricalCSetRef "@crescent_city_bb_fab1_lib.crescent_city_bb_fab1(sch_1):\DDR_CTRL_DLL20-14\" )
				( member ( signalRef "@baseboard_fab2_lib.baseboard_fab2(sch_1):m_c_cs_n(6)") )
				( member ( signalRef "@baseboard_fab2_lib.baseboard_fab2(sch_1):m_c_cs_n(7)") )
				( objectStatus "NG_DDR_C_DLL_22" )
			)
			( netGroup "@crescent_city_bb_fab1_lib.crescent_city_bb_fab1(sch_1):\NG_DDR_C_DLL_23\"
				( memberType ( signal ) )
				( electricalCSetRef "@crescent_city_bb_fab1_lib.crescent_city_bb_fab1(sch_1):\DDR_CTRL_DLL20-14\" )
				( member ( signalRef "@baseboard_fab2_lib.baseboard_fab2(sch_1):m_c_cs_n(5)") )
				( member ( signalRef "@baseboard_fab2_lib.baseboard_fab2(sch_1):m_c_odt(3)") )
				( objectStatus "NG_DDR_C_DLL_23" )
			)
			( netGroup "@crescent_city_bb_fab1_lib.crescent_city_bb_fab1(sch_1):\NG_DDR_C_DLL_24\"
				( memberType ( signal ) )
				( electricalCSetRef "@crescent_city_bb_fab1_lib.crescent_city_bb_fab1(sch_1):\DDR_CTRL_DLL20-14\" )
				( member ( signalRef "@baseboard_fab2_lib.baseboard_fab2(sch_1):m_c_cke(3)") )
				( objectStatus "NG_DDR_C_DLL_24" )
			)
			( netGroup "@crescent_city_bb_fab1_lib.crescent_city_bb_fab1(sch_1):\NG_DDR_B_DLL_1\"
				( memberType ( signal ) )
				( electricalCSetRef "@crescent_city_bb_fab1_lib.crescent_city_bb_fab1(sch_1):\DDR_B_CMD_DLL1-13\" )
				( member ( signalRef "@baseboard_fab2_lib.baseboard_fab2(sch_1):m_b_c(2)") )
				( member ( signalRef "@baseboard_fab2_lib.baseboard_fab2(sch_1):m_b_ma(17)") )
				( objectStatus "NG_DDR_B_DLL_1" )
			)
			( netGroup "@crescent_city_bb_fab1_lib.crescent_city_bb_fab1(sch_1):\NG_DDR_B_DLL_2\"
				( memberType ( signal ) )
				( electricalCSetRef "@crescent_city_bb_fab1_lib.crescent_city_bb_fab1(sch_1):\DDR_B_CMD_DLL1-13\" )
				( member ( signalRef "@baseboard_fab2_lib.baseboard_fab2(sch_1):m_b_ma(13)") )
				( member ( signalRef "@baseboard_fab2_lib.baseboard_fab2(sch_1):m_b_ma(15)") )
				( objectStatus "NG_DDR_B_DLL_2" )
			)
			( netGroup "@crescent_city_bb_fab1_lib.crescent_city_bb_fab1(sch_1):\NG_DDR_B_DLL_3\"
				( memberType ( signal ) )
				( electricalCSetRef "@crescent_city_bb_fab1_lib.crescent_city_bb_fab1(sch_1):\DDR_B_CMD_DLL1-13\" )
				( member ( signalRef "@baseboard_fab2_lib.baseboard_fab2(sch_1):m_b_ma(14)") )
				( member ( signalRef "@baseboard_fab2_lib.baseboard_fab2(sch_1):m_b_ma(16)") )
				( objectStatus "NG_DDR_B_DLL_3" )
			)
			( netGroup "@crescent_city_bb_fab1_lib.crescent_city_bb_fab1(sch_1):\NG_DDR_B_DLL_4\"
				( memberType ( signal ) )
				( electricalCSetRef "@crescent_city_bb_fab1_lib.crescent_city_bb_fab1(sch_1):\DDR_B_CMD_DLL1-13\" )
				( member ( signalRef "@baseboard_fab2_lib.baseboard_fab2(sch_1):m_b_ba(1)") )
				( member ( signalRef "@baseboard_fab2_lib.baseboard_fab2(sch_1):m_b_ma(10)") )
				( objectStatus "NG_DDR_B_DLL_4" )
			)
			( netGroup "@crescent_city_bb_fab1_lib.crescent_city_bb_fab1(sch_1):\NG_DDR_B_DLL_5\"
				( memberType ( signal ) )
				( electricalCSetRef "@crescent_city_bb_fab1_lib.crescent_city_bb_fab1(sch_1):\DDR_B_CMD_DLL1-13\" )
				( member ( signalRef "@baseboard_fab2_lib.baseboard_fab2(sch_1):m_b_ba(0)") )
				( member ( signalRef "@baseboard_fab2_lib.baseboard_fab2(sch_1):m_b_ma(0)") )
				( objectStatus "NG_DDR_B_DLL_5" )
			)
			( netGroup "@crescent_city_bb_fab1_lib.crescent_city_bb_fab1(sch_1):\NG_DDR_B_DLL_6\"
				( memberType ( signal ) )
				( electricalCSetRef "@crescent_city_bb_fab1_lib.crescent_city_bb_fab1(sch_1):\DDR_B_CMD_DLL1-13\" )
				( member ( signalRef "@baseboard_fab2_lib.baseboard_fab2(sch_1):m_b_par") )
				( objectStatus "NG_DDR_B_DLL_6" )
			)
			( netGroup "@crescent_city_bb_fab1_lib.crescent_city_bb_fab1(sch_1):\NG_DDR_B_DLL_7\"
				( memberType ( signal ) )
				( electricalCSetRef "@crescent_city_bb_fab1_lib.crescent_city_bb_fab1(sch_1):\DDR_B_CMD_DLL1-13\" )
				( member ( signalRef "@baseboard_fab2_lib.baseboard_fab2(sch_1):m_b_ma(1)") )
				( member ( signalRef "@baseboard_fab2_lib.baseboard_fab2(sch_1):m_b_ma(3)") )
				( objectStatus "NG_DDR_B_DLL_7" )
			)
			( netGroup "@crescent_city_bb_fab1_lib.crescent_city_bb_fab1(sch_1):\NG_DDR_B_DLL_8\"
				( memberType ( signal ) )
				( electricalCSetRef "@crescent_city_bb_fab1_lib.crescent_city_bb_fab1(sch_1):\DDR_B_CMD_DLL1-13\" )
				( member ( signalRef "@baseboard_fab2_lib.baseboard_fab2(sch_1):m_b_ma(2)") )
				( member ( signalRef "@baseboard_fab2_lib.baseboard_fab2(sch_1):m_b_ma(4)") )
				( objectStatus "NG_DDR_B_DLL_8" )
			)
			( netGroup "@crescent_city_bb_fab1_lib.crescent_city_bb_fab1(sch_1):\NG_DDR_B_DLL_9\"
				( memberType ( signal ) )
				( electricalCSetRef "@crescent_city_bb_fab1_lib.crescent_city_bb_fab1(sch_1):\DDR_B_CMD_DLL1-13\" )
				( member ( signalRef "@baseboard_fab2_lib.baseboard_fab2(sch_1):m_b_ma(5)") )
				( member ( signalRef "@baseboard_fab2_lib.baseboard_fab2(sch_1):m_b_ma(6)") )
				( objectStatus "NG_DDR_B_DLL_9" )
			)
			( netGroup "@crescent_city_bb_fab1_lib.crescent_city_bb_fab1(sch_1):\NG_DDR_B_DLL_10\"
				( memberType ( signal ) )
				( electricalCSetRef "@crescent_city_bb_fab1_lib.crescent_city_bb_fab1(sch_1):\DDR_B_CMD_DLL1-13\" )
				( member ( signalRef "@baseboard_fab2_lib.baseboard_fab2(sch_1):m_b_ma(7)") )
				( member ( signalRef "@baseboard_fab2_lib.baseboard_fab2(sch_1):m_b_ma(8)") )
				( objectStatus "NG_DDR_B_DLL_10" )
			)
			( netGroup "@crescent_city_bb_fab1_lib.crescent_city_bb_fab1(sch_1):\NG_DDR_B_DLL_11\"
				( memberType ( signal ) )
				( electricalCSetRef "@crescent_city_bb_fab1_lib.crescent_city_bb_fab1(sch_1):\DDR_B_CMD_DLL1-13\" )
				( member ( signalRef "@baseboard_fab2_lib.baseboard_fab2(sch_1):m_b_ma(9)") )
				( member ( signalRef "@baseboard_fab2_lib.baseboard_fab2(sch_1):m_b_ma(12)") )
				( objectStatus "NG_DDR_B_DLL_11" )
			)
			( netGroup "@crescent_city_bb_fab1_lib.crescent_city_bb_fab1(sch_1):\NG_DDR_B_DLL_12\"
				( memberType ( signal ) )
				( electricalCSetRef "@crescent_city_bb_fab1_lib.crescent_city_bb_fab1(sch_1):\DDR_B_CMD_DLL1-13\" )
				( member ( signalRef "@baseboard_fab2_lib.baseboard_fab2(sch_1):m_b_bg(1)") )
				( member ( signalRef "@baseboard_fab2_lib.baseboard_fab2(sch_1):m_b_ma(11)") )
				( objectStatus "NG_DDR_B_DLL_12" )
			)
			( netGroup "@crescent_city_bb_fab1_lib.crescent_city_bb_fab1(sch_1):\NG_DDR_B_DLL_13\"
				( memberType ( signal ) )
				( electricalCSetRef "@crescent_city_bb_fab1_lib.crescent_city_bb_fab1(sch_1):\DDR_B_CMD_DLL1-13\" )
				( member ( signalRef "@baseboard_fab2_lib.baseboard_fab2(sch_1):m_b_act_n") )
				( member ( signalRef "@baseboard_fab2_lib.baseboard_fab2(sch_1):m_b_bg(0)") )
				( objectStatus "NG_DDR_B_DLL_13" )
			)
			( netGroup "@crescent_city_bb_fab1_lib.crescent_city_bb_fab1(sch_1):\NG_DDR_B_DLL_14\"
				( memberType ( signal ) )
				( electricalCSetRef "@crescent_city_bb_fab1_lib.crescent_city_bb_fab1(sch_1):\DDR_CTRL_DLL14-19\" )
				( member ( signalRef "@baseboard_fab2_lib.baseboard_fab2(sch_1):m_b_cs_n(0)") )
				( member ( signalRef "@baseboard_fab2_lib.baseboard_fab2(sch_1):m_b_odt(0)") )
				( objectStatus "NG_DDR_B_DLL_14" )
			)
			( netGroup "@crescent_city_bb_fab1_lib.crescent_city_bb_fab1(sch_1):\NG_DDR_B_DLL_15\"
				( memberType ( signal ) )
				( electricalCSetRef "@crescent_city_bb_fab1_lib.crescent_city_bb_fab1(sch_1):\DDR_CTRL_DLL14-19\" )
				( member ( signalRef "@baseboard_fab2_lib.baseboard_fab2(sch_1):m_b_cke(0)") )
				( objectStatus "NG_DDR_B_DLL_15" )
			)
			( netGroup "@crescent_city_bb_fab1_lib.crescent_city_bb_fab1(sch_1):\NG_DDR_B_DLL_16\"
				( memberType ( signal ) )
				( electricalCSetRef "@crescent_city_bb_fab1_lib.crescent_city_bb_fab1(sch_1):\DDR_CTRL_DLL14-19\" )
				( member ( signalRef "@baseboard_fab2_lib.baseboard_fab2(sch_1):m_b_cs_n(2)") )
				( objectStatus "NG_DDR_B_DLL_16" )
			)
			( netGroup "@crescent_city_bb_fab1_lib.crescent_city_bb_fab1(sch_1):\NG_DDR_B_DLL_17\"
				( memberType ( signal ) )
				( electricalCSetRef "@crescent_city_bb_fab1_lib.crescent_city_bb_fab1(sch_1):\DDR_CTRL_DLL14-19\" )
				( member ( signalRef "@baseboard_fab2_lib.baseboard_fab2(sch_1):m_b_cs_n(3)") )
				( objectStatus "NG_DDR_B_DLL_17" )
			)
			( netGroup "@crescent_city_bb_fab1_lib.crescent_city_bb_fab1(sch_1):\NG_DDR_B_DLL_18\"
				( memberType ( signal ) )
				( electricalCSetRef "@crescent_city_bb_fab1_lib.crescent_city_bb_fab1(sch_1):\DDR_CTRL_DLL14-19\" )
				( member ( signalRef "@baseboard_fab2_lib.baseboard_fab2(sch_1):m_b_odt(1)") )
				( member ( signalRef "@baseboard_fab2_lib.baseboard_fab2(sch_1):m_b_cs_n(1)") )
				( objectStatus "NG_DDR_B_DLL_18" )
			)
			( netGroup "@crescent_city_bb_fab1_lib.crescent_city_bb_fab1(sch_1):\NG_DDR_B_DLL_19\"
				( memberType ( signal ) )
				( electricalCSetRef "@crescent_city_bb_fab1_lib.crescent_city_bb_fab1(sch_1):\DDR_CTRL_DLL14-19\" )
				( member ( signalRef "@baseboard_fab2_lib.baseboard_fab2(sch_1):m_b_cke(1)") )
				( objectStatus "NG_DDR_B_DLL_19" )
			)
			( netGroup "@crescent_city_bb_fab1_lib.crescent_city_bb_fab1(sch_1):\NG_DDR_B_DLL_20\"
				( memberType ( signal ) )
				( electricalCSetRef "@crescent_city_bb_fab1_lib.crescent_city_bb_fab1(sch_1):\DDR_CTRL_DLL20-14\" )
				( member ( signalRef "@baseboard_fab2_lib.baseboard_fab2(sch_1):m_b_cs_n(4)") )
				( member ( signalRef "@baseboard_fab2_lib.baseboard_fab2(sch_1):m_b_odt(2)") )
				( objectStatus "NG_DDR_B_DLL_20" )
			)
			( netGroup "@crescent_city_bb_fab1_lib.crescent_city_bb_fab1(sch_1):\NG_DDR_B_DLL_21\"
				( memberType ( signal ) )
				( electricalCSetRef "@crescent_city_bb_fab1_lib.crescent_city_bb_fab1(sch_1):\DDR_CTRL_DLL20-14\" )
				( member ( signalRef "@baseboard_fab2_lib.baseboard_fab2(sch_1):m_b_cke(2)") )
				( objectStatus "NG_DDR_B_DLL_21" )
			)
			( netGroup "@crescent_city_bb_fab1_lib.crescent_city_bb_fab1(sch_1):\NG_DDR_B_DLL_22\"
				( memberType ( signal ) )
				( electricalCSetRef "@crescent_city_bb_fab1_lib.crescent_city_bb_fab1(sch_1):\DDR_CTRL_DLL20-14\" )
				( member ( signalRef "@baseboard_fab2_lib.baseboard_fab2(sch_1):m_b_cs_n(6)") )
				( member ( signalRef "@baseboard_fab2_lib.baseboard_fab2(sch_1):m_b_cs_n(7)") )
				( objectStatus "NG_DDR_B_DLL_22" )
			)
			( netGroup "@crescent_city_bb_fab1_lib.crescent_city_bb_fab1(sch_1):\NG_DDR_B_DLL_23\"
				( memberType ( signal ) )
				( electricalCSetRef "@crescent_city_bb_fab1_lib.crescent_city_bb_fab1(sch_1):\DDR_CTRL_DLL20-14\" )
				( member ( signalRef "@baseboard_fab2_lib.baseboard_fab2(sch_1):m_b_cs_n(5)") )
				( member ( signalRef "@baseboard_fab2_lib.baseboard_fab2(sch_1):m_b_odt(3)") )
				( objectStatus "NG_DDR_B_DLL_23" )
			)
			( netGroup "@crescent_city_bb_fab1_lib.crescent_city_bb_fab1(sch_1):\NG_DDR_B_DLL_24\"
				( memberType ( signal ) )
				( electricalCSetRef "@crescent_city_bb_fab1_lib.crescent_city_bb_fab1(sch_1):\DDR_CTRL_DLL20-14\" )
				( member ( signalRef "@baseboard_fab2_lib.baseboard_fab2(sch_1):m_b_cke(3)") )
				( objectStatus "NG_DDR_B_DLL_24" )
			)
			( netGroup "@crescent_city_bb_fab1_lib.crescent_city_bb_fab1(sch_1):\DDR_A_DLL_1\"
				( memberType ( signal ) )
				( electricalCSetRef "@crescent_city_bb_fab1_lib.crescent_city_bb_fab1(sch_1):\M_A_MA_14_\" )
				( member ( signalRef "@baseboard_fab2_lib.baseboard_fab2(sch_1):m_a_c(2)") )
				( member ( signalRef "@baseboard_fab2_lib.baseboard_fab2(sch_1):m_a_ma(17)") )
				( objectStatus "NG_DDR_A_DLL_1" )
			)
			( netGroup "@crescent_city_bb_fab1_lib.crescent_city_bb_fab1(sch_1):\NG_DDR_A_DLL_2\"
				( memberType ( signal ) )
				( electricalCSetRef "@crescent_city_bb_fab1_lib.crescent_city_bb_fab1(sch_1):\M_A_MA_14_\" )
				( member ( signalRef "@baseboard_fab2_lib.baseboard_fab2(sch_1):m_a_ma(13)") )
				( member ( signalRef "@baseboard_fab2_lib.baseboard_fab2(sch_1):m_a_ma(15)") )
				( objectStatus "NG_DDR_A_DLL_2" )
			)
			( netGroup "@crescent_city_bb_fab1_lib.crescent_city_bb_fab1(sch_1):\NG_DDR_A_DLL_3\"
				( memberType ( signal ) )
				( electricalCSetRef "@crescent_city_bb_fab1_lib.crescent_city_bb_fab1(sch_1):\M_A_MA_14_\" )
				( member ( signalRef "@baseboard_fab2_lib.baseboard_fab2(sch_1):m_a_ma(14)") )
				( member ( signalRef "@baseboard_fab2_lib.baseboard_fab2(sch_1):m_a_ma(16)") )
				( objectStatus "NG_DDR_A_DLL_3" )
			)
			( netGroup "@crescent_city_bb_fab1_lib.crescent_city_bb_fab1(sch_1):\NG_DDR_A_DLL_4\"
				( memberType ( signal ) )
				( electricalCSetRef "@crescent_city_bb_fab1_lib.crescent_city_bb_fab1(sch_1):\M_A_MA_14_\" )
				( member ( signalRef "@baseboard_fab2_lib.baseboard_fab2(sch_1):m_a_ma(10)") )
				( member ( signalRef "@baseboard_fab2_lib.baseboard_fab2(sch_1):m_a_ba(1)") )
				( objectStatus "NG_DDR_A_DLL_4" )
			)
			( netGroup "@crescent_city_bb_fab1_lib.crescent_city_bb_fab1(sch_1):\NG_DDR_A_DLL_5\"
				( memberType ( signal ) )
				( electricalCSetRef "@crescent_city_bb_fab1_lib.crescent_city_bb_fab1(sch_1):\M_A_MA_14_\" )
				( member ( signalRef "@baseboard_fab2_lib.baseboard_fab2(sch_1):m_a_ba(0)") )
				( member ( signalRef "@baseboard_fab2_lib.baseboard_fab2(sch_1):m_a_ma(0)") )
				( objectStatus "NG_DDR_A_DLL_5" )
			)
			( netGroup "@crescent_city_bb_fab1_lib.crescent_city_bb_fab1(sch_1):\NG_DDR_A_DLL_6\"
				( memberType ( signal ) )
				( electricalCSetRef "@crescent_city_bb_fab1_lib.crescent_city_bb_fab1(sch_1):\M_A_MA_14_\" )
				( member ( signalRef "@baseboard_fab2_lib.baseboard_fab2(sch_1):m_a_par") )
				( objectStatus "NG_DDR_A_DLL_6" )
			)
			( netGroup "@crescent_city_bb_fab1_lib.crescent_city_bb_fab1(sch_1):\NG_DDR_A_DLL_7\"
				( memberType ( signal ) )
				( electricalCSetRef "@crescent_city_bb_fab1_lib.crescent_city_bb_fab1(sch_1):\M_A_MA_14_\" )
				( member ( signalRef "@baseboard_fab2_lib.baseboard_fab2(sch_1):m_a_ma(1)") )
				( member ( signalRef "@baseboard_fab2_lib.baseboard_fab2(sch_1):m_a_ma(3)") )
				( objectStatus "NG_DDR_A_DLL_7" )
			)
			( netGroup "@crescent_city_bb_fab1_lib.crescent_city_bb_fab1(sch_1):\NG_DDR_A_DLL_8\"
				( memberType ( signal ) )
				( electricalCSetRef "@crescent_city_bb_fab1_lib.crescent_city_bb_fab1(sch_1):\M_A_MA_14_\" )
				( member ( signalRef "@baseboard_fab2_lib.baseboard_fab2(sch_1):m_a_ma(2)") )
				( member ( signalRef "@baseboard_fab2_lib.baseboard_fab2(sch_1):m_a_ma(4)") )
				( objectStatus "NG_DDR_A_DLL_8" )
			)
			( netGroup "@crescent_city_bb_fab1_lib.crescent_city_bb_fab1(sch_1):\NG_DDR_A_DLL_9\"
				( memberType ( signal ) )
				( electricalCSetRef "@crescent_city_bb_fab1_lib.crescent_city_bb_fab1(sch_1):\M_A_MA_14_\" )
				( member ( signalRef "@baseboard_fab2_lib.baseboard_fab2(sch_1):m_a_ma(5)") )
				( member ( signalRef "@baseboard_fab2_lib.baseboard_fab2(sch_1):m_a_ma(6)") )
				( objectStatus "NG_DDR_A_DLL_9" )
			)
			( netGroup "@crescent_city_bb_fab1_lib.crescent_city_bb_fab1(sch_1):\NG_DDR_A_DLL_10\"
				( memberType ( signal ) )
				( electricalCSetRef "@crescent_city_bb_fab1_lib.crescent_city_bb_fab1(sch_1):\M_A_MA_14_\" )
				( member ( signalRef "@baseboard_fab2_lib.baseboard_fab2(sch_1):m_a_ma(7)") )
				( member ( signalRef "@baseboard_fab2_lib.baseboard_fab2(sch_1):m_a_ma(8)") )
				( objectStatus "NG_DDR_A_DLL_10" )
			)
			( netGroup "@crescent_city_bb_fab1_lib.crescent_city_bb_fab1(sch_1):\NG_DDR_A_DLL_11\"
				( memberType ( signal ) )
				( electricalCSetRef "@crescent_city_bb_fab1_lib.crescent_city_bb_fab1(sch_1):\M_A_MA_14_\" )
				( member ( signalRef "@baseboard_fab2_lib.baseboard_fab2(sch_1):m_a_ma(9)") )
				( member ( signalRef "@baseboard_fab2_lib.baseboard_fab2(sch_1):m_a_ma(12)") )
				( objectStatus "NG_DDR_A_DLL_11" )
			)
			( netGroup "@crescent_city_bb_fab1_lib.crescent_city_bb_fab1(sch_1):\NG_DDR_A_DLL_12\"
				( memberType ( signal ) )
				( electricalCSetRef "@crescent_city_bb_fab1_lib.crescent_city_bb_fab1(sch_1):\M_A_MA_14_\" )
				( member ( signalRef "@baseboard_fab2_lib.baseboard_fab2(sch_1):m_a_bg(1)") )
				( member ( signalRef "@baseboard_fab2_lib.baseboard_fab2(sch_1):m_a_ma(11)") )
				( objectStatus "NG_DDR_A_DLL_12" )
			)
			( netGroup "@crescent_city_bb_fab1_lib.crescent_city_bb_fab1(sch_1):\NG_DDR_A_DLL_13\"
				( memberType ( signal ) )
				( electricalCSetRef "@crescent_city_bb_fab1_lib.crescent_city_bb_fab1(sch_1):\M_A_MA_14_\" )
				( member ( signalRef "@baseboard_fab2_lib.baseboard_fab2(sch_1):m_a_act_n") )
				( member ( signalRef "@baseboard_fab2_lib.baseboard_fab2(sch_1):m_a_bg(0)") )
				( objectStatus "NG_DDR_A_DLL_13" )
			)
			( netGroup "@crescent_city_bb_fab1_lib.crescent_city_bb_fab1(sch_1):\NG_DDR_A_DLL_14\"
				( memberType ( signal ) )
				( electricalCSetRef "@crescent_city_bb_fab1_lib.crescent_city_bb_fab1(sch_1):\DDR_CTRL_DLL14-19\" )
				( member ( signalRef "@baseboard_fab2_lib.baseboard_fab2(sch_1):m_a_cs_n(0)") )
				( member ( signalRef "@baseboard_fab2_lib.baseboard_fab2(sch_1):m_a_odt(0)") )
				( objectStatus "NG_DDR_A_DLL_14" )
			)
			( netGroup "@crescent_city_bb_fab1_lib.crescent_city_bb_fab1(sch_1):\NG_DDR_A_DLL_15\"
				( memberType ( signal ) )
				( electricalCSetRef "@crescent_city_bb_fab1_lib.crescent_city_bb_fab1(sch_1):\DDR_CTRL_DLL14-19\" )
				( member ( signalRef "@baseboard_fab2_lib.baseboard_fab2(sch_1):m_a_cke(0)") )
				( objectStatus "NG_DDR_A_DLL_15" )
			)
			( netGroup "@crescent_city_bb_fab1_lib.crescent_city_bb_fab1(sch_1):\NG_DDR_A_DLL_16\"
				( memberType ( signal ) )
				( electricalCSetRef "@crescent_city_bb_fab1_lib.crescent_city_bb_fab1(sch_1):\DDR_CTRL_DLL14-19\" )
				( member ( signalRef "@baseboard_fab2_lib.baseboard_fab2(sch_1):m_a_cs_n(2)") )
				( objectStatus "NG_DDR_A_DLL_16" )
			)
			( netGroup "@crescent_city_bb_fab1_lib.crescent_city_bb_fab1(sch_1):\NG_DDR_A_DLL_17\"
				( memberType ( signal ) )
				( electricalCSetRef "@crescent_city_bb_fab1_lib.crescent_city_bb_fab1(sch_1):\DDR_CTRL_DLL14-19\" )
				( member ( signalRef "@baseboard_fab2_lib.baseboard_fab2(sch_1):m_a_cs_n(3)") )
				( objectStatus "NG_DDR_A_DLL_17" )
			)
			( netGroup "@crescent_city_bb_fab1_lib.crescent_city_bb_fab1(sch_1):\NG_DDR_A_DLL_18\"
				( memberType ( signal ) )
				( electricalCSetRef "@crescent_city_bb_fab1_lib.crescent_city_bb_fab1(sch_1):\DDR_CTRL_DLL14-19\" )
				( member ( signalRef "@baseboard_fab2_lib.baseboard_fab2(sch_1):m_a_cs_n(1)") )
				( member ( signalRef "@baseboard_fab2_lib.baseboard_fab2(sch_1):m_a_odt(1)") )
				( objectStatus "NG_DDR_A_DLL_18" )
			)
			( netGroup "@crescent_city_bb_fab1_lib.crescent_city_bb_fab1(sch_1):\NG_DDR_A_DLL_19\"
				( memberType ( signal ) )
				( electricalCSetRef "@crescent_city_bb_fab1_lib.crescent_city_bb_fab1(sch_1):\DDR_CTRL_DLL14-19\" )
				( member ( signalRef "@baseboard_fab2_lib.baseboard_fab2(sch_1):m_a_cke(1)") )
				( objectStatus "NG_DDR_A_DLL_19" )
			)
			( netGroup "@crescent_city_bb_fab1_lib.crescent_city_bb_fab1(sch_1):\NG_DDR_A_DLL_20\"
				( memberType ( signal ) )
				( electricalCSetRef "@crescent_city_bb_fab1_lib.crescent_city_bb_fab1(sch_1):\DDR_CTRL_DLL20-14\" )
				( member ( signalRef "@baseboard_fab2_lib.baseboard_fab2(sch_1):m_a_cs_n(4)") )
				( member ( signalRef "@baseboard_fab2_lib.baseboard_fab2(sch_1):m_a_odt(2)") )
				( objectStatus "NG_DDR_A_DLL_20" )
			)
			( netGroup "@crescent_city_bb_fab1_lib.crescent_city_bb_fab1(sch_1):\NG_DDR_A_DLL_21\"
				( memberType ( signal ) )
				( electricalCSetRef "@crescent_city_bb_fab1_lib.crescent_city_bb_fab1(sch_1):\DDR_CTRL_DLL20-14\" )
				( member ( signalRef "@baseboard_fab2_lib.baseboard_fab2(sch_1):m_a_cke(2)") )
				( objectStatus "NG_DDR_A_DLL_21" )
			)
			( netGroup "@crescent_city_bb_fab1_lib.crescent_city_bb_fab1(sch_1):\NG_DDR_A_DLL_22\"
				( memberType ( signal ) )
				( electricalCSetRef "@crescent_city_bb_fab1_lib.crescent_city_bb_fab1(sch_1):\DDR_CTRL_DLL20-14\" )
				( member ( signalRef "@baseboard_fab2_lib.baseboard_fab2(sch_1):m_a_cs_n(6)") )
				( member ( signalRef "@baseboard_fab2_lib.baseboard_fab2(sch_1):m_a_cs_n(7)") )
				( objectStatus "NG_DDR_A_DLL_22" )
			)
			( netGroup "@crescent_city_bb_fab1_lib.crescent_city_bb_fab1(sch_1):\NG_DDR_A_DLL_23\"
				( memberType ( signal ) )
				( electricalCSetRef "@crescent_city_bb_fab1_lib.crescent_city_bb_fab1(sch_1):\DDR_CTRL_DLL20-14\" )
				( member ( signalRef "@baseboard_fab2_lib.baseboard_fab2(sch_1):m_a_cs_n(5)") )
				( member ( signalRef "@baseboard_fab2_lib.baseboard_fab2(sch_1):m_a_odt(3)") )
				( objectStatus "NG_DDR_A_DLL_23" )
			)
			( netGroup "@crescent_city_bb_fab1_lib.crescent_city_bb_fab1(sch_1):\NG_DDR_A_DLL_24\"
				( memberType ( signal ) )
				( electricalCSetRef "@crescent_city_bb_fab1_lib.crescent_city_bb_fab1(sch_1):\DDR_CTRL_DLL20-14\" )
				( member ( signalRef "@baseboard_fab2_lib.baseboard_fab2(sch_1):m_a_cke(3)") )
				( objectStatus "NG_DDR_A_DLL_24" )
			)
			( netGroup "@crescent_city_bb_fab1_lib.crescent_city_bb_fab1(sch_1):\#SPI_SW\"
				( memberType ( signal ) )
				( member ( signalRef "@baseboard_fab2_lib.baseboard_fab2(sch_1):pu_bios_spi_hold1_n") )
				( member ( signalRef "@baseboard_fab2_lib.baseboard_fab2(sch_1):pu_bios_spi_hold0_n") )
				( member ( signalRef "@baseboard_fab2_lib.baseboard_fab2(sch_1):spi_bios_socket_io3") )
				( member ( electricalNetRef "@crescent_city_bb_fab1_lib.crescent_city_bb_fab1(sch_1):spi_cs0_primary_r_n") )
				( member ( electricalNetRef "@crescent_city_bb_fab1_lib.crescent_city_bb_fab1(sch_1):spi_switch_mosi") )
				( member ( electricalNetRef "@crescent_city_bb_fab1_lib.crescent_city_bb_fab1(sch_1):spi_clk_r0") )
				( objectStatus "NG_SPI_SW" )
			)
			( netGroup "@crescent_city_bb_fab1_lib.crescent_city_bb_fab1(sch_1):\#SVID_CPU0_0\"
				( memberType ( signal ) )
				( member ( electricalNetRef "@crescent_city_bb_fab1_lib.crescent_city_bb_fab1(sch_1):svid_dio0_cpu0") )
				( member ( electricalNetRef "@crescent_city_bb_fab1_lib.crescent_city_bb_fab1(sch_1):svid_clk_pvccio_cpu0") )
				( member ( electricalNetRef "@crescent_city_bb_fab1_lib.crescent_city_bb_fab1(sch_1):svid_alert0_cpu0_n") )
				( objectStatus "NG_SVID_CPU0_0" )
			)
			( netGroup "@crescent_city_bb_fab1_lib.crescent_city_bb_fab1(sch_1):\#SVID_CPU0_1\"
				( memberType ( signal ) )
				( member ( electricalNetRef "@crescent_city_bb_fab1_lib.crescent_city_bb_fab1(sch_1):svid_dio0_cpu1") )
				( member ( electricalNetRef "@crescent_city_bb_fab1_lib.crescent_city_bb_fab1(sch_1):svid_clk_pvccio_cpu1") )
				( member ( electricalNetRef "@crescent_city_bb_fab1_lib.crescent_city_bb_fab1(sch_1):svid_alert0_cpu1_n") )
				( objectStatus "NG_SVID_CPU0_1" )
			)
			( netGroup "@crescent_city_bb_fab1_lib.crescent_city_bb_fab1(sch_1):\#SVID_CPU1_0\"
				( memberType ( signal ) )
				( member ( electricalNetRef "@crescent_city_bb_fab1_lib.crescent_city_bb_fab1(sch_1):svid_dio1_cpu0_r") )
				( member ( electricalNetRef "@crescent_city_bb_fab1_lib.crescent_city_bb_fab1(sch_1):svid_clk_pvddq_abc") )
				( member ( electricalNetRef "@crescent_city_bb_fab1_lib.crescent_city_bb_fab1(sch_1):svid_alert1_cpu0_n") )
				( objectStatus "NG_SVID_CPU1_0" )
			)
			( netGroup "@crescent_city_bb_fab1_lib.crescent_city_bb_fab1(sch_1):\#SVID_CPU1_1\"
				( memberType ( signal ) )
				( attribute "DIFFP_PHASE_TOL" "50 mil"
					( Units "uPhaseTol" "ns" 1.000000)
					( Origin gBackEnd )
				)
				( member ( electricalNetRef "@crescent_city_bb_fab1_lib.crescent_city_bb_fab1(sch_1):svid_dio1_cpu1_r") )
				( member ( electricalNetRef "@crescent_city_bb_fab1_lib.crescent_city_bb_fab1(sch_1):svid_clk_pvddq_ghj") )
				( member ( electricalNetRef "@crescent_city_bb_fab1_lib.crescent_city_bb_fab1(sch_1):svid_alert1_cpu1_n") )
				( objectStatus "NG_SVID_CPU1_1" )
			)
			( netGroup "@crescent_city_bb_fab1_lib.crescent_city_bb_fab1(sch_1):\RCC_DFX1940\"
				( memberType ( signal ) )
				( spacingCSetRef "@crescent_city_bb_fab1_lib.crescent_city_bb_fab1(sch_1):\RCC_DFX_1940\" )
				( member ( signalRef "@baseboard_fab2_lib.baseboard_fab2(sch_1):rcc_dfx_1940_1") )
				( member ( signalRef "@baseboard_fab2_lib.baseboard_fab2(sch_1):rcc_dfx_1940_2") )
				( member ( signalRef "@baseboard_fab2_lib.baseboard_fab2(sch_1):rcc_dfx_1940_3") )
				( member ( signalRef "@baseboard_fab2_lib.baseboard_fab2(sch_1):rcc_dfx_1940_4") )
				( objectStatus "RCC_DFX1940" )
			)
			( netGroup "@crescent_city_bb_fab1_lib.crescent_city_bb_fab1(sch_1):\NG_M_M_BYTE7\"
				( memberType ( signal ) )
				( electricalCSetRef "@crescent_city_bb_fab1_lib.crescent_city_bb_fab1(sch_1):\DDR_DQ_A\" )
				( member ( diffPairRef "@sapphirecity_baseboard_lib.sapphirecity_baseboard(sch_1):\M_M_DQS_D\(7)") )
				( member ( diffPairRef "@sapphirecity_baseboard_lib.sapphirecity_baseboard(sch_1):\M_M_DQS_D\(16)") )
				( member ( signalRef "@baseboard_fab2_lib.baseboard_fab2(sch_1):m_m_dq(56)") )
				( member ( signalRef "@baseboard_fab2_lib.baseboard_fab2(sch_1):m_m_dq(57)") )
				( member ( signalRef "@baseboard_fab2_lib.baseboard_fab2(sch_1):m_m_dq(58)") )
				( member ( signalRef "@baseboard_fab2_lib.baseboard_fab2(sch_1):m_m_dq(59)") )
				( member ( signalRef "@baseboard_fab2_lib.baseboard_fab2(sch_1):m_m_dq(60)") )
				( member ( signalRef "@baseboard_fab2_lib.baseboard_fab2(sch_1):m_m_dq(61)") )
				( member ( signalRef "@baseboard_fab2_lib.baseboard_fab2(sch_1):m_m_dq(62)") )
				( member ( signalRef "@baseboard_fab2_lib.baseboard_fab2(sch_1):m_m_dq(63)") )
				( objectStatus "NG_M_M_BYTE7" )
			)
			( netGroup "@crescent_city_bb_fab1_lib.crescent_city_bb_fab1(sch_1):\NG_M_M_BYTE6\"
				( memberType ( signal ) )
				( electricalCSetRef "@crescent_city_bb_fab1_lib.crescent_city_bb_fab1(sch_1):\DDR_DQ_A\" )
				( member ( diffPairRef "@sapphirecity_baseboard_lib.sapphirecity_baseboard(sch_1):\M_M_DQS_D\(6)") )
				( member ( diffPairRef "@sapphirecity_baseboard_lib.sapphirecity_baseboard(sch_1):\M_M_DQS_D\(15)") )
				( member ( signalRef "@baseboard_fab2_lib.baseboard_fab2(sch_1):m_m_dq(48)") )
				( member ( signalRef "@baseboard_fab2_lib.baseboard_fab2(sch_1):m_m_dq(49)") )
				( member ( signalRef "@baseboard_fab2_lib.baseboard_fab2(sch_1):m_m_dq(50)") )
				( member ( signalRef "@baseboard_fab2_lib.baseboard_fab2(sch_1):m_m_dq(51)") )
				( member ( signalRef "@baseboard_fab2_lib.baseboard_fab2(sch_1):m_m_dq(52)") )
				( member ( signalRef "@baseboard_fab2_lib.baseboard_fab2(sch_1):m_m_dq(53)") )
				( member ( signalRef "@baseboard_fab2_lib.baseboard_fab2(sch_1):m_m_dq(54)") )
				( member ( signalRef "@baseboard_fab2_lib.baseboard_fab2(sch_1):m_m_dq(55)") )
				( objectStatus "NG_M_M_BYTE6" )
			)
			( netGroup "@crescent_city_bb_fab1_lib.crescent_city_bb_fab1(sch_1):\NG_M_M_BYTE5\"
				( memberType ( signal ) )
				( electricalCSetRef "@crescent_city_bb_fab1_lib.crescent_city_bb_fab1(sch_1):\DDR_DQ_A\" )
				( member ( diffPairRef "@sapphirecity_baseboard_lib.sapphirecity_baseboard(sch_1):\M_M_DQS_D\(5)") )
				( member ( diffPairRef "@sapphirecity_baseboard_lib.sapphirecity_baseboard(sch_1):\M_M_DQS_D\(14)") )
				( member ( signalRef "@baseboard_fab2_lib.baseboard_fab2(sch_1):m_m_dq(40)") )
				( member ( signalRef "@baseboard_fab2_lib.baseboard_fab2(sch_1):m_m_dq(41)") )
				( member ( signalRef "@baseboard_fab2_lib.baseboard_fab2(sch_1):m_m_dq(42)") )
				( member ( signalRef "@baseboard_fab2_lib.baseboard_fab2(sch_1):m_m_dq(43)") )
				( member ( signalRef "@baseboard_fab2_lib.baseboard_fab2(sch_1):m_m_dq(44)") )
				( member ( signalRef "@baseboard_fab2_lib.baseboard_fab2(sch_1):m_m_dq(45)") )
				( member ( signalRef "@baseboard_fab2_lib.baseboard_fab2(sch_1):m_m_dq(46)") )
				( member ( signalRef "@baseboard_fab2_lib.baseboard_fab2(sch_1):m_m_dq(47)") )
				( objectStatus "NG_M_M_BYTE5" )
			)
			( netGroup "@crescent_city_bb_fab1_lib.crescent_city_bb_fab1(sch_1):\NG_M_M_BYTE4\"
				( memberType ( signal ) )
				( electricalCSetRef "@crescent_city_bb_fab1_lib.crescent_city_bb_fab1(sch_1):\DDR_DQ_A\" )
				( member ( diffPairRef "@sapphirecity_baseboard_lib.sapphirecity_baseboard(sch_1):\M_M_DQS_D\(4)") )
				( member ( diffPairRef "@sapphirecity_baseboard_lib.sapphirecity_baseboard(sch_1):\M_M_DQS_D\(13)") )
				( member ( signalRef "@baseboard_fab2_lib.baseboard_fab2(sch_1):m_m_dq(32)") )
				( member ( signalRef "@baseboard_fab2_lib.baseboard_fab2(sch_1):m_m_dq(33)") )
				( member ( signalRef "@baseboard_fab2_lib.baseboard_fab2(sch_1):m_m_dq(34)") )
				( member ( signalRef "@baseboard_fab2_lib.baseboard_fab2(sch_1):m_m_dq(35)") )
				( member ( signalRef "@baseboard_fab2_lib.baseboard_fab2(sch_1):m_m_dq(36)") )
				( member ( signalRef "@baseboard_fab2_lib.baseboard_fab2(sch_1):m_m_dq(37)") )
				( member ( signalRef "@baseboard_fab2_lib.baseboard_fab2(sch_1):m_m_dq(38)") )
				( member ( signalRef "@baseboard_fab2_lib.baseboard_fab2(sch_1):m_m_dq(39)") )
				( objectStatus "NG_M_M_BYTE4" )
			)
			( netGroup "@crescent_city_bb_fab1_lib.crescent_city_bb_fab1(sch_1):\NG_M_M_BYTE3\"
				( memberType ( signal ) )
				( electricalCSetRef "@crescent_city_bb_fab1_lib.crescent_city_bb_fab1(sch_1):\DDR_DQ_A\" )
				( member ( diffPairRef "@sapphirecity_baseboard_lib.sapphirecity_baseboard(sch_1):\M_M_DQS_D\(3)") )
				( member ( diffPairRef "@sapphirecity_baseboard_lib.sapphirecity_baseboard(sch_1):\M_M_DQS_D\(12)") )
				( member ( signalRef "@baseboard_fab2_lib.baseboard_fab2(sch_1):m_m_dq(24)") )
				( member ( signalRef "@baseboard_fab2_lib.baseboard_fab2(sch_1):m_m_dq(25)") )
				( member ( signalRef "@baseboard_fab2_lib.baseboard_fab2(sch_1):m_m_dq(26)") )
				( member ( signalRef "@baseboard_fab2_lib.baseboard_fab2(sch_1):m_m_dq(27)") )
				( member ( signalRef "@baseboard_fab2_lib.baseboard_fab2(sch_1):m_m_dq(28)") )
				( member ( signalRef "@baseboard_fab2_lib.baseboard_fab2(sch_1):m_m_dq(29)") )
				( member ( signalRef "@baseboard_fab2_lib.baseboard_fab2(sch_1):m_m_dq(30)") )
				( member ( signalRef "@baseboard_fab2_lib.baseboard_fab2(sch_1):m_m_dq(31)") )
				( objectStatus "NG_M_M_BYTE3" )
			)
			( netGroup "@crescent_city_bb_fab1_lib.crescent_city_bb_fab1(sch_1):\NG_M_M_BYTE2\"
				( memberType ( signal ) )
				( electricalCSetRef "@crescent_city_bb_fab1_lib.crescent_city_bb_fab1(sch_1):\DDR_DQ_A\" )
				( member ( diffPairRef "@sapphirecity_baseboard_lib.sapphirecity_baseboard(sch_1):\M_M_DQS_D\(2)") )
				( member ( diffPairRef "@sapphirecity_baseboard_lib.sapphirecity_baseboard(sch_1):\M_M_DQS_D\(11)") )
				( member ( signalRef "@baseboard_fab2_lib.baseboard_fab2(sch_1):m_m_dq(16)") )
				( member ( signalRef "@baseboard_fab2_lib.baseboard_fab2(sch_1):m_m_dq(17)") )
				( member ( signalRef "@baseboard_fab2_lib.baseboard_fab2(sch_1):m_m_dq(18)") )
				( member ( signalRef "@baseboard_fab2_lib.baseboard_fab2(sch_1):m_m_dq(19)") )
				( member ( signalRef "@baseboard_fab2_lib.baseboard_fab2(sch_1):m_m_dq(20)") )
				( member ( signalRef "@baseboard_fab2_lib.baseboard_fab2(sch_1):m_m_dq(21)") )
				( member ( signalRef "@baseboard_fab2_lib.baseboard_fab2(sch_1):m_m_dq(22)") )
				( member ( signalRef "@baseboard_fab2_lib.baseboard_fab2(sch_1):m_m_dq(23)") )
				( objectStatus "NG_M_M_BYTE2" )
			)
			( netGroup "@crescent_city_bb_fab1_lib.crescent_city_bb_fab1(sch_1):\NG_M_M_BYTE1\"
				( memberType ( signal ) )
				( electricalCSetRef "@crescent_city_bb_fab1_lib.crescent_city_bb_fab1(sch_1):\DDR_DQ_A\" )
				( member ( diffPairRef "@sapphirecity_baseboard_lib.sapphirecity_baseboard(sch_1):\M_M_DQS_D\(1)") )
				( member ( diffPairRef "@sapphirecity_baseboard_lib.sapphirecity_baseboard(sch_1):\M_M_DQS_D\(10)") )
				( member ( signalRef "@baseboard_fab2_lib.baseboard_fab2(sch_1):m_m_dq(8)") )
				( member ( signalRef "@baseboard_fab2_lib.baseboard_fab2(sch_1):m_m_dq(9)") )
				( member ( signalRef "@baseboard_fab2_lib.baseboard_fab2(sch_1):m_m_dq(10)") )
				( member ( signalRef "@baseboard_fab2_lib.baseboard_fab2(sch_1):m_m_dq(11)") )
				( member ( signalRef "@baseboard_fab2_lib.baseboard_fab2(sch_1):m_m_dq(12)") )
				( member ( signalRef "@baseboard_fab2_lib.baseboard_fab2(sch_1):m_m_dq(13)") )
				( member ( signalRef "@baseboard_fab2_lib.baseboard_fab2(sch_1):m_m_dq(14)") )
				( member ( signalRef "@baseboard_fab2_lib.baseboard_fab2(sch_1):m_m_dq(15)") )
				( objectStatus "NG_M_M_BYTE1" )
			)
			( netGroup "@crescent_city_bb_fab1_lib.crescent_city_bb_fab1(sch_1):\NG_M_M_BYTE0\"
				( memberType ( signal ) )
				( electricalCSetRef "@crescent_city_bb_fab1_lib.crescent_city_bb_fab1(sch_1):\DDR_DQ_A\" )
				( member ( diffPairRef "@sapphirecity_baseboard_lib.sapphirecity_baseboard(sch_1):\M_M_DQS_D\(0)") )
				( member ( diffPairRef "@sapphirecity_baseboard_lib.sapphirecity_baseboard(sch_1):\M_M_DQS_D\(9)") )
				( member ( signalRef "@baseboard_fab2_lib.baseboard_fab2(sch_1):m_m_dq(0)") )
				( member ( signalRef "@baseboard_fab2_lib.baseboard_fab2(sch_1):m_m_dq(1)") )
				( member ( signalRef "@baseboard_fab2_lib.baseboard_fab2(sch_1):m_m_dq(2)") )
				( member ( signalRef "@baseboard_fab2_lib.baseboard_fab2(sch_1):m_m_dq(3)") )
				( member ( signalRef "@baseboard_fab2_lib.baseboard_fab2(sch_1):m_m_dq(4)") )
				( member ( signalRef "@baseboard_fab2_lib.baseboard_fab2(sch_1):m_m_dq(5)") )
				( member ( signalRef "@baseboard_fab2_lib.baseboard_fab2(sch_1):m_m_dq(6)") )
				( member ( signalRef "@baseboard_fab2_lib.baseboard_fab2(sch_1):m_m_dq(7)") )
				( objectStatus "NG_M_M_BYTE0" )
			)
			( netGroup "@crescent_city_bb_fab1_lib.crescent_city_bb_fab1(sch_1):\NG_M_M_BYTE-ECC\"
				( memberType ( signal ) )
				( electricalCSetRef "@crescent_city_bb_fab1_lib.crescent_city_bb_fab1(sch_1):\DDR_DQ_A\" )
				( member ( diffPairRef "@sapphirecity_baseboard_lib.sapphirecity_baseboard(sch_1):\M_M_DQS_D\(8)") )
				( member ( diffPairRef "@sapphirecity_baseboard_lib.sapphirecity_baseboard(sch_1):\M_M_DQS_D\(17)") )
				( member ( signalRef "@baseboard_fab2_lib.baseboard_fab2(sch_1):m_m_ecc(0)") )
				( member ( signalRef "@baseboard_fab2_lib.baseboard_fab2(sch_1):m_m_ecc(1)") )
				( member ( signalRef "@baseboard_fab2_lib.baseboard_fab2(sch_1):m_m_ecc(2)") )
				( member ( signalRef "@baseboard_fab2_lib.baseboard_fab2(sch_1):m_m_ecc(3)") )
				( member ( signalRef "@baseboard_fab2_lib.baseboard_fab2(sch_1):m_m_ecc(4)") )
				( member ( signalRef "@baseboard_fab2_lib.baseboard_fab2(sch_1):m_m_ecc(5)") )
				( member ( signalRef "@baseboard_fab2_lib.baseboard_fab2(sch_1):m_m_ecc(6)") )
				( member ( signalRef "@baseboard_fab2_lib.baseboard_fab2(sch_1):m_m_ecc(7)") )
				( objectStatus "NG_M_M_BYTE-ECC" )
			)
			( netGroup "@crescent_city_bb_fab1_lib.crescent_city_bb_fab1(sch_1):\NG_M_L_BYTE7\"
				( memberType ( signal ) )
				( electricalCSetRef "@crescent_city_bb_fab1_lib.crescent_city_bb_fab1(sch_1):\DDR_DQ_A\" )
				( member ( diffPairRef "@sapphirecity_baseboard_lib.sapphirecity_baseboard(sch_1):\M_L_DQS_D\(7)") )
				( member ( diffPairRef "@sapphirecity_baseboard_lib.sapphirecity_baseboard(sch_1):\M_L_DQS_D\(16)") )
				( member ( signalRef "@baseboard_fab2_lib.baseboard_fab2(sch_1):m_l_dq(56)") )
				( member ( signalRef "@baseboard_fab2_lib.baseboard_fab2(sch_1):m_l_dq(57)") )
				( member ( signalRef "@baseboard_fab2_lib.baseboard_fab2(sch_1):m_l_dq(58)") )
				( member ( signalRef "@baseboard_fab2_lib.baseboard_fab2(sch_1):m_l_dq(59)") )
				( member ( signalRef "@baseboard_fab2_lib.baseboard_fab2(sch_1):m_l_dq(60)") )
				( member ( signalRef "@baseboard_fab2_lib.baseboard_fab2(sch_1):m_l_dq(61)") )
				( member ( signalRef "@baseboard_fab2_lib.baseboard_fab2(sch_1):m_l_dq(62)") )
				( member ( signalRef "@baseboard_fab2_lib.baseboard_fab2(sch_1):m_l_dq(63)") )
				( objectStatus "NG_M_L_BYTE7" )
			)
			( netGroup "@crescent_city_bb_fab1_lib.crescent_city_bb_fab1(sch_1):\NG_M_L_BYTE6\"
				( memberType ( signal ) )
				( electricalCSetRef "@crescent_city_bb_fab1_lib.crescent_city_bb_fab1(sch_1):\DDR_DQ_A\" )
				( member ( diffPairRef "@sapphirecity_baseboard_lib.sapphirecity_baseboard(sch_1):\M_L_DQS_D\(6)") )
				( member ( diffPairRef "@sapphirecity_baseboard_lib.sapphirecity_baseboard(sch_1):\M_L_DQS_D\(15)") )
				( member ( signalRef "@baseboard_fab2_lib.baseboard_fab2(sch_1):m_l_dq(48)") )
				( member ( signalRef "@baseboard_fab2_lib.baseboard_fab2(sch_1):m_l_dq(49)") )
				( member ( signalRef "@baseboard_fab2_lib.baseboard_fab2(sch_1):m_l_dq(50)") )
				( member ( signalRef "@baseboard_fab2_lib.baseboard_fab2(sch_1):m_l_dq(51)") )
				( member ( signalRef "@baseboard_fab2_lib.baseboard_fab2(sch_1):m_l_dq(52)") )
				( member ( signalRef "@baseboard_fab2_lib.baseboard_fab2(sch_1):m_l_dq(53)") )
				( member ( signalRef "@baseboard_fab2_lib.baseboard_fab2(sch_1):m_l_dq(54)") )
				( member ( signalRef "@baseboard_fab2_lib.baseboard_fab2(sch_1):m_l_dq(55)") )
				( objectStatus "NG_M_L_BYTE6" )
			)
			( netGroup "@crescent_city_bb_fab1_lib.crescent_city_bb_fab1(sch_1):\NG_M_L_BYTE5\"
				( memberType ( signal ) )
				( electricalCSetRef "@crescent_city_bb_fab1_lib.crescent_city_bb_fab1(sch_1):\DDR_DQ_A\" )
				( member ( diffPairRef "@sapphirecity_baseboard_lib.sapphirecity_baseboard(sch_1):\M_L_DQS_D\(5)") )
				( member ( diffPairRef "@sapphirecity_baseboard_lib.sapphirecity_baseboard(sch_1):\M_L_DQS_D\(14)") )
				( member ( signalRef "@baseboard_fab2_lib.baseboard_fab2(sch_1):m_l_dq(40)") )
				( member ( signalRef "@baseboard_fab2_lib.baseboard_fab2(sch_1):m_l_dq(41)") )
				( member ( signalRef "@baseboard_fab2_lib.baseboard_fab2(sch_1):m_l_dq(42)") )
				( member ( signalRef "@baseboard_fab2_lib.baseboard_fab2(sch_1):m_l_dq(43)") )
				( member ( signalRef "@baseboard_fab2_lib.baseboard_fab2(sch_1):m_l_dq(44)") )
				( member ( signalRef "@baseboard_fab2_lib.baseboard_fab2(sch_1):m_l_dq(45)") )
				( member ( signalRef "@baseboard_fab2_lib.baseboard_fab2(sch_1):m_l_dq(46)") )
				( member ( signalRef "@baseboard_fab2_lib.baseboard_fab2(sch_1):m_l_dq(47)") )
				( objectStatus "NG_M_L_BYTE5" )
			)
			( netGroup "@crescent_city_bb_fab1_lib.crescent_city_bb_fab1(sch_1):\NG_M_L_BYTE4\"
				( memberType ( signal ) )
				( electricalCSetRef "@crescent_city_bb_fab1_lib.crescent_city_bb_fab1(sch_1):\DDR_DQ_A\" )
				( member ( diffPairRef "@sapphirecity_baseboard_lib.sapphirecity_baseboard(sch_1):\M_L_DQS_D\(4)") )
				( member ( diffPairRef "@sapphirecity_baseboard_lib.sapphirecity_baseboard(sch_1):\M_L_DQS_D\(13)") )
				( member ( signalRef "@baseboard_fab2_lib.baseboard_fab2(sch_1):m_l_dq(32)") )
				( member ( signalRef "@baseboard_fab2_lib.baseboard_fab2(sch_1):m_l_dq(33)") )
				( member ( signalRef "@baseboard_fab2_lib.baseboard_fab2(sch_1):m_l_dq(34)") )
				( member ( signalRef "@baseboard_fab2_lib.baseboard_fab2(sch_1):m_l_dq(35)") )
				( member ( signalRef "@baseboard_fab2_lib.baseboard_fab2(sch_1):m_l_dq(36)") )
				( member ( signalRef "@baseboard_fab2_lib.baseboard_fab2(sch_1):m_l_dq(37)") )
				( member ( signalRef "@baseboard_fab2_lib.baseboard_fab2(sch_1):m_l_dq(38)") )
				( member ( signalRef "@baseboard_fab2_lib.baseboard_fab2(sch_1):m_l_dq(39)") )
				( objectStatus "NG_M_L_BYTE4" )
			)
			( netGroup "@crescent_city_bb_fab1_lib.crescent_city_bb_fab1(sch_1):\NG_M_L_BYTE3\"
				( memberType ( signal ) )
				( electricalCSetRef "@crescent_city_bb_fab1_lib.crescent_city_bb_fab1(sch_1):\DDR_DQ_A\" )
				( member ( diffPairRef "@sapphirecity_baseboard_lib.sapphirecity_baseboard(sch_1):\M_L_DQS_D\(3)") )
				( member ( diffPairRef "@sapphirecity_baseboard_lib.sapphirecity_baseboard(sch_1):\M_L_DQS_D\(12)") )
				( member ( signalRef "@baseboard_fab2_lib.baseboard_fab2(sch_1):m_l_dq(24)") )
				( member ( signalRef "@baseboard_fab2_lib.baseboard_fab2(sch_1):m_l_dq(25)") )
				( member ( signalRef "@baseboard_fab2_lib.baseboard_fab2(sch_1):m_l_dq(26)") )
				( member ( signalRef "@baseboard_fab2_lib.baseboard_fab2(sch_1):m_l_dq(27)") )
				( member ( signalRef "@baseboard_fab2_lib.baseboard_fab2(sch_1):m_l_dq(28)") )
				( member ( signalRef "@baseboard_fab2_lib.baseboard_fab2(sch_1):m_l_dq(29)") )
				( member ( signalRef "@baseboard_fab2_lib.baseboard_fab2(sch_1):m_l_dq(30)") )
				( member ( signalRef "@baseboard_fab2_lib.baseboard_fab2(sch_1):m_l_dq(31)") )
				( objectStatus "NG_M_L_BYTE3" )
			)
			( netGroup "@crescent_city_bb_fab1_lib.crescent_city_bb_fab1(sch_1):\NG_M_L_BYTE2\"
				( memberType ( signal ) )
				( electricalCSetRef "@crescent_city_bb_fab1_lib.crescent_city_bb_fab1(sch_1):\DDR_DQ_A\" )
				( member ( diffPairRef "@sapphirecity_baseboard_lib.sapphirecity_baseboard(sch_1):\M_L_DQS_D\(2)") )
				( member ( diffPairRef "@sapphirecity_baseboard_lib.sapphirecity_baseboard(sch_1):\M_L_DQS_D\(11)") )
				( member ( signalRef "@baseboard_fab2_lib.baseboard_fab2(sch_1):m_l_dq(16)") )
				( member ( signalRef "@baseboard_fab2_lib.baseboard_fab2(sch_1):m_l_dq(17)") )
				( member ( signalRef "@baseboard_fab2_lib.baseboard_fab2(sch_1):m_l_dq(18)") )
				( member ( signalRef "@baseboard_fab2_lib.baseboard_fab2(sch_1):m_l_dq(19)") )
				( member ( signalRef "@baseboard_fab2_lib.baseboard_fab2(sch_1):m_l_dq(20)") )
				( member ( signalRef "@baseboard_fab2_lib.baseboard_fab2(sch_1):m_l_dq(21)") )
				( member ( signalRef "@baseboard_fab2_lib.baseboard_fab2(sch_1):m_l_dq(22)") )
				( member ( signalRef "@baseboard_fab2_lib.baseboard_fab2(sch_1):m_l_dq(23)") )
				( objectStatus "NG_M_L_BYTE2" )
			)
			( netGroup "@crescent_city_bb_fab1_lib.crescent_city_bb_fab1(sch_1):\NG_M_L_BYTE1\"
				( memberType ( signal ) )
				( electricalCSetRef "@crescent_city_bb_fab1_lib.crescent_city_bb_fab1(sch_1):\DDR_DQ_A\" )
				( member ( diffPairRef "@sapphirecity_baseboard_lib.sapphirecity_baseboard(sch_1):\M_L_DQS_D\(1)") )
				( member ( diffPairRef "@sapphirecity_baseboard_lib.sapphirecity_baseboard(sch_1):\M_L_DQS_D\(10)") )
				( member ( signalRef "@baseboard_fab2_lib.baseboard_fab2(sch_1):m_l_dq(8)") )
				( member ( signalRef "@baseboard_fab2_lib.baseboard_fab2(sch_1):m_l_dq(9)") )
				( member ( signalRef "@baseboard_fab2_lib.baseboard_fab2(sch_1):m_l_dq(10)") )
				( member ( signalRef "@baseboard_fab2_lib.baseboard_fab2(sch_1):m_l_dq(11)") )
				( member ( signalRef "@baseboard_fab2_lib.baseboard_fab2(sch_1):m_l_dq(12)") )
				( member ( signalRef "@baseboard_fab2_lib.baseboard_fab2(sch_1):m_l_dq(13)") )
				( member ( signalRef "@baseboard_fab2_lib.baseboard_fab2(sch_1):m_l_dq(14)") )
				( member ( signalRef "@baseboard_fab2_lib.baseboard_fab2(sch_1):m_l_dq(15)") )
				( objectStatus "NG_M_L_BYTE1" )
			)
			( netGroup "@crescent_city_bb_fab1_lib.crescent_city_bb_fab1(sch_1):\NG_M_L_BYTE0\"
				( memberType ( signal ) )
				( electricalCSetRef "@crescent_city_bb_fab1_lib.crescent_city_bb_fab1(sch_1):\DDR_DQ_A\" )
				( member ( diffPairRef "@sapphirecity_baseboard_lib.sapphirecity_baseboard(sch_1):\M_L_DQS_D\(0)") )
				( member ( diffPairRef "@sapphirecity_baseboard_lib.sapphirecity_baseboard(sch_1):\M_L_DQS_D\(9)") )
				( member ( signalRef "@baseboard_fab2_lib.baseboard_fab2(sch_1):m_l_dq(0)") )
				( member ( signalRef "@baseboard_fab2_lib.baseboard_fab2(sch_1):m_l_dq(1)") )
				( member ( signalRef "@baseboard_fab2_lib.baseboard_fab2(sch_1):m_l_dq(2)") )
				( member ( signalRef "@baseboard_fab2_lib.baseboard_fab2(sch_1):m_l_dq(3)") )
				( member ( signalRef "@baseboard_fab2_lib.baseboard_fab2(sch_1):m_l_dq(4)") )
				( member ( signalRef "@baseboard_fab2_lib.baseboard_fab2(sch_1):m_l_dq(5)") )
				( member ( signalRef "@baseboard_fab2_lib.baseboard_fab2(sch_1):m_l_dq(6)") )
				( member ( signalRef "@baseboard_fab2_lib.baseboard_fab2(sch_1):m_l_dq(7)") )
				( objectStatus "NG_M_L_BYTE0" )
			)
			( netGroup "@crescent_city_bb_fab1_lib.crescent_city_bb_fab1(sch_1):\NG_M_L_BYTE-ECC\"
				( memberType ( signal ) )
				( electricalCSetRef "@crescent_city_bb_fab1_lib.crescent_city_bb_fab1(sch_1):\DDR_DQ_A\" )
				( member ( diffPairRef "@sapphirecity_baseboard_lib.sapphirecity_baseboard(sch_1):\M_L_DQS_D\(8)") )
				( member ( diffPairRef "@sapphirecity_baseboard_lib.sapphirecity_baseboard(sch_1):\M_L_DQS_D\(17)") )
				( member ( signalRef "@baseboard_fab2_lib.baseboard_fab2(sch_1):m_l_ecc(0)") )
				( member ( signalRef "@baseboard_fab2_lib.baseboard_fab2(sch_1):m_l_ecc(1)") )
				( member ( signalRef "@baseboard_fab2_lib.baseboard_fab2(sch_1):m_l_ecc(2)") )
				( member ( signalRef "@baseboard_fab2_lib.baseboard_fab2(sch_1):m_l_ecc(3)") )
				( member ( signalRef "@baseboard_fab2_lib.baseboard_fab2(sch_1):m_l_ecc(4)") )
				( member ( signalRef "@baseboard_fab2_lib.baseboard_fab2(sch_1):m_l_ecc(5)") )
				( member ( signalRef "@baseboard_fab2_lib.baseboard_fab2(sch_1):m_l_ecc(6)") )
				( member ( signalRef "@baseboard_fab2_lib.baseboard_fab2(sch_1):m_l_ecc(7)") )
				( objectStatus "NG_M_L_BYTE-ECC" )
			)
			( netGroup "@crescent_city_bb_fab1_lib.crescent_city_bb_fab1(sch_1):\NG_M_K_BYTE7\"
				( memberType ( signal ) )
				( electricalCSetRef "@crescent_city_bb_fab1_lib.crescent_city_bb_fab1(sch_1):\DDR_DQ_A\" )
				( member ( diffPairRef "@sapphirecity_baseboard_lib.sapphirecity_baseboard(sch_1):\M_K_DQS_D\(7)") )
				( member ( diffPairRef "@sapphirecity_baseboard_lib.sapphirecity_baseboard(sch_1):\M_K_DQS_D\(16)") )
				( member ( signalRef "@baseboard_fab2_lib.baseboard_fab2(sch_1):m_k_dq(56)") )
				( member ( signalRef "@baseboard_fab2_lib.baseboard_fab2(sch_1):m_k_dq(57)") )
				( member ( signalRef "@baseboard_fab2_lib.baseboard_fab2(sch_1):m_k_dq(58)") )
				( member ( signalRef "@baseboard_fab2_lib.baseboard_fab2(sch_1):m_k_dq(59)") )
				( member ( signalRef "@baseboard_fab2_lib.baseboard_fab2(sch_1):m_k_dq(60)") )
				( member ( signalRef "@baseboard_fab2_lib.baseboard_fab2(sch_1):m_k_dq(61)") )
				( member ( signalRef "@baseboard_fab2_lib.baseboard_fab2(sch_1):m_k_dq(62)") )
				( member ( signalRef "@baseboard_fab2_lib.baseboard_fab2(sch_1):m_k_dq(63)") )
				( objectStatus "NG_M_K_BYTE7" )
			)
			( netGroup "@crescent_city_bb_fab1_lib.crescent_city_bb_fab1(sch_1):\NG_M_K_BYTE6\"
				( memberType ( signal ) )
				( electricalCSetRef "@crescent_city_bb_fab1_lib.crescent_city_bb_fab1(sch_1):\DDR_DQ_A\" )
				( member ( diffPairRef "@sapphirecity_baseboard_lib.sapphirecity_baseboard(sch_1):\M_K_DQS_D\(6)") )
				( member ( diffPairRef "@sapphirecity_baseboard_lib.sapphirecity_baseboard(sch_1):\M_K_DQS_D\(15)") )
				( member ( signalRef "@baseboard_fab2_lib.baseboard_fab2(sch_1):m_k_dq(48)") )
				( member ( signalRef "@baseboard_fab2_lib.baseboard_fab2(sch_1):m_k_dq(49)") )
				( member ( signalRef "@baseboard_fab2_lib.baseboard_fab2(sch_1):m_k_dq(50)") )
				( member ( signalRef "@baseboard_fab2_lib.baseboard_fab2(sch_1):m_k_dq(51)") )
				( member ( signalRef "@baseboard_fab2_lib.baseboard_fab2(sch_1):m_k_dq(52)") )
				( member ( signalRef "@baseboard_fab2_lib.baseboard_fab2(sch_1):m_k_dq(53)") )
				( member ( signalRef "@baseboard_fab2_lib.baseboard_fab2(sch_1):m_k_dq(54)") )
				( member ( signalRef "@baseboard_fab2_lib.baseboard_fab2(sch_1):m_k_dq(55)") )
				( objectStatus "NG_M_K_BYTE6" )
			)
			( netGroup "@crescent_city_bb_fab1_lib.crescent_city_bb_fab1(sch_1):\NG_M_K_BYTE5\"
				( memberType ( signal ) )
				( electricalCSetRef "@crescent_city_bb_fab1_lib.crescent_city_bb_fab1(sch_1):\DDR_DQ_A\" )
				( member ( diffPairRef "@sapphirecity_baseboard_lib.sapphirecity_baseboard(sch_1):\M_K_DQS_D\(5)") )
				( member ( diffPairRef "@sapphirecity_baseboard_lib.sapphirecity_baseboard(sch_1):\M_K_DQS_D\(14)") )
				( member ( signalRef "@baseboard_fab2_lib.baseboard_fab2(sch_1):m_k_dq(40)") )
				( member ( signalRef "@baseboard_fab2_lib.baseboard_fab2(sch_1):m_k_dq(41)") )
				( member ( signalRef "@baseboard_fab2_lib.baseboard_fab2(sch_1):m_k_dq(42)") )
				( member ( signalRef "@baseboard_fab2_lib.baseboard_fab2(sch_1):m_k_dq(43)") )
				( member ( signalRef "@baseboard_fab2_lib.baseboard_fab2(sch_1):m_k_dq(44)") )
				( member ( signalRef "@baseboard_fab2_lib.baseboard_fab2(sch_1):m_k_dq(45)") )
				( member ( signalRef "@baseboard_fab2_lib.baseboard_fab2(sch_1):m_k_dq(46)") )
				( member ( signalRef "@baseboard_fab2_lib.baseboard_fab2(sch_1):m_k_dq(47)") )
				( objectStatus "NG_M_K_BYTE5" )
			)
			( netGroup "@crescent_city_bb_fab1_lib.crescent_city_bb_fab1(sch_1):\NG_M_K_BYTE4\"
				( memberType ( signal ) )
				( electricalCSetRef "@crescent_city_bb_fab1_lib.crescent_city_bb_fab1(sch_1):\DDR_DQ_A\" )
				( member ( diffPairRef "@sapphirecity_baseboard_lib.sapphirecity_baseboard(sch_1):\M_K_DQS_D\(4)") )
				( member ( diffPairRef "@sapphirecity_baseboard_lib.sapphirecity_baseboard(sch_1):\M_K_DQS_D\(13)") )
				( member ( signalRef "@baseboard_fab2_lib.baseboard_fab2(sch_1):m_k_dq(32)") )
				( member ( signalRef "@baseboard_fab2_lib.baseboard_fab2(sch_1):m_k_dq(33)") )
				( member ( signalRef "@baseboard_fab2_lib.baseboard_fab2(sch_1):m_k_dq(34)") )
				( member ( signalRef "@baseboard_fab2_lib.baseboard_fab2(sch_1):m_k_dq(35)") )
				( member ( signalRef "@baseboard_fab2_lib.baseboard_fab2(sch_1):m_k_dq(36)") )
				( member ( signalRef "@baseboard_fab2_lib.baseboard_fab2(sch_1):m_k_dq(37)") )
				( member ( signalRef "@baseboard_fab2_lib.baseboard_fab2(sch_1):m_k_dq(38)") )
				( member ( signalRef "@baseboard_fab2_lib.baseboard_fab2(sch_1):m_k_dq(39)") )
				( objectStatus "NG_M_K_BYTE4" )
			)
			( netGroup "@crescent_city_bb_fab1_lib.crescent_city_bb_fab1(sch_1):\NG_M_K_BYTE3\"
				( memberType ( signal ) )
				( electricalCSetRef "@crescent_city_bb_fab1_lib.crescent_city_bb_fab1(sch_1):\DDR_DQ_A\" )
				( member ( diffPairRef "@sapphirecity_baseboard_lib.sapphirecity_baseboard(sch_1):\M_K_DQS_D\(3)") )
				( member ( diffPairRef "@sapphirecity_baseboard_lib.sapphirecity_baseboard(sch_1):\M_K_DQS_D\(12)") )
				( member ( signalRef "@baseboard_fab2_lib.baseboard_fab2(sch_1):m_k_dq(24)") )
				( member ( signalRef "@baseboard_fab2_lib.baseboard_fab2(sch_1):m_k_dq(25)") )
				( member ( signalRef "@baseboard_fab2_lib.baseboard_fab2(sch_1):m_k_dq(26)") )
				( member ( signalRef "@baseboard_fab2_lib.baseboard_fab2(sch_1):m_k_dq(27)") )
				( member ( signalRef "@baseboard_fab2_lib.baseboard_fab2(sch_1):m_k_dq(28)") )
				( member ( signalRef "@baseboard_fab2_lib.baseboard_fab2(sch_1):m_k_dq(29)") )
				( member ( signalRef "@baseboard_fab2_lib.baseboard_fab2(sch_1):m_k_dq(30)") )
				( member ( signalRef "@baseboard_fab2_lib.baseboard_fab2(sch_1):m_k_dq(31)") )
				( objectStatus "NG_M_K_BYTE3" )
			)
			( netGroup "@crescent_city_bb_fab1_lib.crescent_city_bb_fab1(sch_1):\NG_M_K_BYTE2\"
				( memberType ( signal ) )
				( electricalCSetRef "@crescent_city_bb_fab1_lib.crescent_city_bb_fab1(sch_1):\DDR_DQ_A\" )
				( member ( diffPairRef "@sapphirecity_baseboard_lib.sapphirecity_baseboard(sch_1):\M_K_DQS_D\(2)") )
				( member ( diffPairRef "@sapphirecity_baseboard_lib.sapphirecity_baseboard(sch_1):\M_K_DQS_D\(11)") )
				( member ( signalRef "@baseboard_fab2_lib.baseboard_fab2(sch_1):m_k_dq(16)") )
				( member ( signalRef "@baseboard_fab2_lib.baseboard_fab2(sch_1):m_k_dq(17)") )
				( member ( signalRef "@baseboard_fab2_lib.baseboard_fab2(sch_1):m_k_dq(18)") )
				( member ( signalRef "@baseboard_fab2_lib.baseboard_fab2(sch_1):m_k_dq(19)") )
				( member ( signalRef "@baseboard_fab2_lib.baseboard_fab2(sch_1):m_k_dq(20)") )
				( member ( signalRef "@baseboard_fab2_lib.baseboard_fab2(sch_1):m_k_dq(21)") )
				( member ( signalRef "@baseboard_fab2_lib.baseboard_fab2(sch_1):m_k_dq(22)") )
				( member ( signalRef "@baseboard_fab2_lib.baseboard_fab2(sch_1):m_k_dq(23)") )
				( objectStatus "NG_M_K_BYTE2" )
			)
			( netGroup "@crescent_city_bb_fab1_lib.crescent_city_bb_fab1(sch_1):\NG_M_K_BYTE1\"
				( memberType ( signal ) )
				( electricalCSetRef "@crescent_city_bb_fab1_lib.crescent_city_bb_fab1(sch_1):\DDR_DQ_A\" )
				( member ( diffPairRef "@sapphirecity_baseboard_lib.sapphirecity_baseboard(sch_1):\M_K_DQS_D\(1)") )
				( member ( diffPairRef "@sapphirecity_baseboard_lib.sapphirecity_baseboard(sch_1):\M_K_DQS_D\(10)") )
				( member ( signalRef "@baseboard_fab2_lib.baseboard_fab2(sch_1):m_k_dq(8)") )
				( member ( signalRef "@baseboard_fab2_lib.baseboard_fab2(sch_1):m_k_dq(9)") )
				( member ( signalRef "@baseboard_fab2_lib.baseboard_fab2(sch_1):m_k_dq(10)") )
				( member ( signalRef "@baseboard_fab2_lib.baseboard_fab2(sch_1):m_k_dq(11)") )
				( member ( signalRef "@baseboard_fab2_lib.baseboard_fab2(sch_1):m_k_dq(12)") )
				( member ( signalRef "@baseboard_fab2_lib.baseboard_fab2(sch_1):m_k_dq(13)") )
				( member ( signalRef "@baseboard_fab2_lib.baseboard_fab2(sch_1):m_k_dq(14)") )
				( member ( signalRef "@baseboard_fab2_lib.baseboard_fab2(sch_1):m_k_dq(15)") )
				( objectStatus "NG_M_K_BYTE1" )
			)
			( netGroup "@crescent_city_bb_fab1_lib.crescent_city_bb_fab1(sch_1):\NG_M_K_BYTE0\"
				( memberType ( signal ) )
				( electricalCSetRef "@crescent_city_bb_fab1_lib.crescent_city_bb_fab1(sch_1):\DDR_DQ_A\" )
				( member ( diffPairRef "@sapphirecity_baseboard_lib.sapphirecity_baseboard(sch_1):\M_K_DQS_D\(0)") )
				( member ( diffPairRef "@sapphirecity_baseboard_lib.sapphirecity_baseboard(sch_1):\M_K_DQS_D\(9)") )
				( member ( signalRef "@baseboard_fab2_lib.baseboard_fab2(sch_1):m_k_dq(0)") )
				( member ( signalRef "@baseboard_fab2_lib.baseboard_fab2(sch_1):m_k_dq(1)") )
				( member ( signalRef "@baseboard_fab2_lib.baseboard_fab2(sch_1):m_k_dq(2)") )
				( member ( signalRef "@baseboard_fab2_lib.baseboard_fab2(sch_1):m_k_dq(3)") )
				( member ( signalRef "@baseboard_fab2_lib.baseboard_fab2(sch_1):m_k_dq(4)") )
				( member ( signalRef "@baseboard_fab2_lib.baseboard_fab2(sch_1):m_k_dq(5)") )
				( member ( signalRef "@baseboard_fab2_lib.baseboard_fab2(sch_1):m_k_dq(6)") )
				( member ( signalRef "@baseboard_fab2_lib.baseboard_fab2(sch_1):m_k_dq(7)") )
				( objectStatus "NG_M_K_BYTE0" )
			)
			( netGroup "@crescent_city_bb_fab1_lib.crescent_city_bb_fab1(sch_1):\NG_M_K_BYTE-ECC\"
				( memberType ( signal ) )
				( electricalCSetRef "@crescent_city_bb_fab1_lib.crescent_city_bb_fab1(sch_1):\DDR_DQ_A\" )
				( member ( diffPairRef "@sapphirecity_baseboard_lib.sapphirecity_baseboard(sch_1):\M_K_DQS_D\(8)") )
				( member ( diffPairRef "@sapphirecity_baseboard_lib.sapphirecity_baseboard(sch_1):\M_K_DQS_D\(17)") )
				( member ( signalRef "@baseboard_fab2_lib.baseboard_fab2(sch_1):m_k_ecc(0)") )
				( member ( signalRef "@baseboard_fab2_lib.baseboard_fab2(sch_1):m_k_ecc(1)") )
				( member ( signalRef "@baseboard_fab2_lib.baseboard_fab2(sch_1):m_k_ecc(2)") )
				( member ( signalRef "@baseboard_fab2_lib.baseboard_fab2(sch_1):m_k_ecc(3)") )
				( member ( signalRef "@baseboard_fab2_lib.baseboard_fab2(sch_1):m_k_ecc(4)") )
				( member ( signalRef "@baseboard_fab2_lib.baseboard_fab2(sch_1):m_k_ecc(5)") )
				( member ( signalRef "@baseboard_fab2_lib.baseboard_fab2(sch_1):m_k_ecc(6)") )
				( member ( signalRef "@baseboard_fab2_lib.baseboard_fab2(sch_1):m_k_ecc(7)") )
				( objectStatus "NG_M_K_BYTE-ECC" )
			)
			( netGroup "@crescent_city_bb_fab1_lib.crescent_city_bb_fab1(sch_1):\NG_M_J_BYTE7\"
				( memberType ( signal ) )
				( electricalCSetRef "@crescent_city_bb_fab1_lib.crescent_city_bb_fab1(sch_1):\DDR_DQ_A\" )
				( member ( diffPairRef "@sapphirecity_baseboard_lib.sapphirecity_baseboard(sch_1):\M_J_DQS_D\(7)") )
				( member ( diffPairRef "@sapphirecity_baseboard_lib.sapphirecity_baseboard(sch_1):\M_J_DQS_D\(16)") )
				( member ( signalRef "@baseboard_fab2_lib.baseboard_fab2(sch_1):m_j_dq(56)") )
				( member ( signalRef "@baseboard_fab2_lib.baseboard_fab2(sch_1):m_j_dq(57)") )
				( member ( signalRef "@baseboard_fab2_lib.baseboard_fab2(sch_1):m_j_dq(58)") )
				( member ( signalRef "@baseboard_fab2_lib.baseboard_fab2(sch_1):m_j_dq(59)") )
				( member ( signalRef "@baseboard_fab2_lib.baseboard_fab2(sch_1):m_j_dq(60)") )
				( member ( signalRef "@baseboard_fab2_lib.baseboard_fab2(sch_1):m_j_dq(61)") )
				( member ( signalRef "@baseboard_fab2_lib.baseboard_fab2(sch_1):m_j_dq(62)") )
				( member ( signalRef "@baseboard_fab2_lib.baseboard_fab2(sch_1):m_j_dq(63)") )
				( objectStatus "NG_M_J_BYTE7" )
			)
			( netGroup "@crescent_city_bb_fab1_lib.crescent_city_bb_fab1(sch_1):\NG_M_J_BYTE6\"
				( memberType ( signal ) )
				( electricalCSetRef "@crescent_city_bb_fab1_lib.crescent_city_bb_fab1(sch_1):\DDR_DQ_A\" )
				( member ( diffPairRef "@sapphirecity_baseboard_lib.sapphirecity_baseboard(sch_1):\M_J_DQS_D\(6)") )
				( member ( diffPairRef "@sapphirecity_baseboard_lib.sapphirecity_baseboard(sch_1):\M_J_DQS_D\(15)") )
				( member ( signalRef "@baseboard_fab2_lib.baseboard_fab2(sch_1):m_j_dq(48)") )
				( member ( signalRef "@baseboard_fab2_lib.baseboard_fab2(sch_1):m_j_dq(49)") )
				( member ( signalRef "@baseboard_fab2_lib.baseboard_fab2(sch_1):m_j_dq(50)") )
				( member ( signalRef "@baseboard_fab2_lib.baseboard_fab2(sch_1):m_j_dq(51)") )
				( member ( signalRef "@baseboard_fab2_lib.baseboard_fab2(sch_1):m_j_dq(52)") )
				( member ( signalRef "@baseboard_fab2_lib.baseboard_fab2(sch_1):m_j_dq(53)") )
				( member ( signalRef "@baseboard_fab2_lib.baseboard_fab2(sch_1):m_j_dq(54)") )
				( member ( signalRef "@baseboard_fab2_lib.baseboard_fab2(sch_1):m_j_dq(55)") )
				( objectStatus "NG_M_J_BYTE6" )
			)
			( netGroup "@crescent_city_bb_fab1_lib.crescent_city_bb_fab1(sch_1):\NG_M_J_BYTE5\"
				( memberType ( signal ) )
				( electricalCSetRef "@crescent_city_bb_fab1_lib.crescent_city_bb_fab1(sch_1):\DDR_DQ_A\" )
				( member ( diffPairRef "@sapphirecity_baseboard_lib.sapphirecity_baseboard(sch_1):\M_J_DQS_D\(5)") )
				( member ( diffPairRef "@sapphirecity_baseboard_lib.sapphirecity_baseboard(sch_1):\M_J_DQS_D\(14)") )
				( member ( signalRef "@baseboard_fab2_lib.baseboard_fab2(sch_1):m_j_dq(40)") )
				( member ( signalRef "@baseboard_fab2_lib.baseboard_fab2(sch_1):m_j_dq(41)") )
				( member ( signalRef "@baseboard_fab2_lib.baseboard_fab2(sch_1):m_j_dq(42)") )
				( member ( signalRef "@baseboard_fab2_lib.baseboard_fab2(sch_1):m_j_dq(43)") )
				( member ( signalRef "@baseboard_fab2_lib.baseboard_fab2(sch_1):m_j_dq(44)") )
				( member ( signalRef "@baseboard_fab2_lib.baseboard_fab2(sch_1):m_j_dq(45)") )
				( member ( signalRef "@baseboard_fab2_lib.baseboard_fab2(sch_1):m_j_dq(46)") )
				( member ( signalRef "@baseboard_fab2_lib.baseboard_fab2(sch_1):m_j_dq(47)") )
				( objectStatus "NG_M_J_BYTE5" )
			)
			( netGroup "@crescent_city_bb_fab1_lib.crescent_city_bb_fab1(sch_1):\NG_M_J_BYTE4\"
				( memberType ( signal ) )
				( electricalCSetRef "@crescent_city_bb_fab1_lib.crescent_city_bb_fab1(sch_1):\DDR_DQ_A\" )
				( member ( diffPairRef "@sapphirecity_baseboard_lib.sapphirecity_baseboard(sch_1):\M_J_DQS_D\(4)") )
				( member ( diffPairRef "@sapphirecity_baseboard_lib.sapphirecity_baseboard(sch_1):\M_J_DQS_D\(13)") )
				( member ( signalRef "@baseboard_fab2_lib.baseboard_fab2(sch_1):m_j_dq(32)") )
				( member ( signalRef "@baseboard_fab2_lib.baseboard_fab2(sch_1):m_j_dq(33)") )
				( member ( signalRef "@baseboard_fab2_lib.baseboard_fab2(sch_1):m_j_dq(34)") )
				( member ( signalRef "@baseboard_fab2_lib.baseboard_fab2(sch_1):m_j_dq(35)") )
				( member ( signalRef "@baseboard_fab2_lib.baseboard_fab2(sch_1):m_j_dq(36)") )
				( member ( signalRef "@baseboard_fab2_lib.baseboard_fab2(sch_1):m_j_dq(37)") )
				( member ( signalRef "@baseboard_fab2_lib.baseboard_fab2(sch_1):m_j_dq(38)") )
				( member ( signalRef "@baseboard_fab2_lib.baseboard_fab2(sch_1):m_j_dq(39)") )
				( objectStatus "NG_M_J_BYTE4" )
			)
			( netGroup "@crescent_city_bb_fab1_lib.crescent_city_bb_fab1(sch_1):\NG_M_J_BYTE3\"
				( memberType ( signal ) )
				( electricalCSetRef "@crescent_city_bb_fab1_lib.crescent_city_bb_fab1(sch_1):\DDR_DQ_A\" )
				( member ( diffPairRef "@sapphirecity_baseboard_lib.sapphirecity_baseboard(sch_1):\M_J_DQS_D\(3)") )
				( member ( diffPairRef "@sapphirecity_baseboard_lib.sapphirecity_baseboard(sch_1):\M_J_DQS_D\(12)") )
				( member ( signalRef "@baseboard_fab2_lib.baseboard_fab2(sch_1):m_j_dq(24)") )
				( member ( signalRef "@baseboard_fab2_lib.baseboard_fab2(sch_1):m_j_dq(25)") )
				( member ( signalRef "@baseboard_fab2_lib.baseboard_fab2(sch_1):m_j_dq(26)") )
				( member ( signalRef "@baseboard_fab2_lib.baseboard_fab2(sch_1):m_j_dq(27)") )
				( member ( signalRef "@baseboard_fab2_lib.baseboard_fab2(sch_1):m_j_dq(28)") )
				( member ( signalRef "@baseboard_fab2_lib.baseboard_fab2(sch_1):m_j_dq(29)") )
				( member ( signalRef "@baseboard_fab2_lib.baseboard_fab2(sch_1):m_j_dq(30)") )
				( member ( signalRef "@baseboard_fab2_lib.baseboard_fab2(sch_1):m_j_dq(31)") )
				( objectStatus "NG_M_J_BYTE3" )
			)
			( netGroup "@crescent_city_bb_fab1_lib.crescent_city_bb_fab1(sch_1):\NG_M_J_BYTE2\"
				( memberType ( signal ) )
				( electricalCSetRef "@crescent_city_bb_fab1_lib.crescent_city_bb_fab1(sch_1):\DDR_DQ_A\" )
				( member ( diffPairRef "@sapphirecity_baseboard_lib.sapphirecity_baseboard(sch_1):\M_J_DQS_D\(2)") )
				( member ( diffPairRef "@sapphirecity_baseboard_lib.sapphirecity_baseboard(sch_1):\M_J_DQS_D\(11)") )
				( member ( signalRef "@baseboard_fab2_lib.baseboard_fab2(sch_1):m_j_dq(16)") )
				( member ( signalRef "@baseboard_fab2_lib.baseboard_fab2(sch_1):m_j_dq(17)") )
				( member ( signalRef "@baseboard_fab2_lib.baseboard_fab2(sch_1):m_j_dq(18)") )
				( member ( signalRef "@baseboard_fab2_lib.baseboard_fab2(sch_1):m_j_dq(19)") )
				( member ( signalRef "@baseboard_fab2_lib.baseboard_fab2(sch_1):m_j_dq(20)") )
				( member ( signalRef "@baseboard_fab2_lib.baseboard_fab2(sch_1):m_j_dq(21)") )
				( member ( signalRef "@baseboard_fab2_lib.baseboard_fab2(sch_1):m_j_dq(22)") )
				( member ( signalRef "@baseboard_fab2_lib.baseboard_fab2(sch_1):m_j_dq(23)") )
				( objectStatus "NG_M_J_BYTE2" )
			)
			( netGroup "@crescent_city_bb_fab1_lib.crescent_city_bb_fab1(sch_1):\NG_M_J_BYTE1\"
				( memberType ( signal ) )
				( electricalCSetRef "@crescent_city_bb_fab1_lib.crescent_city_bb_fab1(sch_1):\DDR_DQ_A\" )
				( member ( diffPairRef "@sapphirecity_baseboard_lib.sapphirecity_baseboard(sch_1):\M_J_DQS_D\(1)") )
				( member ( diffPairRef "@sapphirecity_baseboard_lib.sapphirecity_baseboard(sch_1):\M_J_DQS_D\(10)") )
				( member ( signalRef "@baseboard_fab2_lib.baseboard_fab2(sch_1):m_j_dq(8)") )
				( member ( signalRef "@baseboard_fab2_lib.baseboard_fab2(sch_1):m_j_dq(9)") )
				( member ( signalRef "@baseboard_fab2_lib.baseboard_fab2(sch_1):m_j_dq(10)") )
				( member ( signalRef "@baseboard_fab2_lib.baseboard_fab2(sch_1):m_j_dq(11)") )
				( member ( signalRef "@baseboard_fab2_lib.baseboard_fab2(sch_1):m_j_dq(12)") )
				( member ( signalRef "@baseboard_fab2_lib.baseboard_fab2(sch_1):m_j_dq(13)") )
				( member ( signalRef "@baseboard_fab2_lib.baseboard_fab2(sch_1):m_j_dq(14)") )
				( member ( signalRef "@baseboard_fab2_lib.baseboard_fab2(sch_1):m_j_dq(15)") )
				( objectStatus "NG_M_J_BYTE1" )
			)
			( netGroup "@crescent_city_bb_fab1_lib.crescent_city_bb_fab1(sch_1):\NG_M_J_BYTE0\"
				( memberType ( signal ) )
				( electricalCSetRef "@crescent_city_bb_fab1_lib.crescent_city_bb_fab1(sch_1):\DDR_DQ_A\" )
				( member ( diffPairRef "@sapphirecity_baseboard_lib.sapphirecity_baseboard(sch_1):\M_J_DQS_D\(0)") )
				( member ( diffPairRef "@sapphirecity_baseboard_lib.sapphirecity_baseboard(sch_1):\M_J_DQS_D\(9)") )
				( member ( signalRef "@baseboard_fab2_lib.baseboard_fab2(sch_1):m_j_dq(0)") )
				( member ( signalRef "@baseboard_fab2_lib.baseboard_fab2(sch_1):m_j_dq(1)") )
				( member ( signalRef "@baseboard_fab2_lib.baseboard_fab2(sch_1):m_j_dq(2)") )
				( member ( signalRef "@baseboard_fab2_lib.baseboard_fab2(sch_1):m_j_dq(3)") )
				( member ( signalRef "@baseboard_fab2_lib.baseboard_fab2(sch_1):m_j_dq(4)") )
				( member ( signalRef "@baseboard_fab2_lib.baseboard_fab2(sch_1):m_j_dq(5)") )
				( member ( signalRef "@baseboard_fab2_lib.baseboard_fab2(sch_1):m_j_dq(6)") )
				( member ( signalRef "@baseboard_fab2_lib.baseboard_fab2(sch_1):m_j_dq(7)") )
				( objectStatus "NG_M_J_BYTE0" )
			)
			( netGroup "@crescent_city_bb_fab1_lib.crescent_city_bb_fab1(sch_1):\NG_M_J_BYTE-ECC\"
				( memberType ( signal ) )
				( electricalCSetRef "@crescent_city_bb_fab1_lib.crescent_city_bb_fab1(sch_1):\DDR_DQ_A\" )
				( member ( diffPairRef "@sapphirecity_baseboard_lib.sapphirecity_baseboard(sch_1):\M_J_DQS_D\(8)") )
				( member ( diffPairRef "@sapphirecity_baseboard_lib.sapphirecity_baseboard(sch_1):\M_J_DQS_D\(17)") )
				( member ( signalRef "@baseboard_fab2_lib.baseboard_fab2(sch_1):m_j_ecc(0)") )
				( member ( signalRef "@baseboard_fab2_lib.baseboard_fab2(sch_1):m_j_ecc(1)") )
				( member ( signalRef "@baseboard_fab2_lib.baseboard_fab2(sch_1):m_j_ecc(2)") )
				( member ( signalRef "@baseboard_fab2_lib.baseboard_fab2(sch_1):m_j_ecc(3)") )
				( member ( signalRef "@baseboard_fab2_lib.baseboard_fab2(sch_1):m_j_ecc(4)") )
				( member ( signalRef "@baseboard_fab2_lib.baseboard_fab2(sch_1):m_j_ecc(5)") )
				( member ( signalRef "@baseboard_fab2_lib.baseboard_fab2(sch_1):m_j_ecc(6)") )
				( member ( signalRef "@baseboard_fab2_lib.baseboard_fab2(sch_1):m_j_ecc(7)") )
				( objectStatus "NG_M_J_BYTE-ECC" )
			)
			( netGroup "@crescent_city_bb_fab1_lib.crescent_city_bb_fab1(sch_1):\NG_M_H_BYTE7\"
				( memberType ( signal ) )
				( electricalCSetRef "@crescent_city_bb_fab1_lib.crescent_city_bb_fab1(sch_1):\DDR_DQ_A\" )
				( member ( diffPairRef "@sapphirecity_baseboard_lib.sapphirecity_baseboard(sch_1):\M_H_DQS_D\(7)") )
				( member ( diffPairRef "@sapphirecity_baseboard_lib.sapphirecity_baseboard(sch_1):\M_H_DQS_D\(16)") )
				( member ( signalRef "@baseboard_fab2_lib.baseboard_fab2(sch_1):m_h_dq(56)") )
				( member ( signalRef "@baseboard_fab2_lib.baseboard_fab2(sch_1):m_h_dq(57)") )
				( member ( signalRef "@baseboard_fab2_lib.baseboard_fab2(sch_1):m_h_dq(58)") )
				( member ( signalRef "@baseboard_fab2_lib.baseboard_fab2(sch_1):m_h_dq(59)") )
				( member ( signalRef "@baseboard_fab2_lib.baseboard_fab2(sch_1):m_h_dq(60)") )
				( member ( signalRef "@baseboard_fab2_lib.baseboard_fab2(sch_1):m_h_dq(61)") )
				( member ( signalRef "@baseboard_fab2_lib.baseboard_fab2(sch_1):m_h_dq(62)") )
				( member ( signalRef "@baseboard_fab2_lib.baseboard_fab2(sch_1):m_h_dq(63)") )
				( objectStatus "NG_M_H_BYTE7" )
			)
			( netGroup "@crescent_city_bb_fab1_lib.crescent_city_bb_fab1(sch_1):\NG_M_H_BYTE6\"
				( memberType ( signal ) )
				( electricalCSetRef "@crescent_city_bb_fab1_lib.crescent_city_bb_fab1(sch_1):\DDR_DQ_A\" )
				( member ( diffPairRef "@sapphirecity_baseboard_lib.sapphirecity_baseboard(sch_1):\M_H_DQS_D\(6)") )
				( member ( diffPairRef "@sapphirecity_baseboard_lib.sapphirecity_baseboard(sch_1):\M_H_DQS_D\(15)") )
				( member ( signalRef "@baseboard_fab2_lib.baseboard_fab2(sch_1):m_h_dq(48)") )
				( member ( signalRef "@baseboard_fab2_lib.baseboard_fab2(sch_1):m_h_dq(49)") )
				( member ( signalRef "@baseboard_fab2_lib.baseboard_fab2(sch_1):m_h_dq(50)") )
				( member ( signalRef "@baseboard_fab2_lib.baseboard_fab2(sch_1):m_h_dq(51)") )
				( member ( signalRef "@baseboard_fab2_lib.baseboard_fab2(sch_1):m_h_dq(52)") )
				( member ( signalRef "@baseboard_fab2_lib.baseboard_fab2(sch_1):m_h_dq(53)") )
				( member ( signalRef "@baseboard_fab2_lib.baseboard_fab2(sch_1):m_h_dq(54)") )
				( member ( signalRef "@baseboard_fab2_lib.baseboard_fab2(sch_1):m_h_dq(55)") )
				( objectStatus "NG_M_H_BYTE6" )
			)
			( netGroup "@crescent_city_bb_fab1_lib.crescent_city_bb_fab1(sch_1):\NG_M_H_BYTE5\"
				( memberType ( signal ) )
				( electricalCSetRef "@crescent_city_bb_fab1_lib.crescent_city_bb_fab1(sch_1):\DDR_DQ_A\" )
				( member ( diffPairRef "@sapphirecity_baseboard_lib.sapphirecity_baseboard(sch_1):\M_H_DQS_D\(5)") )
				( member ( diffPairRef "@sapphirecity_baseboard_lib.sapphirecity_baseboard(sch_1):\M_H_DQS_D\(14)") )
				( member ( signalRef "@baseboard_fab2_lib.baseboard_fab2(sch_1):m_h_dq(40)") )
				( member ( signalRef "@baseboard_fab2_lib.baseboard_fab2(sch_1):m_h_dq(41)") )
				( member ( signalRef "@baseboard_fab2_lib.baseboard_fab2(sch_1):m_h_dq(42)") )
				( member ( signalRef "@baseboard_fab2_lib.baseboard_fab2(sch_1):m_h_dq(43)") )
				( member ( signalRef "@baseboard_fab2_lib.baseboard_fab2(sch_1):m_h_dq(44)") )
				( member ( signalRef "@baseboard_fab2_lib.baseboard_fab2(sch_1):m_h_dq(45)") )
				( member ( signalRef "@baseboard_fab2_lib.baseboard_fab2(sch_1):m_h_dq(46)") )
				( member ( signalRef "@baseboard_fab2_lib.baseboard_fab2(sch_1):m_h_dq(47)") )
				( objectStatus "NG_M_H_BYTE5" )
			)
			( netGroup "@crescent_city_bb_fab1_lib.crescent_city_bb_fab1(sch_1):\NG_M_H_BYTE4\"
				( memberType ( signal ) )
				( electricalCSetRef "@crescent_city_bb_fab1_lib.crescent_city_bb_fab1(sch_1):\DDR_DQ_A\" )
				( member ( diffPairRef "@sapphirecity_baseboard_lib.sapphirecity_baseboard(sch_1):\M_H_DQS_D\(4)") )
				( member ( diffPairRef "@sapphirecity_baseboard_lib.sapphirecity_baseboard(sch_1):\M_H_DQS_D\(13)") )
				( member ( signalRef "@baseboard_fab2_lib.baseboard_fab2(sch_1):m_h_dq(32)") )
				( member ( signalRef "@baseboard_fab2_lib.baseboard_fab2(sch_1):m_h_dq(33)") )
				( member ( signalRef "@baseboard_fab2_lib.baseboard_fab2(sch_1):m_h_dq(34)") )
				( member ( signalRef "@baseboard_fab2_lib.baseboard_fab2(sch_1):m_h_dq(35)") )
				( member ( signalRef "@baseboard_fab2_lib.baseboard_fab2(sch_1):m_h_dq(36)") )
				( member ( signalRef "@baseboard_fab2_lib.baseboard_fab2(sch_1):m_h_dq(37)") )
				( member ( signalRef "@baseboard_fab2_lib.baseboard_fab2(sch_1):m_h_dq(38)") )
				( member ( signalRef "@baseboard_fab2_lib.baseboard_fab2(sch_1):m_h_dq(39)") )
				( objectStatus "NG_M_H_BYTE4" )
			)
			( netGroup "@crescent_city_bb_fab1_lib.crescent_city_bb_fab1(sch_1):\NG_M_H_BYTE3\"
				( memberType ( signal ) )
				( electricalCSetRef "@crescent_city_bb_fab1_lib.crescent_city_bb_fab1(sch_1):\DDR_DQ_A\" )
				( member ( diffPairRef "@sapphirecity_baseboard_lib.sapphirecity_baseboard(sch_1):\M_H_DQS_D\(3)") )
				( member ( diffPairRef "@sapphirecity_baseboard_lib.sapphirecity_baseboard(sch_1):\M_H_DQS_D\(12)") )
				( member ( signalRef "@baseboard_fab2_lib.baseboard_fab2(sch_1):m_h_dq(24)") )
				( member ( signalRef "@baseboard_fab2_lib.baseboard_fab2(sch_1):m_h_dq(25)") )
				( member ( signalRef "@baseboard_fab2_lib.baseboard_fab2(sch_1):m_h_dq(26)") )
				( member ( signalRef "@baseboard_fab2_lib.baseboard_fab2(sch_1):m_h_dq(27)") )
				( member ( signalRef "@baseboard_fab2_lib.baseboard_fab2(sch_1):m_h_dq(28)") )
				( member ( signalRef "@baseboard_fab2_lib.baseboard_fab2(sch_1):m_h_dq(29)") )
				( member ( signalRef "@baseboard_fab2_lib.baseboard_fab2(sch_1):m_h_dq(30)") )
				( member ( signalRef "@baseboard_fab2_lib.baseboard_fab2(sch_1):m_h_dq(31)") )
				( objectStatus "NG_M_H_BYTE3" )
			)
			( netGroup "@crescent_city_bb_fab1_lib.crescent_city_bb_fab1(sch_1):\NG_M_H_BYTE2\"
				( memberType ( signal ) )
				( electricalCSetRef "@crescent_city_bb_fab1_lib.crescent_city_bb_fab1(sch_1):\DDR_DQ_A\" )
				( member ( diffPairRef "@sapphirecity_baseboard_lib.sapphirecity_baseboard(sch_1):\M_H_DQS_D\(2)") )
				( member ( diffPairRef "@sapphirecity_baseboard_lib.sapphirecity_baseboard(sch_1):\M_H_DQS_D\(11)") )
				( member ( signalRef "@baseboard_fab2_lib.baseboard_fab2(sch_1):m_h_dq(16)") )
				( member ( signalRef "@baseboard_fab2_lib.baseboard_fab2(sch_1):m_h_dq(17)") )
				( member ( signalRef "@baseboard_fab2_lib.baseboard_fab2(sch_1):m_h_dq(18)") )
				( member ( signalRef "@baseboard_fab2_lib.baseboard_fab2(sch_1):m_h_dq(19)") )
				( member ( signalRef "@baseboard_fab2_lib.baseboard_fab2(sch_1):m_h_dq(20)") )
				( member ( signalRef "@baseboard_fab2_lib.baseboard_fab2(sch_1):m_h_dq(21)") )
				( member ( signalRef "@baseboard_fab2_lib.baseboard_fab2(sch_1):m_h_dq(22)") )
				( member ( signalRef "@baseboard_fab2_lib.baseboard_fab2(sch_1):m_h_dq(23)") )
				( objectStatus "NG_M_H_BYTE2" )
			)
			( netGroup "@crescent_city_bb_fab1_lib.crescent_city_bb_fab1(sch_1):\NG_M_H_BYTE1\"
				( memberType ( signal ) )
				( electricalCSetRef "@crescent_city_bb_fab1_lib.crescent_city_bb_fab1(sch_1):\DDR_DQ_A\" )
				( member ( diffPairRef "@sapphirecity_baseboard_lib.sapphirecity_baseboard(sch_1):\M_H_DQS_D\(1)") )
				( member ( diffPairRef "@sapphirecity_baseboard_lib.sapphirecity_baseboard(sch_1):\M_H_DQS_D\(10)") )
				( member ( signalRef "@baseboard_fab2_lib.baseboard_fab2(sch_1):m_h_dq(8)") )
				( member ( signalRef "@baseboard_fab2_lib.baseboard_fab2(sch_1):m_h_dq(9)") )
				( member ( signalRef "@baseboard_fab2_lib.baseboard_fab2(sch_1):m_h_dq(10)") )
				( member ( signalRef "@baseboard_fab2_lib.baseboard_fab2(sch_1):m_h_dq(11)") )
				( member ( signalRef "@baseboard_fab2_lib.baseboard_fab2(sch_1):m_h_dq(12)") )
				( member ( signalRef "@baseboard_fab2_lib.baseboard_fab2(sch_1):m_h_dq(13)") )
				( member ( signalRef "@baseboard_fab2_lib.baseboard_fab2(sch_1):m_h_dq(14)") )
				( member ( signalRef "@baseboard_fab2_lib.baseboard_fab2(sch_1):m_h_dq(15)") )
				( objectStatus "NG_M_H_BYTE1" )
			)
			( netGroup "@crescent_city_bb_fab1_lib.crescent_city_bb_fab1(sch_1):\NG_M_H_BYTE0\"
				( memberType ( signal ) )
				( electricalCSetRef "@crescent_city_bb_fab1_lib.crescent_city_bb_fab1(sch_1):\DDR_DQ_A\" )
				( member ( diffPairRef "@sapphirecity_baseboard_lib.sapphirecity_baseboard(sch_1):\M_H_DQS_D\(0)") )
				( member ( diffPairRef "@sapphirecity_baseboard_lib.sapphirecity_baseboard(sch_1):\M_H_DQS_D\(9)") )
				( member ( signalRef "@baseboard_fab2_lib.baseboard_fab2(sch_1):m_h_dq(0)") )
				( member ( signalRef "@baseboard_fab2_lib.baseboard_fab2(sch_1):m_h_dq(1)") )
				( member ( signalRef "@baseboard_fab2_lib.baseboard_fab2(sch_1):m_h_dq(2)") )
				( member ( signalRef "@baseboard_fab2_lib.baseboard_fab2(sch_1):m_h_dq(3)") )
				( member ( signalRef "@baseboard_fab2_lib.baseboard_fab2(sch_1):m_h_dq(4)") )
				( member ( signalRef "@baseboard_fab2_lib.baseboard_fab2(sch_1):m_h_dq(5)") )
				( member ( signalRef "@baseboard_fab2_lib.baseboard_fab2(sch_1):m_h_dq(6)") )
				( member ( signalRef "@baseboard_fab2_lib.baseboard_fab2(sch_1):m_h_dq(7)") )
				( objectStatus "NG_M_H_BYTE0" )
			)
			( netGroup "@crescent_city_bb_fab1_lib.crescent_city_bb_fab1(sch_1):\NG_M_H_BYTE-ECC\"
				( memberType ( signal ) )
				( electricalCSetRef "@crescent_city_bb_fab1_lib.crescent_city_bb_fab1(sch_1):\DDR_DQ_A\" )
				( member ( diffPairRef "@sapphirecity_baseboard_lib.sapphirecity_baseboard(sch_1):\M_H_DQS_D\(8)") )
				( member ( diffPairRef "@sapphirecity_baseboard_lib.sapphirecity_baseboard(sch_1):\M_H_DQS_D\(17)") )
				( member ( signalRef "@baseboard_fab2_lib.baseboard_fab2(sch_1):m_h_ecc(0)") )
				( member ( signalRef "@baseboard_fab2_lib.baseboard_fab2(sch_1):m_h_ecc(1)") )
				( member ( signalRef "@baseboard_fab2_lib.baseboard_fab2(sch_1):m_h_ecc(2)") )
				( member ( signalRef "@baseboard_fab2_lib.baseboard_fab2(sch_1):m_h_ecc(3)") )
				( member ( signalRef "@baseboard_fab2_lib.baseboard_fab2(sch_1):m_h_ecc(4)") )
				( member ( signalRef "@baseboard_fab2_lib.baseboard_fab2(sch_1):m_h_ecc(5)") )
				( member ( signalRef "@baseboard_fab2_lib.baseboard_fab2(sch_1):m_h_ecc(6)") )
				( member ( signalRef "@baseboard_fab2_lib.baseboard_fab2(sch_1):m_h_ecc(7)") )
				( objectStatus "NG_M_H_BYTE-ECC" )
			)
			( netGroup "@crescent_city_bb_fab1_lib.crescent_city_bb_fab1(sch_1):\NG_M_G_BYTE7\"
				( memberType ( signal ) )
				( electricalCSetRef "@crescent_city_bb_fab1_lib.crescent_city_bb_fab1(sch_1):\DDR_DQ_A\" )
				( member ( diffPairRef "@sapphirecity_baseboard_lib.sapphirecity_baseboard(sch_1):\M_G_DQS_D\(7)") )
				( member ( diffPairRef "@sapphirecity_baseboard_lib.sapphirecity_baseboard(sch_1):\M_G_DQS_D\(16)") )
				( member ( signalRef "@baseboard_fab2_lib.baseboard_fab2(sch_1):m_g_dq(56)") )
				( member ( signalRef "@baseboard_fab2_lib.baseboard_fab2(sch_1):m_g_dq(57)") )
				( member ( signalRef "@baseboard_fab2_lib.baseboard_fab2(sch_1):m_g_dq(58)") )
				( member ( signalRef "@baseboard_fab2_lib.baseboard_fab2(sch_1):m_g_dq(59)") )
				( member ( signalRef "@baseboard_fab2_lib.baseboard_fab2(sch_1):m_g_dq(60)") )
				( member ( signalRef "@baseboard_fab2_lib.baseboard_fab2(sch_1):m_g_dq(61)") )
				( member ( signalRef "@baseboard_fab2_lib.baseboard_fab2(sch_1):m_g_dq(62)") )
				( member ( signalRef "@baseboard_fab2_lib.baseboard_fab2(sch_1):m_g_dq(63)") )
				( objectStatus "NG_M_G_BYTE7" )
			)
			( netGroup "@crescent_city_bb_fab1_lib.crescent_city_bb_fab1(sch_1):\NG_M_G_BYTE6\"
				( memberType ( signal ) )
				( electricalCSetRef "@crescent_city_bb_fab1_lib.crescent_city_bb_fab1(sch_1):\DDR_DQ_A\" )
				( member ( diffPairRef "@sapphirecity_baseboard_lib.sapphirecity_baseboard(sch_1):\M_G_DQS_D\(6)") )
				( member ( diffPairRef "@sapphirecity_baseboard_lib.sapphirecity_baseboard(sch_1):\M_G_DQS_D\(15)") )
				( member ( signalRef "@baseboard_fab2_lib.baseboard_fab2(sch_1):m_g_dq(48)") )
				( member ( signalRef "@baseboard_fab2_lib.baseboard_fab2(sch_1):m_g_dq(49)") )
				( member ( signalRef "@baseboard_fab2_lib.baseboard_fab2(sch_1):m_g_dq(50)") )
				( member ( signalRef "@baseboard_fab2_lib.baseboard_fab2(sch_1):m_g_dq(51)") )
				( member ( signalRef "@baseboard_fab2_lib.baseboard_fab2(sch_1):m_g_dq(52)") )
				( member ( signalRef "@baseboard_fab2_lib.baseboard_fab2(sch_1):m_g_dq(53)") )
				( member ( signalRef "@baseboard_fab2_lib.baseboard_fab2(sch_1):m_g_dq(54)") )
				( member ( signalRef "@baseboard_fab2_lib.baseboard_fab2(sch_1):m_g_dq(55)") )
				( objectStatus "NG_M_G_BYTE6" )
			)
			( netGroup "@crescent_city_bb_fab1_lib.crescent_city_bb_fab1(sch_1):\NG_M_G_BYTE5\"
				( memberType ( signal ) )
				( electricalCSetRef "@crescent_city_bb_fab1_lib.crescent_city_bb_fab1(sch_1):\DDR_DQ_A\" )
				( member ( diffPairRef "@sapphirecity_baseboard_lib.sapphirecity_baseboard(sch_1):\M_G_DQS_D\(5)") )
				( member ( diffPairRef "@sapphirecity_baseboard_lib.sapphirecity_baseboard(sch_1):\M_G_DQS_D\(14)") )
				( member ( signalRef "@baseboard_fab2_lib.baseboard_fab2(sch_1):m_g_dq(40)") )
				( member ( signalRef "@baseboard_fab2_lib.baseboard_fab2(sch_1):m_g_dq(41)") )
				( member ( signalRef "@baseboard_fab2_lib.baseboard_fab2(sch_1):m_g_dq(42)") )
				( member ( signalRef "@baseboard_fab2_lib.baseboard_fab2(sch_1):m_g_dq(43)") )
				( member ( signalRef "@baseboard_fab2_lib.baseboard_fab2(sch_1):m_g_dq(44)") )
				( member ( signalRef "@baseboard_fab2_lib.baseboard_fab2(sch_1):m_g_dq(45)") )
				( member ( signalRef "@baseboard_fab2_lib.baseboard_fab2(sch_1):m_g_dq(46)") )
				( member ( signalRef "@baseboard_fab2_lib.baseboard_fab2(sch_1):m_g_dq(47)") )
				( objectStatus "NG_M_G_BYTE5" )
			)
			( netGroup "@crescent_city_bb_fab1_lib.crescent_city_bb_fab1(sch_1):\NG_M_G_BYTE4\"
				( memberType ( signal ) )
				( electricalCSetRef "@crescent_city_bb_fab1_lib.crescent_city_bb_fab1(sch_1):\DDR_DQ_A\" )
				( member ( diffPairRef "@sapphirecity_baseboard_lib.sapphirecity_baseboard(sch_1):\M_G_DQS_D\(4)") )
				( member ( diffPairRef "@sapphirecity_baseboard_lib.sapphirecity_baseboard(sch_1):\M_G_DQS_D\(13)") )
				( member ( signalRef "@baseboard_fab2_lib.baseboard_fab2(sch_1):m_g_dq(32)") )
				( member ( signalRef "@baseboard_fab2_lib.baseboard_fab2(sch_1):m_g_dq(33)") )
				( member ( signalRef "@baseboard_fab2_lib.baseboard_fab2(sch_1):m_g_dq(34)") )
				( member ( signalRef "@baseboard_fab2_lib.baseboard_fab2(sch_1):m_g_dq(35)") )
				( member ( signalRef "@baseboard_fab2_lib.baseboard_fab2(sch_1):m_g_dq(36)") )
				( member ( signalRef "@baseboard_fab2_lib.baseboard_fab2(sch_1):m_g_dq(37)") )
				( member ( signalRef "@baseboard_fab2_lib.baseboard_fab2(sch_1):m_g_dq(38)") )
				( member ( signalRef "@baseboard_fab2_lib.baseboard_fab2(sch_1):m_g_dq(39)") )
				( objectStatus "NG_M_G_BYTE4" )
			)
			( netGroup "@crescent_city_bb_fab1_lib.crescent_city_bb_fab1(sch_1):\NG_M_G_BYTE3\"
				( memberType ( signal ) )
				( electricalCSetRef "@crescent_city_bb_fab1_lib.crescent_city_bb_fab1(sch_1):\DDR_DQ_A\" )
				( member ( diffPairRef "@sapphirecity_baseboard_lib.sapphirecity_baseboard(sch_1):\M_G_DQS_D\(3)") )
				( member ( diffPairRef "@sapphirecity_baseboard_lib.sapphirecity_baseboard(sch_1):\M_G_DQS_D\(12)") )
				( member ( signalRef "@baseboard_fab2_lib.baseboard_fab2(sch_1):m_g_dq(24)") )
				( member ( signalRef "@baseboard_fab2_lib.baseboard_fab2(sch_1):m_g_dq(25)") )
				( member ( signalRef "@baseboard_fab2_lib.baseboard_fab2(sch_1):m_g_dq(26)") )
				( member ( signalRef "@baseboard_fab2_lib.baseboard_fab2(sch_1):m_g_dq(27)") )
				( member ( signalRef "@baseboard_fab2_lib.baseboard_fab2(sch_1):m_g_dq(28)") )
				( member ( signalRef "@baseboard_fab2_lib.baseboard_fab2(sch_1):m_g_dq(29)") )
				( member ( signalRef "@baseboard_fab2_lib.baseboard_fab2(sch_1):m_g_dq(30)") )
				( member ( signalRef "@baseboard_fab2_lib.baseboard_fab2(sch_1):m_g_dq(31)") )
				( objectStatus "NG_M_G_BYTE3" )
			)
			( netGroup "@crescent_city_bb_fab1_lib.crescent_city_bb_fab1(sch_1):\NG_M_G_BYTE2\"
				( memberType ( signal ) )
				( electricalCSetRef "@crescent_city_bb_fab1_lib.crescent_city_bb_fab1(sch_1):\DDR_DQ_A\" )
				( member ( diffPairRef "@sapphirecity_baseboard_lib.sapphirecity_baseboard(sch_1):\M_G_DQS_D\(2)") )
				( member ( diffPairRef "@sapphirecity_baseboard_lib.sapphirecity_baseboard(sch_1):\M_G_DQS_D\(11)") )
				( member ( signalRef "@baseboard_fab2_lib.baseboard_fab2(sch_1):m_g_dq(16)") )
				( member ( signalRef "@baseboard_fab2_lib.baseboard_fab2(sch_1):m_g_dq(17)") )
				( member ( signalRef "@baseboard_fab2_lib.baseboard_fab2(sch_1):m_g_dq(18)") )
				( member ( signalRef "@baseboard_fab2_lib.baseboard_fab2(sch_1):m_g_dq(19)") )
				( member ( signalRef "@baseboard_fab2_lib.baseboard_fab2(sch_1):m_g_dq(20)") )
				( member ( signalRef "@baseboard_fab2_lib.baseboard_fab2(sch_1):m_g_dq(21)") )
				( member ( signalRef "@baseboard_fab2_lib.baseboard_fab2(sch_1):m_g_dq(22)") )
				( member ( signalRef "@baseboard_fab2_lib.baseboard_fab2(sch_1):m_g_dq(23)") )
				( objectStatus "NG_M_G_BYTE2" )
			)
			( netGroup "@crescent_city_bb_fab1_lib.crescent_city_bb_fab1(sch_1):\NG_M_G_BYTE1\"
				( memberType ( signal ) )
				( electricalCSetRef "@crescent_city_bb_fab1_lib.crescent_city_bb_fab1(sch_1):\DDR_DQ_A\" )
				( member ( diffPairRef "@sapphirecity_baseboard_lib.sapphirecity_baseboard(sch_1):\M_G_DQS_D\(1)") )
				( member ( diffPairRef "@sapphirecity_baseboard_lib.sapphirecity_baseboard(sch_1):\M_G_DQS_D\(10)") )
				( member ( signalRef "@baseboard_fab2_lib.baseboard_fab2(sch_1):m_g_dq(8)") )
				( member ( signalRef "@baseboard_fab2_lib.baseboard_fab2(sch_1):m_g_dq(9)") )
				( member ( signalRef "@baseboard_fab2_lib.baseboard_fab2(sch_1):m_g_dq(10)") )
				( member ( signalRef "@baseboard_fab2_lib.baseboard_fab2(sch_1):m_g_dq(11)") )
				( member ( signalRef "@baseboard_fab2_lib.baseboard_fab2(sch_1):m_g_dq(12)") )
				( member ( signalRef "@baseboard_fab2_lib.baseboard_fab2(sch_1):m_g_dq(13)") )
				( member ( signalRef "@baseboard_fab2_lib.baseboard_fab2(sch_1):m_g_dq(14)") )
				( member ( signalRef "@baseboard_fab2_lib.baseboard_fab2(sch_1):m_g_dq(15)") )
				( objectStatus "NG_M_G_BYTE1" )
			)
			( netGroup "@crescent_city_bb_fab1_lib.crescent_city_bb_fab1(sch_1):\NG_M_G_BYTE0\"
				( memberType ( signal ) )
				( electricalCSetRef "@crescent_city_bb_fab1_lib.crescent_city_bb_fab1(sch_1):\DDR_DQ_A\" )
				( member ( diffPairRef "@sapphirecity_baseboard_lib.sapphirecity_baseboard(sch_1):\M_G_DQS_D\(0)") )
				( member ( diffPairRef "@sapphirecity_baseboard_lib.sapphirecity_baseboard(sch_1):\M_G_DQS_D\(9)") )
				( member ( signalRef "@baseboard_fab2_lib.baseboard_fab2(sch_1):m_g_dq(0)") )
				( member ( signalRef "@baseboard_fab2_lib.baseboard_fab2(sch_1):m_g_dq(1)") )
				( member ( signalRef "@baseboard_fab2_lib.baseboard_fab2(sch_1):m_g_dq(2)") )
				( member ( signalRef "@baseboard_fab2_lib.baseboard_fab2(sch_1):m_g_dq(3)") )
				( member ( signalRef "@baseboard_fab2_lib.baseboard_fab2(sch_1):m_g_dq(4)") )
				( member ( signalRef "@baseboard_fab2_lib.baseboard_fab2(sch_1):m_g_dq(5)") )
				( member ( signalRef "@baseboard_fab2_lib.baseboard_fab2(sch_1):m_g_dq(6)") )
				( member ( signalRef "@baseboard_fab2_lib.baseboard_fab2(sch_1):m_g_dq(7)") )
				( objectStatus "NG_M_G_BYTE0" )
			)
			( netGroup "@crescent_city_bb_fab1_lib.crescent_city_bb_fab1(sch_1):\NG_M_G_BYTE-ECC\"
				( memberType ( signal ) )
				( electricalCSetRef "@crescent_city_bb_fab1_lib.crescent_city_bb_fab1(sch_1):\DDR_DQ_A\" )
				( member ( diffPairRef "@sapphirecity_baseboard_lib.sapphirecity_baseboard(sch_1):\M_G_DQS_D\(8)") )
				( member ( diffPairRef "@sapphirecity_baseboard_lib.sapphirecity_baseboard(sch_1):\M_G_DQS_D\(17)") )
				( member ( signalRef "@baseboard_fab2_lib.baseboard_fab2(sch_1):m_g_ecc(0)") )
				( member ( signalRef "@baseboard_fab2_lib.baseboard_fab2(sch_1):m_g_ecc(1)") )
				( member ( signalRef "@baseboard_fab2_lib.baseboard_fab2(sch_1):m_g_ecc(2)") )
				( member ( signalRef "@baseboard_fab2_lib.baseboard_fab2(sch_1):m_g_ecc(3)") )
				( member ( signalRef "@baseboard_fab2_lib.baseboard_fab2(sch_1):m_g_ecc(4)") )
				( member ( signalRef "@baseboard_fab2_lib.baseboard_fab2(sch_1):m_g_ecc(5)") )
				( member ( signalRef "@baseboard_fab2_lib.baseboard_fab2(sch_1):m_g_ecc(6)") )
				( member ( signalRef "@baseboard_fab2_lib.baseboard_fab2(sch_1):m_g_ecc(7)") )
				( objectStatus "NG_M_G_BYTE-ECC" )
			)
			( netGroup "@crescent_city_bb_fab1_lib.crescent_city_bb_fab1(sch_1):\NG_P3E_CPU0_PE3_OCP_TX0809\"
				( memberType ( signal ) )
				( electricalCSetRef "@crescent_city_bb_fab1_lib.crescent_city_bb_fab1(sch_1):\PCIE_SLOT\" )
				( member ( electricalNetRef "@crescent_city_bb_fab1_lib.crescent_city_bb_fab1(sch_1):p3e_cpu0_pe3_ocp_txp(9)") )
				( member ( electricalNetRef "@crescent_city_bb_fab1_lib.crescent_city_bb_fab1(sch_1):p3e_cpu0_pe3_ocp_txn(9)") )
				( member ( electricalNetRef "@crescent_city_bb_fab1_lib.crescent_city_bb_fab1(sch_1):p3e_cpu0_pe3_ocp_txp(8)") )
				( member ( electricalNetRef "@crescent_city_bb_fab1_lib.crescent_city_bb_fab1(sch_1):p3e_cpu0_pe3_ocp_txn(8)") )
				( objectStatus "P3E_CPU0_PE3_OCP_TX0809" )
			)
			( netGroup "@crescent_city_bb_fab1_lib.crescent_city_bb_fab1(sch_1):\NG_P3E_CPU0_PE3_OCP_TX1011\"
				( memberType ( signal ) )
				( electricalCSetRef "@crescent_city_bb_fab1_lib.crescent_city_bb_fab1(sch_1):\PCIE_SLOT\" )
				( member ( electricalNetRef "@crescent_city_bb_fab1_lib.crescent_city_bb_fab1(sch_1):p3e_cpu0_pe3_ocp_txp(11)") )
				( member ( electricalNetRef "@crescent_city_bb_fab1_lib.crescent_city_bb_fab1(sch_1):p3e_cpu0_pe3_ocp_txn(11)") )
				( member ( electricalNetRef "@crescent_city_bb_fab1_lib.crescent_city_bb_fab1(sch_1):p3e_cpu0_pe3_ocp_txp(10)") )
				( member ( electricalNetRef "@crescent_city_bb_fab1_lib.crescent_city_bb_fab1(sch_1):p3e_cpu0_pe3_ocp_txn(10)") )
				( objectStatus "P3E_CPU0_PE3_OCP_TX1011" )
			)
			( netGroup "@crescent_city_bb_fab1_lib.crescent_city_bb_fab1(sch_1):\NG_P3E_CPU0_PE3_OCP_TX1213\"
				( memberType ( signal ) )
				( electricalCSetRef "@crescent_city_bb_fab1_lib.crescent_city_bb_fab1(sch_1):\PCIE_SLOT\" )
				( member ( electricalNetRef "@crescent_city_bb_fab1_lib.crescent_city_bb_fab1(sch_1):p3e_cpu0_pe3_ocp_txp(13)") )
				( member ( electricalNetRef "@crescent_city_bb_fab1_lib.crescent_city_bb_fab1(sch_1):p3e_cpu0_pe3_ocp_txn(13)") )
				( member ( electricalNetRef "@crescent_city_bb_fab1_lib.crescent_city_bb_fab1(sch_1):p3e_cpu0_pe3_ocp_txp(12)") )
				( member ( electricalNetRef "@crescent_city_bb_fab1_lib.crescent_city_bb_fab1(sch_1):p3e_cpu0_pe3_ocp_txn(12)") )
				( objectStatus "P3E_CPU0_PE3_OCP_TX1213" )
			)
			( netGroup "@crescent_city_bb_fab1_lib.crescent_city_bb_fab1(sch_1):\NG_P3E_CPU0_PE3_OCP_TX1415\"
				( memberType ( signal ) )
				( electricalCSetRef "@crescent_city_bb_fab1_lib.crescent_city_bb_fab1(sch_1):\PCIE_SLOT\" )
				( member ( electricalNetRef "@crescent_city_bb_fab1_lib.crescent_city_bb_fab1(sch_1):p3e_cpu0_pe3_ocp_txp(15)") )
				( member ( electricalNetRef "@crescent_city_bb_fab1_lib.crescent_city_bb_fab1(sch_1):p3e_cpu0_pe3_ocp_txn(15)") )
				( member ( electricalNetRef "@crescent_city_bb_fab1_lib.crescent_city_bb_fab1(sch_1):p3e_cpu0_pe3_ocp_txp(14)") )
				( member ( electricalNetRef "@crescent_city_bb_fab1_lib.crescent_city_bb_fab1(sch_1):p3e_cpu0_pe3_ocp_txn(14)") )
				( objectStatus "P3E_CPU0_PE3_OCP_TX1415" )
			)
			( netGroup "@crescent_city_bb_fab1_lib.crescent_city_bb_fab1(sch_1):\#SPI_BMC-SW\"
				( memberType ( signal ) )
				( member ( signalRef "@baseboard_fab2_lib.baseboard_fab2(sch_1):spi_bmc_cs0_n") )
				( member ( signalRef "@baseboard_fab2_lib.baseboard_fab2(sch_1):spi_bmc_di") )
				( member ( signalRef "@baseboard_fab2_lib.baseboard_fab2(sch_1):spi_bmc_do") )
				( member ( signalRef "@baseboard_fab2_lib.baseboard_fab2(sch_1):spi_bmc_clk") )
				( objectStatus "NG_SPI_BMC-SW" )
			)
			( netGroup "@crescent_city_bb_fab1_lib.crescent_city_bb_fab1(sch_1):\#SPI_BMC\"
				( memberType ( signal ) )
				( member ( electricalNetRef "@crescent_city_bb_fab1_lib.crescent_city_bb_fab1(sch_1):spi_bmc_bt_di") )
				( member ( electricalNetRef "@crescent_city_bb_fab1_lib.crescent_city_bb_fab1(sch_1):spi_bmc_bt_do") )
				( member ( electricalNetRef "@crescent_city_bb_fab1_lib.crescent_city_bb_fab1(sch_1):spi_bmc_bt_clk") )
				( member ( electricalNetRef "@crescent_city_bb_fab1_lib.crescent_city_bb_fab1(sch_1):spi_bmc_bt_cs_n") )
				( objectStatus "NG_SPI_BMC" )
			)
			( netGroup "@crescent_city_bb_fab1_lib.crescent_city_bb_fab1(sch_1):\#SPI_PCH\"
				( memberType ( signal ) )
				( member ( electricalNetRef "@crescent_city_bb_fab1_lib.crescent_city_bb_fab1(sch_1):xdp_spi_pch_mosi_boot_halt_n") )
				( member ( electricalNetRef "@crescent_city_bb_fab1_lib.crescent_city_bb_fab1(sch_1):spi_pch_tpm_cs_n") )
				( member ( electricalNetRef "@crescent_city_bb_fab1_lib.crescent_city_bb_fab1(sch_1):spi_pch_miso_r") )
				( member ( electricalNetRef "@crescent_city_bb_fab1_lib.crescent_city_bb_fab1(sch_1):spi_pch_clk") )
				( member ( electricalNetRef "@crescent_city_bb_fab1_lib.crescent_city_bb_fab1(sch_1):spi_pch_io3") )
				( objectStatus "NG_SPI_PCH" )
			)
			( netGroup "@crescent_city_bb_fab1_lib.crescent_city_bb_fab1(sch_1):\NG_P3E_CPU0_PE1_PCH_PCIEUP_TX1415\"
				( memberType ( signal ) )
				( electricalCSetRef "@crescent_city_bb_fab1_lib.crescent_city_bb_fab1(sch_1):\PCIE_DEVICE_C\" )
				( member ( electricalNetRef "@crescent_city_bb_fab1_lib.crescent_city_bb_fab1(sch_1):p3e_cpu0_pe1_pch_c_txp(15)") )
				( member ( electricalNetRef "@crescent_city_bb_fab1_lib.crescent_city_bb_fab1(sch_1):p3e_cpu0_pe1_pch_c_txn(15)") )
				( member ( electricalNetRef "@crescent_city_bb_fab1_lib.crescent_city_bb_fab1(sch_1):p3e_cpu0_pe1_pch_c_txp(14)") )
				( member ( electricalNetRef "@crescent_city_bb_fab1_lib.crescent_city_bb_fab1(sch_1):p3e_cpu0_pe1_pch_c_txn(14)") )
				( objectStatus "P3E_CPU0_PE1_PCH_PCIEUP_TX1415" )
			)
			( netGroup "@crescent_city_bb_fab1_lib.crescent_city_bb_fab1(sch_1):\NG_P3E_CPU0_PE1_PCH_PCIEUP_TX1213\"
				( memberType ( signal ) )
				( electricalCSetRef "@crescent_city_bb_fab1_lib.crescent_city_bb_fab1(sch_1):\PCIE_DEVICE_C\" )
				( member ( electricalNetRef "@crescent_city_bb_fab1_lib.crescent_city_bb_fab1(sch_1):p3e_cpu0_pe1_pch_c_txp(13)") )
				( member ( electricalNetRef "@crescent_city_bb_fab1_lib.crescent_city_bb_fab1(sch_1):p3e_cpu0_pe1_pch_c_txn(13)") )
				( member ( electricalNetRef "@crescent_city_bb_fab1_lib.crescent_city_bb_fab1(sch_1):p3e_cpu0_pe1_pch_c_txp(12)") )
				( member ( electricalNetRef "@crescent_city_bb_fab1_lib.crescent_city_bb_fab1(sch_1):p3e_cpu0_pe1_pch_c_txn(12)") )
				( objectStatus "P3E_CPU0_PE1_PCH_PCIEUP_TX1213" )
			)
			( netGroup "@crescent_city_bb_fab1_lib.crescent_city_bb_fab1(sch_1):\NG_P3E_CPU0_PE1_PCH_PCIEUP_TX1011\"
				( memberType ( signal ) )
				( electricalCSetRef "@crescent_city_bb_fab1_lib.crescent_city_bb_fab1(sch_1):\PCIE_DEVICE_C\" )
				( member ( electricalNetRef "@crescent_city_bb_fab1_lib.crescent_city_bb_fab1(sch_1):p3e_cpu0_pe1_pch_c_txp(11)") )
				( member ( electricalNetRef "@crescent_city_bb_fab1_lib.crescent_city_bb_fab1(sch_1):p3e_cpu0_pe1_pch_c_txn(11)") )
				( member ( electricalNetRef "@crescent_city_bb_fab1_lib.crescent_city_bb_fab1(sch_1):p3e_cpu0_pe1_pch_c_txp(10)") )
				( member ( electricalNetRef "@crescent_city_bb_fab1_lib.crescent_city_bb_fab1(sch_1):p3e_cpu0_pe1_pch_c_txn(10)") )
				( objectStatus "P3E_CPU0_PE1_PCH_PCIEUP_TX1011" )
			)
			( netGroup "@crescent_city_bb_fab1_lib.crescent_city_bb_fab1(sch_1):\NG_P3E_CPU0_PE1_PCH_PCIEUP_TX0809\"
				( memberType ( signal ) )
				( electricalCSetRef "@crescent_city_bb_fab1_lib.crescent_city_bb_fab1(sch_1):\PCIE_DEVICE_C\" )
				( member ( electricalNetRef "@crescent_city_bb_fab1_lib.crescent_city_bb_fab1(sch_1):p3e_cpu0_pe1_pch_c_txp(9)") )
				( member ( electricalNetRef "@crescent_city_bb_fab1_lib.crescent_city_bb_fab1(sch_1):p3e_cpu0_pe1_pch_c_txn(9)") )
				( member ( electricalNetRef "@crescent_city_bb_fab1_lib.crescent_city_bb_fab1(sch_1):p3e_cpu0_pe1_pch_c_txp(8)") )
				( member ( electricalNetRef "@crescent_city_bb_fab1_lib.crescent_city_bb_fab1(sch_1):p3e_cpu0_pe1_pch_c_txn(8)") )
				( objectStatus "P3E_CPU0_PE1_PCH_PCIEUP_TX0809" )
			)
			( netGroup "@crescent_city_bb_fab1_lib.crescent_city_bb_fab1(sch_1):\NG_P3E_CPU0_PE1_PCH_PCIEUP_RX1415\"
				( memberType ( signal ) )
				( electricalCSetRef "@crescent_city_bb_fab1_lib.crescent_city_bb_fab1(sch_1):\PCIE_DEVICE_C\" )
				( member ( electricalNetRef "@crescent_city_bb_fab1_lib.crescent_city_bb_fab1(sch_1):p3e_cpu0_pe1_pch_rxp(15)") )
				( member ( electricalNetRef "@crescent_city_bb_fab1_lib.crescent_city_bb_fab1(sch_1):p3e_cpu0_pe1_pch_rxn(15)") )
				( member ( electricalNetRef "@crescent_city_bb_fab1_lib.crescent_city_bb_fab1(sch_1):p3e_cpu0_pe1_pch_rxp(14)") )
				( member ( electricalNetRef "@crescent_city_bb_fab1_lib.crescent_city_bb_fab1(sch_1):p3e_cpu0_pe1_pch_rxn(14)") )
				( objectStatus "P3E_CPU0_PE1_PCH_PCIEUP_RX1415" )
			)
			( netGroup "@crescent_city_bb_fab1_lib.crescent_city_bb_fab1(sch_1):\NG_P3E_CPU0_PE1_PCH_PCIEUP_RX1213\"
				( memberType ( signal ) )
				( electricalCSetRef "@crescent_city_bb_fab1_lib.crescent_city_bb_fab1(sch_1):\PCIE_DEVICE_C\" )
				( member ( electricalNetRef "@crescent_city_bb_fab1_lib.crescent_city_bb_fab1(sch_1):p3e_cpu0_pe1_pch_rxp(13)") )
				( member ( electricalNetRef "@crescent_city_bb_fab1_lib.crescent_city_bb_fab1(sch_1):p3e_cpu0_pe1_pch_rxn(13)") )
				( member ( electricalNetRef "@crescent_city_bb_fab1_lib.crescent_city_bb_fab1(sch_1):p3e_cpu0_pe1_pch_rxp(12)") )
				( member ( electricalNetRef "@crescent_city_bb_fab1_lib.crescent_city_bb_fab1(sch_1):p3e_cpu0_pe1_pch_rxn(12)") )
				( objectStatus "P3E_CPU0_PE1_PCH_PCIEUP_RX1213" )
			)
			( netGroup "@crescent_city_bb_fab1_lib.crescent_city_bb_fab1(sch_1):\NG_P3E_CPU0_PE1_PCH_PCIEUP_RX1011\"
				( memberType ( signal ) )
				( electricalCSetRef "@crescent_city_bb_fab1_lib.crescent_city_bb_fab1(sch_1):\PCIE_DEVICE_C\" )
				( member ( electricalNetRef "@crescent_city_bb_fab1_lib.crescent_city_bb_fab1(sch_1):p3e_cpu0_pe1_pch_rxp(11)") )
				( member ( electricalNetRef "@crescent_city_bb_fab1_lib.crescent_city_bb_fab1(sch_1):p3e_cpu0_pe1_pch_rxn(11)") )
				( member ( electricalNetRef "@crescent_city_bb_fab1_lib.crescent_city_bb_fab1(sch_1):p3e_cpu0_pe1_pch_rxp(10)") )
				( member ( electricalNetRef "@crescent_city_bb_fab1_lib.crescent_city_bb_fab1(sch_1):p3e_cpu0_pe1_pch_rxn(10)") )
				( objectStatus "P3E_CPU0_PE1_PCH_PCIEUP_RX1011" )
			)
			( netGroup "@crescent_city_bb_fab1_lib.crescent_city_bb_fab1(sch_1):\NG_P3E_CPU0_PE1_PCH_PCIEUP_RX0809\"
				( memberType ( signal ) )
				( electricalCSetRef "@crescent_city_bb_fab1_lib.crescent_city_bb_fab1(sch_1):\PCIE_DEVICE_C\" )
				( member ( electricalNetRef "@crescent_city_bb_fab1_lib.crescent_city_bb_fab1(sch_1):p3e_cpu0_pe1_pch_rxp(9)") )
				( member ( electricalNetRef "@crescent_city_bb_fab1_lib.crescent_city_bb_fab1(sch_1):p3e_cpu0_pe1_pch_rxn(9)") )
				( member ( electricalNetRef "@crescent_city_bb_fab1_lib.crescent_city_bb_fab1(sch_1):p3e_cpu0_pe1_pch_rxp(8)") )
				( member ( electricalNetRef "@crescent_city_bb_fab1_lib.crescent_city_bb_fab1(sch_1):p3e_cpu0_pe1_pch_rxn(8)") )
				( objectStatus "P3E_CPU0_PE1_PCH_PCIEUP_RX0809" )
			)
			( netGroup "@crescent_city_bb_fab1_lib.crescent_city_bb_fab1(sch_1):\NG_P3E_CPU1_PE3_MP_RX1415\"
				( memberType ( signal ) )
				( electricalCSetRef "@crescent_city_bb_fab1_lib.crescent_city_bb_fab1(sch_1):\PCIE_SLOT_1\" )
				( member ( signalRef "@baseboard_fab2_lib.baseboard_fab2(sch_1):p3e_cpu1_pe3_mp_rxn(14)") )
				( member ( signalRef "@baseboard_fab2_lib.baseboard_fab2(sch_1):p3e_cpu1_pe3_mp_rxn(15)") )
				( member ( signalRef "@baseboard_fab2_lib.baseboard_fab2(sch_1):p3e_cpu1_pe3_mp_rxp(14)") )
				( member ( signalRef "@baseboard_fab2_lib.baseboard_fab2(sch_1):p3e_cpu1_pe3_mp_rxp(15)") )
				( objectStatus "P3E_CPU1_PE3_MP_RX1415" )
			)
			( netGroup "@crescent_city_bb_fab1_lib.crescent_city_bb_fab1(sch_1):\NG_P3E_CPU1_PE3_MP_RX1213\"
				( memberType ( signal ) )
				( electricalCSetRef "@crescent_city_bb_fab1_lib.crescent_city_bb_fab1(sch_1):\PCIE_SLOT_1\" )
				( member ( signalRef "@baseboard_fab2_lib.baseboard_fab2(sch_1):p3e_cpu1_pe3_mp_rxn(12)") )
				( member ( signalRef "@baseboard_fab2_lib.baseboard_fab2(sch_1):p3e_cpu1_pe3_mp_rxn(13)") )
				( member ( signalRef "@baseboard_fab2_lib.baseboard_fab2(sch_1):p3e_cpu1_pe3_mp_rxp(12)") )
				( member ( signalRef "@baseboard_fab2_lib.baseboard_fab2(sch_1):p3e_cpu1_pe3_mp_rxp(13)") )
				( objectStatus "P3E_CPU1_PE3_MP_RX1213" )
			)
			( netGroup "@crescent_city_bb_fab1_lib.crescent_city_bb_fab1(sch_1):\NG_P3E_CPU1_PE3_MP_RX1011\"
				( memberType ( signal ) )
				( electricalCSetRef "@crescent_city_bb_fab1_lib.crescent_city_bb_fab1(sch_1):\PCIE_SLOT_1\" )
				( member ( signalRef "@baseboard_fab2_lib.baseboard_fab2(sch_1):p3e_cpu1_pe3_mp_rxn(10)") )
				( member ( signalRef "@baseboard_fab2_lib.baseboard_fab2(sch_1):p3e_cpu1_pe3_mp_rxn(11)") )
				( member ( signalRef "@baseboard_fab2_lib.baseboard_fab2(sch_1):p3e_cpu1_pe3_mp_rxp(10)") )
				( member ( signalRef "@baseboard_fab2_lib.baseboard_fab2(sch_1):p3e_cpu1_pe3_mp_rxp(11)") )
				( objectStatus "P3E_CPU1_PE3_MP_RX1011" )
			)
			( netGroup "@crescent_city_bb_fab1_lib.crescent_city_bb_fab1(sch_1):\NG_P3E_CPU1_PE3_MP_RX0809\"
				( memberType ( signal ) )
				( electricalCSetRef "@crescent_city_bb_fab1_lib.crescent_city_bb_fab1(sch_1):\PCIE_SLOT_1\" )
				( member ( signalRef "@baseboard_fab2_lib.baseboard_fab2(sch_1):p3e_cpu1_pe3_mp_rxn(8)") )
				( member ( signalRef "@baseboard_fab2_lib.baseboard_fab2(sch_1):p3e_cpu1_pe3_mp_rxn(9)") )
				( member ( signalRef "@baseboard_fab2_lib.baseboard_fab2(sch_1):p3e_cpu1_pe3_mp_rxp(8)") )
				( member ( signalRef "@baseboard_fab2_lib.baseboard_fab2(sch_1):p3e_cpu1_pe3_mp_rxp(9)") )
				( objectStatus "P3E_CPU1_PE3_MP_RX0809" )
			)
			( netGroup "@crescent_city_bb_fab1_lib.crescent_city_bb_fab1(sch_1):\NG_P3E_CPU1_PE3_MP_RX0607\"
				( memberType ( signal ) )
				( electricalCSetRef "@crescent_city_bb_fab1_lib.crescent_city_bb_fab1(sch_1):\PCIE_SLOT_1\" )
				( member ( signalRef "@baseboard_fab2_lib.baseboard_fab2(sch_1):p3e_cpu1_pe3_mp_rxn(6)") )
				( member ( signalRef "@baseboard_fab2_lib.baseboard_fab2(sch_1):p3e_cpu1_pe3_mp_rxn(7)") )
				( member ( signalRef "@baseboard_fab2_lib.baseboard_fab2(sch_1):p3e_cpu1_pe3_mp_rxp(6)") )
				( member ( signalRef "@baseboard_fab2_lib.baseboard_fab2(sch_1):p3e_cpu1_pe3_mp_rxp(7)") )
				( objectStatus "P3E_CPU1_PE3_MP_RX0607" )
			)
			( netGroup "@crescent_city_bb_fab1_lib.crescent_city_bb_fab1(sch_1):\NG_P3E_CPU1_PE3_MP_RX0405\"
				( memberType ( signal ) )
				( electricalCSetRef "@crescent_city_bb_fab1_lib.crescent_city_bb_fab1(sch_1):\PCIE_SLOT_1\" )
				( member ( signalRef "@baseboard_fab2_lib.baseboard_fab2(sch_1):p3e_cpu1_pe3_mp_rxn(4)") )
				( member ( signalRef "@baseboard_fab2_lib.baseboard_fab2(sch_1):p3e_cpu1_pe3_mp_rxn(5)") )
				( member ( signalRef "@baseboard_fab2_lib.baseboard_fab2(sch_1):p3e_cpu1_pe3_mp_rxp(4)") )
				( member ( signalRef "@baseboard_fab2_lib.baseboard_fab2(sch_1):p3e_cpu1_pe3_mp_rxp(5)") )
				( objectStatus "P3E_CPU1_PE3_MP_RX0405" )
			)
			( netGroup "@crescent_city_bb_fab1_lib.crescent_city_bb_fab1(sch_1):\0203\"
				( memberType ( signal ) )
				( electricalCSetRef "@crescent_city_bb_fab1_lib.crescent_city_bb_fab1(sch_1):\PCIE_SLOT_1\" )
				( member ( signalRef "@baseboard_fab2_lib.baseboard_fab2(sch_1):p3e_cpu1_pe3_mp_rxn(2)") )
				( member ( signalRef "@baseboard_fab2_lib.baseboard_fab2(sch_1):p3e_cpu1_pe3_mp_rxn(3)") )
				( member ( signalRef "@baseboard_fab2_lib.baseboard_fab2(sch_1):p3e_cpu1_pe3_mp_rxp(2)") )
				( member ( signalRef "@baseboard_fab2_lib.baseboard_fab2(sch_1):p3e_cpu1_pe3_mp_rxp(3)") )
				( objectStatus "P3E_CPU1_PE3_MP_RX0203" )
			)
			( netGroup "@crescent_city_bb_fab1_lib.crescent_city_bb_fab1(sch_1):\NG_P3E_CPU1_PE3_MP_RX0001\"
				( memberType ( signal ) )
				( electricalCSetRef "@crescent_city_bb_fab1_lib.crescent_city_bb_fab1(sch_1):\PCIE_SLOT_1\" )
				( member ( signalRef "@baseboard_fab2_lib.baseboard_fab2(sch_1):p3e_cpu1_pe3_mp_rxn(0)") )
				( member ( signalRef "@baseboard_fab2_lib.baseboard_fab2(sch_1):p3e_cpu1_pe3_mp_rxn(1)") )
				( member ( signalRef "@baseboard_fab2_lib.baseboard_fab2(sch_1):p3e_cpu1_pe3_mp_rxp(0)") )
				( member ( signalRef "@baseboard_fab2_lib.baseboard_fab2(sch_1):p3e_cpu1_pe3_mp_rxp(1)") )
				( objectStatus "P3E_CPU1_PE3_MP_RX0001" )
			)
			( netGroup "@crescent_city_bb_fab1_lib.crescent_city_bb_fab1(sch_1):\NG_P3E_CPU0_PE3_MP_TX1415\"
				( memberType ( signal ) )
				( electricalCSetRef "@crescent_city_bb_fab1_lib.crescent_city_bb_fab1(sch_1):\PCIE_SLOT\" )
				( member ( electricalNetRef "@crescent_city_bb_fab1_lib.crescent_city_bb_fab1(sch_1):p3e_cpu1_pe3_mp_c_txp(14)") )
				( member ( electricalNetRef "@crescent_city_bb_fab1_lib.crescent_city_bb_fab1(sch_1):p3e_cpu1_pe3_mp_c_txn(14)") )
				( member ( electricalNetRef "@crescent_city_bb_fab1_lib.crescent_city_bb_fab1(sch_1):p3e_cpu1_pe3_mp_c_txp(15)") )
				( member ( electricalNetRef "@crescent_city_bb_fab1_lib.crescent_city_bb_fab1(sch_1):p3e_cpu1_pe3_mp_c_txn(15)") )
				( objectStatus "P3E_CPU1_PE3_MP_TX1415" )
			)
			( netGroup "@crescent_city_bb_fab1_lib.crescent_city_bb_fab1(sch_1):\NG_P3E_CPU0_PE3_MP_TX1213\"
				( memberType ( signal ) )
				( electricalCSetRef "@crescent_city_bb_fab1_lib.crescent_city_bb_fab1(sch_1):\PCIE_SLOT\" )
				( member ( electricalNetRef "@crescent_city_bb_fab1_lib.crescent_city_bb_fab1(sch_1):p3e_cpu1_pe3_mp_c_txp(12)") )
				( member ( electricalNetRef "@crescent_city_bb_fab1_lib.crescent_city_bb_fab1(sch_1):p3e_cpu1_pe3_mp_c_txn(12)") )
				( member ( electricalNetRef "@crescent_city_bb_fab1_lib.crescent_city_bb_fab1(sch_1):p3e_cpu1_pe3_mp_c_txp(13)") )
				( member ( electricalNetRef "@crescent_city_bb_fab1_lib.crescent_city_bb_fab1(sch_1):p3e_cpu1_pe3_mp_c_txn(13)") )
				( objectStatus "P3E_CPU1_PE3_MP_TX1213" )
			)
			( netGroup "@crescent_city_bb_fab1_lib.crescent_city_bb_fab1(sch_1):\NG_P3E_CPU0_PE3_MP_TX1011\"
				( memberType ( signal ) )
				( electricalCSetRef "@crescent_city_bb_fab1_lib.crescent_city_bb_fab1(sch_1):\PCIE_SLOT\" )
				( member ( electricalNetRef "@crescent_city_bb_fab1_lib.crescent_city_bb_fab1(sch_1):p3e_cpu1_pe3_mp_c_txp(11)") )
				( member ( electricalNetRef "@crescent_city_bb_fab1_lib.crescent_city_bb_fab1(sch_1):p3e_cpu1_pe3_mp_c_txn(11)") )
				( member ( electricalNetRef "@crescent_city_bb_fab1_lib.crescent_city_bb_fab1(sch_1):p3e_cpu1_pe3_mp_c_txp(10)") )
				( member ( electricalNetRef "@crescent_city_bb_fab1_lib.crescent_city_bb_fab1(sch_1):p3e_cpu1_pe3_mp_c_txn(10)") )
				( objectStatus "P3E_CPU1_PE3_MP_TX1011" )
			)
			( netGroup "@crescent_city_bb_fab1_lib.crescent_city_bb_fab1(sch_1):\NG_P3E_CPU0_PE3_MP_TX0809\"
				( memberType ( signal ) )
				( electricalCSetRef "@crescent_city_bb_fab1_lib.crescent_city_bb_fab1(sch_1):\PCIE_SLOT\" )
				( member ( electricalNetRef "@crescent_city_bb_fab1_lib.crescent_city_bb_fab1(sch_1):p3e_cpu1_pe3_mp_c_txp(9)") )
				( member ( electricalNetRef "@crescent_city_bb_fab1_lib.crescent_city_bb_fab1(sch_1):p3e_cpu1_pe3_mp_c_txn(9)") )
				( member ( electricalNetRef "@crescent_city_bb_fab1_lib.crescent_city_bb_fab1(sch_1):p3e_cpu1_pe3_mp_c_txp(8)") )
				( member ( electricalNetRef "@crescent_city_bb_fab1_lib.crescent_city_bb_fab1(sch_1):p3e_cpu1_pe3_mp_c_txn(8)") )
				( objectStatus "P3E_CPU1_PE3_MP_TX0809" )
			)
			( netGroup "@crescent_city_bb_fab1_lib.crescent_city_bb_fab1(sch_1):\NG_P3E_CPU0_PE3_MP_TX0607\"
				( memberType ( signal ) )
				( electricalCSetRef "@crescent_city_bb_fab1_lib.crescent_city_bb_fab1(sch_1):\PCIE_SLOT\" )
				( member ( electricalNetRef "@crescent_city_bb_fab1_lib.crescent_city_bb_fab1(sch_1):p3e_cpu1_pe3_mp_c_txp(7)") )
				( member ( electricalNetRef "@crescent_city_bb_fab1_lib.crescent_city_bb_fab1(sch_1):p3e_cpu1_pe3_mp_c_txn(7)") )
				( member ( electricalNetRef "@crescent_city_bb_fab1_lib.crescent_city_bb_fab1(sch_1):p3e_cpu1_pe3_mp_c_txp(6)") )
				( member ( electricalNetRef "@crescent_city_bb_fab1_lib.crescent_city_bb_fab1(sch_1):p3e_cpu1_pe3_mp_c_txn(6)") )
				( objectStatus "P3E_CPU1_PE3_MP_TX0607" )
			)
			( netGroup "@crescent_city_bb_fab1_lib.crescent_city_bb_fab1(sch_1):\NG_P3E_CPU0_PE3_MP_TX0405\"
				( memberType ( signal ) )
				( electricalCSetRef "@crescent_city_bb_fab1_lib.crescent_city_bb_fab1(sch_1):\PCIE_SLOT\" )
				( member ( electricalNetRef "@crescent_city_bb_fab1_lib.crescent_city_bb_fab1(sch_1):p3e_cpu1_pe3_mp_c_txp(5)") )
				( member ( electricalNetRef "@crescent_city_bb_fab1_lib.crescent_city_bb_fab1(sch_1):p3e_cpu1_pe3_mp_c_txn(5)") )
				( member ( electricalNetRef "@crescent_city_bb_fab1_lib.crescent_city_bb_fab1(sch_1):p3e_cpu1_pe3_mp_c_txp(4)") )
				( member ( electricalNetRef "@crescent_city_bb_fab1_lib.crescent_city_bb_fab1(sch_1):p3e_cpu1_pe3_mp_c_txn(4)") )
				( objectStatus "P3E_CPU1_PE3_MP_TX0405" )
			)
			( netGroup "@crescent_city_bb_fab1_lib.crescent_city_bb_fab1(sch_1):\NG_P3E_CPU0_PE3_MP_TX0203\"
				( memberType ( signal ) )
				( electricalCSetRef "@crescent_city_bb_fab1_lib.crescent_city_bb_fab1(sch_1):\PCIE_SLOT\" )
				( member ( electricalNetRef "@crescent_city_bb_fab1_lib.crescent_city_bb_fab1(sch_1):p3e_cpu1_pe3_mp_c_txp(3)") )
				( member ( electricalNetRef "@crescent_city_bb_fab1_lib.crescent_city_bb_fab1(sch_1):p3e_cpu1_pe3_mp_c_txn(3)") )
				( member ( electricalNetRef "@crescent_city_bb_fab1_lib.crescent_city_bb_fab1(sch_1):p3e_cpu1_pe3_mp_c_txp(2)") )
				( member ( electricalNetRef "@crescent_city_bb_fab1_lib.crescent_city_bb_fab1(sch_1):p3e_cpu1_pe3_mp_c_txn(2)") )
				( objectStatus "P3E_CPU1_PE3_MP_TX0203" )
			)
			( netGroup "@crescent_city_bb_fab1_lib.crescent_city_bb_fab1(sch_1):\NG_P3E_CPU0_PE3_MP_TX0001\"
				( memberType ( signal ) )
				( electricalCSetRef "@crescent_city_bb_fab1_lib.crescent_city_bb_fab1(sch_1):\PCIE_SLOT\" )
				( member ( electricalNetRef "@crescent_city_bb_fab1_lib.crescent_city_bb_fab1(sch_1):p3e_cpu1_pe3_mp_c_txp(1)") )
				( member ( electricalNetRef "@crescent_city_bb_fab1_lib.crescent_city_bb_fab1(sch_1):p3e_cpu1_pe3_mp_c_txn(1)") )
				( member ( electricalNetRef "@crescent_city_bb_fab1_lib.crescent_city_bb_fab1(sch_1):p3e_cpu1_pe3_mp_c_txp(0)") )
				( member ( electricalNetRef "@crescent_city_bb_fab1_lib.crescent_city_bb_fab1(sch_1):p3e_cpu1_pe3_mp_c_txn(0)") )
				( objectStatus "P3E_CPU1_PE3_MP_TX0001" )
			)
			( netGroup "@crescent_city_bb_fab1_lib.crescent_city_bb_fab1(sch_1):\NG_P3E_CPU0_PE3_OCP_TX0607\"
				( memberType ( signal ) )
				( electricalCSetRef "@crescent_city_bb_fab1_lib.crescent_city_bb_fab1(sch_1):\PCIE_SLOT\" )
				( member ( electricalNetRef "@crescent_city_bb_fab1_lib.crescent_city_bb_fab1(sch_1):p3e_cpu0_pe3_ocp_txp(7)") )
				( member ( electricalNetRef "@crescent_city_bb_fab1_lib.crescent_city_bb_fab1(sch_1):p3e_cpu0_pe3_ocp_txn(7)") )
				( member ( electricalNetRef "@crescent_city_bb_fab1_lib.crescent_city_bb_fab1(sch_1):p3e_cpu0_pe3_ocp_txp(6)") )
				( member ( electricalNetRef "@crescent_city_bb_fab1_lib.crescent_city_bb_fab1(sch_1):p3e_cpu0_pe3_ocp_txn(6)") )
				( objectStatus "P3E_CPU0_PE3_OCP_TX0607" )
			)
			( netGroup "@crescent_city_bb_fab1_lib.crescent_city_bb_fab1(sch_1):\NG_P3E_CPU0_PE3_OCP_TX0405\"
				( memberType ( signal ) )
				( electricalCSetRef "@crescent_city_bb_fab1_lib.crescent_city_bb_fab1(sch_1):\PCIE_SLOT\" )
				( member ( electricalNetRef "@crescent_city_bb_fab1_lib.crescent_city_bb_fab1(sch_1):p3e_cpu0_pe3_ocp_txp(5)") )
				( member ( electricalNetRef "@crescent_city_bb_fab1_lib.crescent_city_bb_fab1(sch_1):p3e_cpu0_pe3_ocp_txn(5)") )
				( member ( electricalNetRef "@crescent_city_bb_fab1_lib.crescent_city_bb_fab1(sch_1):p3e_cpu0_pe3_ocp_txp(4)") )
				( member ( electricalNetRef "@crescent_city_bb_fab1_lib.crescent_city_bb_fab1(sch_1):p3e_cpu0_pe3_ocp_txn(4)") )
				( objectStatus "P3E_CPU0_PE3_OCP_TX0405" )
			)
			( netGroup "@crescent_city_bb_fab1_lib.crescent_city_bb_fab1(sch_1):\NG_P3E_CPU0_PE3_OCP_TX0203\"
				( memberType ( signal ) )
				( electricalCSetRef "@crescent_city_bb_fab1_lib.crescent_city_bb_fab1(sch_1):\PCIE_SLOT\" )
				( member ( electricalNetRef "@crescent_city_bb_fab1_lib.crescent_city_bb_fab1(sch_1):p3e_cpu0_pe3_ocp_txp(3)") )
				( member ( electricalNetRef "@crescent_city_bb_fab1_lib.crescent_city_bb_fab1(sch_1):p3e_cpu0_pe3_ocp_txn(3)") )
				( member ( electricalNetRef "@crescent_city_bb_fab1_lib.crescent_city_bb_fab1(sch_1):p3e_cpu0_pe3_ocp_txp(2)") )
				( member ( electricalNetRef "@crescent_city_bb_fab1_lib.crescent_city_bb_fab1(sch_1):p3e_cpu0_pe3_ocp_txn(2)") )
				( objectStatus "P3E_CPU0_PE3_OCP_TX0203" )
			)
			( netGroup "@crescent_city_bb_fab1_lib.crescent_city_bb_fab1(sch_1):\NG_P3E_CPU0_PE3_OCP_TX0001\"
				( memberType ( signal ) )
				( electricalCSetRef "@crescent_city_bb_fab1_lib.crescent_city_bb_fab1(sch_1):\PCIE_SLOT\" )
				( member ( electricalNetRef "@crescent_city_bb_fab1_lib.crescent_city_bb_fab1(sch_1):p3e_cpu0_pe3_ocp_txp(1)") )
				( member ( electricalNetRef "@crescent_city_bb_fab1_lib.crescent_city_bb_fab1(sch_1):p3e_cpu0_pe3_ocp_txn(1)") )
				( member ( electricalNetRef "@crescent_city_bb_fab1_lib.crescent_city_bb_fab1(sch_1):p3e_cpu0_pe3_ocp_txp(0)") )
				( member ( electricalNetRef "@crescent_city_bb_fab1_lib.crescent_city_bb_fab1(sch_1):p3e_cpu0_pe3_ocp_txn(0)") )
				( objectStatus "P3E_CPU0_PE3_OCP_TX0001" )
			)
			( netGroup "@crescent_city_bb_fab1_lib.crescent_city_bb_fab1(sch_1):\NG_P3E_CPU0_PE2_OCP_RX1415\"
				( memberType ( signal ) )
				( electricalCSetRef "@crescent_city_bb_fab1_lib.crescent_city_bb_fab1(sch_1):\PCIE_SLOT_1\" )
				( member ( signalRef "@baseboard_fab2_lib.baseboard_fab2(sch_1):p3e_cpu0_pe3_ocp_rxn(14)") )
				( member ( signalRef "@baseboard_fab2_lib.baseboard_fab2(sch_1):p3e_cpu0_pe3_ocp_rxn(15)") )
				( member ( signalRef "@baseboard_fab2_lib.baseboard_fab2(sch_1):p3e_cpu0_pe3_ocp_rxp(14)") )
				( member ( signalRef "@baseboard_fab2_lib.baseboard_fab2(sch_1):p3e_cpu0_pe3_ocp_rxp(15)") )
				( objectStatus "P3E_CPU0_PE3_OCP_RX1415" )
			)
			( netGroup "@crescent_city_bb_fab1_lib.crescent_city_bb_fab1(sch_1):\NG_P3E_CPU0_PE2_OCP_RX1213\"
				( memberType ( signal ) )
				( electricalCSetRef "@crescent_city_bb_fab1_lib.crescent_city_bb_fab1(sch_1):\PCIE_SLOT_1\" )
				( member ( signalRef "@baseboard_fab2_lib.baseboard_fab2(sch_1):p3e_cpu0_pe3_ocp_rxn(12)") )
				( member ( signalRef "@baseboard_fab2_lib.baseboard_fab2(sch_1):p3e_cpu0_pe3_ocp_rxn(13)") )
				( member ( signalRef "@baseboard_fab2_lib.baseboard_fab2(sch_1):p3e_cpu0_pe3_ocp_rxp(12)") )
				( member ( signalRef "@baseboard_fab2_lib.baseboard_fab2(sch_1):p3e_cpu0_pe3_ocp_rxp(13)") )
				( objectStatus "P3E_CPU0_PE3_OCP_RX1213" )
			)
			( netGroup "@crescent_city_bb_fab1_lib.crescent_city_bb_fab1(sch_1):\NG_P3E_CPU0_PE2_OCP_RX1011\"
				( memberType ( signal ) )
				( electricalCSetRef "@crescent_city_bb_fab1_lib.crescent_city_bb_fab1(sch_1):\PCIE_SLOT_1\" )
				( member ( signalRef "@baseboard_fab2_lib.baseboard_fab2(sch_1):p3e_cpu0_pe3_ocp_rxn(10)") )
				( member ( signalRef "@baseboard_fab2_lib.baseboard_fab2(sch_1):p3e_cpu0_pe3_ocp_rxn(11)") )
				( member ( signalRef "@baseboard_fab2_lib.baseboard_fab2(sch_1):p3e_cpu0_pe3_ocp_rxp(10)") )
				( member ( signalRef "@baseboard_fab2_lib.baseboard_fab2(sch_1):p3e_cpu0_pe3_ocp_rxp(11)") )
				( objectStatus "P3E_CPU0_PE3_OCP_RX1011" )
			)
			( netGroup "@crescent_city_bb_fab1_lib.crescent_city_bb_fab1(sch_1):\NG_P3E_CPU0_PE2_OCP_RX0809\"
				( memberType ( signal ) )
				( electricalCSetRef "@crescent_city_bb_fab1_lib.crescent_city_bb_fab1(sch_1):\PCIE_SLOT_1\" )
				( member ( signalRef "@baseboard_fab2_lib.baseboard_fab2(sch_1):p3e_cpu0_pe3_ocp_rxn(8)") )
				( member ( signalRef "@baseboard_fab2_lib.baseboard_fab2(sch_1):p3e_cpu0_pe3_ocp_rxn(9)") )
				( member ( signalRef "@baseboard_fab2_lib.baseboard_fab2(sch_1):p3e_cpu0_pe3_ocp_rxp(8)") )
				( member ( signalRef "@baseboard_fab2_lib.baseboard_fab2(sch_1):p3e_cpu0_pe3_ocp_rxp(9)") )
				( objectStatus "P3E_CPU0_PE3_OCP_RX0809" )
			)
			( netGroup "@crescent_city_bb_fab1_lib.crescent_city_bb_fab1(sch_1):\NG_P3E_CPU0_PE2_OCP_RX0607\"
				( memberType ( signal ) )
				( electricalCSetRef "@crescent_city_bb_fab1_lib.crescent_city_bb_fab1(sch_1):\PCIE_SLOT_1\" )
				( member ( signalRef "@baseboard_fab2_lib.baseboard_fab2(sch_1):p3e_cpu0_pe3_ocp_rxn(6)") )
				( member ( signalRef "@baseboard_fab2_lib.baseboard_fab2(sch_1):p3e_cpu0_pe3_ocp_rxn(7)") )
				( member ( signalRef "@baseboard_fab2_lib.baseboard_fab2(sch_1):p3e_cpu0_pe3_ocp_rxp(6)") )
				( member ( signalRef "@baseboard_fab2_lib.baseboard_fab2(sch_1):p3e_cpu0_pe3_ocp_rxp(7)") )
				( objectStatus "P3E_CPU0_PE3_OCP_RX0607" )
			)
			( netGroup "@crescent_city_bb_fab1_lib.crescent_city_bb_fab1(sch_1):\NG_P3E_CPU0_PE2_OCP_RX0405\"
				( memberType ( signal ) )
				( electricalCSetRef "@crescent_city_bb_fab1_lib.crescent_city_bb_fab1(sch_1):\PCIE_SLOT_1\" )
				( member ( signalRef "@baseboard_fab2_lib.baseboard_fab2(sch_1):p3e_cpu0_pe3_ocp_rxn(4)") )
				( member ( signalRef "@baseboard_fab2_lib.baseboard_fab2(sch_1):p3e_cpu0_pe3_ocp_rxn(5)") )
				( member ( signalRef "@baseboard_fab2_lib.baseboard_fab2(sch_1):p3e_cpu0_pe3_ocp_rxp(4)") )
				( member ( signalRef "@baseboard_fab2_lib.baseboard_fab2(sch_1):p3e_cpu0_pe3_ocp_rxp(5)") )
				( objectStatus "P3E_CPU0_PE3_OCP_RX0405" )
			)
			( netGroup "@crescent_city_bb_fab1_lib.crescent_city_bb_fab1(sch_1):\NG_P3E_CPU0_PE2_OCP_RX0203\"
				( memberType ( signal ) )
				( electricalCSetRef "@crescent_city_bb_fab1_lib.crescent_city_bb_fab1(sch_1):\PCIE_SLOT_1\" )
				( member ( signalRef "@baseboard_fab2_lib.baseboard_fab2(sch_1):p3e_cpu0_pe3_ocp_rxn(2)") )
				( member ( signalRef "@baseboard_fab2_lib.baseboard_fab2(sch_1):p3e_cpu0_pe3_ocp_rxn(3)") )
				( member ( signalRef "@baseboard_fab2_lib.baseboard_fab2(sch_1):p3e_cpu0_pe3_ocp_rxp(2)") )
				( member ( signalRef "@baseboard_fab2_lib.baseboard_fab2(sch_1):p3e_cpu0_pe3_ocp_rxp(3)") )
				( objectStatus "P3E_CPU0_PE3_OCP_RX0203" )
			)
			( netGroup "@crescent_city_bb_fab1_lib.crescent_city_bb_fab1(sch_1):\NG_P3E_CPU0_PE2_OCP_RX0001\"
				( memberType ( signal ) )
				( electricalCSetRef "@crescent_city_bb_fab1_lib.crescent_city_bb_fab1(sch_1):\PCIE_SLOT_1\" )
				( member ( signalRef "@baseboard_fab2_lib.baseboard_fab2(sch_1):p3e_cpu0_pe3_ocp_rxn(0)") )
				( member ( signalRef "@baseboard_fab2_lib.baseboard_fab2(sch_1):p3e_cpu0_pe3_ocp_rxn(1)") )
				( member ( signalRef "@baseboard_fab2_lib.baseboard_fab2(sch_1):p3e_cpu0_pe3_ocp_rxp(0)") )
				( member ( signalRef "@baseboard_fab2_lib.baseboard_fab2(sch_1):p3e_cpu0_pe3_ocp_rxp(1)") )
				( objectStatus "P3E_CPU0_PE3_OCP_RX0001" )
			)
			( netGroup "@crescent_city_bb_fab1_lib.crescent_city_bb_fab1(sch_1):\NG_P3E_CPU0_PE2_SS_RX1415\"
				( memberType ( signal ) )
				( electricalCSetRef "@crescent_city_bb_fab1_lib.crescent_city_bb_fab1(sch_1):\PCIE_SLOT_1\" )
				( member ( signalRef "@baseboard_fab2_lib.baseboard_fab2(sch_1):p3e_cpu0_pe2_ss_rxn(14)") )
				( member ( signalRef "@baseboard_fab2_lib.baseboard_fab2(sch_1):p3e_cpu0_pe2_ss_rxn(15)") )
				( member ( signalRef "@baseboard_fab2_lib.baseboard_fab2(sch_1):p3e_cpu0_pe2_ss_rxp(14)") )
				( member ( signalRef "@baseboard_fab2_lib.baseboard_fab2(sch_1):p3e_cpu0_pe2_ss_rxp(15)") )
				( objectStatus "P3E_CPU0_PE2_SS_RX1415" )
			)
			( netGroup "@crescent_city_bb_fab1_lib.crescent_city_bb_fab1(sch_1):\NG_P3E_CPU0_PE2_SS_RX1213\"
				( memberType ( signal ) )
				( electricalCSetRef "@crescent_city_bb_fab1_lib.crescent_city_bb_fab1(sch_1):\PCIE_SLOT_1\" )
				( member ( signalRef "@baseboard_fab2_lib.baseboard_fab2(sch_1):p3e_cpu0_pe2_ss_rxn(12)") )
				( member ( signalRef "@baseboard_fab2_lib.baseboard_fab2(sch_1):p3e_cpu0_pe2_ss_rxn(13)") )
				( member ( signalRef "@baseboard_fab2_lib.baseboard_fab2(sch_1):p3e_cpu0_pe2_ss_rxp(12)") )
				( member ( signalRef "@baseboard_fab2_lib.baseboard_fab2(sch_1):p3e_cpu0_pe2_ss_rxp(13)") )
				( objectStatus "P3E_CPU0_PE2_SS_RX1213" )
			)
			( netGroup "@crescent_city_bb_fab1_lib.crescent_city_bb_fab1(sch_1):\NG_P3E_CPU0_PE2_SS_RX1011\"
				( memberType ( signal ) )
				( electricalCSetRef "@crescent_city_bb_fab1_lib.crescent_city_bb_fab1(sch_1):\PCIE_SLOT_1\" )
				( member ( signalRef "@baseboard_fab2_lib.baseboard_fab2(sch_1):p3e_cpu0_pe2_ss_rxn(10)") )
				( member ( signalRef "@baseboard_fab2_lib.baseboard_fab2(sch_1):p3e_cpu0_pe2_ss_rxn(11)") )
				( member ( signalRef "@baseboard_fab2_lib.baseboard_fab2(sch_1):p3e_cpu0_pe2_ss_rxp(10)") )
				( member ( signalRef "@baseboard_fab2_lib.baseboard_fab2(sch_1):p3e_cpu0_pe2_ss_rxp(11)") )
				( objectStatus "P3E_CPU0_PE2_SS_RX1011" )
			)
			( netGroup "@crescent_city_bb_fab1_lib.crescent_city_bb_fab1(sch_1):\NG_P3E_CPU0_PE2_SS_RX0809\"
				( memberType ( signal ) )
				( electricalCSetRef "@crescent_city_bb_fab1_lib.crescent_city_bb_fab1(sch_1):\PCIE_SLOT_1\" )
				( member ( signalRef "@baseboard_fab2_lib.baseboard_fab2(sch_1):p3e_cpu0_pe2_ss_rxn(8)") )
				( member ( signalRef "@baseboard_fab2_lib.baseboard_fab2(sch_1):p3e_cpu0_pe2_ss_rxn(9)") )
				( member ( signalRef "@baseboard_fab2_lib.baseboard_fab2(sch_1):p3e_cpu0_pe2_ss_rxp(8)") )
				( member ( signalRef "@baseboard_fab2_lib.baseboard_fab2(sch_1):p3e_cpu0_pe2_ss_rxp(9)") )
				( objectStatus "P3E_CPU0_PE2_SS_RX0809" )
			)
			( netGroup "@crescent_city_bb_fab1_lib.crescent_city_bb_fab1(sch_1):\NG_P3E_CPU0_PE2_SS_RX0607\"
				( memberType ( signal ) )
				( electricalCSetRef "@crescent_city_bb_fab1_lib.crescent_city_bb_fab1(sch_1):\PCIE_SLOT_1\" )
				( member ( signalRef "@baseboard_fab2_lib.baseboard_fab2(sch_1):p3e_cpu0_pe2_ss_rxn(6)") )
				( member ( signalRef "@baseboard_fab2_lib.baseboard_fab2(sch_1):p3e_cpu0_pe2_ss_rxn(7)") )
				( member ( signalRef "@baseboard_fab2_lib.baseboard_fab2(sch_1):p3e_cpu0_pe2_ss_rxp(6)") )
				( member ( signalRef "@baseboard_fab2_lib.baseboard_fab2(sch_1):p3e_cpu0_pe2_ss_rxp(7)") )
				( objectStatus "P3E_CPU0_PE2_SS_RX0607" )
			)
			( netGroup "@crescent_city_bb_fab1_lib.crescent_city_bb_fab1(sch_1):\NG_P3E_CPU0_PE2_SS_RX0405\"
				( memberType ( signal ) )
				( electricalCSetRef "@crescent_city_bb_fab1_lib.crescent_city_bb_fab1(sch_1):\PCIE_SLOT_1\" )
				( member ( signalRef "@baseboard_fab2_lib.baseboard_fab2(sch_1):p3e_cpu0_pe2_ss_rxn(4)") )
				( member ( signalRef "@baseboard_fab2_lib.baseboard_fab2(sch_1):p3e_cpu0_pe2_ss_rxn(5)") )
				( member ( signalRef "@baseboard_fab2_lib.baseboard_fab2(sch_1):p3e_cpu0_pe2_ss_rxp(4)") )
				( member ( signalRef "@baseboard_fab2_lib.baseboard_fab2(sch_1):p3e_cpu0_pe2_ss_rxp(5)") )
				( objectStatus "P3E_CPU0_PE2_SS_RX0405" )
			)
			( netGroup "@crescent_city_bb_fab1_lib.crescent_city_bb_fab1(sch_1):\NG_P3E_CPU0_PE2_SS_RX0203\"
				( memberType ( signal ) )
				( electricalCSetRef "@crescent_city_bb_fab1_lib.crescent_city_bb_fab1(sch_1):\PCIE_SLOT_1\" )
				( member ( signalRef "@baseboard_fab2_lib.baseboard_fab2(sch_1):p3e_cpu0_pe2_ss_rxn(2)") )
				( member ( signalRef "@baseboard_fab2_lib.baseboard_fab2(sch_1):p3e_cpu0_pe2_ss_rxn(3)") )
				( member ( signalRef "@baseboard_fab2_lib.baseboard_fab2(sch_1):p3e_cpu0_pe2_ss_rxp(2)") )
				( member ( signalRef "@baseboard_fab2_lib.baseboard_fab2(sch_1):p3e_cpu0_pe2_ss_rxp(3)") )
				( objectStatus "P3E_CPU0_PE2_SS_RX0203" )
			)
			( netGroup "@crescent_city_bb_fab1_lib.crescent_city_bb_fab1(sch_1):\NG_P3E_CPU0_PE2_SS_RX0001\"
				( memberType ( signal ) )
				( electricalCSetRef "@crescent_city_bb_fab1_lib.crescent_city_bb_fab1(sch_1):\PCIE_SLOT_1\" )
				( member ( signalRef "@baseboard_fab2_lib.baseboard_fab2(sch_1):p3e_cpu0_pe2_ss_rxn(0)") )
				( member ( signalRef "@baseboard_fab2_lib.baseboard_fab2(sch_1):p3e_cpu0_pe2_ss_rxn(1)") )
				( member ( signalRef "@baseboard_fab2_lib.baseboard_fab2(sch_1):p3e_cpu0_pe2_ss_rxp(0)") )
				( member ( signalRef "@baseboard_fab2_lib.baseboard_fab2(sch_1):p3e_cpu0_pe2_ss_rxp(1)") )
				( objectStatus "P3E_CPU0_PE2_SS_RX0001" )
			)
			( netGroup "@crescent_city_bb_fab1_lib.crescent_city_bb_fab1(sch_1):\NG_P3E_CPU0_PE2_SS_TX1415\"
				( memberType ( signal ) )
				( electricalCSetRef "@crescent_city_bb_fab1_lib.crescent_city_bb_fab1(sch_1):\PCIE_SLOT\" )
				( member ( electricalNetRef "@crescent_city_bb_fab1_lib.crescent_city_bb_fab1(sch_1):p3e_cpu0_pe2_ss_c_txp(15)") )
				( member ( electricalNetRef "@crescent_city_bb_fab1_lib.crescent_city_bb_fab1(sch_1):p3e_cpu0_pe2_ss_c_txn(15)") )
				( member ( electricalNetRef "@crescent_city_bb_fab1_lib.crescent_city_bb_fab1(sch_1):p3e_cpu0_pe2_ss_c_txp(14)") )
				( member ( electricalNetRef "@crescent_city_bb_fab1_lib.crescent_city_bb_fab1(sch_1):p3e_cpu0_pe2_ss_c_txn(14)") )
				( objectStatus "P3E_CPU0_PE2_SS_TX1415" )
			)
			( netGroup "@crescent_city_bb_fab1_lib.crescent_city_bb_fab1(sch_1):\NG_P3E_CPU0_PE2_SS_TX1213\"
				( memberType ( signal ) )
				( electricalCSetRef "@crescent_city_bb_fab1_lib.crescent_city_bb_fab1(sch_1):\PCIE_SLOT\" )
				( member ( electricalNetRef "@crescent_city_bb_fab1_lib.crescent_city_bb_fab1(sch_1):p3e_cpu0_pe2_ss_c_txp(13)") )
				( member ( electricalNetRef "@crescent_city_bb_fab1_lib.crescent_city_bb_fab1(sch_1):p3e_cpu0_pe2_ss_c_txn(13)") )
				( member ( electricalNetRef "@crescent_city_bb_fab1_lib.crescent_city_bb_fab1(sch_1):p3e_cpu0_pe2_ss_c_txp(12)") )
				( member ( electricalNetRef "@crescent_city_bb_fab1_lib.crescent_city_bb_fab1(sch_1):p3e_cpu0_pe2_ss_c_txn(12)") )
				( objectStatus "P3E_CPU0_PE2_SS_TX1213" )
			)
			( netGroup "@crescent_city_bb_fab1_lib.crescent_city_bb_fab1(sch_1):\NG_P3E_CPU0_PE2_SS_TX1011\"
				( memberType ( signal ) )
				( electricalCSetRef "@crescent_city_bb_fab1_lib.crescent_city_bb_fab1(sch_1):\PCIE_SLOT\" )
				( member ( electricalNetRef "@crescent_city_bb_fab1_lib.crescent_city_bb_fab1(sch_1):p3e_cpu0_pe2_ss_c_txp(11)") )
				( member ( electricalNetRef "@crescent_city_bb_fab1_lib.crescent_city_bb_fab1(sch_1):p3e_cpu0_pe2_ss_c_txn(11)") )
				( member ( electricalNetRef "@crescent_city_bb_fab1_lib.crescent_city_bb_fab1(sch_1):p3e_cpu0_pe2_ss_c_txp(10)") )
				( member ( electricalNetRef "@crescent_city_bb_fab1_lib.crescent_city_bb_fab1(sch_1):p3e_cpu0_pe2_ss_c_txn(10)") )
				( objectStatus "P3E_CPU0_PE2_SS_TX1011" )
			)
			( netGroup "@crescent_city_bb_fab1_lib.crescent_city_bb_fab1(sch_1):\NG_P3E_CPU0_PE2_SS_TX0809\"
				( memberType ( signal ) )
				( electricalCSetRef "@crescent_city_bb_fab1_lib.crescent_city_bb_fab1(sch_1):\PCIE_SLOT\" )
				( member ( electricalNetRef "@crescent_city_bb_fab1_lib.crescent_city_bb_fab1(sch_1):p3e_cpu0_pe2_ss_c_txp(9)") )
				( member ( electricalNetRef "@crescent_city_bb_fab1_lib.crescent_city_bb_fab1(sch_1):p3e_cpu0_pe2_ss_c_txn(9)") )
				( member ( electricalNetRef "@crescent_city_bb_fab1_lib.crescent_city_bb_fab1(sch_1):p3e_cpu0_pe2_ss_c_txp(8)") )
				( member ( electricalNetRef "@crescent_city_bb_fab1_lib.crescent_city_bb_fab1(sch_1):p3e_cpu0_pe2_ss_c_txn(8)") )
				( objectStatus "P3E_CPU0_PE2_SS_TX0809" )
			)
			( netGroup "@crescent_city_bb_fab1_lib.crescent_city_bb_fab1(sch_1):\NG_P3E_CPU0_PE2_SS_TX0607\"
				( memberType ( signal ) )
				( electricalCSetRef "@crescent_city_bb_fab1_lib.crescent_city_bb_fab1(sch_1):\PCIE_SLOT\" )
				( member ( electricalNetRef "@crescent_city_bb_fab1_lib.crescent_city_bb_fab1(sch_1):p3e_cpu0_pe2_ss_c_txp(7)") )
				( member ( electricalNetRef "@crescent_city_bb_fab1_lib.crescent_city_bb_fab1(sch_1):p3e_cpu0_pe2_ss_c_txn(7)") )
				( member ( electricalNetRef "@crescent_city_bb_fab1_lib.crescent_city_bb_fab1(sch_1):p3e_cpu0_pe2_ss_c_txp(6)") )
				( member ( electricalNetRef "@crescent_city_bb_fab1_lib.crescent_city_bb_fab1(sch_1):p3e_cpu0_pe2_ss_c_txn(6)") )
				( objectStatus "P3E_CPU0_PE2_SS_TX0607" )
			)
			( netGroup "@crescent_city_bb_fab1_lib.crescent_city_bb_fab1(sch_1):\NG_P3E_CPU0_PE2_SS_TX0405\"
				( memberType ( signal ) )
				( electricalCSetRef "@crescent_city_bb_fab1_lib.crescent_city_bb_fab1(sch_1):\PCIE_SLOT\" )
				( member ( electricalNetRef "@crescent_city_bb_fab1_lib.crescent_city_bb_fab1(sch_1):p3e_cpu0_pe2_ss_c_txp(5)") )
				( member ( electricalNetRef "@crescent_city_bb_fab1_lib.crescent_city_bb_fab1(sch_1):p3e_cpu0_pe2_ss_c_txn(5)") )
				( member ( electricalNetRef "@crescent_city_bb_fab1_lib.crescent_city_bb_fab1(sch_1):p3e_cpu0_pe2_ss_c_txp(4)") )
				( member ( electricalNetRef "@crescent_city_bb_fab1_lib.crescent_city_bb_fab1(sch_1):p3e_cpu0_pe2_ss_c_txn(4)") )
				( objectStatus "P3E_CPU0_PE2_SS_TX0405" )
			)
			( netGroup "@crescent_city_bb_fab1_lib.crescent_city_bb_fab1(sch_1):\P3E_CPU0_PE2_SS_TX0203\"
				( memberType ( signal ) )
				( electricalCSetRef "@crescent_city_bb_fab1_lib.crescent_city_bb_fab1(sch_1):\PCIE_SLOT\" )
				( member ( electricalNetRef "@crescent_city_bb_fab1_lib.crescent_city_bb_fab1(sch_1):p3e_cpu0_pe2_ss_c_txp(3)") )
				( member ( electricalNetRef "@crescent_city_bb_fab1_lib.crescent_city_bb_fab1(sch_1):p3e_cpu0_pe2_ss_c_txn(3)") )
				( member ( electricalNetRef "@crescent_city_bb_fab1_lib.crescent_city_bb_fab1(sch_1):p3e_cpu0_pe2_ss_c_txp(2)") )
				( member ( electricalNetRef "@crescent_city_bb_fab1_lib.crescent_city_bb_fab1(sch_1):p3e_cpu0_pe2_ss_c_txn(2)") )
				( objectStatus "P3E_CPU0_PE2_SS_TX0203" )
			)
			( netGroup "@crescent_city_bb_fab1_lib.crescent_city_bb_fab1(sch_1):\P3E_CPU0_PE2_SS_TX0001\"
				( memberType ( signal ) )
				( electricalCSetRef "@crescent_city_bb_fab1_lib.crescent_city_bb_fab1(sch_1):\PCIE_SLOT\" )
				( member ( electricalNetRef "@crescent_city_bb_fab1_lib.crescent_city_bb_fab1(sch_1):p3e_cpu0_pe2_ss_c_txp(1)") )
				( member ( electricalNetRef "@crescent_city_bb_fab1_lib.crescent_city_bb_fab1(sch_1):p3e_cpu0_pe2_ss_c_txn(1)") )
				( member ( electricalNetRef "@crescent_city_bb_fab1_lib.crescent_city_bb_fab1(sch_1):p3e_cpu0_pe2_ss_c_txp(0)") )
				( member ( electricalNetRef "@crescent_city_bb_fab1_lib.crescent_city_bb_fab1(sch_1):p3e_cpu0_pe2_ss_c_txn(0)") )
				( objectStatus "P3E_CPU0_PE2_SS_TX0001" )
			)
			( netGroup "@crescent_city_bb_fab1_lib.crescent_city_bb_fab1(sch_1):\NG_M_F_BYTE-ECC\"
				( memberType ( signal ) )
				( electricalCSetRef "@crescent_city_bb_fab1_lib.crescent_city_bb_fab1(sch_1):\DDR_DQ_A\" )
				( member ( diffPairRef "@sapphirecity_baseboard_lib.sapphirecity_baseboard(sch_1):\M_F_DQS_D\(8)") )
				( member ( diffPairRef "@sapphirecity_baseboard_lib.sapphirecity_baseboard(sch_1):\M_F_DQS_D\(17)") )
				( member ( signalRef "@baseboard_fab2_lib.baseboard_fab2(sch_1):m_f_ecc(0)") )
				( member ( signalRef "@baseboard_fab2_lib.baseboard_fab2(sch_1):m_f_ecc(1)") )
				( member ( signalRef "@baseboard_fab2_lib.baseboard_fab2(sch_1):m_f_ecc(2)") )
				( member ( signalRef "@baseboard_fab2_lib.baseboard_fab2(sch_1):m_f_ecc(3)") )
				( member ( signalRef "@baseboard_fab2_lib.baseboard_fab2(sch_1):m_f_ecc(4)") )
				( member ( signalRef "@baseboard_fab2_lib.baseboard_fab2(sch_1):m_f_ecc(5)") )
				( member ( signalRef "@baseboard_fab2_lib.baseboard_fab2(sch_1):m_f_ecc(6)") )
				( member ( signalRef "@baseboard_fab2_lib.baseboard_fab2(sch_1):m_f_ecc(7)") )
				( objectStatus "NG_M_F_BYTE-ECC" )
			)
			( netGroup "@crescent_city_bb_fab1_lib.crescent_city_bb_fab1(sch_1):\NG_M_F_BYTE7\"
				( memberType ( signal ) )
				( electricalCSetRef "@crescent_city_bb_fab1_lib.crescent_city_bb_fab1(sch_1):\DDR_DQ_A\" )
				( member ( diffPairRef "@sapphirecity_baseboard_lib.sapphirecity_baseboard(sch_1):\M_F_DQS_D\(7)") )
				( member ( diffPairRef "@sapphirecity_baseboard_lib.sapphirecity_baseboard(sch_1):\M_F_DQS_D\(16)") )
				( member ( signalRef "@baseboard_fab2_lib.baseboard_fab2(sch_1):m_f_dq(56)") )
				( member ( signalRef "@baseboard_fab2_lib.baseboard_fab2(sch_1):m_f_dq(57)") )
				( member ( signalRef "@baseboard_fab2_lib.baseboard_fab2(sch_1):m_f_dq(58)") )
				( member ( signalRef "@baseboard_fab2_lib.baseboard_fab2(sch_1):m_f_dq(59)") )
				( member ( signalRef "@baseboard_fab2_lib.baseboard_fab2(sch_1):m_f_dq(60)") )
				( member ( signalRef "@baseboard_fab2_lib.baseboard_fab2(sch_1):m_f_dq(61)") )
				( member ( signalRef "@baseboard_fab2_lib.baseboard_fab2(sch_1):m_f_dq(62)") )
				( member ( signalRef "@baseboard_fab2_lib.baseboard_fab2(sch_1):m_f_dq(63)") )
				( objectStatus "NG_M_F_BYTE7" )
			)
			( netGroup "@crescent_city_bb_fab1_lib.crescent_city_bb_fab1(sch_1):\NG_M_F_BYTE6\"
				( memberType ( signal ) )
				( electricalCSetRef "@crescent_city_bb_fab1_lib.crescent_city_bb_fab1(sch_1):\DDR_DQ_A\" )
				( member ( diffPairRef "@sapphirecity_baseboard_lib.sapphirecity_baseboard(sch_1):\M_F_DQS_D\(6)") )
				( member ( diffPairRef "@sapphirecity_baseboard_lib.sapphirecity_baseboard(sch_1):\M_F_DQS_D\(15)") )
				( member ( signalRef "@baseboard_fab2_lib.baseboard_fab2(sch_1):m_f_dq(48)") )
				( member ( signalRef "@baseboard_fab2_lib.baseboard_fab2(sch_1):m_f_dq(49)") )
				( member ( signalRef "@baseboard_fab2_lib.baseboard_fab2(sch_1):m_f_dq(50)") )
				( member ( signalRef "@baseboard_fab2_lib.baseboard_fab2(sch_1):m_f_dq(51)") )
				( member ( signalRef "@baseboard_fab2_lib.baseboard_fab2(sch_1):m_f_dq(52)") )
				( member ( signalRef "@baseboard_fab2_lib.baseboard_fab2(sch_1):m_f_dq(53)") )
				( member ( signalRef "@baseboard_fab2_lib.baseboard_fab2(sch_1):m_f_dq(54)") )
				( member ( signalRef "@baseboard_fab2_lib.baseboard_fab2(sch_1):m_f_dq(55)") )
				( objectStatus "NG_M_F_BYTE6" )
			)
			( netGroup "@crescent_city_bb_fab1_lib.crescent_city_bb_fab1(sch_1):\NG_M_F_BYTE5\"
				( memberType ( signal ) )
				( electricalCSetRef "@crescent_city_bb_fab1_lib.crescent_city_bb_fab1(sch_1):\DDR_DQ_A\" )
				( member ( diffPairRef "@sapphirecity_baseboard_lib.sapphirecity_baseboard(sch_1):\M_F_DQS_D\(5)") )
				( member ( diffPairRef "@sapphirecity_baseboard_lib.sapphirecity_baseboard(sch_1):\M_F_DQS_D\(14)") )
				( member ( signalRef "@baseboard_fab2_lib.baseboard_fab2(sch_1):m_f_dq(40)") )
				( member ( signalRef "@baseboard_fab2_lib.baseboard_fab2(sch_1):m_f_dq(41)") )
				( member ( signalRef "@baseboard_fab2_lib.baseboard_fab2(sch_1):m_f_dq(42)") )
				( member ( signalRef "@baseboard_fab2_lib.baseboard_fab2(sch_1):m_f_dq(43)") )
				( member ( signalRef "@baseboard_fab2_lib.baseboard_fab2(sch_1):m_f_dq(44)") )
				( member ( signalRef "@baseboard_fab2_lib.baseboard_fab2(sch_1):m_f_dq(45)") )
				( member ( signalRef "@baseboard_fab2_lib.baseboard_fab2(sch_1):m_f_dq(46)") )
				( member ( signalRef "@baseboard_fab2_lib.baseboard_fab2(sch_1):m_f_dq(47)") )
				( objectStatus "NG_M_F_BYTE5" )
			)
			( netGroup "@crescent_city_bb_fab1_lib.crescent_city_bb_fab1(sch_1):\NG_M_F_BYTE4\"
				( memberType ( signal ) )
				( electricalCSetRef "@crescent_city_bb_fab1_lib.crescent_city_bb_fab1(sch_1):\DDR_DQ_A\" )
				( member ( diffPairRef "@sapphirecity_baseboard_lib.sapphirecity_baseboard(sch_1):\M_F_DQS_D\(4)") )
				( member ( diffPairRef "@sapphirecity_baseboard_lib.sapphirecity_baseboard(sch_1):\M_F_DQS_D\(13)") )
				( member ( signalRef "@baseboard_fab2_lib.baseboard_fab2(sch_1):m_f_dq(32)") )
				( member ( signalRef "@baseboard_fab2_lib.baseboard_fab2(sch_1):m_f_dq(33)") )
				( member ( signalRef "@baseboard_fab2_lib.baseboard_fab2(sch_1):m_f_dq(34)") )
				( member ( signalRef "@baseboard_fab2_lib.baseboard_fab2(sch_1):m_f_dq(35)") )
				( member ( signalRef "@baseboard_fab2_lib.baseboard_fab2(sch_1):m_f_dq(36)") )
				( member ( signalRef "@baseboard_fab2_lib.baseboard_fab2(sch_1):m_f_dq(37)") )
				( member ( signalRef "@baseboard_fab2_lib.baseboard_fab2(sch_1):m_f_dq(38)") )
				( member ( signalRef "@baseboard_fab2_lib.baseboard_fab2(sch_1):m_f_dq(39)") )
				( objectStatus "NG_M_F_BYTE4" )
			)
			( netGroup "@crescent_city_bb_fab1_lib.crescent_city_bb_fab1(sch_1):\NG_M_F_BYTE3\"
				( memberType ( signal ) )
				( electricalCSetRef "@crescent_city_bb_fab1_lib.crescent_city_bb_fab1(sch_1):\DDR_DQ_A\" )
				( member ( diffPairRef "@sapphirecity_baseboard_lib.sapphirecity_baseboard(sch_1):\M_F_DQS_D\(3)") )
				( member ( diffPairRef "@sapphirecity_baseboard_lib.sapphirecity_baseboard(sch_1):\M_F_DQS_D\(12)") )
				( member ( signalRef "@baseboard_fab2_lib.baseboard_fab2(sch_1):m_f_dq(24)") )
				( member ( signalRef "@baseboard_fab2_lib.baseboard_fab2(sch_1):m_f_dq(25)") )
				( member ( signalRef "@baseboard_fab2_lib.baseboard_fab2(sch_1):m_f_dq(26)") )
				( member ( signalRef "@baseboard_fab2_lib.baseboard_fab2(sch_1):m_f_dq(27)") )
				( member ( signalRef "@baseboard_fab2_lib.baseboard_fab2(sch_1):m_f_dq(28)") )
				( member ( signalRef "@baseboard_fab2_lib.baseboard_fab2(sch_1):m_f_dq(29)") )
				( member ( signalRef "@baseboard_fab2_lib.baseboard_fab2(sch_1):m_f_dq(30)") )
				( member ( signalRef "@baseboard_fab2_lib.baseboard_fab2(sch_1):m_f_dq(31)") )
				( objectStatus "NG_M_F_BYTE3" )
			)
			( netGroup "@crescent_city_bb_fab1_lib.crescent_city_bb_fab1(sch_1):\NG_M_F_BYTE2\"
				( memberType ( signal ) )
				( electricalCSetRef "@crescent_city_bb_fab1_lib.crescent_city_bb_fab1(sch_1):\DDR_DQ_A\" )
				( member ( diffPairRef "@sapphirecity_baseboard_lib.sapphirecity_baseboard(sch_1):\M_F_DQS_D\(2)") )
				( member ( diffPairRef "@sapphirecity_baseboard_lib.sapphirecity_baseboard(sch_1):\M_F_DQS_D\(11)") )
				( member ( signalRef "@baseboard_fab2_lib.baseboard_fab2(sch_1):m_f_dq(16)") )
				( member ( signalRef "@baseboard_fab2_lib.baseboard_fab2(sch_1):m_f_dq(17)") )
				( member ( signalRef "@baseboard_fab2_lib.baseboard_fab2(sch_1):m_f_dq(18)") )
				( member ( signalRef "@baseboard_fab2_lib.baseboard_fab2(sch_1):m_f_dq(19)") )
				( member ( signalRef "@baseboard_fab2_lib.baseboard_fab2(sch_1):m_f_dq(20)") )
				( member ( signalRef "@baseboard_fab2_lib.baseboard_fab2(sch_1):m_f_dq(21)") )
				( member ( signalRef "@baseboard_fab2_lib.baseboard_fab2(sch_1):m_f_dq(22)") )
				( member ( signalRef "@baseboard_fab2_lib.baseboard_fab2(sch_1):m_f_dq(23)") )
				( objectStatus "NG_M_F_BYTE2" )
			)
			( netGroup "@crescent_city_bb_fab1_lib.crescent_city_bb_fab1(sch_1):\NG_M_F_BYTE1\"
				( memberType ( signal ) )
				( electricalCSetRef "@crescent_city_bb_fab1_lib.crescent_city_bb_fab1(sch_1):\DDR_DQ_A\" )
				( member ( diffPairRef "@sapphirecity_baseboard_lib.sapphirecity_baseboard(sch_1):\M_F_DQS_D\(1)") )
				( member ( diffPairRef "@sapphirecity_baseboard_lib.sapphirecity_baseboard(sch_1):\M_F_DQS_D\(10)") )
				( member ( signalRef "@baseboard_fab2_lib.baseboard_fab2(sch_1):m_f_dq(8)") )
				( member ( signalRef "@baseboard_fab2_lib.baseboard_fab2(sch_1):m_f_dq(9)") )
				( member ( signalRef "@baseboard_fab2_lib.baseboard_fab2(sch_1):m_f_dq(10)") )
				( member ( signalRef "@baseboard_fab2_lib.baseboard_fab2(sch_1):m_f_dq(11)") )
				( member ( signalRef "@baseboard_fab2_lib.baseboard_fab2(sch_1):m_f_dq(12)") )
				( member ( signalRef "@baseboard_fab2_lib.baseboard_fab2(sch_1):m_f_dq(13)") )
				( member ( signalRef "@baseboard_fab2_lib.baseboard_fab2(sch_1):m_f_dq(14)") )
				( member ( signalRef "@baseboard_fab2_lib.baseboard_fab2(sch_1):m_f_dq(15)") )
				( objectStatus "NG_M_F_BYTE1" )
			)
			( netGroup "@crescent_city_bb_fab1_lib.crescent_city_bb_fab1(sch_1):\NG_M_F_BYTE0\"
				( memberType ( signal ) )
				( electricalCSetRef "@crescent_city_bb_fab1_lib.crescent_city_bb_fab1(sch_1):\DDR_DQ_A\" )
				( member ( diffPairRef "@sapphirecity_baseboard_lib.sapphirecity_baseboard(sch_1):\M_F_DQS_D\(0)") )
				( member ( diffPairRef "@sapphirecity_baseboard_lib.sapphirecity_baseboard(sch_1):\M_F_DQS_D\(9)") )
				( member ( signalRef "@baseboard_fab2_lib.baseboard_fab2(sch_1):m_f_dq(0)") )
				( member ( signalRef "@baseboard_fab2_lib.baseboard_fab2(sch_1):m_f_dq(1)") )
				( member ( signalRef "@baseboard_fab2_lib.baseboard_fab2(sch_1):m_f_dq(2)") )
				( member ( signalRef "@baseboard_fab2_lib.baseboard_fab2(sch_1):m_f_dq(3)") )
				( member ( signalRef "@baseboard_fab2_lib.baseboard_fab2(sch_1):m_f_dq(4)") )
				( member ( signalRef "@baseboard_fab2_lib.baseboard_fab2(sch_1):m_f_dq(5)") )
				( member ( signalRef "@baseboard_fab2_lib.baseboard_fab2(sch_1):m_f_dq(6)") )
				( member ( signalRef "@baseboard_fab2_lib.baseboard_fab2(sch_1):m_f_dq(7)") )
				( objectStatus "NG_M_F_BYTE0" )
			)
			( netGroup "@crescent_city_bb_fab1_lib.crescent_city_bb_fab1(sch_1):\NG_M_E_BYTE-ECC_1\"
				( memberType ( signal ) )
				( electricalCSetRef "@crescent_city_bb_fab1_lib.crescent_city_bb_fab1(sch_1):\DDR_DQ_A\" )
				( member ( diffPairRef "@sapphirecity_baseboard_lib.sapphirecity_baseboard(sch_1):\M_E_DQS_D\(8)") )
				( member ( diffPairRef "@sapphirecity_baseboard_lib.sapphirecity_baseboard(sch_1):\M_E_DQS_D\(17)") )
				( member ( signalRef "@baseboard_fab2_lib.baseboard_fab2(sch_1):m_e_ecc(0)") )
				( member ( signalRef "@baseboard_fab2_lib.baseboard_fab2(sch_1):m_e_ecc(1)") )
				( member ( signalRef "@baseboard_fab2_lib.baseboard_fab2(sch_1):m_e_ecc(2)") )
				( member ( signalRef "@baseboard_fab2_lib.baseboard_fab2(sch_1):m_e_ecc(3)") )
				( member ( signalRef "@baseboard_fab2_lib.baseboard_fab2(sch_1):m_e_ecc(4)") )
				( member ( signalRef "@baseboard_fab2_lib.baseboard_fab2(sch_1):m_e_ecc(5)") )
				( member ( signalRef "@baseboard_fab2_lib.baseboard_fab2(sch_1):m_e_ecc(6)") )
				( member ( signalRef "@baseboard_fab2_lib.baseboard_fab2(sch_1):m_e_ecc(7)") )
				( objectStatus "NG_M_E_BYTE-ECC" )
			)
			( netGroup "@crescent_city_bb_fab1_lib.crescent_city_bb_fab1(sch_1):\NG_M_E_BYTE3\"
				( memberType ( signal ) )
				( electricalCSetRef "@crescent_city_bb_fab1_lib.crescent_city_bb_fab1(sch_1):\DDR_DQ_A\" )
				( member ( diffPairRef "@sapphirecity_baseboard_lib.sapphirecity_baseboard(sch_1):\M_E_DQS_D\(3)") )
				( member ( diffPairRef "@sapphirecity_baseboard_lib.sapphirecity_baseboard(sch_1):\M_E_DQS_D\(12)") )
				( member ( signalRef "@baseboard_fab2_lib.baseboard_fab2(sch_1):m_e_dq(24)") )
				( member ( signalRef "@baseboard_fab2_lib.baseboard_fab2(sch_1):m_e_dq(25)") )
				( member ( signalRef "@baseboard_fab2_lib.baseboard_fab2(sch_1):m_e_dq(26)") )
				( member ( signalRef "@baseboard_fab2_lib.baseboard_fab2(sch_1):m_e_dq(27)") )
				( member ( signalRef "@baseboard_fab2_lib.baseboard_fab2(sch_1):m_e_dq(28)") )
				( member ( signalRef "@baseboard_fab2_lib.baseboard_fab2(sch_1):m_e_dq(29)") )
				( member ( signalRef "@baseboard_fab2_lib.baseboard_fab2(sch_1):m_e_dq(30)") )
				( member ( signalRef "@baseboard_fab2_lib.baseboard_fab2(sch_1):m_e_dq(31)") )
				( objectStatus "NG_M_E_BYTE3" )
			)
			( netGroup "@crescent_city_bb_fab1_lib.crescent_city_bb_fab1(sch_1):\NG_M_E_BYTE-ECC\"
				( memberType ( signal ) )
				( electricalCSetRef "@crescent_city_bb_fab1_lib.crescent_city_bb_fab1(sch_1):\DDR_DQ_A\" )
				( member ( diffPairRef "@sapphirecity_baseboard_lib.sapphirecity_baseboard(sch_1):\M_E_DQS_D\(7)") )
				( member ( diffPairRef "@sapphirecity_baseboard_lib.sapphirecity_baseboard(sch_1):\M_E_DQS_D\(16)") )
				( member ( signalRef "@baseboard_fab2_lib.baseboard_fab2(sch_1):m_e_dq(56)") )
				( member ( signalRef "@baseboard_fab2_lib.baseboard_fab2(sch_1):m_e_dq(57)") )
				( member ( signalRef "@baseboard_fab2_lib.baseboard_fab2(sch_1):m_e_dq(58)") )
				( member ( signalRef "@baseboard_fab2_lib.baseboard_fab2(sch_1):m_e_dq(59)") )
				( member ( signalRef "@baseboard_fab2_lib.baseboard_fab2(sch_1):m_e_dq(60)") )
				( member ( signalRef "@baseboard_fab2_lib.baseboard_fab2(sch_1):m_e_dq(61)") )
				( member ( signalRef "@baseboard_fab2_lib.baseboard_fab2(sch_1):m_e_dq(62)") )
				( member ( signalRef "@baseboard_fab2_lib.baseboard_fab2(sch_1):m_e_dq(63)") )
				( objectStatus "NG_M_E_BYTE7" )
			)
			( netGroup "@crescent_city_bb_fab1_lib.crescent_city_bb_fab1(sch_1):\NG_M_E_BYTE6\"
				( memberType ( signal ) )
				( electricalCSetRef "@crescent_city_bb_fab1_lib.crescent_city_bb_fab1(sch_1):\DDR_DQ_A\" )
				( member ( diffPairRef "@sapphirecity_baseboard_lib.sapphirecity_baseboard(sch_1):\M_E_DQS_D\(6)") )
				( member ( diffPairRef "@sapphirecity_baseboard_lib.sapphirecity_baseboard(sch_1):\M_E_DQS_D\(15)") )
				( member ( signalRef "@baseboard_fab2_lib.baseboard_fab2(sch_1):m_e_dq(48)") )
				( member ( signalRef "@baseboard_fab2_lib.baseboard_fab2(sch_1):m_e_dq(49)") )
				( member ( signalRef "@baseboard_fab2_lib.baseboard_fab2(sch_1):m_e_dq(50)") )
				( member ( signalRef "@baseboard_fab2_lib.baseboard_fab2(sch_1):m_e_dq(51)") )
				( member ( signalRef "@baseboard_fab2_lib.baseboard_fab2(sch_1):m_e_dq(52)") )
				( member ( signalRef "@baseboard_fab2_lib.baseboard_fab2(sch_1):m_e_dq(53)") )
				( member ( signalRef "@baseboard_fab2_lib.baseboard_fab2(sch_1):m_e_dq(54)") )
				( member ( signalRef "@baseboard_fab2_lib.baseboard_fab2(sch_1):m_e_dq(55)") )
				( objectStatus "NG_M_E_BYTE6" )
			)
			( netGroup "@crescent_city_bb_fab1_lib.crescent_city_bb_fab1(sch_1):\NG_M_E_BYTE5\"
				( memberType ( signal ) )
				( electricalCSetRef "@crescent_city_bb_fab1_lib.crescent_city_bb_fab1(sch_1):\DDR_DQ_A\" )
				( member ( diffPairRef "@sapphirecity_baseboard_lib.sapphirecity_baseboard(sch_1):\M_E_DQS_D\(5)") )
				( member ( diffPairRef "@sapphirecity_baseboard_lib.sapphirecity_baseboard(sch_1):\M_E_DQS_D\(14)") )
				( member ( signalRef "@baseboard_fab2_lib.baseboard_fab2(sch_1):m_e_dq(40)") )
				( member ( signalRef "@baseboard_fab2_lib.baseboard_fab2(sch_1):m_e_dq(41)") )
				( member ( signalRef "@baseboard_fab2_lib.baseboard_fab2(sch_1):m_e_dq(42)") )
				( member ( signalRef "@baseboard_fab2_lib.baseboard_fab2(sch_1):m_e_dq(43)") )
				( member ( signalRef "@baseboard_fab2_lib.baseboard_fab2(sch_1):m_e_dq(44)") )
				( member ( signalRef "@baseboard_fab2_lib.baseboard_fab2(sch_1):m_e_dq(45)") )
				( member ( signalRef "@baseboard_fab2_lib.baseboard_fab2(sch_1):m_e_dq(46)") )
				( member ( signalRef "@baseboard_fab2_lib.baseboard_fab2(sch_1):m_e_dq(47)") )
				( objectStatus "NG_M_E_BYTE5" )
			)
			( netGroup "@crescent_city_bb_fab1_lib.crescent_city_bb_fab1(sch_1):\NG_M_E_BYTE4\"
				( memberType ( signal ) )
				( electricalCSetRef "@crescent_city_bb_fab1_lib.crescent_city_bb_fab1(sch_1):\DDR_DQ_A\" )
				( member ( diffPairRef "@sapphirecity_baseboard_lib.sapphirecity_baseboard(sch_1):\M_E_DQS_D\(4)") )
				( member ( diffPairRef "@sapphirecity_baseboard_lib.sapphirecity_baseboard(sch_1):\M_E_DQS_D\(13)") )
				( member ( signalRef "@baseboard_fab2_lib.baseboard_fab2(sch_1):m_e_dq(32)") )
				( member ( signalRef "@baseboard_fab2_lib.baseboard_fab2(sch_1):m_e_dq(33)") )
				( member ( signalRef "@baseboard_fab2_lib.baseboard_fab2(sch_1):m_e_dq(34)") )
				( member ( signalRef "@baseboard_fab2_lib.baseboard_fab2(sch_1):m_e_dq(35)") )
				( member ( signalRef "@baseboard_fab2_lib.baseboard_fab2(sch_1):m_e_dq(36)") )
				( member ( signalRef "@baseboard_fab2_lib.baseboard_fab2(sch_1):m_e_dq(37)") )
				( member ( signalRef "@baseboard_fab2_lib.baseboard_fab2(sch_1):m_e_dq(38)") )
				( member ( signalRef "@baseboard_fab2_lib.baseboard_fab2(sch_1):m_e_dq(39)") )
				( objectStatus "NG_M_E_BYTE4" )
			)
			( netGroup "@crescent_city_bb_fab1_lib.crescent_city_bb_fab1(sch_1):\NG_M_E_BYTE2\"
				( memberType ( signal ) )
				( electricalCSetRef "@crescent_city_bb_fab1_lib.crescent_city_bb_fab1(sch_1):\DDR_DQ_A\" )
				( member ( diffPairRef "@sapphirecity_baseboard_lib.sapphirecity_baseboard(sch_1):\M_E_DQS_D\(2)") )
				( member ( diffPairRef "@sapphirecity_baseboard_lib.sapphirecity_baseboard(sch_1):\M_E_DQS_D\(11)") )
				( member ( signalRef "@baseboard_fab2_lib.baseboard_fab2(sch_1):m_e_dq(16)") )
				( member ( signalRef "@baseboard_fab2_lib.baseboard_fab2(sch_1):m_e_dq(17)") )
				( member ( signalRef "@baseboard_fab2_lib.baseboard_fab2(sch_1):m_e_dq(18)") )
				( member ( signalRef "@baseboard_fab2_lib.baseboard_fab2(sch_1):m_e_dq(19)") )
				( member ( signalRef "@baseboard_fab2_lib.baseboard_fab2(sch_1):m_e_dq(20)") )
				( member ( signalRef "@baseboard_fab2_lib.baseboard_fab2(sch_1):m_e_dq(21)") )
				( member ( signalRef "@baseboard_fab2_lib.baseboard_fab2(sch_1):m_e_dq(22)") )
				( member ( signalRef "@baseboard_fab2_lib.baseboard_fab2(sch_1):m_e_dq(23)") )
				( objectStatus "NG_M_E_BYTE2" )
			)
			( netGroup "@crescent_city_bb_fab1_lib.crescent_city_bb_fab1(sch_1):\NG_M_E_BYTE1\"
				( memberType ( signal ) )
				( electricalCSetRef "@crescent_city_bb_fab1_lib.crescent_city_bb_fab1(sch_1):\DDR_DQ_A\" )
				( member ( diffPairRef "@sapphirecity_baseboard_lib.sapphirecity_baseboard(sch_1):\M_E_DQS_D\(1)") )
				( member ( diffPairRef "@sapphirecity_baseboard_lib.sapphirecity_baseboard(sch_1):\M_E_DQS_D\(10)") )
				( member ( signalRef "@baseboard_fab2_lib.baseboard_fab2(sch_1):m_e_dq(8)") )
				( member ( signalRef "@baseboard_fab2_lib.baseboard_fab2(sch_1):m_e_dq(9)") )
				( member ( signalRef "@baseboard_fab2_lib.baseboard_fab2(sch_1):m_e_dq(10)") )
				( member ( signalRef "@baseboard_fab2_lib.baseboard_fab2(sch_1):m_e_dq(11)") )
				( member ( signalRef "@baseboard_fab2_lib.baseboard_fab2(sch_1):m_e_dq(12)") )
				( member ( signalRef "@baseboard_fab2_lib.baseboard_fab2(sch_1):m_e_dq(13)") )
				( member ( signalRef "@baseboard_fab2_lib.baseboard_fab2(sch_1):m_e_dq(14)") )
				( member ( signalRef "@baseboard_fab2_lib.baseboard_fab2(sch_1):m_e_dq(15)") )
				( objectStatus "NG_M_E_BYTE1" )
			)
			( netGroup "@crescent_city_bb_fab1_lib.crescent_city_bb_fab1(sch_1):\NG_M_E_BYTE0\"
				( memberType ( signal ) )
				( electricalCSetRef "@crescent_city_bb_fab1_lib.crescent_city_bb_fab1(sch_1):\DDR_DQ_A\" )
				( member ( diffPairRef "@sapphirecity_baseboard_lib.sapphirecity_baseboard(sch_1):\M_E_DQS_D\(0)") )
				( member ( diffPairRef "@sapphirecity_baseboard_lib.sapphirecity_baseboard(sch_1):\M_E_DQS_D\(9)") )
				( member ( signalRef "@baseboard_fab2_lib.baseboard_fab2(sch_1):m_e_dq(0)") )
				( member ( signalRef "@baseboard_fab2_lib.baseboard_fab2(sch_1):m_e_dq(1)") )
				( member ( signalRef "@baseboard_fab2_lib.baseboard_fab2(sch_1):m_e_dq(2)") )
				( member ( signalRef "@baseboard_fab2_lib.baseboard_fab2(sch_1):m_e_dq(3)") )
				( member ( signalRef "@baseboard_fab2_lib.baseboard_fab2(sch_1):m_e_dq(4)") )
				( member ( signalRef "@baseboard_fab2_lib.baseboard_fab2(sch_1):m_e_dq(5)") )
				( member ( signalRef "@baseboard_fab2_lib.baseboard_fab2(sch_1):m_e_dq(6)") )
				( member ( signalRef "@baseboard_fab2_lib.baseboard_fab2(sch_1):m_e_dq(7)") )
				( objectStatus "NG_M_E_BYTE0" )
			)
			( netGroup "@crescent_city_bb_fab1_lib.crescent_city_bb_fab1(sch_1):\NG_M_D_BYTE-ECC\"
				( memberType ( signal ) )
				( electricalCSetRef "@crescent_city_bb_fab1_lib.crescent_city_bb_fab1(sch_1):\DDR_DQ_A\" )
				( member ( diffPairRef "@sapphirecity_baseboard_lib.sapphirecity_baseboard(sch_1):\M_D_DQS_D\(8)") )
				( member ( diffPairRef "@sapphirecity_baseboard_lib.sapphirecity_baseboard(sch_1):\M_D_DQS_D\(17)") )
				( member ( signalRef "@baseboard_fab2_lib.baseboard_fab2(sch_1):m_d_ecc(0)") )
				( member ( signalRef "@baseboard_fab2_lib.baseboard_fab2(sch_1):m_d_ecc(1)") )
				( member ( signalRef "@baseboard_fab2_lib.baseboard_fab2(sch_1):m_d_ecc(2)") )
				( member ( signalRef "@baseboard_fab2_lib.baseboard_fab2(sch_1):m_d_ecc(3)") )
				( member ( signalRef "@baseboard_fab2_lib.baseboard_fab2(sch_1):m_d_ecc(4)") )
				( member ( signalRef "@baseboard_fab2_lib.baseboard_fab2(sch_1):m_d_ecc(5)") )
				( member ( signalRef "@baseboard_fab2_lib.baseboard_fab2(sch_1):m_d_ecc(6)") )
				( member ( signalRef "@baseboard_fab2_lib.baseboard_fab2(sch_1):m_d_ecc(7)") )
				( objectStatus "NG_M_D_BYTE-ECC" )
			)
			( netGroup "@crescent_city_bb_fab1_lib.crescent_city_bb_fab1(sch_1):\NG_M_D_BYTE7\"
				( memberType ( signal ) )
				( electricalCSetRef "@crescent_city_bb_fab1_lib.crescent_city_bb_fab1(sch_1):\DDR_DQ_A\" )
				( member ( diffPairRef "@sapphirecity_baseboard_lib.sapphirecity_baseboard(sch_1):\M_D_DQS_D\(7)") )
				( member ( diffPairRef "@sapphirecity_baseboard_lib.sapphirecity_baseboard(sch_1):\M_D_DQS_D\(16)") )
				( member ( signalRef "@baseboard_fab2_lib.baseboard_fab2(sch_1):m_d_dq(56)") )
				( member ( signalRef "@baseboard_fab2_lib.baseboard_fab2(sch_1):m_d_dq(57)") )
				( member ( signalRef "@baseboard_fab2_lib.baseboard_fab2(sch_1):m_d_dq(58)") )
				( member ( signalRef "@baseboard_fab2_lib.baseboard_fab2(sch_1):m_d_dq(59)") )
				( member ( signalRef "@baseboard_fab2_lib.baseboard_fab2(sch_1):m_d_dq(60)") )
				( member ( signalRef "@baseboard_fab2_lib.baseboard_fab2(sch_1):m_d_dq(61)") )
				( member ( signalRef "@baseboard_fab2_lib.baseboard_fab2(sch_1):m_d_dq(62)") )
				( member ( signalRef "@baseboard_fab2_lib.baseboard_fab2(sch_1):m_d_dq(63)") )
				( objectStatus "NG_M_D_BYTE7" )
			)
			( netGroup "@crescent_city_bb_fab1_lib.crescent_city_bb_fab1(sch_1):\NG_M_D_BYTE6\"
				( memberType ( signal ) )
				( electricalCSetRef "@crescent_city_bb_fab1_lib.crescent_city_bb_fab1(sch_1):\DDR_DQ_A\" )
				( member ( diffPairRef "@sapphirecity_baseboard_lib.sapphirecity_baseboard(sch_1):\M_D_DQS_D\(6)") )
				( member ( diffPairRef "@sapphirecity_baseboard_lib.sapphirecity_baseboard(sch_1):\M_D_DQS_D\(15)") )
				( member ( signalRef "@baseboard_fab2_lib.baseboard_fab2(sch_1):m_d_dq(48)") )
				( member ( signalRef "@baseboard_fab2_lib.baseboard_fab2(sch_1):m_d_dq(49)") )
				( member ( signalRef "@baseboard_fab2_lib.baseboard_fab2(sch_1):m_d_dq(50)") )
				( member ( signalRef "@baseboard_fab2_lib.baseboard_fab2(sch_1):m_d_dq(51)") )
				( member ( signalRef "@baseboard_fab2_lib.baseboard_fab2(sch_1):m_d_dq(52)") )
				( member ( signalRef "@baseboard_fab2_lib.baseboard_fab2(sch_1):m_d_dq(53)") )
				( member ( signalRef "@baseboard_fab2_lib.baseboard_fab2(sch_1):m_d_dq(54)") )
				( member ( signalRef "@baseboard_fab2_lib.baseboard_fab2(sch_1):m_d_dq(55)") )
				( objectStatus "NG_M_D_BYTE6" )
			)
			( netGroup "@crescent_city_bb_fab1_lib.crescent_city_bb_fab1(sch_1):\NG_M_D_BYTE5\"
				( memberType ( signal ) )
				( electricalCSetRef "@crescent_city_bb_fab1_lib.crescent_city_bb_fab1(sch_1):\DDR_DQ_A\" )
				( member ( diffPairRef "@sapphirecity_baseboard_lib.sapphirecity_baseboard(sch_1):\M_D_DQS_D\(5)") )
				( member ( diffPairRef "@sapphirecity_baseboard_lib.sapphirecity_baseboard(sch_1):\M_D_DQS_D\(14)") )
				( member ( signalRef "@baseboard_fab2_lib.baseboard_fab2(sch_1):m_d_dq(40)") )
				( member ( signalRef "@baseboard_fab2_lib.baseboard_fab2(sch_1):m_d_dq(41)") )
				( member ( signalRef "@baseboard_fab2_lib.baseboard_fab2(sch_1):m_d_dq(42)") )
				( member ( signalRef "@baseboard_fab2_lib.baseboard_fab2(sch_1):m_d_dq(43)") )
				( member ( signalRef "@baseboard_fab2_lib.baseboard_fab2(sch_1):m_d_dq(44)") )
				( member ( signalRef "@baseboard_fab2_lib.baseboard_fab2(sch_1):m_d_dq(45)") )
				( member ( signalRef "@baseboard_fab2_lib.baseboard_fab2(sch_1):m_d_dq(46)") )
				( member ( signalRef "@baseboard_fab2_lib.baseboard_fab2(sch_1):m_d_dq(47)") )
				( objectStatus "NG_M_D_BYTE5" )
			)
			( netGroup "@crescent_city_bb_fab1_lib.crescent_city_bb_fab1(sch_1):\NG_M_D_BYTE4\"
				( memberType ( signal ) )
				( electricalCSetRef "@crescent_city_bb_fab1_lib.crescent_city_bb_fab1(sch_1):\DDR_DQ_A\" )
				( member ( diffPairRef "@sapphirecity_baseboard_lib.sapphirecity_baseboard(sch_1):\M_D_DQS_D\(4)") )
				( member ( diffPairRef "@sapphirecity_baseboard_lib.sapphirecity_baseboard(sch_1):\M_D_DQS_D\(13)") )
				( member ( signalRef "@baseboard_fab2_lib.baseboard_fab2(sch_1):m_d_dq(32)") )
				( member ( signalRef "@baseboard_fab2_lib.baseboard_fab2(sch_1):m_d_dq(33)") )
				( member ( signalRef "@baseboard_fab2_lib.baseboard_fab2(sch_1):m_d_dq(34)") )
				( member ( signalRef "@baseboard_fab2_lib.baseboard_fab2(sch_1):m_d_dq(35)") )
				( member ( signalRef "@baseboard_fab2_lib.baseboard_fab2(sch_1):m_d_dq(36)") )
				( member ( signalRef "@baseboard_fab2_lib.baseboard_fab2(sch_1):m_d_dq(37)") )
				( member ( signalRef "@baseboard_fab2_lib.baseboard_fab2(sch_1):m_d_dq(38)") )
				( member ( signalRef "@baseboard_fab2_lib.baseboard_fab2(sch_1):m_d_dq(39)") )
				( objectStatus "NG_M_D_BYTE4" )
			)
			( netGroup "@crescent_city_bb_fab1_lib.crescent_city_bb_fab1(sch_1):\NG_M_D_BYTE3\"
				( memberType ( signal ) )
				( electricalCSetRef "@crescent_city_bb_fab1_lib.crescent_city_bb_fab1(sch_1):\DDR_DQ_A\" )
				( member ( diffPairRef "@sapphirecity_baseboard_lib.sapphirecity_baseboard(sch_1):\M_D_DQS_D\(3)") )
				( member ( diffPairRef "@sapphirecity_baseboard_lib.sapphirecity_baseboard(sch_1):\M_D_DQS_D\(12)") )
				( member ( signalRef "@baseboard_fab2_lib.baseboard_fab2(sch_1):m_d_dq(24)") )
				( member ( signalRef "@baseboard_fab2_lib.baseboard_fab2(sch_1):m_d_dq(25)") )
				( member ( signalRef "@baseboard_fab2_lib.baseboard_fab2(sch_1):m_d_dq(26)") )
				( member ( signalRef "@baseboard_fab2_lib.baseboard_fab2(sch_1):m_d_dq(27)") )
				( member ( signalRef "@baseboard_fab2_lib.baseboard_fab2(sch_1):m_d_dq(28)") )
				( member ( signalRef "@baseboard_fab2_lib.baseboard_fab2(sch_1):m_d_dq(29)") )
				( member ( signalRef "@baseboard_fab2_lib.baseboard_fab2(sch_1):m_d_dq(30)") )
				( member ( signalRef "@baseboard_fab2_lib.baseboard_fab2(sch_1):m_d_dq(31)") )
				( objectStatus "NG_M_D_BYTE3" )
			)
			( netGroup "@crescent_city_bb_fab1_lib.crescent_city_bb_fab1(sch_1):\NG_M_D_BYTE2\"
				( memberType ( signal ) )
				( electricalCSetRef "@crescent_city_bb_fab1_lib.crescent_city_bb_fab1(sch_1):\DDR_DQ_A\" )
				( member ( diffPairRef "@sapphirecity_baseboard_lib.sapphirecity_baseboard(sch_1):\M_D_DQS_D\(2)") )
				( member ( diffPairRef "@sapphirecity_baseboard_lib.sapphirecity_baseboard(sch_1):\M_D_DQS_D\(11)") )
				( member ( signalRef "@baseboard_fab2_lib.baseboard_fab2(sch_1):m_d_dq(16)") )
				( member ( signalRef "@baseboard_fab2_lib.baseboard_fab2(sch_1):m_d_dq(17)") )
				( member ( signalRef "@baseboard_fab2_lib.baseboard_fab2(sch_1):m_d_dq(18)") )
				( member ( signalRef "@baseboard_fab2_lib.baseboard_fab2(sch_1):m_d_dq(19)") )
				( member ( signalRef "@baseboard_fab2_lib.baseboard_fab2(sch_1):m_d_dq(20)") )
				( member ( signalRef "@baseboard_fab2_lib.baseboard_fab2(sch_1):m_d_dq(21)") )
				( member ( signalRef "@baseboard_fab2_lib.baseboard_fab2(sch_1):m_d_dq(22)") )
				( member ( signalRef "@baseboard_fab2_lib.baseboard_fab2(sch_1):m_d_dq(23)") )
				( objectStatus "NG_M_D_BYTE2" )
			)
			( netGroup "@crescent_city_bb_fab1_lib.crescent_city_bb_fab1(sch_1):\NG_M_D_BYTE1\"
				( memberType ( signal ) )
				( electricalCSetRef "@crescent_city_bb_fab1_lib.crescent_city_bb_fab1(sch_1):\DDR_DQ_A\" )
				( member ( diffPairRef "@sapphirecity_baseboard_lib.sapphirecity_baseboard(sch_1):\M_D_DQS_D\(1)") )
				( member ( diffPairRef "@sapphirecity_baseboard_lib.sapphirecity_baseboard(sch_1):\M_D_DQS_D\(10)") )
				( member ( signalRef "@baseboard_fab2_lib.baseboard_fab2(sch_1):m_d_dq(8)") )
				( member ( signalRef "@baseboard_fab2_lib.baseboard_fab2(sch_1):m_d_dq(9)") )
				( member ( signalRef "@baseboard_fab2_lib.baseboard_fab2(sch_1):m_d_dq(10)") )
				( member ( signalRef "@baseboard_fab2_lib.baseboard_fab2(sch_1):m_d_dq(11)") )
				( member ( signalRef "@baseboard_fab2_lib.baseboard_fab2(sch_1):m_d_dq(12)") )
				( member ( signalRef "@baseboard_fab2_lib.baseboard_fab2(sch_1):m_d_dq(13)") )
				( member ( signalRef "@baseboard_fab2_lib.baseboard_fab2(sch_1):m_d_dq(14)") )
				( member ( signalRef "@baseboard_fab2_lib.baseboard_fab2(sch_1):m_d_dq(15)") )
				( objectStatus "NG_M_D_BYTE1" )
			)
			( netGroup "@crescent_city_bb_fab1_lib.crescent_city_bb_fab1(sch_1):\NG_M_D_BYTE0\"
				( memberType ( signal ) )
				( electricalCSetRef "@crescent_city_bb_fab1_lib.crescent_city_bb_fab1(sch_1):\DDR_DQ_A\" )
				( member ( diffPairRef "@sapphirecity_baseboard_lib.sapphirecity_baseboard(sch_1):\M_D_DQS_D\(0)") )
				( member ( diffPairRef "@sapphirecity_baseboard_lib.sapphirecity_baseboard(sch_1):\M_D_DQS_D\(9)") )
				( member ( signalRef "@baseboard_fab2_lib.baseboard_fab2(sch_1):m_d_dq(0)") )
				( member ( signalRef "@baseboard_fab2_lib.baseboard_fab2(sch_1):m_d_dq(1)") )
				( member ( signalRef "@baseboard_fab2_lib.baseboard_fab2(sch_1):m_d_dq(2)") )
				( member ( signalRef "@baseboard_fab2_lib.baseboard_fab2(sch_1):m_d_dq(3)") )
				( member ( signalRef "@baseboard_fab2_lib.baseboard_fab2(sch_1):m_d_dq(4)") )
				( member ( signalRef "@baseboard_fab2_lib.baseboard_fab2(sch_1):m_d_dq(5)") )
				( member ( signalRef "@baseboard_fab2_lib.baseboard_fab2(sch_1):m_d_dq(6)") )
				( member ( signalRef "@baseboard_fab2_lib.baseboard_fab2(sch_1):m_d_dq(7)") )
				( objectStatus "NG_M_D_BYTE0" )
			)
			( netGroup "@crescent_city_bb_fab1_lib.crescent_city_bb_fab1(sch_1):\NG_M_C_BYTE7\"
				( memberType ( signal ) )
				( electricalCSetRef "@crescent_city_bb_fab1_lib.crescent_city_bb_fab1(sch_1):\DDR_DQ_A\" )
				( member ( diffPairRef "@sapphirecity_baseboard_lib.sapphirecity_baseboard(sch_1):\M_C_DQS_D\(7)") )
				( member ( diffPairRef "@sapphirecity_baseboard_lib.sapphirecity_baseboard(sch_1):\M_C_DQS_D\(16)") )
				( member ( signalRef "@baseboard_fab2_lib.baseboard_fab2(sch_1):m_c_dq(56)") )
				( member ( signalRef "@baseboard_fab2_lib.baseboard_fab2(sch_1):m_c_dq(57)") )
				( member ( signalRef "@baseboard_fab2_lib.baseboard_fab2(sch_1):m_c_dq(58)") )
				( member ( signalRef "@baseboard_fab2_lib.baseboard_fab2(sch_1):m_c_dq(59)") )
				( member ( signalRef "@baseboard_fab2_lib.baseboard_fab2(sch_1):m_c_dq(60)") )
				( member ( signalRef "@baseboard_fab2_lib.baseboard_fab2(sch_1):m_c_dq(61)") )
				( member ( signalRef "@baseboard_fab2_lib.baseboard_fab2(sch_1):m_c_dq(62)") )
				( member ( signalRef "@baseboard_fab2_lib.baseboard_fab2(sch_1):m_c_dq(63)") )
				( objectStatus "NG_M_C_BYTE7" )
			)
			( netGroup "@crescent_city_bb_fab1_lib.crescent_city_bb_fab1(sch_1):\NG_M_C_BYTE6\"
				( memberType ( signal ) )
				( electricalCSetRef "@crescent_city_bb_fab1_lib.crescent_city_bb_fab1(sch_1):\DDR_DQ_A\" )
				( member ( diffPairRef "@sapphirecity_baseboard_lib.sapphirecity_baseboard(sch_1):\M_C_DQS_D\(6)") )
				( member ( diffPairRef "@sapphirecity_baseboard_lib.sapphirecity_baseboard(sch_1):\M_C_DQS_D\(15)") )
				( member ( signalRef "@baseboard_fab2_lib.baseboard_fab2(sch_1):m_c_dq(48)") )
				( member ( signalRef "@baseboard_fab2_lib.baseboard_fab2(sch_1):m_c_dq(49)") )
				( member ( signalRef "@baseboard_fab2_lib.baseboard_fab2(sch_1):m_c_dq(50)") )
				( member ( signalRef "@baseboard_fab2_lib.baseboard_fab2(sch_1):m_c_dq(51)") )
				( member ( signalRef "@baseboard_fab2_lib.baseboard_fab2(sch_1):m_c_dq(52)") )
				( member ( signalRef "@baseboard_fab2_lib.baseboard_fab2(sch_1):m_c_dq(53)") )
				( member ( signalRef "@baseboard_fab2_lib.baseboard_fab2(sch_1):m_c_dq(54)") )
				( member ( signalRef "@baseboard_fab2_lib.baseboard_fab2(sch_1):m_c_dq(55)") )
				( objectStatus "NG_M_C_BYTE6" )
			)
			( netGroup "@crescent_city_bb_fab1_lib.crescent_city_bb_fab1(sch_1):\NG_M_C_BYTE5\"
				( memberType ( signal ) )
				( electricalCSetRef "@crescent_city_bb_fab1_lib.crescent_city_bb_fab1(sch_1):\DDR_DQ_A\" )
				( member ( diffPairRef "@sapphirecity_baseboard_lib.sapphirecity_baseboard(sch_1):\M_C_DQS_D\(5)") )
				( member ( diffPairRef "@sapphirecity_baseboard_lib.sapphirecity_baseboard(sch_1):\M_C_DQS_D\(14)") )
				( member ( signalRef "@baseboard_fab2_lib.baseboard_fab2(sch_1):m_c_dq(40)") )
				( member ( signalRef "@baseboard_fab2_lib.baseboard_fab2(sch_1):m_c_dq(41)") )
				( member ( signalRef "@baseboard_fab2_lib.baseboard_fab2(sch_1):m_c_dq(42)") )
				( member ( signalRef "@baseboard_fab2_lib.baseboard_fab2(sch_1):m_c_dq(43)") )
				( member ( signalRef "@baseboard_fab2_lib.baseboard_fab2(sch_1):m_c_dq(44)") )
				( member ( signalRef "@baseboard_fab2_lib.baseboard_fab2(sch_1):m_c_dq(45)") )
				( member ( signalRef "@baseboard_fab2_lib.baseboard_fab2(sch_1):m_c_dq(46)") )
				( member ( signalRef "@baseboard_fab2_lib.baseboard_fab2(sch_1):m_c_dq(47)") )
				( objectStatus "NG_M_C_BYTE5" )
			)
			( netGroup "@crescent_city_bb_fab1_lib.crescent_city_bb_fab1(sch_1):\NG_M_C_BYTE4\"
				( memberType ( signal ) )
				( electricalCSetRef "@crescent_city_bb_fab1_lib.crescent_city_bb_fab1(sch_1):\DDR_DQ_A\" )
				( member ( diffPairRef "@sapphirecity_baseboard_lib.sapphirecity_baseboard(sch_1):\M_C_DQS_D\(4)") )
				( member ( diffPairRef "@sapphirecity_baseboard_lib.sapphirecity_baseboard(sch_1):\M_C_DQS_D\(13)") )
				( member ( signalRef "@baseboard_fab2_lib.baseboard_fab2(sch_1):m_c_dq(32)") )
				( member ( signalRef "@baseboard_fab2_lib.baseboard_fab2(sch_1):m_c_dq(33)") )
				( member ( signalRef "@baseboard_fab2_lib.baseboard_fab2(sch_1):m_c_dq(34)") )
				( member ( signalRef "@baseboard_fab2_lib.baseboard_fab2(sch_1):m_c_dq(35)") )
				( member ( signalRef "@baseboard_fab2_lib.baseboard_fab2(sch_1):m_c_dq(36)") )
				( member ( signalRef "@baseboard_fab2_lib.baseboard_fab2(sch_1):m_c_dq(37)") )
				( member ( signalRef "@baseboard_fab2_lib.baseboard_fab2(sch_1):m_c_dq(38)") )
				( member ( signalRef "@baseboard_fab2_lib.baseboard_fab2(sch_1):m_c_dq(39)") )
				( objectStatus "NG_M_C_BYTE4" )
			)
			( netGroup "@crescent_city_bb_fab1_lib.crescent_city_bb_fab1(sch_1):\NG_M_C_BYTE3\"
				( memberType ( signal ) )
				( electricalCSetRef "@crescent_city_bb_fab1_lib.crescent_city_bb_fab1(sch_1):\DDR_DQ_A\" )
				( member ( diffPairRef "@sapphirecity_baseboard_lib.sapphirecity_baseboard(sch_1):\M_C_DQS_D\(3)") )
				( member ( diffPairRef "@sapphirecity_baseboard_lib.sapphirecity_baseboard(sch_1):\M_C_DQS_D\(12)") )
				( member ( signalRef "@baseboard_fab2_lib.baseboard_fab2(sch_1):m_c_dq(24)") )
				( member ( signalRef "@baseboard_fab2_lib.baseboard_fab2(sch_1):m_c_dq(25)") )
				( member ( signalRef "@baseboard_fab2_lib.baseboard_fab2(sch_1):m_c_dq(26)") )
				( member ( signalRef "@baseboard_fab2_lib.baseboard_fab2(sch_1):m_c_dq(27)") )
				( member ( signalRef "@baseboard_fab2_lib.baseboard_fab2(sch_1):m_c_dq(28)") )
				( member ( signalRef "@baseboard_fab2_lib.baseboard_fab2(sch_1):m_c_dq(29)") )
				( member ( signalRef "@baseboard_fab2_lib.baseboard_fab2(sch_1):m_c_dq(30)") )
				( member ( signalRef "@baseboard_fab2_lib.baseboard_fab2(sch_1):m_c_dq(31)") )
				( objectStatus "NG_M_C_BYTE3" )
			)
			( netGroup "@crescent_city_bb_fab1_lib.crescent_city_bb_fab1(sch_1):\NG_M_C_BYTE2\"
				( memberType ( signal ) )
				( electricalCSetRef "@crescent_city_bb_fab1_lib.crescent_city_bb_fab1(sch_1):\DDR_DQ_A\" )
				( member ( diffPairRef "@sapphirecity_baseboard_lib.sapphirecity_baseboard(sch_1):\M_C_DQS_D\(2)") )
				( member ( diffPairRef "@sapphirecity_baseboard_lib.sapphirecity_baseboard(sch_1):\M_C_DQS_D\(11)") )
				( member ( signalRef "@baseboard_fab2_lib.baseboard_fab2(sch_1):m_c_dq(16)") )
				( member ( signalRef "@baseboard_fab2_lib.baseboard_fab2(sch_1):m_c_dq(17)") )
				( member ( signalRef "@baseboard_fab2_lib.baseboard_fab2(sch_1):m_c_dq(18)") )
				( member ( signalRef "@baseboard_fab2_lib.baseboard_fab2(sch_1):m_c_dq(19)") )
				( member ( signalRef "@baseboard_fab2_lib.baseboard_fab2(sch_1):m_c_dq(20)") )
				( member ( signalRef "@baseboard_fab2_lib.baseboard_fab2(sch_1):m_c_dq(21)") )
				( member ( signalRef "@baseboard_fab2_lib.baseboard_fab2(sch_1):m_c_dq(22)") )
				( member ( signalRef "@baseboard_fab2_lib.baseboard_fab2(sch_1):m_c_dq(23)") )
				( objectStatus "NG_M_C_BYTE2" )
			)
			( netGroup "@crescent_city_bb_fab1_lib.crescent_city_bb_fab1(sch_1):\NG_M_C_BYTE1\"
				( memberType ( signal ) )
				( electricalCSetRef "@crescent_city_bb_fab1_lib.crescent_city_bb_fab1(sch_1):\DDR_DQ_A\" )
				( member ( diffPairRef "@sapphirecity_baseboard_lib.sapphirecity_baseboard(sch_1):\M_C_DQS_D\(1)") )
				( member ( diffPairRef "@sapphirecity_baseboard_lib.sapphirecity_baseboard(sch_1):\M_C_DQS_D\(10)") )
				( member ( signalRef "@baseboard_fab2_lib.baseboard_fab2(sch_1):m_c_dq(8)") )
				( member ( signalRef "@baseboard_fab2_lib.baseboard_fab2(sch_1):m_c_dq(9)") )
				( member ( signalRef "@baseboard_fab2_lib.baseboard_fab2(sch_1):m_c_dq(10)") )
				( member ( signalRef "@baseboard_fab2_lib.baseboard_fab2(sch_1):m_c_dq(11)") )
				( member ( signalRef "@baseboard_fab2_lib.baseboard_fab2(sch_1):m_c_dq(12)") )
				( member ( signalRef "@baseboard_fab2_lib.baseboard_fab2(sch_1):m_c_dq(13)") )
				( member ( signalRef "@baseboard_fab2_lib.baseboard_fab2(sch_1):m_c_dq(14)") )
				( member ( signalRef "@baseboard_fab2_lib.baseboard_fab2(sch_1):m_c_dq(15)") )
				( objectStatus "NG_M_C_BYTE1" )
			)
			( netGroup "@crescent_city_bb_fab1_lib.crescent_city_bb_fab1(sch_1):\NG_M_C_BYTE0\"
				( memberType ( signal ) )
				( electricalCSetRef "@crescent_city_bb_fab1_lib.crescent_city_bb_fab1(sch_1):\DDR_DQ_A\" )
				( member ( diffPairRef "@sapphirecity_baseboard_lib.sapphirecity_baseboard(sch_1):\M_C_DQS_D\(0)") )
				( member ( diffPairRef "@sapphirecity_baseboard_lib.sapphirecity_baseboard(sch_1):\M_C_DQS_D\(9)") )
				( member ( signalRef "@baseboard_fab2_lib.baseboard_fab2(sch_1):m_c_dq(0)") )
				( member ( signalRef "@baseboard_fab2_lib.baseboard_fab2(sch_1):m_c_dq(1)") )
				( member ( signalRef "@baseboard_fab2_lib.baseboard_fab2(sch_1):m_c_dq(2)") )
				( member ( signalRef "@baseboard_fab2_lib.baseboard_fab2(sch_1):m_c_dq(3)") )
				( member ( signalRef "@baseboard_fab2_lib.baseboard_fab2(sch_1):m_c_dq(4)") )
				( member ( signalRef "@baseboard_fab2_lib.baseboard_fab2(sch_1):m_c_dq(5)") )
				( member ( signalRef "@baseboard_fab2_lib.baseboard_fab2(sch_1):m_c_dq(6)") )
				( member ( signalRef "@baseboard_fab2_lib.baseboard_fab2(sch_1):m_c_dq(7)") )
				( objectStatus "NG_M_C_BYTE0" )
			)
			( netGroup "@crescent_city_bb_fab1_lib.crescent_city_bb_fab1(sch_1):\NG_M_C_BYTE-ECC\"
				( memberType ( signal ) )
				( electricalCSetRef "@crescent_city_bb_fab1_lib.crescent_city_bb_fab1(sch_1):\DDR_DQ_A\" )
				( member ( diffPairRef "@sapphirecity_baseboard_lib.sapphirecity_baseboard(sch_1):\M_C_DQS_D\(8)") )
				( member ( diffPairRef "@sapphirecity_baseboard_lib.sapphirecity_baseboard(sch_1):\M_C_DQS_D\(17)") )
				( member ( signalRef "@baseboard_fab2_lib.baseboard_fab2(sch_1):m_c_ecc(0)") )
				( member ( signalRef "@baseboard_fab2_lib.baseboard_fab2(sch_1):m_c_ecc(1)") )
				( member ( signalRef "@baseboard_fab2_lib.baseboard_fab2(sch_1):m_c_ecc(2)") )
				( member ( signalRef "@baseboard_fab2_lib.baseboard_fab2(sch_1):m_c_ecc(3)") )
				( member ( signalRef "@baseboard_fab2_lib.baseboard_fab2(sch_1):m_c_ecc(4)") )
				( member ( signalRef "@baseboard_fab2_lib.baseboard_fab2(sch_1):m_c_ecc(5)") )
				( member ( signalRef "@baseboard_fab2_lib.baseboard_fab2(sch_1):m_c_ecc(6)") )
				( member ( signalRef "@baseboard_fab2_lib.baseboard_fab2(sch_1):m_c_ecc(7)") )
				( objectStatus "NG_M_C_BYTE-ECC" )
			)
			( netGroup "@crescent_city_bb_fab1_lib.crescent_city_bb_fab1(sch_1):\NG_M_B_BYTE7\"
				( memberType ( signal ) )
				( electricalCSetRef "@crescent_city_bb_fab1_lib.crescent_city_bb_fab1(sch_1):\DDR_DQ_A\" )
				( member ( diffPairRef "@sapphirecity_baseboard_lib.sapphirecity_baseboard(sch_1):\M_B_DQS_D\(7)") )
				( member ( diffPairRef "@sapphirecity_baseboard_lib.sapphirecity_baseboard(sch_1):\M_B_DQS_D\(16)") )
				( member ( signalRef "@baseboard_fab2_lib.baseboard_fab2(sch_1):m_b_dq(56)") )
				( member ( signalRef "@baseboard_fab2_lib.baseboard_fab2(sch_1):m_b_dq(57)") )
				( member ( signalRef "@baseboard_fab2_lib.baseboard_fab2(sch_1):m_b_dq(58)") )
				( member ( signalRef "@baseboard_fab2_lib.baseboard_fab2(sch_1):m_b_dq(59)") )
				( member ( signalRef "@baseboard_fab2_lib.baseboard_fab2(sch_1):m_b_dq(60)") )
				( member ( signalRef "@baseboard_fab2_lib.baseboard_fab2(sch_1):m_b_dq(61)") )
				( member ( signalRef "@baseboard_fab2_lib.baseboard_fab2(sch_1):m_b_dq(62)") )
				( member ( signalRef "@baseboard_fab2_lib.baseboard_fab2(sch_1):m_b_dq(63)") )
				( objectStatus "NG_M_B_BYTE7" )
			)
			( netGroup "@crescent_city_bb_fab1_lib.crescent_city_bb_fab1(sch_1):\NG_M_B_BYTE6\"
				( memberType ( signal ) )
				( electricalCSetRef "@crescent_city_bb_fab1_lib.crescent_city_bb_fab1(sch_1):\DDR_DQ_A\" )
				( member ( diffPairRef "@sapphirecity_baseboard_lib.sapphirecity_baseboard(sch_1):\M_B_DQS_D\(6)") )
				( member ( diffPairRef "@sapphirecity_baseboard_lib.sapphirecity_baseboard(sch_1):\M_B_DQS_D\(15)") )
				( member ( signalRef "@baseboard_fab2_lib.baseboard_fab2(sch_1):m_b_dq(48)") )
				( member ( signalRef "@baseboard_fab2_lib.baseboard_fab2(sch_1):m_b_dq(49)") )
				( member ( signalRef "@baseboard_fab2_lib.baseboard_fab2(sch_1):m_b_dq(50)") )
				( member ( signalRef "@baseboard_fab2_lib.baseboard_fab2(sch_1):m_b_dq(51)") )
				( member ( signalRef "@baseboard_fab2_lib.baseboard_fab2(sch_1):m_b_dq(52)") )
				( member ( signalRef "@baseboard_fab2_lib.baseboard_fab2(sch_1):m_b_dq(53)") )
				( member ( signalRef "@baseboard_fab2_lib.baseboard_fab2(sch_1):m_b_dq(54)") )
				( member ( signalRef "@baseboard_fab2_lib.baseboard_fab2(sch_1):m_b_dq(55)") )
				( objectStatus "NG_M_B_BYTE6" )
			)
			( netGroup "@crescent_city_bb_fab1_lib.crescent_city_bb_fab1(sch_1):\NG_M_B_BYTE5\"
				( memberType ( signal ) )
				( electricalCSetRef "@crescent_city_bb_fab1_lib.crescent_city_bb_fab1(sch_1):\DDR_DQ_A\" )
				( member ( diffPairRef "@sapphirecity_baseboard_lib.sapphirecity_baseboard(sch_1):\M_B_DQS_D\(5)") )
				( member ( diffPairRef "@sapphirecity_baseboard_lib.sapphirecity_baseboard(sch_1):\M_B_DQS_D\(14)") )
				( member ( signalRef "@baseboard_fab2_lib.baseboard_fab2(sch_1):m_b_dq(40)") )
				( member ( signalRef "@baseboard_fab2_lib.baseboard_fab2(sch_1):m_b_dq(41)") )
				( member ( signalRef "@baseboard_fab2_lib.baseboard_fab2(sch_1):m_b_dq(42)") )
				( member ( signalRef "@baseboard_fab2_lib.baseboard_fab2(sch_1):m_b_dq(43)") )
				( member ( signalRef "@baseboard_fab2_lib.baseboard_fab2(sch_1):m_b_dq(44)") )
				( member ( signalRef "@baseboard_fab2_lib.baseboard_fab2(sch_1):m_b_dq(45)") )
				( member ( signalRef "@baseboard_fab2_lib.baseboard_fab2(sch_1):m_b_dq(46)") )
				( member ( signalRef "@baseboard_fab2_lib.baseboard_fab2(sch_1):m_b_dq(47)") )
				( objectStatus "NG_M_B_BYTE5" )
			)
			( netGroup "@crescent_city_bb_fab1_lib.crescent_city_bb_fab1(sch_1):\NG_M_B_BYTE4\"
				( memberType ( signal ) )
				( electricalCSetRef "@crescent_city_bb_fab1_lib.crescent_city_bb_fab1(sch_1):\DDR_DQ_A\" )
				( member ( diffPairRef "@sapphirecity_baseboard_lib.sapphirecity_baseboard(sch_1):\M_B_DQS_D\(4)") )
				( member ( diffPairRef "@sapphirecity_baseboard_lib.sapphirecity_baseboard(sch_1):\M_B_DQS_D\(13)") )
				( member ( signalRef "@baseboard_fab2_lib.baseboard_fab2(sch_1):m_b_dq(32)") )
				( member ( signalRef "@baseboard_fab2_lib.baseboard_fab2(sch_1):m_b_dq(33)") )
				( member ( signalRef "@baseboard_fab2_lib.baseboard_fab2(sch_1):m_b_dq(34)") )
				( member ( signalRef "@baseboard_fab2_lib.baseboard_fab2(sch_1):m_b_dq(35)") )
				( member ( signalRef "@baseboard_fab2_lib.baseboard_fab2(sch_1):m_b_dq(36)") )
				( member ( signalRef "@baseboard_fab2_lib.baseboard_fab2(sch_1):m_b_dq(37)") )
				( member ( signalRef "@baseboard_fab2_lib.baseboard_fab2(sch_1):m_b_dq(38)") )
				( member ( signalRef "@baseboard_fab2_lib.baseboard_fab2(sch_1):m_b_dq(39)") )
				( objectStatus "NG_M_B_BYTE4" )
			)
			( netGroup "@crescent_city_bb_fab1_lib.crescent_city_bb_fab1(sch_1):\NG_M_B_BYTE3\"
				( memberType ( signal ) )
				( electricalCSetRef "@crescent_city_bb_fab1_lib.crescent_city_bb_fab1(sch_1):\DDR_DQ_A\" )
				( member ( diffPairRef "@sapphirecity_baseboard_lib.sapphirecity_baseboard(sch_1):\M_B_DQS_D\(3)") )
				( member ( diffPairRef "@sapphirecity_baseboard_lib.sapphirecity_baseboard(sch_1):\M_B_DQS_D\(12)") )
				( member ( signalRef "@baseboard_fab2_lib.baseboard_fab2(sch_1):m_b_dq(24)") )
				( member ( signalRef "@baseboard_fab2_lib.baseboard_fab2(sch_1):m_b_dq(25)") )
				( member ( signalRef "@baseboard_fab2_lib.baseboard_fab2(sch_1):m_b_dq(26)") )
				( member ( signalRef "@baseboard_fab2_lib.baseboard_fab2(sch_1):m_b_dq(27)") )
				( member ( signalRef "@baseboard_fab2_lib.baseboard_fab2(sch_1):m_b_dq(28)") )
				( member ( signalRef "@baseboard_fab2_lib.baseboard_fab2(sch_1):m_b_dq(29)") )
				( member ( signalRef "@baseboard_fab2_lib.baseboard_fab2(sch_1):m_b_dq(30)") )
				( member ( signalRef "@baseboard_fab2_lib.baseboard_fab2(sch_1):m_b_dq(31)") )
				( objectStatus "NG_M_B_BYTE3" )
			)
			( netGroup "@crescent_city_bb_fab1_lib.crescent_city_bb_fab1(sch_1):\NG_M_B_BYTE2\"
				( memberType ( signal ) )
				( electricalCSetRef "@crescent_city_bb_fab1_lib.crescent_city_bb_fab1(sch_1):\DDR_DQ_A\" )
				( member ( diffPairRef "@sapphirecity_baseboard_lib.sapphirecity_baseboard(sch_1):\M_B_DQS_D\(2)") )
				( member ( diffPairRef "@sapphirecity_baseboard_lib.sapphirecity_baseboard(sch_1):\M_B_DQS_D\(11)") )
				( member ( signalRef "@baseboard_fab2_lib.baseboard_fab2(sch_1):m_b_dq(16)") )
				( member ( signalRef "@baseboard_fab2_lib.baseboard_fab2(sch_1):m_b_dq(17)") )
				( member ( signalRef "@baseboard_fab2_lib.baseboard_fab2(sch_1):m_b_dq(18)") )
				( member ( signalRef "@baseboard_fab2_lib.baseboard_fab2(sch_1):m_b_dq(19)") )
				( member ( signalRef "@baseboard_fab2_lib.baseboard_fab2(sch_1):m_b_dq(20)") )
				( member ( signalRef "@baseboard_fab2_lib.baseboard_fab2(sch_1):m_b_dq(21)") )
				( member ( signalRef "@baseboard_fab2_lib.baseboard_fab2(sch_1):m_b_dq(22)") )
				( member ( signalRef "@baseboard_fab2_lib.baseboard_fab2(sch_1):m_b_dq(23)") )
				( objectStatus "NG_M_B_BYTE2" )
			)
			( netGroup "@crescent_city_bb_fab1_lib.crescent_city_bb_fab1(sch_1):\NG_M_B_BYTE1\"
				( memberType ( signal ) )
				( electricalCSetRef "@crescent_city_bb_fab1_lib.crescent_city_bb_fab1(sch_1):\DDR_DQ_A\" )
				( member ( diffPairRef "@sapphirecity_baseboard_lib.sapphirecity_baseboard(sch_1):\M_B_DQS_D\(1)") )
				( member ( diffPairRef "@sapphirecity_baseboard_lib.sapphirecity_baseboard(sch_1):\M_B_DQS_D\(10)") )
				( member ( signalRef "@baseboard_fab2_lib.baseboard_fab2(sch_1):m_b_dq(8)") )
				( member ( signalRef "@baseboard_fab2_lib.baseboard_fab2(sch_1):m_b_dq(9)") )
				( member ( signalRef "@baseboard_fab2_lib.baseboard_fab2(sch_1):m_b_dq(10)") )
				( member ( signalRef "@baseboard_fab2_lib.baseboard_fab2(sch_1):m_b_dq(11)") )
				( member ( signalRef "@baseboard_fab2_lib.baseboard_fab2(sch_1):m_b_dq(12)") )
				( member ( signalRef "@baseboard_fab2_lib.baseboard_fab2(sch_1):m_b_dq(13)") )
				( member ( signalRef "@baseboard_fab2_lib.baseboard_fab2(sch_1):m_b_dq(14)") )
				( member ( signalRef "@baseboard_fab2_lib.baseboard_fab2(sch_1):m_b_dq(15)") )
				( objectStatus "NG_M_B_BYTE1" )
			)
			( netGroup "@crescent_city_bb_fab1_lib.crescent_city_bb_fab1(sch_1):\NG_M_B_BYTE0\"
				( memberType ( signal ) )
				( electricalCSetRef "@crescent_city_bb_fab1_lib.crescent_city_bb_fab1(sch_1):\DDR_DQ_A\" )
				( member ( diffPairRef "@sapphirecity_baseboard_lib.sapphirecity_baseboard(sch_1):\M_B_DQS_D\(0)") )
				( member ( diffPairRef "@sapphirecity_baseboard_lib.sapphirecity_baseboard(sch_1):\M_B_DQS_D\(9)") )
				( member ( signalRef "@baseboard_fab2_lib.baseboard_fab2(sch_1):m_b_dq(0)") )
				( member ( signalRef "@baseboard_fab2_lib.baseboard_fab2(sch_1):m_b_dq(1)") )
				( member ( signalRef "@baseboard_fab2_lib.baseboard_fab2(sch_1):m_b_dq(2)") )
				( member ( signalRef "@baseboard_fab2_lib.baseboard_fab2(sch_1):m_b_dq(3)") )
				( member ( signalRef "@baseboard_fab2_lib.baseboard_fab2(sch_1):m_b_dq(4)") )
				( member ( signalRef "@baseboard_fab2_lib.baseboard_fab2(sch_1):m_b_dq(5)") )
				( member ( signalRef "@baseboard_fab2_lib.baseboard_fab2(sch_1):m_b_dq(6)") )
				( member ( signalRef "@baseboard_fab2_lib.baseboard_fab2(sch_1):m_b_dq(7)") )
				( objectStatus "NG_M_B_BYTE0" )
			)
			( netGroup "@crescent_city_bb_fab1_lib.crescent_city_bb_fab1(sch_1):\NG_M_B_BYTE-ECC\"
				( memberType ( signal ) )
				( electricalCSetRef "@crescent_city_bb_fab1_lib.crescent_city_bb_fab1(sch_1):\DDR_DQ_A\" )
				( member ( diffPairRef "@sapphirecity_baseboard_lib.sapphirecity_baseboard(sch_1):\M_B_DQS_D\(8)") )
				( member ( diffPairRef "@sapphirecity_baseboard_lib.sapphirecity_baseboard(sch_1):\M_B_DQS_D\(17)") )
				( member ( signalRef "@baseboard_fab2_lib.baseboard_fab2(sch_1):m_b_ecc(0)") )
				( member ( signalRef "@baseboard_fab2_lib.baseboard_fab2(sch_1):m_b_ecc(1)") )
				( member ( signalRef "@baseboard_fab2_lib.baseboard_fab2(sch_1):m_b_ecc(2)") )
				( member ( signalRef "@baseboard_fab2_lib.baseboard_fab2(sch_1):m_b_ecc(3)") )
				( member ( signalRef "@baseboard_fab2_lib.baseboard_fab2(sch_1):m_b_ecc(4)") )
				( member ( signalRef "@baseboard_fab2_lib.baseboard_fab2(sch_1):m_b_ecc(5)") )
				( member ( signalRef "@baseboard_fab2_lib.baseboard_fab2(sch_1):m_b_ecc(6)") )
				( member ( signalRef "@baseboard_fab2_lib.baseboard_fab2(sch_1):m_b_ecc(7)") )
				( objectStatus "NG_M_B_BYTE-ECC" )
			)
			( netGroup "@crescent_city_bb_fab1_lib.crescent_city_bb_fab1(sch_1):\NG_M_A_BYTE-ECC\"
				( memberType ( signal ) )
				( electricalCSetRef "@crescent_city_bb_fab1_lib.crescent_city_bb_fab1(sch_1):\DDR_DQ_A\" )
				( member ( diffPairRef "@sapphirecity_baseboard_lib.sapphirecity_baseboard(sch_1):\M_A_DQS_D\(8)") )
				( member ( diffPairRef "@sapphirecity_baseboard_lib.sapphirecity_baseboard(sch_1):\M_A_DQS_D\(17)") )
				( member ( signalRef "@baseboard_fab2_lib.baseboard_fab2(sch_1):m_a_ecc(0)") )
				( member ( signalRef "@baseboard_fab2_lib.baseboard_fab2(sch_1):m_a_ecc(1)") )
				( member ( signalRef "@baseboard_fab2_lib.baseboard_fab2(sch_1):m_a_ecc(2)") )
				( member ( signalRef "@baseboard_fab2_lib.baseboard_fab2(sch_1):m_a_ecc(3)") )
				( member ( signalRef "@baseboard_fab2_lib.baseboard_fab2(sch_1):m_a_ecc(4)") )
				( member ( signalRef "@baseboard_fab2_lib.baseboard_fab2(sch_1):m_a_ecc(5)") )
				( member ( signalRef "@baseboard_fab2_lib.baseboard_fab2(sch_1):m_a_ecc(6)") )
				( member ( signalRef "@baseboard_fab2_lib.baseboard_fab2(sch_1):m_a_ecc(7)") )
				( objectStatus "NG_M_A_BYTE-ECC" )
			)
			( netGroup "@crescent_city_bb_fab1_lib.crescent_city_bb_fab1(sch_1):\NG_M_A_BYTE7\"
				( memberType ( signal ) )
				( electricalCSetRef "@crescent_city_bb_fab1_lib.crescent_city_bb_fab1(sch_1):\DDR_DQ_A\" )
				( member ( diffPairRef "@sapphirecity_baseboard_lib.sapphirecity_baseboard(sch_1):\M_A_DQS_D\(7)") )
				( member ( diffPairRef "@sapphirecity_baseboard_lib.sapphirecity_baseboard(sch_1):\M_A_DQS_D\(16)") )
				( member ( signalRef "@baseboard_fab2_lib.baseboard_fab2(sch_1):m_a_dq(56)") )
				( member ( signalRef "@baseboard_fab2_lib.baseboard_fab2(sch_1):m_a_dq(57)") )
				( member ( signalRef "@baseboard_fab2_lib.baseboard_fab2(sch_1):m_a_dq(58)") )
				( member ( signalRef "@baseboard_fab2_lib.baseboard_fab2(sch_1):m_a_dq(59)") )
				( member ( signalRef "@baseboard_fab2_lib.baseboard_fab2(sch_1):m_a_dq(60)") )
				( member ( signalRef "@baseboard_fab2_lib.baseboard_fab2(sch_1):m_a_dq(61)") )
				( member ( signalRef "@baseboard_fab2_lib.baseboard_fab2(sch_1):m_a_dq(62)") )
				( member ( signalRef "@baseboard_fab2_lib.baseboard_fab2(sch_1):m_a_dq(63)") )
				( objectStatus "NG_M_A_BYTE7" )
			)
			( netGroup "@crescent_city_bb_fab1_lib.crescent_city_bb_fab1(sch_1):\NG_M_A_BYTE6\"
				( memberType ( signal ) )
				( electricalCSetRef "@crescent_city_bb_fab1_lib.crescent_city_bb_fab1(sch_1):\DDR_DQ_A\" )
				( member ( diffPairRef "@sapphirecity_baseboard_lib.sapphirecity_baseboard(sch_1):\M_A_DQS_D\(6)") )
				( member ( diffPairRef "@sapphirecity_baseboard_lib.sapphirecity_baseboard(sch_1):\M_A_DQS_D\(15)") )
				( member ( signalRef "@baseboard_fab2_lib.baseboard_fab2(sch_1):m_a_dq(48)") )
				( member ( signalRef "@baseboard_fab2_lib.baseboard_fab2(sch_1):m_a_dq(49)") )
				( member ( signalRef "@baseboard_fab2_lib.baseboard_fab2(sch_1):m_a_dq(50)") )
				( member ( signalRef "@baseboard_fab2_lib.baseboard_fab2(sch_1):m_a_dq(51)") )
				( member ( signalRef "@baseboard_fab2_lib.baseboard_fab2(sch_1):m_a_dq(52)") )
				( member ( signalRef "@baseboard_fab2_lib.baseboard_fab2(sch_1):m_a_dq(53)") )
				( member ( signalRef "@baseboard_fab2_lib.baseboard_fab2(sch_1):m_a_dq(54)") )
				( member ( signalRef "@baseboard_fab2_lib.baseboard_fab2(sch_1):m_a_dq(55)") )
				( objectStatus "NG_M_A_BYTE6" )
			)
			( netGroup "@crescent_city_bb_fab1_lib.crescent_city_bb_fab1(sch_1):\NG_M_A_BYTE5\"
				( memberType ( signal ) )
				( electricalCSetRef "@crescent_city_bb_fab1_lib.crescent_city_bb_fab1(sch_1):\DDR_DQ_A\" )
				( member ( diffPairRef "@sapphirecity_baseboard_lib.sapphirecity_baseboard(sch_1):\M_A_DQS_D\(5)") )
				( member ( diffPairRef "@sapphirecity_baseboard_lib.sapphirecity_baseboard(sch_1):\M_A_DQS_D\(14)") )
				( member ( signalRef "@baseboard_fab2_lib.baseboard_fab2(sch_1):m_a_dq(40)") )
				( member ( signalRef "@baseboard_fab2_lib.baseboard_fab2(sch_1):m_a_dq(41)") )
				( member ( signalRef "@baseboard_fab2_lib.baseboard_fab2(sch_1):m_a_dq(42)") )
				( member ( signalRef "@baseboard_fab2_lib.baseboard_fab2(sch_1):m_a_dq(43)") )
				( member ( signalRef "@baseboard_fab2_lib.baseboard_fab2(sch_1):m_a_dq(44)") )
				( member ( signalRef "@baseboard_fab2_lib.baseboard_fab2(sch_1):m_a_dq(45)") )
				( member ( signalRef "@baseboard_fab2_lib.baseboard_fab2(sch_1):m_a_dq(46)") )
				( member ( signalRef "@baseboard_fab2_lib.baseboard_fab2(sch_1):m_a_dq(47)") )
				( objectStatus "NG_M_A_BYTE5" )
			)
			( netGroup "@crescent_city_bb_fab1_lib.crescent_city_bb_fab1(sch_1):\NG_M_A_BYTE4\"
				( memberType ( signal ) )
				( electricalCSetRef "@crescent_city_bb_fab1_lib.crescent_city_bb_fab1(sch_1):\DDR_DQ_A\" )
				( member ( diffPairRef "@sapphirecity_baseboard_lib.sapphirecity_baseboard(sch_1):\M_A_DQS_D\(4)") )
				( member ( diffPairRef "@sapphirecity_baseboard_lib.sapphirecity_baseboard(sch_1):\M_A_DQS_D\(13)") )
				( member ( signalRef "@baseboard_fab2_lib.baseboard_fab2(sch_1):m_a_dq(32)") )
				( member ( signalRef "@baseboard_fab2_lib.baseboard_fab2(sch_1):m_a_dq(33)") )
				( member ( signalRef "@baseboard_fab2_lib.baseboard_fab2(sch_1):m_a_dq(34)") )
				( member ( signalRef "@baseboard_fab2_lib.baseboard_fab2(sch_1):m_a_dq(35)") )
				( member ( signalRef "@baseboard_fab2_lib.baseboard_fab2(sch_1):m_a_dq(36)") )
				( member ( signalRef "@baseboard_fab2_lib.baseboard_fab2(sch_1):m_a_dq(37)") )
				( member ( signalRef "@baseboard_fab2_lib.baseboard_fab2(sch_1):m_a_dq(38)") )
				( member ( signalRef "@baseboard_fab2_lib.baseboard_fab2(sch_1):m_a_dq(39)") )
				( objectStatus "NG_M_A_BYTE4" )
			)
			( netGroup "@crescent_city_bb_fab1_lib.crescent_city_bb_fab1(sch_1):\NG_M_A_BYTE3\"
				( memberType ( signal ) )
				( electricalCSetRef "@crescent_city_bb_fab1_lib.crescent_city_bb_fab1(sch_1):\DDR_DQ_A\" )
				( member ( diffPairRef "@sapphirecity_baseboard_lib.sapphirecity_baseboard(sch_1):\M_A_DQS_D\(3)") )
				( member ( diffPairRef "@sapphirecity_baseboard_lib.sapphirecity_baseboard(sch_1):\M_A_DQS_D\(12)") )
				( member ( signalRef "@baseboard_fab2_lib.baseboard_fab2(sch_1):m_a_dq(24)") )
				( member ( signalRef "@baseboard_fab2_lib.baseboard_fab2(sch_1):m_a_dq(25)") )
				( member ( signalRef "@baseboard_fab2_lib.baseboard_fab2(sch_1):m_a_dq(26)") )
				( member ( signalRef "@baseboard_fab2_lib.baseboard_fab2(sch_1):m_a_dq(27)") )
				( member ( signalRef "@baseboard_fab2_lib.baseboard_fab2(sch_1):m_a_dq(28)") )
				( member ( signalRef "@baseboard_fab2_lib.baseboard_fab2(sch_1):m_a_dq(29)") )
				( member ( signalRef "@baseboard_fab2_lib.baseboard_fab2(sch_1):m_a_dq(30)") )
				( member ( signalRef "@baseboard_fab2_lib.baseboard_fab2(sch_1):m_a_dq(31)") )
				( objectStatus "NG_M_A_BYTE3" )
			)
			( netGroup "@crescent_city_bb_fab1_lib.crescent_city_bb_fab1(sch_1):\NG_M_A_BYTE2\"
				( memberType ( signal ) )
				( electricalCSetRef "@crescent_city_bb_fab1_lib.crescent_city_bb_fab1(sch_1):\DDR_DQ_A\" )
				( member ( diffPairRef "@sapphirecity_baseboard_lib.sapphirecity_baseboard(sch_1):\M_A_DQS_D\(2)") )
				( member ( diffPairRef "@sapphirecity_baseboard_lib.sapphirecity_baseboard(sch_1):\M_A_DQS_D\(11)") )
				( member ( signalRef "@baseboard_fab2_lib.baseboard_fab2(sch_1):m_a_dq(16)") )
				( member ( signalRef "@baseboard_fab2_lib.baseboard_fab2(sch_1):m_a_dq(17)") )
				( member ( signalRef "@baseboard_fab2_lib.baseboard_fab2(sch_1):m_a_dq(18)") )
				( member ( signalRef "@baseboard_fab2_lib.baseboard_fab2(sch_1):m_a_dq(19)") )
				( member ( signalRef "@baseboard_fab2_lib.baseboard_fab2(sch_1):m_a_dq(20)") )
				( member ( signalRef "@baseboard_fab2_lib.baseboard_fab2(sch_1):m_a_dq(21)") )
				( member ( signalRef "@baseboard_fab2_lib.baseboard_fab2(sch_1):m_a_dq(22)") )
				( member ( signalRef "@baseboard_fab2_lib.baseboard_fab2(sch_1):m_a_dq(23)") )
				( objectStatus "NG_M_A_BYTE2" )
			)
			( netGroup "@crescent_city_bb_fab1_lib.crescent_city_bb_fab1(sch_1):\NG_M_A_BYTE1\"
				( memberType ( signal ) )
				( electricalCSetRef "@crescent_city_bb_fab1_lib.crescent_city_bb_fab1(sch_1):\DDR_DQ_A\" )
				( member ( diffPairRef "@sapphirecity_baseboard_lib.sapphirecity_baseboard(sch_1):\M_A_DQS_D\(1)") )
				( member ( diffPairRef "@sapphirecity_baseboard_lib.sapphirecity_baseboard(sch_1):\M_A_DQS_D\(10)") )
				( member ( signalRef "@baseboard_fab2_lib.baseboard_fab2(sch_1):m_a_dq(8)") )
				( member ( signalRef "@baseboard_fab2_lib.baseboard_fab2(sch_1):m_a_dq(9)") )
				( member ( signalRef "@baseboard_fab2_lib.baseboard_fab2(sch_1):m_a_dq(10)") )
				( member ( signalRef "@baseboard_fab2_lib.baseboard_fab2(sch_1):m_a_dq(11)") )
				( member ( signalRef "@baseboard_fab2_lib.baseboard_fab2(sch_1):m_a_dq(12)") )
				( member ( signalRef "@baseboard_fab2_lib.baseboard_fab2(sch_1):m_a_dq(13)") )
				( member ( signalRef "@baseboard_fab2_lib.baseboard_fab2(sch_1):m_a_dq(14)") )
				( member ( signalRef "@baseboard_fab2_lib.baseboard_fab2(sch_1):m_a_dq(15)") )
				( objectStatus "NG_M_A_BYTE1" )
			)
			( netGroup "@crescent_city_bb_fab1_lib.crescent_city_bb_fab1(sch_1):\NG_M_A_BYTE0\"
				( memberType ( signal ) )
				( electricalCSetRef "@crescent_city_bb_fab1_lib.crescent_city_bb_fab1(sch_1):\DDR_DQ_A\" )
				( member ( diffPairRef "@sapphirecity_baseboard_lib.sapphirecity_baseboard(sch_1):\M_A_DQS_D\(9)") )
				( member ( diffPairRef "@sapphirecity_baseboard_lib.sapphirecity_baseboard(sch_1):\M_A_DQS_D\(0)") )
				( member ( signalRef "@baseboard_fab2_lib.baseboard_fab2(sch_1):m_a_dq(0)") )
				( member ( signalRef "@baseboard_fab2_lib.baseboard_fab2(sch_1):m_a_dq(1)") )
				( member ( signalRef "@baseboard_fab2_lib.baseboard_fab2(sch_1):m_a_dq(2)") )
				( member ( signalRef "@baseboard_fab2_lib.baseboard_fab2(sch_1):m_a_dq(3)") )
				( member ( signalRef "@baseboard_fab2_lib.baseboard_fab2(sch_1):m_a_dq(4)") )
				( member ( signalRef "@baseboard_fab2_lib.baseboard_fab2(sch_1):m_a_dq(5)") )
				( member ( signalRef "@baseboard_fab2_lib.baseboard_fab2(sch_1):m_a_dq(6)") )
				( member ( signalRef "@baseboard_fab2_lib.baseboard_fab2(sch_1):m_a_dq(7)") )
				( objectStatus "NG_M_A_BYTE0" )
			)
			( classClass "@baseboard_fab2_lib.baseboard_fab2(sch_1):\CC6\"
				( spacingCSetRef "@baseboard_fab2_lib.baseboard_fab2(sch_1):\NEW_KR_15H_US_&_7H_SL\" )
				( netClassRef "@baseboard_fab2_lib.baseboard_fab2(sch_1):\SNCSL_KR_RX\" )
				( netClassRef "@baseboard_fab2_lib.baseboard_fab2(sch_1):\SNCLS_KR_TX\" )
			)
			( classClass "@baseboard_fab2_lib.baseboard_fab2(sch_1):\CC7\"
				( spacingCSetRef "@baseboard_fab2_lib.baseboard_fab2(sch_1):\NEW_KR_12H_US_&_5H_SL\" )
				( netClassRef "@baseboard_fab2_lib.baseboard_fab2(sch_1):\SNCLS_KR_TX\" )
				( netClassRef "@baseboard_fab2_lib.baseboard_fab2(sch_1):\SNCLS_KR_TX\" )
			)
			( classClass "@baseboard_fab2_lib.baseboard_fab2(sch_1):\CC5\"
				( spacingCSetRef "@crescent_city_bb_fab1_lib.crescent_city_bb_fab1(sch_1):\DEFAULT\" )
				( netClassRef "@sapphirecity_baseboard_lib.sapphirecity_baseboard(sch_1):\GND\" )
				( netClassRef "@baseboard_fab2_lib.baseboard_fab2(sch_1):\SNCLS_KR_TX\" )
			)
			( classClass "@baseboard_fab2_lib.baseboard_fab2(sch_1):\CC2\"
				( spacingCSetRef "@crescent_city_bb_fab1_lib.crescent_city_bb_fab1(sch_1):\DEFAULT\" )
				( netClassRef "@sapphirecity_baseboard_lib.sapphirecity_baseboard(sch_1):\POWER\" )
				( netClassRef "@baseboard_fab2_lib.baseboard_fab2(sch_1):\SNCLS_KR_TX\" )
			)
			( classClass "@baseboard_fab2_lib.baseboard_fab2(sch_1):\CC8\"
				( spacingCSetRef "@baseboard_fab2_lib.baseboard_fab2(sch_1):\NEW_KR_12H_US_&_5H_SL\" )
				( netClassRef "@baseboard_fab2_lib.baseboard_fab2(sch_1):\SNCSL_KR_RX\" )
				( netClassRef "@baseboard_fab2_lib.baseboard_fab2(sch_1):\SNCSL_KR_RX\" )
			)
			( classClass "@baseboard_fab2_lib.baseboard_fab2(sch_1):\CC4\"
				( spacingCSetRef "@crescent_city_bb_fab1_lib.crescent_city_bb_fab1(sch_1):\DEFAULT\" )
				( netClassRef "@sapphirecity_baseboard_lib.sapphirecity_baseboard(sch_1):\GND\" )
				( netClassRef "@baseboard_fab2_lib.baseboard_fab2(sch_1):\SNCSL_KR_RX\" )
			)
			( classClass "@baseboard_fab2_lib.baseboard_fab2(sch_1):\CC1\"
				( spacingCSetRef "@crescent_city_bb_fab1_lib.crescent_city_bb_fab1(sch_1):\DEFAULT\" )
				( netClassRef "@sapphirecity_baseboard_lib.sapphirecity_baseboard(sch_1):\POWER\" )
				( netClassRef "@baseboard_fab2_lib.baseboard_fab2(sch_1):\SNCSL_KR_RX\" )
			)
			( classClass "@baseboard_fab2_lib.baseboard_fab2(sch_1):\CC3\"
				( spacingCSetRef "@crescent_city_bb_fab1_lib.crescent_city_bb_fab1(sch_1):\DEFAULT\" )
				( netClassRef "@sapphirecity_baseboard_lib.sapphirecity_baseboard(sch_1):\GND\" )
				( netClassRef "@baseboard_fab2_lib.baseboard_fab2(sch_1):\SNCLS_ISENSE\" )
			)
			( classClass "@baseboard_fab2_lib.baseboard_fab2(sch_1):\CC9\"
				( spacingCSetRef "@baseboard_fab2_lib.baseboard_fab2(sch_1):\10_MIL_L-V_10MIL\" )
				( netClassRef "@baseboard_fab2_lib.baseboard_fab2(sch_1):\SNCLS_ISENSE\" )
				( netClassRef "@crescent_city_bb_fab1_lib.crescent_city_bb_fab1(sch_1):\SNCLS_NOISY_NETS\" )
			)
			( classClass "@baseboard_fab2_lib.baseboard_fab2(sch_1):\CC10\"
				( spacingCSetRef "@baseboard_fab2_lib.baseboard_fab2(sch_1):\10_MIL_L-V_10MIL\" )
				( netClassRef "@baseboard_fab2_lib.baseboard_fab2(sch_1):\SNCLS_ISENSE\" )
				( netClassRef "@sapphirecity_baseboard_lib.sapphirecity_baseboard(sch_1):\VR_CPU_PWM\" )
			)
			( classClass "@crescent_city_bb_fab1_lib.crescent_city_bb_fab1(sch_1):\CC987\"
				( spacingCSetRef "@sapphirecity_baseboard_lib.sapphirecity_baseboard(sch_1):\20_MILS\" )
				( netClassRef "@crescent_city_bb_fab1_lib.crescent_city_bb_fab1(sch_1):\SNCLS_NOISY_NETS\" )
				( netClassRef "@crescent_city_bb_fab1_lib.crescent_city_bb_fab1(sch_1):\SNCLS_VR_SENSITIVE_NETS\" )
			)
			( classClass "@crescent_city_bb_fab1_lib.crescent_city_bb_fab1(sch_1):\CC988\"
				( spacingCSetRef "@sapphirecity_baseboard_lib.sapphirecity_baseboard(sch_1):\20_MILS\" )
				( netClassRef "@sapphirecity_baseboard_lib.sapphirecity_baseboard(sch_1):\VR_CPU_PWM\" )
				( netClassRef "@crescent_city_bb_fab1_lib.crescent_city_bb_fab1(sch_1):\SNCLS_VR_SENSITIVE_NETS\" )
			)
			( classClass "@crescent_city_bb_fab1_lib.crescent_city_bb_fab1(sch_1):\CC983\"
				( spacingCSetRef "@crescent_city_bb_fab1_lib.crescent_city_bb_fab1(sch_1):\4_MILS\" )
				( netClassRef "@crescent_city_bb_fab1_lib.crescent_city_bb_fab1(sch_1):\SNCLS_RMII_RX\" )
				( netClassRef "@crescent_city_bb_fab1_lib.crescent_city_bb_fab1(sch_1):\SNCLS_RMII_RX\" )
			)
			( classClass "@crescent_city_bb_fab1_lib.crescent_city_bb_fab1(sch_1):\CC975\"
				( spacingCSetRef "@crescent_city_bb_fab1_lib.crescent_city_bb_fab1(sch_1):\4_MILS\" )
				( netClassRef "@sapphirecity_baseboard_lib.sapphirecity_baseboard(sch_1):\GND\" )
				( netClassRef "@crescent_city_bb_fab1_lib.crescent_city_bb_fab1(sch_1):\SNCLS_RMII_RX\" )
			)
			( classClass "@crescent_city_bb_fab1_lib.crescent_city_bb_fab1(sch_1):\CC958\"
				( spacingCSetRef "@crescent_city_bb_fab1_lib.crescent_city_bb_fab1(sch_1):\4_MILS\" )
				( netClassRef "@sapphirecity_baseboard_lib.sapphirecity_baseboard(sch_1):\POWER\" )
				( netClassRef "@crescent_city_bb_fab1_lib.crescent_city_bb_fab1(sch_1):\SNCLS_RMII_RX\" )
			)
			( classClass "@crescent_city_bb_fab1_lib.crescent_city_bb_fab1(sch_1):\CC984\"
				( spacingCSetRef "@crescent_city_bb_fab1_lib.crescent_city_bb_fab1(sch_1):\4_MILS\" )
				( netClassRef "@sapphirecity_baseboard_lib.sapphirecity_baseboard(sch_1):\MISC_INTEL_STATIC\" )
				( netClassRef "@crescent_city_bb_fab1_lib.crescent_city_bb_fab1(sch_1):\SNCLS_RMII_RX\" )
			)
			( classClass "@crescent_city_bb_fab1_lib.crescent_city_bb_fab1(sch_1):\CC985\"
				( spacingCSetRef "@crescent_city_bb_fab1_lib.crescent_city_bb_fab1(sch_1):\4_MILS\" )
				( netClassRef "@crescent_city_bb_fab1_lib.crescent_city_bb_fab1(sch_1):\SNCLS_RMII_TX\" )
				( netClassRef "@crescent_city_bb_fab1_lib.crescent_city_bb_fab1(sch_1):\SNCLS_RMII_TX\" )
			)
			( classClass "@crescent_city_bb_fab1_lib.crescent_city_bb_fab1(sch_1):\CC976\"
				( spacingCSetRef "@crescent_city_bb_fab1_lib.crescent_city_bb_fab1(sch_1):\4_MILS\" )
				( netClassRef "@sapphirecity_baseboard_lib.sapphirecity_baseboard(sch_1):\GND\" )
				( netClassRef "@crescent_city_bb_fab1_lib.crescent_city_bb_fab1(sch_1):\SNCLS_RMII_TX\" )
			)
			( classClass "@crescent_city_bb_fab1_lib.crescent_city_bb_fab1(sch_1):\CC963\"
				( spacingCSetRef "@crescent_city_bb_fab1_lib.crescent_city_bb_fab1(sch_1):\4_MILS\" )
				( netClassRef "@sapphirecity_baseboard_lib.sapphirecity_baseboard(sch_1):\POWER\" )
				( netClassRef "@crescent_city_bb_fab1_lib.crescent_city_bb_fab1(sch_1):\SNCLS_RMII_TX\" )
			)
			( classClass "@crescent_city_bb_fab1_lib.crescent_city_bb_fab1(sch_1):\CC986\"
				( spacingCSetRef "@crescent_city_bb_fab1_lib.crescent_city_bb_fab1(sch_1):\4_MILS\" )
				( netClassRef "@sapphirecity_baseboard_lib.sapphirecity_baseboard(sch_1):\MISC_INTEL_STATIC\" )
				( netClassRef "@crescent_city_bb_fab1_lib.crescent_city_bb_fab1(sch_1):\SNCLS_RMII_TX\" )
			)
			( classClass "@crescent_city_bb_fab1_lib.crescent_city_bb_fab1(sch_1):\CC974\"
				( spacingCSetRef "@crescent_city_bb_fab1_lib.crescent_city_bb_fab1(sch_1):\DEFAULT\" )
				( netClassRef "@sapphirecity_baseboard_lib.sapphirecity_baseboard(sch_1):\GND\" )
				( netClassRef "@crescent_city_bb_fab1_lib.crescent_city_bb_fab1(sch_1):\SNCLS_DDR4_VREF\" )
			)
			( classClass "@crescent_city_bb_fab1_lib.crescent_city_bb_fab1(sch_1):\CC949\"
				( spacingCSetRef "@crescent_city_bb_fab1_lib.crescent_city_bb_fab1(sch_1):\DEFAULT\" )
				( attribute "LINE_TO_SHAPE_SPACING" "20.00"
					( Origin gBackEnd )
				)
				( netClassRef "@sapphirecity_baseboard_lib.sapphirecity_baseboard(sch_1):\POWER\" )
				( netClassRef "@crescent_city_bb_fab1_lib.crescent_city_bb_fab1(sch_1):\SNCLS_DDR4_VREF\" )
			)
			( classClass "@crescent_city_bb_fab1_lib.crescent_city_bb_fab1(sch_1):\CC973\"
				( spacingCSetRef "@crescent_city_bb_fab1_lib.crescent_city_bb_fab1(sch_1):\DEFAULT\" )
				( netClassRef "@sapphirecity_baseboard_lib.sapphirecity_baseboard(sch_1):\GND\" )
				( netClassRef "@crescent_city_bb_fab1_lib.crescent_city_bb_fab1(sch_1):\SNCLS_DDR4_RST\" )
			)
			( classClass "@crescent_city_bb_fab1_lib.crescent_city_bb_fab1(sch_1):\CC948\"
				( spacingCSetRef "@crescent_city_bb_fab1_lib.crescent_city_bb_fab1(sch_1):\DEFAULT\" )
				( netClassRef "@sapphirecity_baseboard_lib.sapphirecity_baseboard(sch_1):\POWER\" )
				( netClassRef "@crescent_city_bb_fab1_lib.crescent_city_bb_fab1(sch_1):\SNCLS_DDR4_RST\" )
			)
			( classClass "@crescent_city_bb_fab1_lib.crescent_city_bb_fab1(sch_1):\CC972\"
				( spacingCSetRef "@crescent_city_bb_fab1_lib.crescent_city_bb_fab1(sch_1):\DEFAULT\" )
				( netClassRef "@sapphirecity_baseboard_lib.sapphirecity_baseboard(sch_1):\GND\" )
				( netClassRef "@crescent_city_bb_fab1_lib.crescent_city_bb_fab1(sch_1):\SPGIO_SSATA\" )
			)
			( classClass "@crescent_city_bb_fab1_lib.crescent_city_bb_fab1(sch_1):\CC989\"
				( spacingCSetRef "@sapphirecity_baseboard_lib.sapphirecity_baseboard(sch_1):\20_MILS\" )
				( netClassRef "@crescent_city_bb_fab1_lib.crescent_city_bb_fab1(sch_1):\SNCLS_NOISY_NETS\" )
				( netClassRef "@sapphirecity_baseboard_lib.sapphirecity_baseboard(sch_1):\VR_CPU_PWM\" )
			)
			( classClass "@crescent_city_bb_fab1_lib.crescent_city_bb_fab1(sch_1):\CC990\"
				( spacingCSetRef "@crescent_city_bb_fab1_lib.crescent_city_bb_fab1(sch_1):\15H_US_&_7H_SL\" )
				( netClassRef "@crescent_city_bb_fab1_lib.crescent_city_bb_fab1(sch_1):\SNCLS_SFI_RX\" )
				( netClassRef "@crescent_city_bb_fab1_lib.crescent_city_bb_fab1(sch_1):\SNCLS_SFI_TX\" )
			)
			( classClass "@crescent_city_bb_fab1_lib.crescent_city_bb_fab1(sch_1):\CC991\"
				( spacingCSetRef "@crescent_city_bb_fab1_lib.crescent_city_bb_fab1(sch_1):\12H_US_&_5H_SL\" )
				( netClassRef "@crescent_city_bb_fab1_lib.crescent_city_bb_fab1(sch_1):\SNCLS_SFI_TX\" )
				( netClassRef "@crescent_city_bb_fab1_lib.crescent_city_bb_fab1(sch_1):\SNCLS_SFI_TX\" )
			)
			( classClass "@crescent_city_bb_fab1_lib.crescent_city_bb_fab1(sch_1):\CC992\"
				( spacingCSetRef "@crescent_city_bb_fab1_lib.crescent_city_bb_fab1(sch_1):\12H_US_&_5H_SL\" )
				( netClassRef "@crescent_city_bb_fab1_lib.crescent_city_bb_fab1(sch_1):\SNCLS_SFI_RX\" )
				( netClassRef "@crescent_city_bb_fab1_lib.crescent_city_bb_fab1(sch_1):\SNCLS_SFI_RX\" )
			)
			( classClass "@crescent_city_bb_fab1_lib.crescent_city_bb_fab1(sch_1):\CC969\"
				( spacingCSetRef "@crescent_city_bb_fab1_lib.crescent_city_bb_fab1(sch_1):\DEFAULT\" )
				( netClassRef "@sapphirecity_baseboard_lib.sapphirecity_baseboard(sch_1):\GND\" )
				( netClassRef "@crescent_city_bb_fab1_lib.crescent_city_bb_fab1(sch_1):\SNCLS_NIC_MDI_7H-6H\" )
			)
			( classClass "@crescent_city_bb_fab1_lib.crescent_city_bb_fab1(sch_1):\CC979\"
				( spacingCSetRef "@sapphirecity_baseboard_lib.sapphirecity_baseboard(sch_1):\3H_SL_9H_MS_VIA_3H+A\" )
				( netClassRef "@crescent_city_bb_fab1_lib.crescent_city_bb_fab1(sch_1):\P3E_CPU1_PE1_MP_TX\" )
				( netClassRef "@crescent_city_bb_fab1_lib.crescent_city_bb_fab1(sch_1):\P3E_CPU1_PE1_MP_TX\" )
			)
			( classClass "@crescent_city_bb_fab1_lib.crescent_city_bb_fab1(sch_1):\CC966\"
				( spacingCSetRef "@crescent_city_bb_fab1_lib.crescent_city_bb_fab1(sch_1):\DEFAULT\" )
				( netClassRef "@sapphirecity_baseboard_lib.sapphirecity_baseboard(sch_1):\GND\" )
				( netClassRef "@crescent_city_bb_fab1_lib.crescent_city_bb_fab1(sch_1):\P3E_CPU1_PE1_MP_TX\" )
			)
			( classClass "@crescent_city_bb_fab1_lib.crescent_city_bb_fab1(sch_1):\CC945\"
				( spacingCSetRef "@crescent_city_bb_fab1_lib.crescent_city_bb_fab1(sch_1):\DEFAULT\" )
				( netClassRef "@sapphirecity_baseboard_lib.sapphirecity_baseboard(sch_1):\POWER\" )
				( netClassRef "@crescent_city_bb_fab1_lib.crescent_city_bb_fab1(sch_1):\P3E_CPU1_PE1_MP_TX\" )
			)
			( classClass "@crescent_city_bb_fab1_lib.crescent_city_bb_fab1(sch_1):\CC977\"
				( spacingCSetRef "@sapphirecity_baseboard_lib.sapphirecity_baseboard(sch_1):\3H_SL_9H_MS_VIA_3H+A\" )
				( netClassRef "@crescent_city_bb_fab1_lib.crescent_city_bb_fab1(sch_1):\P3E_CPU1_PE1_MP_RX\" )
				( netClassRef "@crescent_city_bb_fab1_lib.crescent_city_bb_fab1(sch_1):\P3E_CPU1_PE1_MP_RX\" )
			)
			( classClass "@crescent_city_bb_fab1_lib.crescent_city_bb_fab1(sch_1):\CC965\"
				( spacingCSetRef "@crescent_city_bb_fab1_lib.crescent_city_bb_fab1(sch_1):\DEFAULT\" )
				( netClassRef "@sapphirecity_baseboard_lib.sapphirecity_baseboard(sch_1):\GND\" )
				( netClassRef "@crescent_city_bb_fab1_lib.crescent_city_bb_fab1(sch_1):\P3E_CPU1_PE1_MP_RX\" )
			)
			( classClass "@crescent_city_bb_fab1_lib.crescent_city_bb_fab1(sch_1):\CC944\"
				( spacingCSetRef "@crescent_city_bb_fab1_lib.crescent_city_bb_fab1(sch_1):\DEFAULT\" )
				( netClassRef "@sapphirecity_baseboard_lib.sapphirecity_baseboard(sch_1):\POWER\" )
				( netClassRef "@crescent_city_bb_fab1_lib.crescent_city_bb_fab1(sch_1):\P3E_CPU1_PE1_MP_RX\" )
			)
			( classClass "@crescent_city_bb_fab1_lib.crescent_city_bb_fab1(sch_1):\CC964\"
				( spacingCSetRef "@crescent_city_bb_fab1_lib.crescent_city_bb_fab1(sch_1):\5MIL_US_&_4MIL_SL\" )
				( netClassRef "@sapphirecity_baseboard_lib.sapphirecity_baseboard(sch_1):\GND\" )
				( netClassRef "@crescent_city_bb_fab1_lib.crescent_city_bb_fab1(sch_1):\SNCLS_SIDEBAND\" )
			)
			( classClass "@crescent_city_bb_fab1_lib.crescent_city_bb_fab1(sch_1):\CC943\"
				( spacingCSetRef "@crescent_city_bb_fab1_lib.crescent_city_bb_fab1(sch_1):\5MIL_US_&_4MIL_SL\" )
				( netClassRef "@sapphirecity_baseboard_lib.sapphirecity_baseboard(sch_1):\POWER\" )
				( netClassRef "@crescent_city_bb_fab1_lib.crescent_city_bb_fab1(sch_1):\SNCLS_SIDEBAND\" )
			)
			( classClass "@crescent_city_bb_fab1_lib.crescent_city_bb_fab1(sch_1):\CC941\"
				( spacingCSetRef "@crescent_city_bb_fab1_lib.crescent_city_bb_fab1(sch_1):\9H_US_&_5H_SL_VIA+3H_A\" )
				( netClassRef "@crescent_city_bb_fab1_lib.crescent_city_bb_fab1(sch_1):\USB3_TX\" )
				( netClassRef "@crescent_city_bb_fab1_lib.crescent_city_bb_fab1(sch_1):\USB3_TX\" )
			)
			( classClass "@crescent_city_bb_fab1_lib.crescent_city_bb_fab1(sch_1):\CC968\"
				( spacingCSetRef "@crescent_city_bb_fab1_lib.crescent_city_bb_fab1(sch_1):\DEFAULT\" )
				( netClassRef "@sapphirecity_baseboard_lib.sapphirecity_baseboard(sch_1):\GND\" )
				( netClassRef "@crescent_city_bb_fab1_lib.crescent_city_bb_fab1(sch_1):\USB3_TX\" )
			)
			( classClass "@crescent_city_bb_fab1_lib.crescent_city_bb_fab1(sch_1):\CC993\"
				( spacingCSetRef "@sapphirecity_baseboard_lib.sapphirecity_baseboard(sch_1):\20_MILS\" )
				( netClassRef "@sapphirecity_baseboard_lib.sapphirecity_baseboard(sch_1):\VR_CPU_PWM\" )
				( netClassRef "@sapphirecity_baseboard_lib.sapphirecity_baseboard(sch_1):\VR_CPU_PWM\" )
			)
			( classClass "@sapphirecity_baseboard_lib.sapphirecity_baseboard(sch_1):\CC111\"
				( spacingCSetRef "@crescent_city_bb_fab1_lib.crescent_city_bb_fab1(sch_1):\DEFAULT\" )
				( netClassRef "@sapphirecity_baseboard_lib.sapphirecity_baseboard(sch_1):\GND\" )
				( netClassRef "@sapphirecity_baseboard_lib.sapphirecity_baseboard(sch_1):\P2E_CPU0_LAN_RX\" )
			)
			( classClass "@sapphirecity_baseboard_lib.sapphirecity_baseboard(sch_1):\CC864\"
				( spacingCSetRef "@sapphirecity_baseboard_lib.sapphirecity_baseboard(sch_1):\3H_SL_9H_MS_VIA_3H+A\" )
				( netClassRef "@sapphirecity_baseboard_lib.sapphirecity_baseboard(sch_1):\P2E_CPU0_LAN_RX\" )
				( netClassRef "@sapphirecity_baseboard_lib.sapphirecity_baseboard(sch_1):\P2E_CPU0_LAN_RX\" )
			)
			( classClass "@sapphirecity_baseboard_lib.sapphirecity_baseboard(sch_1):\CC118\"
				( spacingCSetRef "@crescent_city_bb_fab1_lib.crescent_city_bb_fab1(sch_1):\DEFAULT\" )
				( netClassRef "@sapphirecity_baseboard_lib.sapphirecity_baseboard(sch_1):\GND\" )
				( netClassRef "@sapphirecity_baseboard_lib.sapphirecity_baseboard(sch_1):\P2E_CPU0_LAN_TX\" )
			)
			( classClass "@sapphirecity_baseboard_lib.sapphirecity_baseboard(sch_1):\CC861\"
				( spacingCSetRef "@sapphirecity_baseboard_lib.sapphirecity_baseboard(sch_1):\3H_SL_9H_MS_VIA_3H+A\" )
				( netClassRef "@sapphirecity_baseboard_lib.sapphirecity_baseboard(sch_1):\P2E_CPU0_LAN_TX\" )
				( netClassRef "@sapphirecity_baseboard_lib.sapphirecity_baseboard(sch_1):\P2E_CPU0_LAN_TX\" )
			)
			( classClass "@sapphirecity_baseboard_lib.sapphirecity_baseboard(sch_1):\CC54\"
				( spacingCSetRef "@crescent_city_bb_fab1_lib.crescent_city_bb_fab1(sch_1):\DEFAULT\" )
				( netClassRef "@sapphirecity_baseboard_lib.sapphirecity_baseboard(sch_1):\GND\" )
				( netClassRef "@sapphirecity_baseboard_lib.sapphirecity_baseboard(sch_1):\DDR4_CHN_A_DQ_DQS_BYTE7\" )
			)
			( classClass "@sapphirecity_baseboard_lib.sapphirecity_baseboard(sch_1):\CC369\"
				( spacingCSetRef "@sapphirecity_baseboard_lib.sapphirecity_baseboard(sch_1):\DQ_TO_DQ\" )
				( netClassRef "@sapphirecity_baseboard_lib.sapphirecity_baseboard(sch_1):\DDR4_CHN_A_CLK\" )
				( netClassRef "@sapphirecity_baseboard_lib.sapphirecity_baseboard(sch_1):\DDR4_CHN_A_DQ_DQS_BYTE7\" )
			)
			( classClass "@sapphirecity_baseboard_lib.sapphirecity_baseboard(sch_1):\CC381\"
				( spacingCSetRef "@sapphirecity_baseboard_lib.sapphirecity_baseboard(sch_1):\DQ_TO_DQ\" )
				( netClassRef "@sapphirecity_baseboard_lib.sapphirecity_baseboard(sch_1):\DDR4_CHN_A_CMD_ADD\" )
				( netClassRef "@sapphirecity_baseboard_lib.sapphirecity_baseboard(sch_1):\DDR4_CHN_A_DQ_DQS_BYTE7\" )
			)
			( classClass "@sapphirecity_baseboard_lib.sapphirecity_baseboard(sch_1):\CC390\"
				( spacingCSetRef "@sapphirecity_baseboard_lib.sapphirecity_baseboard(sch_1):\DQ_TO_DQ\" )
				( netClassRef "@sapphirecity_baseboard_lib.sapphirecity_baseboard(sch_1):\DDR4_CHN_A_CTRL\" )
				( netClassRef "@sapphirecity_baseboard_lib.sapphirecity_baseboard(sch_1):\DDR4_CHN_A_DQ_DQS_BYTE7\" )
			)
			( classClass "@sapphirecity_baseboard_lib.sapphirecity_baseboard(sch_1):\CC400\"
				( spacingCSetRef "@sapphirecity_baseboard_lib.sapphirecity_baseboard(sch_1):\DQ_TO_DQ\" )
				( netClassRef "@sapphirecity_baseboard_lib.sapphirecity_baseboard(sch_1):\DDR4_CHN_A_DQ_DQS_BYTE7\" )
				( netClassRef "@sapphirecity_baseboard_lib.sapphirecity_baseboard(sch_1):\DDR4_CHN_A_ECC\" )
			)
			( classClass "@sapphirecity_baseboard_lib.sapphirecity_baseboard(sch_1):\CC716\"
				( spacingCSetRef "@sapphirecity_baseboard_lib.sapphirecity_baseboard(sch_1):\DQ_TO_DQ\" )
				( netClassRef "@sapphirecity_baseboard_lib.sapphirecity_baseboard(sch_1):\DDR4_CHN_A_DQ_DQS_BYTE0\" )
				( netClassRef "@sapphirecity_baseboard_lib.sapphirecity_baseboard(sch_1):\DDR4_CHN_A_DQ_DQS_BYTE7\" )
			)
			( classClass "@sapphirecity_baseboard_lib.sapphirecity_baseboard(sch_1):\CC719\"
				( spacingCSetRef "@sapphirecity_baseboard_lib.sapphirecity_baseboard(sch_1):\DQ_TO_DQ\" )
				( netClassRef "@sapphirecity_baseboard_lib.sapphirecity_baseboard(sch_1):\DDR4_CHN_A_DQ_DQS_BYTE1\" )
				( netClassRef "@sapphirecity_baseboard_lib.sapphirecity_baseboard(sch_1):\DDR4_CHN_A_DQ_DQS_BYTE7\" )
			)
			( classClass "@sapphirecity_baseboard_lib.sapphirecity_baseboard(sch_1):\CC727\"
				( spacingCSetRef "@sapphirecity_baseboard_lib.sapphirecity_baseboard(sch_1):\DQ_TO_DQ\" )
				( netClassRef "@sapphirecity_baseboard_lib.sapphirecity_baseboard(sch_1):\DDR4_CHN_A_DQ_DQS_BYTE2\" )
				( netClassRef "@sapphirecity_baseboard_lib.sapphirecity_baseboard(sch_1):\DDR4_CHN_A_DQ_DQS_BYTE7\" )
			)
			( classClass "@sapphirecity_baseboard_lib.sapphirecity_baseboard(sch_1):\CC734\"
				( spacingCSetRef "@sapphirecity_baseboard_lib.sapphirecity_baseboard(sch_1):\DQ_TO_DQ\" )
				( netClassRef "@sapphirecity_baseboard_lib.sapphirecity_baseboard(sch_1):\DDR4_CHN_A_DQ_DQS_BYTE3\" )
				( netClassRef "@sapphirecity_baseboard_lib.sapphirecity_baseboard(sch_1):\DDR4_CHN_A_DQ_DQS_BYTE7\" )
			)
			( classClass "@sapphirecity_baseboard_lib.sapphirecity_baseboard(sch_1):\CC740\"
				( spacingCSetRef "@sapphirecity_baseboard_lib.sapphirecity_baseboard(sch_1):\DQ_TO_DQ\" )
				( netClassRef "@sapphirecity_baseboard_lib.sapphirecity_baseboard(sch_1):\DDR4_CHN_A_DQ_DQS_BYTE4\" )
				( netClassRef "@sapphirecity_baseboard_lib.sapphirecity_baseboard(sch_1):\DDR4_CHN_A_DQ_DQS_BYTE7\" )
			)
			( classClass "@sapphirecity_baseboard_lib.sapphirecity_baseboard(sch_1):\CC745\"
				( spacingCSetRef "@sapphirecity_baseboard_lib.sapphirecity_baseboard(sch_1):\DQ_TO_DQ\" )
				( netClassRef "@sapphirecity_baseboard_lib.sapphirecity_baseboard(sch_1):\DDR4_CHN_A_DQ_DQS_BYTE5\" )
				( netClassRef "@sapphirecity_baseboard_lib.sapphirecity_baseboard(sch_1):\DDR4_CHN_A_DQ_DQS_BYTE7\" )
			)
			( classClass "@sapphirecity_baseboard_lib.sapphirecity_baseboard(sch_1):\CC750\"
				( spacingCSetRef "@sapphirecity_baseboard_lib.sapphirecity_baseboard(sch_1):\DQ_TO_DQ\" )
				( netClassRef "@sapphirecity_baseboard_lib.sapphirecity_baseboard(sch_1):\DDR4_CHN_A_DQ_DQS_BYTE6\" )
				( netClassRef "@sapphirecity_baseboard_lib.sapphirecity_baseboard(sch_1):\DDR4_CHN_A_DQ_DQS_BYTE7\" )
			)
			( classClass "@sapphirecity_baseboard_lib.sapphirecity_baseboard(sch_1):\CC751\"
				( spacingCSetRef "@sapphirecity_baseboard_lib.sapphirecity_baseboard(sch_1):\DDR4_2SPC_DQ/DQS\" )
				( netClassRef "@sapphirecity_baseboard_lib.sapphirecity_baseboard(sch_1):\DDR4_CHN_A_DQ_DQS_BYTE7\" )
				( netClassRef "@sapphirecity_baseboard_lib.sapphirecity_baseboard(sch_1):\DDR4_CHN_A_DQ_DQS_BYTE7\" )
			)
			( classClass "@crescent_city_bb_fab1_lib.crescent_city_bb_fab1(sch_1):\CC8\"
				( spacingCSetRef "@crescent_city_bb_fab1_lib.crescent_city_bb_fab1(sch_1):\DEFAULT\" )
				( netClassRef "@sapphirecity_baseboard_lib.sapphirecity_baseboard(sch_1):\POWER\" )
				( netClassRef "@sapphirecity_baseboard_lib.sapphirecity_baseboard(sch_1):\DDR4_CHN_A_DQ_DQS_BYTE7\" )
			)
			( classClass "@sapphirecity_baseboard_lib.sapphirecity_baseboard(sch_1):\CC55\"
				( spacingCSetRef "@crescent_city_bb_fab1_lib.crescent_city_bb_fab1(sch_1):\DEFAULT\" )
				( netClassRef "@sapphirecity_baseboard_lib.sapphirecity_baseboard(sch_1):\GND\" )
				( netClassRef "@sapphirecity_baseboard_lib.sapphirecity_baseboard(sch_1):\DDR4_CHN_A_DQ_DQS_BYTE6\" )
			)
			( classClass "@sapphirecity_baseboard_lib.sapphirecity_baseboard(sch_1):\CC368\"
				( spacingCSetRef "@sapphirecity_baseboard_lib.sapphirecity_baseboard(sch_1):\DQ_TO_DQ\" )
				( netClassRef "@sapphirecity_baseboard_lib.sapphirecity_baseboard(sch_1):\DDR4_CHN_A_CLK\" )
				( netClassRef "@sapphirecity_baseboard_lib.sapphirecity_baseboard(sch_1):\DDR4_CHN_A_DQ_DQS_BYTE6\" )
			)
			( classClass "@sapphirecity_baseboard_lib.sapphirecity_baseboard(sch_1):\CC380\"
				( spacingCSetRef "@sapphirecity_baseboard_lib.sapphirecity_baseboard(sch_1):\DQ_TO_DQ\" )
				( netClassRef "@sapphirecity_baseboard_lib.sapphirecity_baseboard(sch_1):\DDR4_CHN_A_CMD_ADD\" )
				( netClassRef "@sapphirecity_baseboard_lib.sapphirecity_baseboard(sch_1):\DDR4_CHN_A_DQ_DQS_BYTE6\" )
			)
			( classClass "@sapphirecity_baseboard_lib.sapphirecity_baseboard(sch_1):\CC389\"
				( spacingCSetRef "@sapphirecity_baseboard_lib.sapphirecity_baseboard(sch_1):\DQ_TO_DQ\" )
				( netClassRef "@sapphirecity_baseboard_lib.sapphirecity_baseboard(sch_1):\DDR4_CHN_A_CTRL\" )
				( netClassRef "@sapphirecity_baseboard_lib.sapphirecity_baseboard(sch_1):\DDR4_CHN_A_DQ_DQS_BYTE6\" )
			)
			( classClass "@sapphirecity_baseboard_lib.sapphirecity_baseboard(sch_1):\CC399\"
				( spacingCSetRef "@sapphirecity_baseboard_lib.sapphirecity_baseboard(sch_1):\DQ_TO_DQ\" )
				( netClassRef "@sapphirecity_baseboard_lib.sapphirecity_baseboard(sch_1):\DDR4_CHN_A_DQ_DQS_BYTE6\" )
				( netClassRef "@sapphirecity_baseboard_lib.sapphirecity_baseboard(sch_1):\DDR4_CHN_A_ECC\" )
			)
			( classClass "@sapphirecity_baseboard_lib.sapphirecity_baseboard(sch_1):\CC715\"
				( spacingCSetRef "@sapphirecity_baseboard_lib.sapphirecity_baseboard(sch_1):\DQ_TO_DQ\" )
				( netClassRef "@sapphirecity_baseboard_lib.sapphirecity_baseboard(sch_1):\DDR4_CHN_A_DQ_DQS_BYTE0\" )
				( netClassRef "@sapphirecity_baseboard_lib.sapphirecity_baseboard(sch_1):\DDR4_CHN_A_DQ_DQS_BYTE6\" )
			)
			( classClass "@sapphirecity_baseboard_lib.sapphirecity_baseboard(sch_1):\CC720\"
				( spacingCSetRef "@sapphirecity_baseboard_lib.sapphirecity_baseboard(sch_1):\DQ_TO_DQ\" )
				( netClassRef "@sapphirecity_baseboard_lib.sapphirecity_baseboard(sch_1):\DDR4_CHN_A_DQ_DQS_BYTE1\" )
				( netClassRef "@sapphirecity_baseboard_lib.sapphirecity_baseboard(sch_1):\DDR4_CHN_A_DQ_DQS_BYTE6\" )
			)
			( classClass "@sapphirecity_baseboard_lib.sapphirecity_baseboard(sch_1):\CC728\"
				( spacingCSetRef "@sapphirecity_baseboard_lib.sapphirecity_baseboard(sch_1):\DQ_TO_DQ\" )
				( netClassRef "@sapphirecity_baseboard_lib.sapphirecity_baseboard(sch_1):\DDR4_CHN_A_DQ_DQS_BYTE2\" )
				( netClassRef "@sapphirecity_baseboard_lib.sapphirecity_baseboard(sch_1):\DDR4_CHN_A_DQ_DQS_BYTE6\" )
			)
			( classClass "@sapphirecity_baseboard_lib.sapphirecity_baseboard(sch_1):\CC735\"
				( spacingCSetRef "@sapphirecity_baseboard_lib.sapphirecity_baseboard(sch_1):\DQ_TO_DQ\" )
				( netClassRef "@sapphirecity_baseboard_lib.sapphirecity_baseboard(sch_1):\DDR4_CHN_A_DQ_DQS_BYTE3\" )
				( netClassRef "@sapphirecity_baseboard_lib.sapphirecity_baseboard(sch_1):\DDR4_CHN_A_DQ_DQS_BYTE6\" )
			)
			( classClass "@sapphirecity_baseboard_lib.sapphirecity_baseboard(sch_1):\CC741\"
				( spacingCSetRef "@sapphirecity_baseboard_lib.sapphirecity_baseboard(sch_1):\DQ_TO_DQ\" )
				( netClassRef "@sapphirecity_baseboard_lib.sapphirecity_baseboard(sch_1):\DDR4_CHN_A_DQ_DQS_BYTE4\" )
				( netClassRef "@sapphirecity_baseboard_lib.sapphirecity_baseboard(sch_1):\DDR4_CHN_A_DQ_DQS_BYTE6\" )
			)
			( classClass "@sapphirecity_baseboard_lib.sapphirecity_baseboard(sch_1):\CC746\"
				( spacingCSetRef "@sapphirecity_baseboard_lib.sapphirecity_baseboard(sch_1):\DQ_TO_DQ\" )
				( netClassRef "@sapphirecity_baseboard_lib.sapphirecity_baseboard(sch_1):\DDR4_CHN_A_DQ_DQS_BYTE5\" )
				( netClassRef "@sapphirecity_baseboard_lib.sapphirecity_baseboard(sch_1):\DDR4_CHN_A_DQ_DQS_BYTE6\" )
			)
			( classClass "@sapphirecity_baseboard_lib.sapphirecity_baseboard(sch_1):\CC747\"
				( spacingCSetRef "@sapphirecity_baseboard_lib.sapphirecity_baseboard(sch_1):\DDR4_2SPC_DQ/DQS\" )
				( netClassRef "@sapphirecity_baseboard_lib.sapphirecity_baseboard(sch_1):\DDR4_CHN_A_DQ_DQS_BYTE6\" )
				( netClassRef "@sapphirecity_baseboard_lib.sapphirecity_baseboard(sch_1):\DDR4_CHN_A_DQ_DQS_BYTE6\" )
			)
			( classClass "@crescent_city_bb_fab1_lib.crescent_city_bb_fab1(sch_1):\CC7\"
				( spacingCSetRef "@crescent_city_bb_fab1_lib.crescent_city_bb_fab1(sch_1):\DEFAULT\" )
				( netClassRef "@sapphirecity_baseboard_lib.sapphirecity_baseboard(sch_1):\POWER\" )
				( netClassRef "@sapphirecity_baseboard_lib.sapphirecity_baseboard(sch_1):\DDR4_CHN_A_DQ_DQS_BYTE6\" )
			)
			( classClass "@sapphirecity_baseboard_lib.sapphirecity_baseboard(sch_1):\CC56\"
				( spacingCSetRef "@crescent_city_bb_fab1_lib.crescent_city_bb_fab1(sch_1):\DEFAULT\" )
				( netClassRef "@sapphirecity_baseboard_lib.sapphirecity_baseboard(sch_1):\GND\" )
				( netClassRef "@sapphirecity_baseboard_lib.sapphirecity_baseboard(sch_1):\DDR4_CHN_A_DQ_DQS_BYTE5\" )
			)
			( classClass "@sapphirecity_baseboard_lib.sapphirecity_baseboard(sch_1):\CC367\"
				( spacingCSetRef "@sapphirecity_baseboard_lib.sapphirecity_baseboard(sch_1):\DQ_TO_DQ\" )
				( netClassRef "@sapphirecity_baseboard_lib.sapphirecity_baseboard(sch_1):\DDR4_CHN_A_CLK\" )
				( netClassRef "@sapphirecity_baseboard_lib.sapphirecity_baseboard(sch_1):\DDR4_CHN_A_DQ_DQS_BYTE5\" )
			)
			( classClass "@sapphirecity_baseboard_lib.sapphirecity_baseboard(sch_1):\CC379\"
				( spacingCSetRef "@sapphirecity_baseboard_lib.sapphirecity_baseboard(sch_1):\DQ_TO_DQ\" )
				( netClassRef "@sapphirecity_baseboard_lib.sapphirecity_baseboard(sch_1):\DDR4_CHN_A_CMD_ADD\" )
				( netClassRef "@sapphirecity_baseboard_lib.sapphirecity_baseboard(sch_1):\DDR4_CHN_A_DQ_DQS_BYTE5\" )
			)
			( classClass "@sapphirecity_baseboard_lib.sapphirecity_baseboard(sch_1):\CC388\"
				( spacingCSetRef "@sapphirecity_baseboard_lib.sapphirecity_baseboard(sch_1):\DQ_TO_DQ\" )
				( netClassRef "@sapphirecity_baseboard_lib.sapphirecity_baseboard(sch_1):\DDR4_CHN_A_CTRL\" )
				( netClassRef "@sapphirecity_baseboard_lib.sapphirecity_baseboard(sch_1):\DDR4_CHN_A_DQ_DQS_BYTE5\" )
			)
			( classClass "@sapphirecity_baseboard_lib.sapphirecity_baseboard(sch_1):\CC398\"
				( spacingCSetRef "@sapphirecity_baseboard_lib.sapphirecity_baseboard(sch_1):\DQ_TO_DQ\" )
				( netClassRef "@sapphirecity_baseboard_lib.sapphirecity_baseboard(sch_1):\DDR4_CHN_A_DQ_DQS_BYTE5\" )
				( netClassRef "@sapphirecity_baseboard_lib.sapphirecity_baseboard(sch_1):\DDR4_CHN_A_ECC\" )
			)
			( classClass "@sapphirecity_baseboard_lib.sapphirecity_baseboard(sch_1):\CC714\"
				( spacingCSetRef "@sapphirecity_baseboard_lib.sapphirecity_baseboard(sch_1):\DQ_TO_DQ\" )
				( netClassRef "@sapphirecity_baseboard_lib.sapphirecity_baseboard(sch_1):\DDR4_CHN_A_DQ_DQS_BYTE0\" )
				( netClassRef "@sapphirecity_baseboard_lib.sapphirecity_baseboard(sch_1):\DDR4_CHN_A_DQ_DQS_BYTE5\" )
			)
			( classClass "@sapphirecity_baseboard_lib.sapphirecity_baseboard(sch_1):\CC721\"
				( spacingCSetRef "@sapphirecity_baseboard_lib.sapphirecity_baseboard(sch_1):\DQ_TO_DQ\" )
				( netClassRef "@sapphirecity_baseboard_lib.sapphirecity_baseboard(sch_1):\DDR4_CHN_A_DQ_DQS_BYTE1\" )
				( netClassRef "@sapphirecity_baseboard_lib.sapphirecity_baseboard(sch_1):\DDR4_CHN_A_DQ_DQS_BYTE5\" )
			)
			( classClass "@sapphirecity_baseboard_lib.sapphirecity_baseboard(sch_1):\CC729\"
				( spacingCSetRef "@sapphirecity_baseboard_lib.sapphirecity_baseboard(sch_1):\DQ_TO_DQ\" )
				( netClassRef "@sapphirecity_baseboard_lib.sapphirecity_baseboard(sch_1):\DDR4_CHN_A_DQ_DQS_BYTE2\" )
				( netClassRef "@sapphirecity_baseboard_lib.sapphirecity_baseboard(sch_1):\DDR4_CHN_A_DQ_DQS_BYTE5\" )
			)
			( classClass "@sapphirecity_baseboard_lib.sapphirecity_baseboard(sch_1):\CC736\"
				( spacingCSetRef "@sapphirecity_baseboard_lib.sapphirecity_baseboard(sch_1):\DQ_TO_DQ\" )
				( netClassRef "@sapphirecity_baseboard_lib.sapphirecity_baseboard(sch_1):\DDR4_CHN_A_DQ_DQS_BYTE3\" )
				( netClassRef "@sapphirecity_baseboard_lib.sapphirecity_baseboard(sch_1):\DDR4_CHN_A_DQ_DQS_BYTE5\" )
			)
			( classClass "@sapphirecity_baseboard_lib.sapphirecity_baseboard(sch_1):\CC742\"
				( spacingCSetRef "@sapphirecity_baseboard_lib.sapphirecity_baseboard(sch_1):\DQ_TO_DQ\" )
				( netClassRef "@sapphirecity_baseboard_lib.sapphirecity_baseboard(sch_1):\DDR4_CHN_A_DQ_DQS_BYTE4\" )
				( netClassRef "@sapphirecity_baseboard_lib.sapphirecity_baseboard(sch_1):\DDR4_CHN_A_DQ_DQS_BYTE5\" )
			)
			( classClass "@sapphirecity_baseboard_lib.sapphirecity_baseboard(sch_1):\CC743\"
				( spacingCSetRef "@sapphirecity_baseboard_lib.sapphirecity_baseboard(sch_1):\DDR4_2SPC_DQ/DQS\" )
				( netClassRef "@sapphirecity_baseboard_lib.sapphirecity_baseboard(sch_1):\DDR4_CHN_A_DQ_DQS_BYTE5\" )
				( netClassRef "@sapphirecity_baseboard_lib.sapphirecity_baseboard(sch_1):\DDR4_CHN_A_DQ_DQS_BYTE5\" )
			)
			( classClass "@crescent_city_bb_fab1_lib.crescent_city_bb_fab1(sch_1):\CC6\"
				( spacingCSetRef "@crescent_city_bb_fab1_lib.crescent_city_bb_fab1(sch_1):\DEFAULT\" )
				( netClassRef "@sapphirecity_baseboard_lib.sapphirecity_baseboard(sch_1):\POWER\" )
				( netClassRef "@sapphirecity_baseboard_lib.sapphirecity_baseboard(sch_1):\DDR4_CHN_A_DQ_DQS_BYTE5\" )
			)
			( classClass "@sapphirecity_baseboard_lib.sapphirecity_baseboard(sch_1):\CC57\"
				( spacingCSetRef "@crescent_city_bb_fab1_lib.crescent_city_bb_fab1(sch_1):\DEFAULT\" )
				( netClassRef "@sapphirecity_baseboard_lib.sapphirecity_baseboard(sch_1):\GND\" )
				( netClassRef "@sapphirecity_baseboard_lib.sapphirecity_baseboard(sch_1):\DDR4_CHN_A_DQ_DQS_BYTE4\" )
			)
			( classClass "@sapphirecity_baseboard_lib.sapphirecity_baseboard(sch_1):\CC366\"
				( spacingCSetRef "@sapphirecity_baseboard_lib.sapphirecity_baseboard(sch_1):\DQ_TO_DQ\" )
				( netClassRef "@sapphirecity_baseboard_lib.sapphirecity_baseboard(sch_1):\DDR4_CHN_A_CLK\" )
				( netClassRef "@sapphirecity_baseboard_lib.sapphirecity_baseboard(sch_1):\DDR4_CHN_A_DQ_DQS_BYTE4\" )
			)
			( classClass "@sapphirecity_baseboard_lib.sapphirecity_baseboard(sch_1):\CC378\"
				( spacingCSetRef "@sapphirecity_baseboard_lib.sapphirecity_baseboard(sch_1):\DQ_TO_DQ\" )
				( netClassRef "@sapphirecity_baseboard_lib.sapphirecity_baseboard(sch_1):\DDR4_CHN_A_CMD_ADD\" )
				( netClassRef "@sapphirecity_baseboard_lib.sapphirecity_baseboard(sch_1):\DDR4_CHN_A_DQ_DQS_BYTE4\" )
			)
			( classClass "@sapphirecity_baseboard_lib.sapphirecity_baseboard(sch_1):\CC387\"
				( spacingCSetRef "@sapphirecity_baseboard_lib.sapphirecity_baseboard(sch_1):\DQ_TO_DQ\" )
				( netClassRef "@sapphirecity_baseboard_lib.sapphirecity_baseboard(sch_1):\DDR4_CHN_A_CTRL\" )
				( netClassRef "@sapphirecity_baseboard_lib.sapphirecity_baseboard(sch_1):\DDR4_CHN_A_DQ_DQS_BYTE4\" )
			)
			( classClass "@sapphirecity_baseboard_lib.sapphirecity_baseboard(sch_1):\CC397\"
				( spacingCSetRef "@sapphirecity_baseboard_lib.sapphirecity_baseboard(sch_1):\DQ_TO_DQ\" )
				( netClassRef "@sapphirecity_baseboard_lib.sapphirecity_baseboard(sch_1):\DDR4_CHN_A_DQ_DQS_BYTE4\" )
				( netClassRef "@sapphirecity_baseboard_lib.sapphirecity_baseboard(sch_1):\DDR4_CHN_A_ECC\" )
			)
			( classClass "@sapphirecity_baseboard_lib.sapphirecity_baseboard(sch_1):\CC713\"
				( spacingCSetRef "@sapphirecity_baseboard_lib.sapphirecity_baseboard(sch_1):\DQ_TO_DQ\" )
				( netClassRef "@sapphirecity_baseboard_lib.sapphirecity_baseboard(sch_1):\DDR4_CHN_A_DQ_DQS_BYTE0\" )
				( netClassRef "@sapphirecity_baseboard_lib.sapphirecity_baseboard(sch_1):\DDR4_CHN_A_DQ_DQS_BYTE4\" )
			)
			( classClass "@sapphirecity_baseboard_lib.sapphirecity_baseboard(sch_1):\CC722\"
				( spacingCSetRef "@sapphirecity_baseboard_lib.sapphirecity_baseboard(sch_1):\DQ_TO_DQ\" )
				( netClassRef "@sapphirecity_baseboard_lib.sapphirecity_baseboard(sch_1):\DDR4_CHN_A_DQ_DQS_BYTE1\" )
				( netClassRef "@sapphirecity_baseboard_lib.sapphirecity_baseboard(sch_1):\DDR4_CHN_A_DQ_DQS_BYTE4\" )
			)
			( classClass "@sapphirecity_baseboard_lib.sapphirecity_baseboard(sch_1):\CC730\"
				( spacingCSetRef "@sapphirecity_baseboard_lib.sapphirecity_baseboard(sch_1):\DQ_TO_DQ\" )
				( netClassRef "@sapphirecity_baseboard_lib.sapphirecity_baseboard(sch_1):\DDR4_CHN_A_DQ_DQS_BYTE2\" )
				( netClassRef "@sapphirecity_baseboard_lib.sapphirecity_baseboard(sch_1):\DDR4_CHN_A_DQ_DQS_BYTE4\" )
			)
			( classClass "@sapphirecity_baseboard_lib.sapphirecity_baseboard(sch_1):\CC737\"
				( spacingCSetRef "@sapphirecity_baseboard_lib.sapphirecity_baseboard(sch_1):\DQ_TO_DQ\" )
				( netClassRef "@sapphirecity_baseboard_lib.sapphirecity_baseboard(sch_1):\DDR4_CHN_A_DQ_DQS_BYTE3\" )
				( netClassRef "@sapphirecity_baseboard_lib.sapphirecity_baseboard(sch_1):\DDR4_CHN_A_DQ_DQS_BYTE4\" )
			)
			( classClass "@sapphirecity_baseboard_lib.sapphirecity_baseboard(sch_1):\CC738\"
				( spacingCSetRef "@sapphirecity_baseboard_lib.sapphirecity_baseboard(sch_1):\DDR4_2SPC_DQ/DQS\" )
				( netClassRef "@sapphirecity_baseboard_lib.sapphirecity_baseboard(sch_1):\DDR4_CHN_A_DQ_DQS_BYTE4\" )
				( netClassRef "@sapphirecity_baseboard_lib.sapphirecity_baseboard(sch_1):\DDR4_CHN_A_DQ_DQS_BYTE4\" )
			)
			( classClass "@crescent_city_bb_fab1_lib.crescent_city_bb_fab1(sch_1):\CC5\"
				( spacingCSetRef "@crescent_city_bb_fab1_lib.crescent_city_bb_fab1(sch_1):\DEFAULT\" )
				( netClassRef "@sapphirecity_baseboard_lib.sapphirecity_baseboard(sch_1):\POWER\" )
				( netClassRef "@sapphirecity_baseboard_lib.sapphirecity_baseboard(sch_1):\DDR4_CHN_A_DQ_DQS_BYTE4\" )
			)
			( classClass "@sapphirecity_baseboard_lib.sapphirecity_baseboard(sch_1):\CC58\"
				( spacingCSetRef "@crescent_city_bb_fab1_lib.crescent_city_bb_fab1(sch_1):\DEFAULT\" )
				( netClassRef "@sapphirecity_baseboard_lib.sapphirecity_baseboard(sch_1):\GND\" )
				( netClassRef "@sapphirecity_baseboard_lib.sapphirecity_baseboard(sch_1):\DDR4_CHN_A_DQ_DQS_BYTE3\" )
			)
			( classClass "@sapphirecity_baseboard_lib.sapphirecity_baseboard(sch_1):\CC365\"
				( spacingCSetRef "@sapphirecity_baseboard_lib.sapphirecity_baseboard(sch_1):\DQ_TO_DQ\" )
				( netClassRef "@sapphirecity_baseboard_lib.sapphirecity_baseboard(sch_1):\DDR4_CHN_A_CLK\" )
				( netClassRef "@sapphirecity_baseboard_lib.sapphirecity_baseboard(sch_1):\DDR4_CHN_A_DQ_DQS_BYTE3\" )
			)
			( classClass "@sapphirecity_baseboard_lib.sapphirecity_baseboard(sch_1):\CC377\"
				( spacingCSetRef "@sapphirecity_baseboard_lib.sapphirecity_baseboard(sch_1):\DQ_TO_DQ\" )
				( netClassRef "@sapphirecity_baseboard_lib.sapphirecity_baseboard(sch_1):\DDR4_CHN_A_CMD_ADD\" )
				( netClassRef "@sapphirecity_baseboard_lib.sapphirecity_baseboard(sch_1):\DDR4_CHN_A_DQ_DQS_BYTE3\" )
			)
			( classClass "@sapphirecity_baseboard_lib.sapphirecity_baseboard(sch_1):\CC386\"
				( spacingCSetRef "@sapphirecity_baseboard_lib.sapphirecity_baseboard(sch_1):\DQ_TO_DQ\" )
				( netClassRef "@sapphirecity_baseboard_lib.sapphirecity_baseboard(sch_1):\DDR4_CHN_A_CTRL\" )
				( netClassRef "@sapphirecity_baseboard_lib.sapphirecity_baseboard(sch_1):\DDR4_CHN_A_DQ_DQS_BYTE3\" )
			)
			( classClass "@sapphirecity_baseboard_lib.sapphirecity_baseboard(sch_1):\CC396\"
				( spacingCSetRef "@sapphirecity_baseboard_lib.sapphirecity_baseboard(sch_1):\DQ_TO_DQ\" )
				( netClassRef "@sapphirecity_baseboard_lib.sapphirecity_baseboard(sch_1):\DDR4_CHN_A_DQ_DQS_BYTE3\" )
				( netClassRef "@sapphirecity_baseboard_lib.sapphirecity_baseboard(sch_1):\DDR4_CHN_A_ECC\" )
			)
			( classClass "@sapphirecity_baseboard_lib.sapphirecity_baseboard(sch_1):\CC712\"
				( spacingCSetRef "@sapphirecity_baseboard_lib.sapphirecity_baseboard(sch_1):\DQ_TO_DQ\" )
				( netClassRef "@sapphirecity_baseboard_lib.sapphirecity_baseboard(sch_1):\DDR4_CHN_A_DQ_DQS_BYTE0\" )
				( netClassRef "@sapphirecity_baseboard_lib.sapphirecity_baseboard(sch_1):\DDR4_CHN_A_DQ_DQS_BYTE3\" )
			)
			( classClass "@sapphirecity_baseboard_lib.sapphirecity_baseboard(sch_1):\CC723\"
				( spacingCSetRef "@sapphirecity_baseboard_lib.sapphirecity_baseboard(sch_1):\DQ_TO_DQ\" )
				( netClassRef "@sapphirecity_baseboard_lib.sapphirecity_baseboard(sch_1):\DDR4_CHN_A_DQ_DQS_BYTE1\" )
				( netClassRef "@sapphirecity_baseboard_lib.sapphirecity_baseboard(sch_1):\DDR4_CHN_A_DQ_DQS_BYTE3\" )
			)
			( classClass "@sapphirecity_baseboard_lib.sapphirecity_baseboard(sch_1):\CC731\"
				( spacingCSetRef "@sapphirecity_baseboard_lib.sapphirecity_baseboard(sch_1):\DQ_TO_DQ\" )
				( netClassRef "@sapphirecity_baseboard_lib.sapphirecity_baseboard(sch_1):\DDR4_CHN_A_DQ_DQS_BYTE2\" )
				( netClassRef "@sapphirecity_baseboard_lib.sapphirecity_baseboard(sch_1):\DDR4_CHN_A_DQ_DQS_BYTE3\" )
			)
			( classClass "@sapphirecity_baseboard_lib.sapphirecity_baseboard(sch_1):\CC732\"
				( spacingCSetRef "@sapphirecity_baseboard_lib.sapphirecity_baseboard(sch_1):\DDR4_2SPC_DQ/DQS\" )
				( netClassRef "@sapphirecity_baseboard_lib.sapphirecity_baseboard(sch_1):\DDR4_CHN_A_DQ_DQS_BYTE3\" )
				( netClassRef "@sapphirecity_baseboard_lib.sapphirecity_baseboard(sch_1):\DDR4_CHN_A_DQ_DQS_BYTE3\" )
			)
			( classClass "@crescent_city_bb_fab1_lib.crescent_city_bb_fab1(sch_1):\CC4\"
				( spacingCSetRef "@crescent_city_bb_fab1_lib.crescent_city_bb_fab1(sch_1):\DEFAULT\" )
				( netClassRef "@sapphirecity_baseboard_lib.sapphirecity_baseboard(sch_1):\POWER\" )
				( netClassRef "@sapphirecity_baseboard_lib.sapphirecity_baseboard(sch_1):\DDR4_CHN_A_DQ_DQS_BYTE3\" )
			)
			( classClass "@sapphirecity_baseboard_lib.sapphirecity_baseboard(sch_1):\CC59\"
				( spacingCSetRef "@crescent_city_bb_fab1_lib.crescent_city_bb_fab1(sch_1):\DEFAULT\" )
				( netClassRef "@sapphirecity_baseboard_lib.sapphirecity_baseboard(sch_1):\GND\" )
				( netClassRef "@sapphirecity_baseboard_lib.sapphirecity_baseboard(sch_1):\DDR4_CHN_A_DQ_DQS_BYTE2\" )
			)
			( classClass "@sapphirecity_baseboard_lib.sapphirecity_baseboard(sch_1):\CC364\"
				( spacingCSetRef "@sapphirecity_baseboard_lib.sapphirecity_baseboard(sch_1):\DQ_TO_DQ\" )
				( netClassRef "@sapphirecity_baseboard_lib.sapphirecity_baseboard(sch_1):\DDR4_CHN_A_CLK\" )
				( netClassRef "@sapphirecity_baseboard_lib.sapphirecity_baseboard(sch_1):\DDR4_CHN_A_DQ_DQS_BYTE2\" )
			)
			( classClass "@sapphirecity_baseboard_lib.sapphirecity_baseboard(sch_1):\CC376\"
				( spacingCSetRef "@sapphirecity_baseboard_lib.sapphirecity_baseboard(sch_1):\DQ_TO_DQ\" )
				( netClassRef "@sapphirecity_baseboard_lib.sapphirecity_baseboard(sch_1):\DDR4_CHN_A_CMD_ADD\" )
				( netClassRef "@sapphirecity_baseboard_lib.sapphirecity_baseboard(sch_1):\DDR4_CHN_A_DQ_DQS_BYTE2\" )
			)
			( classClass "@sapphirecity_baseboard_lib.sapphirecity_baseboard(sch_1):\CC385\"
				( spacingCSetRef "@sapphirecity_baseboard_lib.sapphirecity_baseboard(sch_1):\DQ_TO_DQ\" )
				( netClassRef "@sapphirecity_baseboard_lib.sapphirecity_baseboard(sch_1):\DDR4_CHN_A_CTRL\" )
				( netClassRef "@sapphirecity_baseboard_lib.sapphirecity_baseboard(sch_1):\DDR4_CHN_A_DQ_DQS_BYTE2\" )
			)
			( classClass "@sapphirecity_baseboard_lib.sapphirecity_baseboard(sch_1):\CC395\"
				( spacingCSetRef "@sapphirecity_baseboard_lib.sapphirecity_baseboard(sch_1):\DQ_TO_DQ\" )
				( netClassRef "@sapphirecity_baseboard_lib.sapphirecity_baseboard(sch_1):\DDR4_CHN_A_DQ_DQS_BYTE2\" )
				( netClassRef "@sapphirecity_baseboard_lib.sapphirecity_baseboard(sch_1):\DDR4_CHN_A_ECC\" )
			)
			( classClass "@sapphirecity_baseboard_lib.sapphirecity_baseboard(sch_1):\CC711\"
				( spacingCSetRef "@sapphirecity_baseboard_lib.sapphirecity_baseboard(sch_1):\DQ_TO_DQ\" )
				( netClassRef "@sapphirecity_baseboard_lib.sapphirecity_baseboard(sch_1):\DDR4_CHN_A_DQ_DQS_BYTE0\" )
				( netClassRef "@sapphirecity_baseboard_lib.sapphirecity_baseboard(sch_1):\DDR4_CHN_A_DQ_DQS_BYTE2\" )
			)
			( classClass "@sapphirecity_baseboard_lib.sapphirecity_baseboard(sch_1):\CC724\"
				( spacingCSetRef "@sapphirecity_baseboard_lib.sapphirecity_baseboard(sch_1):\DQ_TO_DQ\" )
				( netClassRef "@sapphirecity_baseboard_lib.sapphirecity_baseboard(sch_1):\DDR4_CHN_A_DQ_DQS_BYTE1\" )
				( netClassRef "@sapphirecity_baseboard_lib.sapphirecity_baseboard(sch_1):\DDR4_CHN_A_DQ_DQS_BYTE2\" )
			)
			( classClass "@sapphirecity_baseboard_lib.sapphirecity_baseboard(sch_1):\CC725\"
				( spacingCSetRef "@sapphirecity_baseboard_lib.sapphirecity_baseboard(sch_1):\DDR4_2SPC_DQ/DQS\" )
				( netClassRef "@sapphirecity_baseboard_lib.sapphirecity_baseboard(sch_1):\DDR4_CHN_A_DQ_DQS_BYTE2\" )
				( netClassRef "@sapphirecity_baseboard_lib.sapphirecity_baseboard(sch_1):\DDR4_CHN_A_DQ_DQS_BYTE2\" )
			)
			( classClass "@crescent_city_bb_fab1_lib.crescent_city_bb_fab1(sch_1):\CC3\"
				( spacingCSetRef "@crescent_city_bb_fab1_lib.crescent_city_bb_fab1(sch_1):\DEFAULT\" )
				( netClassRef "@sapphirecity_baseboard_lib.sapphirecity_baseboard(sch_1):\POWER\" )
				( netClassRef "@sapphirecity_baseboard_lib.sapphirecity_baseboard(sch_1):\DDR4_CHN_A_DQ_DQS_BYTE2\" )
			)
			( classClass "@sapphirecity_baseboard_lib.sapphirecity_baseboard(sch_1):\CC60\"
				( spacingCSetRef "@crescent_city_bb_fab1_lib.crescent_city_bb_fab1(sch_1):\DEFAULT\" )
				( netClassRef "@sapphirecity_baseboard_lib.sapphirecity_baseboard(sch_1):\GND\" )
				( netClassRef "@sapphirecity_baseboard_lib.sapphirecity_baseboard(sch_1):\DDR4_CHN_A_DQ_DQS_BYTE1\" )
			)
			( classClass "@sapphirecity_baseboard_lib.sapphirecity_baseboard(sch_1):\CC363\"
				( spacingCSetRef "@sapphirecity_baseboard_lib.sapphirecity_baseboard(sch_1):\DQ_TO_DQ\" )
				( netClassRef "@sapphirecity_baseboard_lib.sapphirecity_baseboard(sch_1):\DDR4_CHN_A_CLK\" )
				( netClassRef "@sapphirecity_baseboard_lib.sapphirecity_baseboard(sch_1):\DDR4_CHN_A_DQ_DQS_BYTE1\" )
			)
			( classClass "@sapphirecity_baseboard_lib.sapphirecity_baseboard(sch_1):\CC375\"
				( spacingCSetRef "@sapphirecity_baseboard_lib.sapphirecity_baseboard(sch_1):\DQ_TO_DQ\" )
				( netClassRef "@sapphirecity_baseboard_lib.sapphirecity_baseboard(sch_1):\DDR4_CHN_A_CMD_ADD\" )
				( netClassRef "@sapphirecity_baseboard_lib.sapphirecity_baseboard(sch_1):\DDR4_CHN_A_DQ_DQS_BYTE1\" )
			)
			( classClass "@sapphirecity_baseboard_lib.sapphirecity_baseboard(sch_1):\CC384\"
				( spacingCSetRef "@sapphirecity_baseboard_lib.sapphirecity_baseboard(sch_1):\DQ_TO_DQ\" )
				( netClassRef "@sapphirecity_baseboard_lib.sapphirecity_baseboard(sch_1):\DDR4_CHN_A_CTRL\" )
				( netClassRef "@sapphirecity_baseboard_lib.sapphirecity_baseboard(sch_1):\DDR4_CHN_A_DQ_DQS_BYTE1\" )
			)
			( classClass "@sapphirecity_baseboard_lib.sapphirecity_baseboard(sch_1):\CC394\"
				( spacingCSetRef "@sapphirecity_baseboard_lib.sapphirecity_baseboard(sch_1):\DQ_TO_DQ\" )
				( netClassRef "@sapphirecity_baseboard_lib.sapphirecity_baseboard(sch_1):\DDR4_CHN_A_DQ_DQS_BYTE1\" )
				( netClassRef "@sapphirecity_baseboard_lib.sapphirecity_baseboard(sch_1):\DDR4_CHN_A_ECC\" )
			)
			( classClass "@sapphirecity_baseboard_lib.sapphirecity_baseboard(sch_1):\CC710\"
				( spacingCSetRef "@sapphirecity_baseboard_lib.sapphirecity_baseboard(sch_1):\DQ_TO_DQ\" )
				( netClassRef "@sapphirecity_baseboard_lib.sapphirecity_baseboard(sch_1):\DDR4_CHN_A_DQ_DQS_BYTE0\" )
				( netClassRef "@sapphirecity_baseboard_lib.sapphirecity_baseboard(sch_1):\DDR4_CHN_A_DQ_DQS_BYTE1\" )
			)
			( classClass "@sapphirecity_baseboard_lib.sapphirecity_baseboard(sch_1):\CC717\"
				( spacingCSetRef "@sapphirecity_baseboard_lib.sapphirecity_baseboard(sch_1):\DDR4_2SPC_DQ/DQS\" )
				( netClassRef "@sapphirecity_baseboard_lib.sapphirecity_baseboard(sch_1):\DDR4_CHN_A_DQ_DQS_BYTE1\" )
				( netClassRef "@sapphirecity_baseboard_lib.sapphirecity_baseboard(sch_1):\DDR4_CHN_A_DQ_DQS_BYTE1\" )
			)
			( classClass "@crescent_city_bb_fab1_lib.crescent_city_bb_fab1(sch_1):\CC2\"
				( spacingCSetRef "@crescent_city_bb_fab1_lib.crescent_city_bb_fab1(sch_1):\DEFAULT\" )
				( netClassRef "@sapphirecity_baseboard_lib.sapphirecity_baseboard(sch_1):\POWER\" )
				( netClassRef "@sapphirecity_baseboard_lib.sapphirecity_baseboard(sch_1):\DDR4_CHN_A_DQ_DQS_BYTE1\" )
			)
			( classClass "@sapphirecity_baseboard_lib.sapphirecity_baseboard(sch_1):\CC61\"
				( spacingCSetRef "@crescent_city_bb_fab1_lib.crescent_city_bb_fab1(sch_1):\DEFAULT\" )
				( netClassRef "@sapphirecity_baseboard_lib.sapphirecity_baseboard(sch_1):\GND\" )
				( netClassRef "@sapphirecity_baseboard_lib.sapphirecity_baseboard(sch_1):\DDR4_CHN_A_DQ_DQS_BYTE0\" )
			)
			( classClass "@sapphirecity_baseboard_lib.sapphirecity_baseboard(sch_1):\CC391\"
				( spacingCSetRef "@sapphirecity_baseboard_lib.sapphirecity_baseboard(sch_1):\DQ_TO_DQ\" )
				( netClassRef "@sapphirecity_baseboard_lib.sapphirecity_baseboard(sch_1):\DDR4_CHN_A_CTRL\" )
				( netClassRef "@sapphirecity_baseboard_lib.sapphirecity_baseboard(sch_1):\DDR4_CHN_A_DQ_DQS_BYTE0\" )
			)
			( classClass "@sapphirecity_baseboard_lib.sapphirecity_baseboard(sch_1):\CC401\"
				( spacingCSetRef "@sapphirecity_baseboard_lib.sapphirecity_baseboard(sch_1):\DQ_TO_DQ\" )
				( netClassRef "@sapphirecity_baseboard_lib.sapphirecity_baseboard(sch_1):\DDR4_CHN_A_DQ_DQS_BYTE0\" )
				( netClassRef "@sapphirecity_baseboard_lib.sapphirecity_baseboard(sch_1):\DDR4_CHN_A_ECC\" )
			)
			( classClass "@sapphirecity_baseboard_lib.sapphirecity_baseboard(sch_1):\CC708\"
				( spacingCSetRef "@sapphirecity_baseboard_lib.sapphirecity_baseboard(sch_1):\DDR4_2SPC_DQ/DQS\" )
				( netClassRef "@sapphirecity_baseboard_lib.sapphirecity_baseboard(sch_1):\DDR4_CHN_A_DQ_DQS_BYTE0\" )
				( netClassRef "@sapphirecity_baseboard_lib.sapphirecity_baseboard(sch_1):\DDR4_CHN_A_DQ_DQS_BYTE0\" )
			)
			( classClass "@crescent_city_bb_fab1_lib.crescent_city_bb_fab1(sch_1):\CC1\"
				( spacingCSetRef "@crescent_city_bb_fab1_lib.crescent_city_bb_fab1(sch_1):\DEFAULT\" )
				( netClassRef "@sapphirecity_baseboard_lib.sapphirecity_baseboard(sch_1):\POWER\" )
				( netClassRef "@sapphirecity_baseboard_lib.sapphirecity_baseboard(sch_1):\DDR4_CHN_A_DQ_DQS_BYTE0\" )
			)
			( classClass "@crescent_city_bb_fab1_lib.crescent_city_bb_fab1(sch_1):\CC291\"
				( spacingCSetRef "@sapphirecity_baseboard_lib.sapphirecity_baseboard(sch_1):\DQ_TO_DQ\" )
				( netClassRef "@sapphirecity_baseboard_lib.sapphirecity_baseboard(sch_1):\DDR4_CHN_A_CLK\" )
				( netClassRef "@sapphirecity_baseboard_lib.sapphirecity_baseboard(sch_1):\DDR4_CHN_A_DQ_DQS_BYTE0\" )
			)
			( classClass "@crescent_city_bb_fab1_lib.crescent_city_bb_fab1(sch_1):\CC292\"
				( spacingCSetRef "@sapphirecity_baseboard_lib.sapphirecity_baseboard(sch_1):\DQ_TO_DQ\" )
				( netClassRef "@sapphirecity_baseboard_lib.sapphirecity_baseboard(sch_1):\DDR4_CHN_A_CMD_ADD\" )
				( netClassRef "@sapphirecity_baseboard_lib.sapphirecity_baseboard(sch_1):\DDR4_CHN_A_DQ_DQS_BYTE0\" )
			)
			( classClass "@sapphirecity_baseboard_lib.sapphirecity_baseboard(sch_1):\CC63\"
				( spacingCSetRef "@crescent_city_bb_fab1_lib.crescent_city_bb_fab1(sch_1):\DEFAULT\" )
				( netClassRef "@sapphirecity_baseboard_lib.sapphirecity_baseboard(sch_1):\GND\" )
				( netClassRef "@sapphirecity_baseboard_lib.sapphirecity_baseboard(sch_1):\DDR4_CHN_B_DQ_DQS_BYTE7\" )
			)
			( classClass "@sapphirecity_baseboard_lib.sapphirecity_baseboard(sch_1):\CC410\"
				( spacingCSetRef "@sapphirecity_baseboard_lib.sapphirecity_baseboard(sch_1):\DQ_TO_DQ\" )
				( netClassRef "@sapphirecity_baseboard_lib.sapphirecity_baseboard(sch_1):\DDR4_CHN_B_CLK\" )
				( netClassRef "@sapphirecity_baseboard_lib.sapphirecity_baseboard(sch_1):\DDR4_CHN_B_DQ_DQS_BYTE7\" )
			)
			( classClass "@sapphirecity_baseboard_lib.sapphirecity_baseboard(sch_1):\CC424\"
				( spacingCSetRef "@sapphirecity_baseboard_lib.sapphirecity_baseboard(sch_1):\DQ_TO_DQ\" )
				( netClassRef "@sapphirecity_baseboard_lib.sapphirecity_baseboard(sch_1):\DDR4_CHN_B_CMD_ADD\" )
				( netClassRef "@sapphirecity_baseboard_lib.sapphirecity_baseboard(sch_1):\DDR4_CHN_B_DQ_DQS_BYTE7\" )
			)
			( classClass "@sapphirecity_baseboard_lib.sapphirecity_baseboard(sch_1):\CC433\"
				( spacingCSetRef "@sapphirecity_baseboard_lib.sapphirecity_baseboard(sch_1):\DQ_TO_DQ\" )
				( netClassRef "@sapphirecity_baseboard_lib.sapphirecity_baseboard(sch_1):\DDR4_CHN_B_CTRL\" )
				( netClassRef "@sapphirecity_baseboard_lib.sapphirecity_baseboard(sch_1):\DDR4_CHN_B_DQ_DQS_BYTE7\" )
			)
			( classClass "@sapphirecity_baseboard_lib.sapphirecity_baseboard(sch_1):\CC443\"
				( spacingCSetRef "@sapphirecity_baseboard_lib.sapphirecity_baseboard(sch_1):\DQ_TO_DQ\" )
				( netClassRef "@sapphirecity_baseboard_lib.sapphirecity_baseboard(sch_1):\DDR4_CHN_B_DQ_DQS_BYTE7\" )
				( netClassRef "@sapphirecity_baseboard_lib.sapphirecity_baseboard(sch_1):\DDR4_CHN_B_ECC\" )
			)
			( classClass "@sapphirecity_baseboard_lib.sapphirecity_baseboard(sch_1):\CC664\"
				( spacingCSetRef "@sapphirecity_baseboard_lib.sapphirecity_baseboard(sch_1):\DQ_TO_DQ\" )
				( netClassRef "@sapphirecity_baseboard_lib.sapphirecity_baseboard(sch_1):\DDR4_CHN_B_DQ_DQS_BYTE0\" )
				( netClassRef "@sapphirecity_baseboard_lib.sapphirecity_baseboard(sch_1):\DDR4_CHN_B_DQ_DQS_BYTE7\" )
			)
			( classClass "@sapphirecity_baseboard_lib.sapphirecity_baseboard(sch_1):\CC673\"
				( spacingCSetRef "@sapphirecity_baseboard_lib.sapphirecity_baseboard(sch_1):\DQ_TO_DQ\" )
				( netClassRef "@sapphirecity_baseboard_lib.sapphirecity_baseboard(sch_1):\DDR4_CHN_B_DQ_DQS_BYTE1\" )
				( netClassRef "@sapphirecity_baseboard_lib.sapphirecity_baseboard(sch_1):\DDR4_CHN_B_DQ_DQS_BYTE7\" )
			)
			( classClass "@sapphirecity_baseboard_lib.sapphirecity_baseboard(sch_1):\CC681\"
				( spacingCSetRef "@sapphirecity_baseboard_lib.sapphirecity_baseboard(sch_1):\DQ_TO_DQ\" )
				( netClassRef "@sapphirecity_baseboard_lib.sapphirecity_baseboard(sch_1):\DDR4_CHN_B_DQ_DQS_BYTE2\" )
				( netClassRef "@sapphirecity_baseboard_lib.sapphirecity_baseboard(sch_1):\DDR4_CHN_B_DQ_DQS_BYTE7\" )
			)
			( classClass "@sapphirecity_baseboard_lib.sapphirecity_baseboard(sch_1):\CC688\"
				( spacingCSetRef "@sapphirecity_baseboard_lib.sapphirecity_baseboard(sch_1):\DQ_TO_DQ\" )
				( netClassRef "@sapphirecity_baseboard_lib.sapphirecity_baseboard(sch_1):\DDR4_CHN_B_DQ_DQS_BYTE3\" )
				( netClassRef "@sapphirecity_baseboard_lib.sapphirecity_baseboard(sch_1):\DDR4_CHN_B_DQ_DQS_BYTE7\" )
			)
			( classClass "@sapphirecity_baseboard_lib.sapphirecity_baseboard(sch_1):\CC694\"
				( spacingCSetRef "@sapphirecity_baseboard_lib.sapphirecity_baseboard(sch_1):\DQ_TO_DQ\" )
				( netClassRef "@sapphirecity_baseboard_lib.sapphirecity_baseboard(sch_1):\DDR4_CHN_B_DQ_DQS_BYTE4\" )
				( netClassRef "@sapphirecity_baseboard_lib.sapphirecity_baseboard(sch_1):\DDR4_CHN_B_DQ_DQS_BYTE7\" )
			)
			( classClass "@sapphirecity_baseboard_lib.sapphirecity_baseboard(sch_1):\CC699\"
				( spacingCSetRef "@sapphirecity_baseboard_lib.sapphirecity_baseboard(sch_1):\DQ_TO_DQ\" )
				( netClassRef "@sapphirecity_baseboard_lib.sapphirecity_baseboard(sch_1):\DDR4_CHN_B_DQ_DQS_BYTE5\" )
				( netClassRef "@sapphirecity_baseboard_lib.sapphirecity_baseboard(sch_1):\DDR4_CHN_B_DQ_DQS_BYTE7\" )
			)
			( classClass "@sapphirecity_baseboard_lib.sapphirecity_baseboard(sch_1):\CC703\"
				( spacingCSetRef "@sapphirecity_baseboard_lib.sapphirecity_baseboard(sch_1):\DQ_TO_DQ\" )
				( netClassRef "@sapphirecity_baseboard_lib.sapphirecity_baseboard(sch_1):\DDR4_CHN_B_DQ_DQS_BYTE6\" )
				( netClassRef "@sapphirecity_baseboard_lib.sapphirecity_baseboard(sch_1):\DDR4_CHN_B_DQ_DQS_BYTE7\" )
			)
			( classClass "@sapphirecity_baseboard_lib.sapphirecity_baseboard(sch_1):\CC704\"
				( spacingCSetRef "@sapphirecity_baseboard_lib.sapphirecity_baseboard(sch_1):\DDR4_2SPC_DQ/DQS\" )
				( netClassRef "@sapphirecity_baseboard_lib.sapphirecity_baseboard(sch_1):\DDR4_CHN_B_DQ_DQS_BYTE7\" )
				( netClassRef "@sapphirecity_baseboard_lib.sapphirecity_baseboard(sch_1):\DDR4_CHN_B_DQ_DQS_BYTE7\" )
			)
			( classClass "@crescent_city_bb_fab1_lib.crescent_city_bb_fab1(sch_1):\CC16\"
				( spacingCSetRef "@crescent_city_bb_fab1_lib.crescent_city_bb_fab1(sch_1):\DEFAULT\" )
				( netClassRef "@sapphirecity_baseboard_lib.sapphirecity_baseboard(sch_1):\POWER\" )
				( netClassRef "@sapphirecity_baseboard_lib.sapphirecity_baseboard(sch_1):\DDR4_CHN_B_DQ_DQS_BYTE7\" )
			)
			( classClass "@sapphirecity_baseboard_lib.sapphirecity_baseboard(sch_1):\CC64\"
				( spacingCSetRef "@crescent_city_bb_fab1_lib.crescent_city_bb_fab1(sch_1):\DEFAULT\" )
				( netClassRef "@sapphirecity_baseboard_lib.sapphirecity_baseboard(sch_1):\GND\" )
				( netClassRef "@sapphirecity_baseboard_lib.sapphirecity_baseboard(sch_1):\DDR4_CHN_B_DQ_DQS_BYTE6\" )
			)
			( classClass "@sapphirecity_baseboard_lib.sapphirecity_baseboard(sch_1):\CC409\"
				( spacingCSetRef "@sapphirecity_baseboard_lib.sapphirecity_baseboard(sch_1):\DQ_TO_DQ\" )
				( netClassRef "@sapphirecity_baseboard_lib.sapphirecity_baseboard(sch_1):\DDR4_CHN_B_CLK\" )
				( netClassRef "@sapphirecity_baseboard_lib.sapphirecity_baseboard(sch_1):\DDR4_CHN_B_DQ_DQS_BYTE6\" )
			)
			( classClass "@sapphirecity_baseboard_lib.sapphirecity_baseboard(sch_1):\CC423\"
				( spacingCSetRef "@sapphirecity_baseboard_lib.sapphirecity_baseboard(sch_1):\DQ_TO_DQ\" )
				( netClassRef "@sapphirecity_baseboard_lib.sapphirecity_baseboard(sch_1):\DDR4_CHN_B_CMD_ADD\" )
				( netClassRef "@sapphirecity_baseboard_lib.sapphirecity_baseboard(sch_1):\DDR4_CHN_B_DQ_DQS_BYTE6\" )
			)
			( classClass "@sapphirecity_baseboard_lib.sapphirecity_baseboard(sch_1):\CC432\"
				( spacingCSetRef "@sapphirecity_baseboard_lib.sapphirecity_baseboard(sch_1):\DQ_TO_DQ\" )
				( netClassRef "@sapphirecity_baseboard_lib.sapphirecity_baseboard(sch_1):\DDR4_CHN_B_CTRL\" )
				( netClassRef "@sapphirecity_baseboard_lib.sapphirecity_baseboard(sch_1):\DDR4_CHN_B_DQ_DQS_BYTE6\" )
			)
			( classClass "@sapphirecity_baseboard_lib.sapphirecity_baseboard(sch_1):\CC442\"
				( spacingCSetRef "@sapphirecity_baseboard_lib.sapphirecity_baseboard(sch_1):\DQ_TO_DQ\" )
				( netClassRef "@sapphirecity_baseboard_lib.sapphirecity_baseboard(sch_1):\DDR4_CHN_B_DQ_DQS_BYTE6\" )
				( netClassRef "@sapphirecity_baseboard_lib.sapphirecity_baseboard(sch_1):\DDR4_CHN_B_ECC\" )
			)
			( classClass "@sapphirecity_baseboard_lib.sapphirecity_baseboard(sch_1):\CC665\"
				( spacingCSetRef "@sapphirecity_baseboard_lib.sapphirecity_baseboard(sch_1):\DQ_TO_DQ\" )
				( netClassRef "@sapphirecity_baseboard_lib.sapphirecity_baseboard(sch_1):\DDR4_CHN_B_DQ_DQS_BYTE0\" )
				( netClassRef "@sapphirecity_baseboard_lib.sapphirecity_baseboard(sch_1):\DDR4_CHN_B_DQ_DQS_BYTE6\" )
			)
			( classClass "@sapphirecity_baseboard_lib.sapphirecity_baseboard(sch_1):\CC674\"
				( spacingCSetRef "@sapphirecity_baseboard_lib.sapphirecity_baseboard(sch_1):\DQ_TO_DQ\" )
				( netClassRef "@sapphirecity_baseboard_lib.sapphirecity_baseboard(sch_1):\DDR4_CHN_B_DQ_DQS_BYTE1\" )
				( netClassRef "@sapphirecity_baseboard_lib.sapphirecity_baseboard(sch_1):\DDR4_CHN_B_DQ_DQS_BYTE6\" )
			)
			( classClass "@sapphirecity_baseboard_lib.sapphirecity_baseboard(sch_1):\CC682\"
				( spacingCSetRef "@sapphirecity_baseboard_lib.sapphirecity_baseboard(sch_1):\DQ_TO_DQ\" )
				( netClassRef "@sapphirecity_baseboard_lib.sapphirecity_baseboard(sch_1):\DDR4_CHN_B_DQ_DQS_BYTE2\" )
				( netClassRef "@sapphirecity_baseboard_lib.sapphirecity_baseboard(sch_1):\DDR4_CHN_B_DQ_DQS_BYTE6\" )
			)
			( classClass "@sapphirecity_baseboard_lib.sapphirecity_baseboard(sch_1):\CC689\"
				( spacingCSetRef "@sapphirecity_baseboard_lib.sapphirecity_baseboard(sch_1):\DQ_TO_DQ\" )
				( netClassRef "@sapphirecity_baseboard_lib.sapphirecity_baseboard(sch_1):\DDR4_CHN_B_DQ_DQS_BYTE3\" )
				( netClassRef "@sapphirecity_baseboard_lib.sapphirecity_baseboard(sch_1):\DDR4_CHN_B_DQ_DQS_BYTE6\" )
			)
			( classClass "@sapphirecity_baseboard_lib.sapphirecity_baseboard(sch_1):\CC695\"
				( spacingCSetRef "@sapphirecity_baseboard_lib.sapphirecity_baseboard(sch_1):\DQ_TO_DQ\" )
				( netClassRef "@sapphirecity_baseboard_lib.sapphirecity_baseboard(sch_1):\DDR4_CHN_B_DQ_DQS_BYTE4\" )
				( netClassRef "@sapphirecity_baseboard_lib.sapphirecity_baseboard(sch_1):\DDR4_CHN_B_DQ_DQS_BYTE6\" )
			)
			( classClass "@sapphirecity_baseboard_lib.sapphirecity_baseboard(sch_1):\CC700\"
				( spacingCSetRef "@sapphirecity_baseboard_lib.sapphirecity_baseboard(sch_1):\DQ_TO_DQ\" )
				( netClassRef "@sapphirecity_baseboard_lib.sapphirecity_baseboard(sch_1):\DDR4_CHN_B_DQ_DQS_BYTE5\" )
				( netClassRef "@sapphirecity_baseboard_lib.sapphirecity_baseboard(sch_1):\DDR4_CHN_B_DQ_DQS_BYTE6\" )
			)
			( classClass "@sapphirecity_baseboard_lib.sapphirecity_baseboard(sch_1):\CC701\"
				( spacingCSetRef "@sapphirecity_baseboard_lib.sapphirecity_baseboard(sch_1):\DDR4_2SPC_DQ/DQS\" )
				( netClassRef "@sapphirecity_baseboard_lib.sapphirecity_baseboard(sch_1):\DDR4_CHN_B_DQ_DQS_BYTE6\" )
				( netClassRef "@sapphirecity_baseboard_lib.sapphirecity_baseboard(sch_1):\DDR4_CHN_B_DQ_DQS_BYTE6\" )
			)
			( classClass "@crescent_city_bb_fab1_lib.crescent_city_bb_fab1(sch_1):\CC15\"
				( spacingCSetRef "@crescent_city_bb_fab1_lib.crescent_city_bb_fab1(sch_1):\DEFAULT\" )
				( netClassRef "@sapphirecity_baseboard_lib.sapphirecity_baseboard(sch_1):\POWER\" )
				( netClassRef "@sapphirecity_baseboard_lib.sapphirecity_baseboard(sch_1):\DDR4_CHN_B_DQ_DQS_BYTE6\" )
			)
			( classClass "@sapphirecity_baseboard_lib.sapphirecity_baseboard(sch_1):\CC65\"
				( spacingCSetRef "@crescent_city_bb_fab1_lib.crescent_city_bb_fab1(sch_1):\DEFAULT\" )
				( netClassRef "@sapphirecity_baseboard_lib.sapphirecity_baseboard(sch_1):\GND\" )
				( netClassRef "@sapphirecity_baseboard_lib.sapphirecity_baseboard(sch_1):\DDR4_CHN_B_DQ_DQS_BYTE5\" )
			)
			( classClass "@sapphirecity_baseboard_lib.sapphirecity_baseboard(sch_1):\CC408\"
				( spacingCSetRef "@sapphirecity_baseboard_lib.sapphirecity_baseboard(sch_1):\DQ_TO_DQ\" )
				( netClassRef "@sapphirecity_baseboard_lib.sapphirecity_baseboard(sch_1):\DDR4_CHN_B_CLK\" )
				( netClassRef "@sapphirecity_baseboard_lib.sapphirecity_baseboard(sch_1):\DDR4_CHN_B_DQ_DQS_BYTE5\" )
			)
			( classClass "@sapphirecity_baseboard_lib.sapphirecity_baseboard(sch_1):\CC422\"
				( spacingCSetRef "@sapphirecity_baseboard_lib.sapphirecity_baseboard(sch_1):\DQ_TO_DQ\" )
				( netClassRef "@sapphirecity_baseboard_lib.sapphirecity_baseboard(sch_1):\DDR4_CHN_B_CMD_ADD\" )
				( netClassRef "@sapphirecity_baseboard_lib.sapphirecity_baseboard(sch_1):\DDR4_CHN_B_DQ_DQS_BYTE5\" )
			)
			( classClass "@sapphirecity_baseboard_lib.sapphirecity_baseboard(sch_1):\CC431\"
				( spacingCSetRef "@sapphirecity_baseboard_lib.sapphirecity_baseboard(sch_1):\DQ_TO_DQ\" )
				( netClassRef "@sapphirecity_baseboard_lib.sapphirecity_baseboard(sch_1):\DDR4_CHN_B_CTRL\" )
				( netClassRef "@sapphirecity_baseboard_lib.sapphirecity_baseboard(sch_1):\DDR4_CHN_B_DQ_DQS_BYTE5\" )
			)
			( classClass "@sapphirecity_baseboard_lib.sapphirecity_baseboard(sch_1):\CC441\"
				( spacingCSetRef "@sapphirecity_baseboard_lib.sapphirecity_baseboard(sch_1):\DQ_TO_DQ\" )
				( netClassRef "@sapphirecity_baseboard_lib.sapphirecity_baseboard(sch_1):\DDR4_CHN_B_DQ_DQS_BYTE5\" )
				( netClassRef "@sapphirecity_baseboard_lib.sapphirecity_baseboard(sch_1):\DDR4_CHN_B_ECC\" )
			)
			( classClass "@sapphirecity_baseboard_lib.sapphirecity_baseboard(sch_1):\CC666\"
				( spacingCSetRef "@sapphirecity_baseboard_lib.sapphirecity_baseboard(sch_1):\DQ_TO_DQ\" )
				( netClassRef "@sapphirecity_baseboard_lib.sapphirecity_baseboard(sch_1):\DDR4_CHN_B_DQ_DQS_BYTE0\" )
				( netClassRef "@sapphirecity_baseboard_lib.sapphirecity_baseboard(sch_1):\DDR4_CHN_B_DQ_DQS_BYTE5\" )
			)
			( classClass "@sapphirecity_baseboard_lib.sapphirecity_baseboard(sch_1):\CC675\"
				( spacingCSetRef "@sapphirecity_baseboard_lib.sapphirecity_baseboard(sch_1):\DQ_TO_DQ\" )
				( netClassRef "@sapphirecity_baseboard_lib.sapphirecity_baseboard(sch_1):\DDR4_CHN_B_DQ_DQS_BYTE1\" )
				( netClassRef "@sapphirecity_baseboard_lib.sapphirecity_baseboard(sch_1):\DDR4_CHN_B_DQ_DQS_BYTE5\" )
			)
			( classClass "@sapphirecity_baseboard_lib.sapphirecity_baseboard(sch_1):\CC683\"
				( spacingCSetRef "@sapphirecity_baseboard_lib.sapphirecity_baseboard(sch_1):\DQ_TO_DQ\" )
				( netClassRef "@sapphirecity_baseboard_lib.sapphirecity_baseboard(sch_1):\DDR4_CHN_B_DQ_DQS_BYTE2\" )
				( netClassRef "@sapphirecity_baseboard_lib.sapphirecity_baseboard(sch_1):\DDR4_CHN_B_DQ_DQS_BYTE5\" )
			)
			( classClass "@sapphirecity_baseboard_lib.sapphirecity_baseboard(sch_1):\CC690\"
				( spacingCSetRef "@sapphirecity_baseboard_lib.sapphirecity_baseboard(sch_1):\DQ_TO_DQ\" )
				( netClassRef "@sapphirecity_baseboard_lib.sapphirecity_baseboard(sch_1):\DDR4_CHN_B_DQ_DQS_BYTE3\" )
				( netClassRef "@sapphirecity_baseboard_lib.sapphirecity_baseboard(sch_1):\DDR4_CHN_B_DQ_DQS_BYTE5\" )
			)
			( classClass "@sapphirecity_baseboard_lib.sapphirecity_baseboard(sch_1):\CC696\"
				( spacingCSetRef "@sapphirecity_baseboard_lib.sapphirecity_baseboard(sch_1):\DQ_TO_DQ\" )
				( netClassRef "@sapphirecity_baseboard_lib.sapphirecity_baseboard(sch_1):\DDR4_CHN_B_DQ_DQS_BYTE4\" )
				( netClassRef "@sapphirecity_baseboard_lib.sapphirecity_baseboard(sch_1):\DDR4_CHN_B_DQ_DQS_BYTE5\" )
			)
			( classClass "@sapphirecity_baseboard_lib.sapphirecity_baseboard(sch_1):\CC697\"
				( spacingCSetRef "@sapphirecity_baseboard_lib.sapphirecity_baseboard(sch_1):\DDR4_2SPC_DQ/DQS\" )
				( netClassRef "@sapphirecity_baseboard_lib.sapphirecity_baseboard(sch_1):\DDR4_CHN_B_DQ_DQS_BYTE5\" )
				( netClassRef "@sapphirecity_baseboard_lib.sapphirecity_baseboard(sch_1):\DDR4_CHN_B_DQ_DQS_BYTE5\" )
			)
			( classClass "@crescent_city_bb_fab1_lib.crescent_city_bb_fab1(sch_1):\CC14\"
				( spacingCSetRef "@crescent_city_bb_fab1_lib.crescent_city_bb_fab1(sch_1):\DEFAULT\" )
				( netClassRef "@sapphirecity_baseboard_lib.sapphirecity_baseboard(sch_1):\POWER\" )
				( netClassRef "@sapphirecity_baseboard_lib.sapphirecity_baseboard(sch_1):\DDR4_CHN_B_DQ_DQS_BYTE5\" )
			)
			( classClass "@sapphirecity_baseboard_lib.sapphirecity_baseboard(sch_1):\CC66\"
				( spacingCSetRef "@crescent_city_bb_fab1_lib.crescent_city_bb_fab1(sch_1):\DEFAULT\" )
				( netClassRef "@sapphirecity_baseboard_lib.sapphirecity_baseboard(sch_1):\GND\" )
				( netClassRef "@sapphirecity_baseboard_lib.sapphirecity_baseboard(sch_1):\DDR4_CHN_B_DQ_DQS_BYTE4\" )
			)
			( classClass "@sapphirecity_baseboard_lib.sapphirecity_baseboard(sch_1):\CC407\"
				( spacingCSetRef "@sapphirecity_baseboard_lib.sapphirecity_baseboard(sch_1):\DQ_TO_DQ\" )
				( netClassRef "@sapphirecity_baseboard_lib.sapphirecity_baseboard(sch_1):\DDR4_CHN_B_CLK\" )
				( netClassRef "@sapphirecity_baseboard_lib.sapphirecity_baseboard(sch_1):\DDR4_CHN_B_DQ_DQS_BYTE4\" )
			)
			( classClass "@sapphirecity_baseboard_lib.sapphirecity_baseboard(sch_1):\CC421\"
				( spacingCSetRef "@sapphirecity_baseboard_lib.sapphirecity_baseboard(sch_1):\DQ_TO_DQ\" )
				( netClassRef "@sapphirecity_baseboard_lib.sapphirecity_baseboard(sch_1):\DDR4_CHN_B_CMD_ADD\" )
				( netClassRef "@sapphirecity_baseboard_lib.sapphirecity_baseboard(sch_1):\DDR4_CHN_B_DQ_DQS_BYTE4\" )
			)
			( classClass "@sapphirecity_baseboard_lib.sapphirecity_baseboard(sch_1):\CC430\"
				( spacingCSetRef "@sapphirecity_baseboard_lib.sapphirecity_baseboard(sch_1):\DQ_TO_DQ\" )
				( netClassRef "@sapphirecity_baseboard_lib.sapphirecity_baseboard(sch_1):\DDR4_CHN_B_CTRL\" )
				( netClassRef "@sapphirecity_baseboard_lib.sapphirecity_baseboard(sch_1):\DDR4_CHN_B_DQ_DQS_BYTE4\" )
			)
			( classClass "@sapphirecity_baseboard_lib.sapphirecity_baseboard(sch_1):\CC440\"
				( spacingCSetRef "@sapphirecity_baseboard_lib.sapphirecity_baseboard(sch_1):\DQ_TO_DQ\" )
				( netClassRef "@sapphirecity_baseboard_lib.sapphirecity_baseboard(sch_1):\DDR4_CHN_B_DQ_DQS_BYTE4\" )
				( netClassRef "@sapphirecity_baseboard_lib.sapphirecity_baseboard(sch_1):\DDR4_CHN_B_ECC\" )
			)
			( classClass "@sapphirecity_baseboard_lib.sapphirecity_baseboard(sch_1):\CC667\"
				( spacingCSetRef "@sapphirecity_baseboard_lib.sapphirecity_baseboard(sch_1):\DQ_TO_DQ\" )
				( netClassRef "@sapphirecity_baseboard_lib.sapphirecity_baseboard(sch_1):\DDR4_CHN_B_DQ_DQS_BYTE0\" )
				( netClassRef "@sapphirecity_baseboard_lib.sapphirecity_baseboard(sch_1):\DDR4_CHN_B_DQ_DQS_BYTE4\" )
			)
			( classClass "@sapphirecity_baseboard_lib.sapphirecity_baseboard(sch_1):\CC676\"
				( spacingCSetRef "@sapphirecity_baseboard_lib.sapphirecity_baseboard(sch_1):\DQ_TO_DQ\" )
				( netClassRef "@sapphirecity_baseboard_lib.sapphirecity_baseboard(sch_1):\DDR4_CHN_B_DQ_DQS_BYTE1\" )
				( netClassRef "@sapphirecity_baseboard_lib.sapphirecity_baseboard(sch_1):\DDR4_CHN_B_DQ_DQS_BYTE4\" )
			)
			( classClass "@sapphirecity_baseboard_lib.sapphirecity_baseboard(sch_1):\CC684\"
				( spacingCSetRef "@sapphirecity_baseboard_lib.sapphirecity_baseboard(sch_1):\DQ_TO_DQ\" )
				( netClassRef "@sapphirecity_baseboard_lib.sapphirecity_baseboard(sch_1):\DDR4_CHN_B_DQ_DQS_BYTE2\" )
				( netClassRef "@sapphirecity_baseboard_lib.sapphirecity_baseboard(sch_1):\DDR4_CHN_B_DQ_DQS_BYTE4\" )
			)
			( classClass "@sapphirecity_baseboard_lib.sapphirecity_baseboard(sch_1):\CC691\"
				( spacingCSetRef "@sapphirecity_baseboard_lib.sapphirecity_baseboard(sch_1):\DQ_TO_DQ\" )
				( netClassRef "@sapphirecity_baseboard_lib.sapphirecity_baseboard(sch_1):\DDR4_CHN_B_DQ_DQS_BYTE3\" )
				( netClassRef "@sapphirecity_baseboard_lib.sapphirecity_baseboard(sch_1):\DDR4_CHN_B_DQ_DQS_BYTE4\" )
			)
			( classClass "@sapphirecity_baseboard_lib.sapphirecity_baseboard(sch_1):\CC692\"
				( spacingCSetRef "@sapphirecity_baseboard_lib.sapphirecity_baseboard(sch_1):\DDR4_2SPC_DQ/DQS\" )
				( netClassRef "@sapphirecity_baseboard_lib.sapphirecity_baseboard(sch_1):\DDR4_CHN_B_DQ_DQS_BYTE4\" )
				( netClassRef "@sapphirecity_baseboard_lib.sapphirecity_baseboard(sch_1):\DDR4_CHN_B_DQ_DQS_BYTE4\" )
			)
			( classClass "@crescent_city_bb_fab1_lib.crescent_city_bb_fab1(sch_1):\CC13\"
				( spacingCSetRef "@crescent_city_bb_fab1_lib.crescent_city_bb_fab1(sch_1):\DEFAULT\" )
				( netClassRef "@sapphirecity_baseboard_lib.sapphirecity_baseboard(sch_1):\POWER\" )
				( netClassRef "@sapphirecity_baseboard_lib.sapphirecity_baseboard(sch_1):\DDR4_CHN_B_DQ_DQS_BYTE4\" )
			)
			( classClass "@sapphirecity_baseboard_lib.sapphirecity_baseboard(sch_1):\CC67\"
				( spacingCSetRef "@crescent_city_bb_fab1_lib.crescent_city_bb_fab1(sch_1):\DEFAULT\" )
				( netClassRef "@sapphirecity_baseboard_lib.sapphirecity_baseboard(sch_1):\GND\" )
				( netClassRef "@sapphirecity_baseboard_lib.sapphirecity_baseboard(sch_1):\DDR4_CHN_B_DQ_DQS_BYTE3\" )
			)
			( classClass "@sapphirecity_baseboard_lib.sapphirecity_baseboard(sch_1):\CC406\"
				( spacingCSetRef "@sapphirecity_baseboard_lib.sapphirecity_baseboard(sch_1):\DQ_TO_DQ\" )
				( netClassRef "@sapphirecity_baseboard_lib.sapphirecity_baseboard(sch_1):\DDR4_CHN_B_CLK\" )
				( netClassRef "@sapphirecity_baseboard_lib.sapphirecity_baseboard(sch_1):\DDR4_CHN_B_DQ_DQS_BYTE3\" )
			)
			( classClass "@sapphirecity_baseboard_lib.sapphirecity_baseboard(sch_1):\CC420\"
				( spacingCSetRef "@sapphirecity_baseboard_lib.sapphirecity_baseboard(sch_1):\DQ_TO_DQ\" )
				( netClassRef "@sapphirecity_baseboard_lib.sapphirecity_baseboard(sch_1):\DDR4_CHN_B_CMD_ADD\" )
				( netClassRef "@sapphirecity_baseboard_lib.sapphirecity_baseboard(sch_1):\DDR4_CHN_B_DQ_DQS_BYTE3\" )
			)
			( classClass "@sapphirecity_baseboard_lib.sapphirecity_baseboard(sch_1):\CC429\"
				( spacingCSetRef "@sapphirecity_baseboard_lib.sapphirecity_baseboard(sch_1):\DQ_TO_DQ\" )
				( netClassRef "@sapphirecity_baseboard_lib.sapphirecity_baseboard(sch_1):\DDR4_CHN_B_CTRL\" )
				( netClassRef "@sapphirecity_baseboard_lib.sapphirecity_baseboard(sch_1):\DDR4_CHN_B_DQ_DQS_BYTE3\" )
			)
			( classClass "@sapphirecity_baseboard_lib.sapphirecity_baseboard(sch_1):\CC439\"
				( spacingCSetRef "@sapphirecity_baseboard_lib.sapphirecity_baseboard(sch_1):\DQ_TO_DQ\" )
				( netClassRef "@sapphirecity_baseboard_lib.sapphirecity_baseboard(sch_1):\DDR4_CHN_B_DQ_DQS_BYTE3\" )
				( netClassRef "@sapphirecity_baseboard_lib.sapphirecity_baseboard(sch_1):\DDR4_CHN_B_ECC\" )
			)
			( classClass "@sapphirecity_baseboard_lib.sapphirecity_baseboard(sch_1):\CC668\"
				( spacingCSetRef "@sapphirecity_baseboard_lib.sapphirecity_baseboard(sch_1):\DQ_TO_DQ\" )
				( netClassRef "@sapphirecity_baseboard_lib.sapphirecity_baseboard(sch_1):\DDR4_CHN_B_DQ_DQS_BYTE0\" )
				( netClassRef "@sapphirecity_baseboard_lib.sapphirecity_baseboard(sch_1):\DDR4_CHN_B_DQ_DQS_BYTE3\" )
			)
			( classClass "@sapphirecity_baseboard_lib.sapphirecity_baseboard(sch_1):\CC677\"
				( spacingCSetRef "@sapphirecity_baseboard_lib.sapphirecity_baseboard(sch_1):\DQ_TO_DQ\" )
				( netClassRef "@sapphirecity_baseboard_lib.sapphirecity_baseboard(sch_1):\DDR4_CHN_B_DQ_DQS_BYTE1\" )
				( netClassRef "@sapphirecity_baseboard_lib.sapphirecity_baseboard(sch_1):\DDR4_CHN_B_DQ_DQS_BYTE3\" )
			)
			( classClass "@sapphirecity_baseboard_lib.sapphirecity_baseboard(sch_1):\CC685\"
				( spacingCSetRef "@sapphirecity_baseboard_lib.sapphirecity_baseboard(sch_1):\DQ_TO_DQ\" )
				( netClassRef "@sapphirecity_baseboard_lib.sapphirecity_baseboard(sch_1):\DDR4_CHN_B_DQ_DQS_BYTE2\" )
				( netClassRef "@sapphirecity_baseboard_lib.sapphirecity_baseboard(sch_1):\DDR4_CHN_B_DQ_DQS_BYTE3\" )
			)
			( classClass "@sapphirecity_baseboard_lib.sapphirecity_baseboard(sch_1):\CC686\"
				( spacingCSetRef "@sapphirecity_baseboard_lib.sapphirecity_baseboard(sch_1):\DDR4_2SPC_DQ/DQS\" )
				( netClassRef "@sapphirecity_baseboard_lib.sapphirecity_baseboard(sch_1):\DDR4_CHN_B_DQ_DQS_BYTE3\" )
				( netClassRef "@sapphirecity_baseboard_lib.sapphirecity_baseboard(sch_1):\DDR4_CHN_B_DQ_DQS_BYTE3\" )
			)
			( classClass "@crescent_city_bb_fab1_lib.crescent_city_bb_fab1(sch_1):\CC12\"
				( spacingCSetRef "@crescent_city_bb_fab1_lib.crescent_city_bb_fab1(sch_1):\DEFAULT\" )
				( netClassRef "@sapphirecity_baseboard_lib.sapphirecity_baseboard(sch_1):\POWER\" )
				( netClassRef "@sapphirecity_baseboard_lib.sapphirecity_baseboard(sch_1):\DDR4_CHN_B_DQ_DQS_BYTE3\" )
			)
			( classClass "@sapphirecity_baseboard_lib.sapphirecity_baseboard(sch_1):\CC68\"
				( spacingCSetRef "@crescent_city_bb_fab1_lib.crescent_city_bb_fab1(sch_1):\DEFAULT\" )
				( netClassRef "@sapphirecity_baseboard_lib.sapphirecity_baseboard(sch_1):\GND\" )
				( netClassRef "@sapphirecity_baseboard_lib.sapphirecity_baseboard(sch_1):\DDR4_CHN_B_DQ_DQS_BYTE2\" )
			)
			( classClass "@sapphirecity_baseboard_lib.sapphirecity_baseboard(sch_1):\CC405\"
				( spacingCSetRef "@sapphirecity_baseboard_lib.sapphirecity_baseboard(sch_1):\DQ_TO_DQ\" )
				( netClassRef "@sapphirecity_baseboard_lib.sapphirecity_baseboard(sch_1):\DDR4_CHN_B_CLK\" )
				( netClassRef "@sapphirecity_baseboard_lib.sapphirecity_baseboard(sch_1):\DDR4_CHN_B_DQ_DQS_BYTE2\" )
			)
			( classClass "@sapphirecity_baseboard_lib.sapphirecity_baseboard(sch_1):\CC419\"
				( spacingCSetRef "@sapphirecity_baseboard_lib.sapphirecity_baseboard(sch_1):\DQ_TO_DQ\" )
				( netClassRef "@sapphirecity_baseboard_lib.sapphirecity_baseboard(sch_1):\DDR4_CHN_B_CMD_ADD\" )
				( netClassRef "@sapphirecity_baseboard_lib.sapphirecity_baseboard(sch_1):\DDR4_CHN_B_DQ_DQS_BYTE2\" )
			)
			( classClass "@sapphirecity_baseboard_lib.sapphirecity_baseboard(sch_1):\CC428\"
				( spacingCSetRef "@sapphirecity_baseboard_lib.sapphirecity_baseboard(sch_1):\DQ_TO_DQ\" )
				( netClassRef "@sapphirecity_baseboard_lib.sapphirecity_baseboard(sch_1):\DDR4_CHN_B_CTRL\" )
				( netClassRef "@sapphirecity_baseboard_lib.sapphirecity_baseboard(sch_1):\DDR4_CHN_B_DQ_DQS_BYTE2\" )
			)
			( classClass "@sapphirecity_baseboard_lib.sapphirecity_baseboard(sch_1):\CC438\"
				( spacingCSetRef "@sapphirecity_baseboard_lib.sapphirecity_baseboard(sch_1):\DQ_TO_DQ\" )
				( netClassRef "@sapphirecity_baseboard_lib.sapphirecity_baseboard(sch_1):\DDR4_CHN_B_DQ_DQS_BYTE2\" )
				( netClassRef "@sapphirecity_baseboard_lib.sapphirecity_baseboard(sch_1):\DDR4_CHN_B_ECC\" )
			)
			( classClass "@sapphirecity_baseboard_lib.sapphirecity_baseboard(sch_1):\CC669\"
				( spacingCSetRef "@sapphirecity_baseboard_lib.sapphirecity_baseboard(sch_1):\DQ_TO_DQ\" )
				( netClassRef "@sapphirecity_baseboard_lib.sapphirecity_baseboard(sch_1):\DDR4_CHN_B_DQ_DQS_BYTE0\" )
				( netClassRef "@sapphirecity_baseboard_lib.sapphirecity_baseboard(sch_1):\DDR4_CHN_B_DQ_DQS_BYTE2\" )
			)
			( classClass "@sapphirecity_baseboard_lib.sapphirecity_baseboard(sch_1):\CC678\"
				( spacingCSetRef "@sapphirecity_baseboard_lib.sapphirecity_baseboard(sch_1):\DQ_TO_DQ\" )
				( netClassRef "@sapphirecity_baseboard_lib.sapphirecity_baseboard(sch_1):\DDR4_CHN_B_DQ_DQS_BYTE1\" )
				( netClassRef "@sapphirecity_baseboard_lib.sapphirecity_baseboard(sch_1):\DDR4_CHN_B_DQ_DQS_BYTE2\" )
			)
			( classClass "@sapphirecity_baseboard_lib.sapphirecity_baseboard(sch_1):\CC679\"
				( spacingCSetRef "@sapphirecity_baseboard_lib.sapphirecity_baseboard(sch_1):\DDR4_2SPC_DQ/DQS\" )
				( netClassRef "@sapphirecity_baseboard_lib.sapphirecity_baseboard(sch_1):\DDR4_CHN_B_DQ_DQS_BYTE2\" )
				( netClassRef "@sapphirecity_baseboard_lib.sapphirecity_baseboard(sch_1):\DDR4_CHN_B_DQ_DQS_BYTE2\" )
			)
			( classClass "@crescent_city_bb_fab1_lib.crescent_city_bb_fab1(sch_1):\CC11\"
				( spacingCSetRef "@crescent_city_bb_fab1_lib.crescent_city_bb_fab1(sch_1):\DEFAULT\" )
				( netClassRef "@sapphirecity_baseboard_lib.sapphirecity_baseboard(sch_1):\POWER\" )
				( netClassRef "@sapphirecity_baseboard_lib.sapphirecity_baseboard(sch_1):\DDR4_CHN_B_DQ_DQS_BYTE2\" )
			)
			( classClass "@sapphirecity_baseboard_lib.sapphirecity_baseboard(sch_1):\CC69\"
				( spacingCSetRef "@crescent_city_bb_fab1_lib.crescent_city_bb_fab1(sch_1):\DEFAULT\" )
				( netClassRef "@sapphirecity_baseboard_lib.sapphirecity_baseboard(sch_1):\GND\" )
				( netClassRef "@sapphirecity_baseboard_lib.sapphirecity_baseboard(sch_1):\DDR4_CHN_B_DQ_DQS_BYTE1\" )
			)
			( classClass "@sapphirecity_baseboard_lib.sapphirecity_baseboard(sch_1):\CC404\"
				( spacingCSetRef "@sapphirecity_baseboard_lib.sapphirecity_baseboard(sch_1):\DQ_TO_DQ\" )
				( netClassRef "@sapphirecity_baseboard_lib.sapphirecity_baseboard(sch_1):\DDR4_CHN_B_CLK\" )
				( netClassRef "@sapphirecity_baseboard_lib.sapphirecity_baseboard(sch_1):\DDR4_CHN_B_DQ_DQS_BYTE1\" )
			)
			( classClass "@sapphirecity_baseboard_lib.sapphirecity_baseboard(sch_1):\CC418\"
				( spacingCSetRef "@sapphirecity_baseboard_lib.sapphirecity_baseboard(sch_1):\DQ_TO_DQ\" )
				( netClassRef "@sapphirecity_baseboard_lib.sapphirecity_baseboard(sch_1):\DDR4_CHN_B_CMD_ADD\" )
				( netClassRef "@sapphirecity_baseboard_lib.sapphirecity_baseboard(sch_1):\DDR4_CHN_B_DQ_DQS_BYTE1\" )
			)
			( classClass "@sapphirecity_baseboard_lib.sapphirecity_baseboard(sch_1):\CC427\"
				( spacingCSetRef "@sapphirecity_baseboard_lib.sapphirecity_baseboard(sch_1):\DQ_TO_DQ\" )
				( netClassRef "@sapphirecity_baseboard_lib.sapphirecity_baseboard(sch_1):\DDR4_CHN_B_CTRL\" )
				( netClassRef "@sapphirecity_baseboard_lib.sapphirecity_baseboard(sch_1):\DDR4_CHN_B_DQ_DQS_BYTE1\" )
			)
			( classClass "@sapphirecity_baseboard_lib.sapphirecity_baseboard(sch_1):\CC437\"
				( spacingCSetRef "@sapphirecity_baseboard_lib.sapphirecity_baseboard(sch_1):\DQ_TO_DQ\" )
				( netClassRef "@sapphirecity_baseboard_lib.sapphirecity_baseboard(sch_1):\DDR4_CHN_B_DQ_DQS_BYTE1\" )
				( netClassRef "@sapphirecity_baseboard_lib.sapphirecity_baseboard(sch_1):\DDR4_CHN_B_ECC\" )
			)
			( classClass "@sapphirecity_baseboard_lib.sapphirecity_baseboard(sch_1):\CC670\"
				( spacingCSetRef "@sapphirecity_baseboard_lib.sapphirecity_baseboard(sch_1):\DQ_TO_DQ\" )
				( netClassRef "@sapphirecity_baseboard_lib.sapphirecity_baseboard(sch_1):\DDR4_CHN_B_DQ_DQS_BYTE0\" )
				( netClassRef "@sapphirecity_baseboard_lib.sapphirecity_baseboard(sch_1):\DDR4_CHN_B_DQ_DQS_BYTE1\" )
			)
			( classClass "@sapphirecity_baseboard_lib.sapphirecity_baseboard(sch_1):\CC671\"
				( spacingCSetRef "@sapphirecity_baseboard_lib.sapphirecity_baseboard(sch_1):\DDR4_2SPC_DQ/DQS\" )
				( netClassRef "@sapphirecity_baseboard_lib.sapphirecity_baseboard(sch_1):\DDR4_CHN_B_DQ_DQS_BYTE1\" )
				( netClassRef "@sapphirecity_baseboard_lib.sapphirecity_baseboard(sch_1):\DDR4_CHN_B_DQ_DQS_BYTE1\" )
			)
			( classClass "@crescent_city_bb_fab1_lib.crescent_city_bb_fab1(sch_1):\CC10\"
				( spacingCSetRef "@crescent_city_bb_fab1_lib.crescent_city_bb_fab1(sch_1):\DEFAULT\" )
				( netClassRef "@sapphirecity_baseboard_lib.sapphirecity_baseboard(sch_1):\POWER\" )
				( netClassRef "@sapphirecity_baseboard_lib.sapphirecity_baseboard(sch_1):\DDR4_CHN_B_DQ_DQS_BYTE1\" )
			)
			( classClass "@sapphirecity_baseboard_lib.sapphirecity_baseboard(sch_1):\CC70\"
				( spacingCSetRef "@crescent_city_bb_fab1_lib.crescent_city_bb_fab1(sch_1):\DEFAULT\" )
				( netClassRef "@sapphirecity_baseboard_lib.sapphirecity_baseboard(sch_1):\GND\" )
				( netClassRef "@sapphirecity_baseboard_lib.sapphirecity_baseboard(sch_1):\DDR4_CHN_B_DQ_DQS_BYTE0\" )
			)
			( classClass "@sapphirecity_baseboard_lib.sapphirecity_baseboard(sch_1):\CC403\"
				( spacingCSetRef "@sapphirecity_baseboard_lib.sapphirecity_baseboard(sch_1):\DQ_TO_DQ\" )
				( netClassRef "@sapphirecity_baseboard_lib.sapphirecity_baseboard(sch_1):\DDR4_CHN_B_CLK\" )
				( netClassRef "@sapphirecity_baseboard_lib.sapphirecity_baseboard(sch_1):\DDR4_CHN_B_DQ_DQS_BYTE0\" )
			)
			( classClass "@sapphirecity_baseboard_lib.sapphirecity_baseboard(sch_1):\CC417\"
				( spacingCSetRef "@sapphirecity_baseboard_lib.sapphirecity_baseboard(sch_1):\DQ_TO_DQ\" )
				( netClassRef "@sapphirecity_baseboard_lib.sapphirecity_baseboard(sch_1):\DDR4_CHN_B_CMD_ADD\" )
				( netClassRef "@sapphirecity_baseboard_lib.sapphirecity_baseboard(sch_1):\DDR4_CHN_B_DQ_DQS_BYTE0\" )
			)
			( classClass "@sapphirecity_baseboard_lib.sapphirecity_baseboard(sch_1):\CC426\"
				( spacingCSetRef "@sapphirecity_baseboard_lib.sapphirecity_baseboard(sch_1):\DQ_TO_DQ\" )
				( netClassRef "@sapphirecity_baseboard_lib.sapphirecity_baseboard(sch_1):\DDR4_CHN_B_CTRL\" )
				( netClassRef "@sapphirecity_baseboard_lib.sapphirecity_baseboard(sch_1):\DDR4_CHN_B_DQ_DQS_BYTE0\" )
			)
			( classClass "@sapphirecity_baseboard_lib.sapphirecity_baseboard(sch_1):\CC436\"
				( spacingCSetRef "@sapphirecity_baseboard_lib.sapphirecity_baseboard(sch_1):\DQ_TO_DQ\" )
				( netClassRef "@sapphirecity_baseboard_lib.sapphirecity_baseboard(sch_1):\DDR4_CHN_B_DQ_DQS_BYTE0\" )
				( netClassRef "@sapphirecity_baseboard_lib.sapphirecity_baseboard(sch_1):\DDR4_CHN_B_ECC\" )
			)
			( classClass "@sapphirecity_baseboard_lib.sapphirecity_baseboard(sch_1):\CC662\"
				( spacingCSetRef "@sapphirecity_baseboard_lib.sapphirecity_baseboard(sch_1):\DDR4_2SPC_DQ/DQS\" )
				( netClassRef "@sapphirecity_baseboard_lib.sapphirecity_baseboard(sch_1):\DDR4_CHN_B_DQ_DQS_BYTE0\" )
				( netClassRef "@sapphirecity_baseboard_lib.sapphirecity_baseboard(sch_1):\DDR4_CHN_B_DQ_DQS_BYTE0\" )
			)
			( classClass "@crescent_city_bb_fab1_lib.crescent_city_bb_fab1(sch_1):\CC9\"
				( spacingCSetRef "@crescent_city_bb_fab1_lib.crescent_city_bb_fab1(sch_1):\DEFAULT\" )
				( netClassRef "@sapphirecity_baseboard_lib.sapphirecity_baseboard(sch_1):\POWER\" )
				( netClassRef "@sapphirecity_baseboard_lib.sapphirecity_baseboard(sch_1):\DDR4_CHN_B_DQ_DQS_BYTE0\" )
			)
			( classClass "@sapphirecity_baseboard_lib.sapphirecity_baseboard(sch_1):\CC72\"
				( spacingCSetRef "@crescent_city_bb_fab1_lib.crescent_city_bb_fab1(sch_1):\DEFAULT\" )
				( netClassRef "@sapphirecity_baseboard_lib.sapphirecity_baseboard(sch_1):\GND\" )
				( netClassRef "@sapphirecity_baseboard_lib.sapphirecity_baseboard(sch_1):\DDR4_CHN_C_DQ_DQS_BYTE7\" )
			)
			( classClass "@sapphirecity_baseboard_lib.sapphirecity_baseboard(sch_1):\CC452\"
				( spacingCSetRef "@sapphirecity_baseboard_lib.sapphirecity_baseboard(sch_1):\DQ_TO_DQ\" )
				( netClassRef "@sapphirecity_baseboard_lib.sapphirecity_baseboard(sch_1):\DDR4_CHN_C_CLK\" )
				( netClassRef "@sapphirecity_baseboard_lib.sapphirecity_baseboard(sch_1):\DDR4_CHN_C_DQ_DQS_BYTE7\" )
			)
			( classClass "@sapphirecity_baseboard_lib.sapphirecity_baseboard(sch_1):\CC464\"
				( spacingCSetRef "@sapphirecity_baseboard_lib.sapphirecity_baseboard(sch_1):\DQ_TO_DQ\" )
				( netClassRef "@sapphirecity_baseboard_lib.sapphirecity_baseboard(sch_1):\DDR4_CHN_C_CMD_ADD\" )
				( netClassRef "@sapphirecity_baseboard_lib.sapphirecity_baseboard(sch_1):\DDR4_CHN_C_DQ_DQS_BYTE7\" )
			)
			( classClass "@sapphirecity_baseboard_lib.sapphirecity_baseboard(sch_1):\CC475\"
				( spacingCSetRef "@sapphirecity_baseboard_lib.sapphirecity_baseboard(sch_1):\DQ_TO_DQ\" )
				( netClassRef "@sapphirecity_baseboard_lib.sapphirecity_baseboard(sch_1):\DDR4_CHN_C_CTRL\" )
				( netClassRef "@sapphirecity_baseboard_lib.sapphirecity_baseboard(sch_1):\DDR4_CHN_C_DQ_DQS_BYTE7\" )
			)
			( classClass "@sapphirecity_baseboard_lib.sapphirecity_baseboard(sch_1):\CC485\"
				( spacingCSetRef "@sapphirecity_baseboard_lib.sapphirecity_baseboard(sch_1):\DQ_TO_DQ\" )
				( netClassRef "@sapphirecity_baseboard_lib.sapphirecity_baseboard(sch_1):\DDR4_CHN_C_DQ_DQS_BYTE7\" )
				( netClassRef "@sapphirecity_baseboard_lib.sapphirecity_baseboard(sch_1):\DDR4_CHN_C_ECC\" )
			)
			( classClass "@sapphirecity_baseboard_lib.sapphirecity_baseboard(sch_1):\CC618\"
				( spacingCSetRef "@sapphirecity_baseboard_lib.sapphirecity_baseboard(sch_1):\DQ_TO_DQ\" )
				( netClassRef "@sapphirecity_baseboard_lib.sapphirecity_baseboard(sch_1):\DDR4_CHN_C_DQ_DQS_BYTE0\" )
				( netClassRef "@sapphirecity_baseboard_lib.sapphirecity_baseboard(sch_1):\DDR4_CHN_C_DQ_DQS_BYTE7\" )
			)
			( classClass "@sapphirecity_baseboard_lib.sapphirecity_baseboard(sch_1):\CC627\"
				( spacingCSetRef "@sapphirecity_baseboard_lib.sapphirecity_baseboard(sch_1):\DQ_TO_DQ\" )
				( netClassRef "@sapphirecity_baseboard_lib.sapphirecity_baseboard(sch_1):\DDR4_CHN_C_DQ_DQS_BYTE1\" )
				( netClassRef "@sapphirecity_baseboard_lib.sapphirecity_baseboard(sch_1):\DDR4_CHN_C_DQ_DQS_BYTE7\" )
			)
			( classClass "@sapphirecity_baseboard_lib.sapphirecity_baseboard(sch_1):\CC635\"
				( spacingCSetRef "@sapphirecity_baseboard_lib.sapphirecity_baseboard(sch_1):\DQ_TO_DQ\" )
				( netClassRef "@sapphirecity_baseboard_lib.sapphirecity_baseboard(sch_1):\DDR4_CHN_C_DQ_DQS_BYTE2\" )
				( netClassRef "@sapphirecity_baseboard_lib.sapphirecity_baseboard(sch_1):\DDR4_CHN_C_DQ_DQS_BYTE7\" )
			)
			( classClass "@sapphirecity_baseboard_lib.sapphirecity_baseboard(sch_1):\CC642\"
				( spacingCSetRef "@sapphirecity_baseboard_lib.sapphirecity_baseboard(sch_1):\DQ_TO_DQ\" )
				( netClassRef "@sapphirecity_baseboard_lib.sapphirecity_baseboard(sch_1):\DDR4_CHN_C_DQ_DQS_BYTE3\" )
				( netClassRef "@sapphirecity_baseboard_lib.sapphirecity_baseboard(sch_1):\DDR4_CHN_C_DQ_DQS_BYTE7\" )
			)
			( classClass "@sapphirecity_baseboard_lib.sapphirecity_baseboard(sch_1):\CC648\"
				( spacingCSetRef "@sapphirecity_baseboard_lib.sapphirecity_baseboard(sch_1):\DQ_TO_DQ\" )
				( netClassRef "@sapphirecity_baseboard_lib.sapphirecity_baseboard(sch_1):\DDR4_CHN_C_DQ_DQS_BYTE4\" )
				( netClassRef "@sapphirecity_baseboard_lib.sapphirecity_baseboard(sch_1):\DDR4_CHN_C_DQ_DQS_BYTE7\" )
			)
			( classClass "@sapphirecity_baseboard_lib.sapphirecity_baseboard(sch_1):\CC653\"
				( spacingCSetRef "@sapphirecity_baseboard_lib.sapphirecity_baseboard(sch_1):\DQ_TO_DQ\" )
				( netClassRef "@sapphirecity_baseboard_lib.sapphirecity_baseboard(sch_1):\DDR4_CHN_C_DQ_DQS_BYTE5\" )
				( netClassRef "@sapphirecity_baseboard_lib.sapphirecity_baseboard(sch_1):\DDR4_CHN_C_DQ_DQS_BYTE7\" )
			)
			( classClass "@sapphirecity_baseboard_lib.sapphirecity_baseboard(sch_1):\CC657\"
				( spacingCSetRef "@sapphirecity_baseboard_lib.sapphirecity_baseboard(sch_1):\DQ_TO_DQ\" )
				( netClassRef "@sapphirecity_baseboard_lib.sapphirecity_baseboard(sch_1):\DDR4_CHN_C_DQ_DQS_BYTE6\" )
				( netClassRef "@sapphirecity_baseboard_lib.sapphirecity_baseboard(sch_1):\DDR4_CHN_C_DQ_DQS_BYTE7\" )
			)
			( classClass "@sapphirecity_baseboard_lib.sapphirecity_baseboard(sch_1):\CC658\"
				( spacingCSetRef "@sapphirecity_baseboard_lib.sapphirecity_baseboard(sch_1):\DDR4_2SPC_DQ/DQS\" )
				( netClassRef "@sapphirecity_baseboard_lib.sapphirecity_baseboard(sch_1):\DDR4_CHN_C_DQ_DQS_BYTE7\" )
				( netClassRef "@sapphirecity_baseboard_lib.sapphirecity_baseboard(sch_1):\DDR4_CHN_C_DQ_DQS_BYTE7\" )
			)
			( classClass "@crescent_city_bb_fab1_lib.crescent_city_bb_fab1(sch_1):\CC24\"
				( spacingCSetRef "@crescent_city_bb_fab1_lib.crescent_city_bb_fab1(sch_1):\DEFAULT\" )
				( netClassRef "@sapphirecity_baseboard_lib.sapphirecity_baseboard(sch_1):\POWER\" )
				( netClassRef "@sapphirecity_baseboard_lib.sapphirecity_baseboard(sch_1):\DDR4_CHN_C_DQ_DQS_BYTE7\" )
			)
			( classClass "@sapphirecity_baseboard_lib.sapphirecity_baseboard(sch_1):\CC73\"
				( spacingCSetRef "@crescent_city_bb_fab1_lib.crescent_city_bb_fab1(sch_1):\DEFAULT\" )
				( netClassRef "@sapphirecity_baseboard_lib.sapphirecity_baseboard(sch_1):\GND\" )
				( netClassRef "@sapphirecity_baseboard_lib.sapphirecity_baseboard(sch_1):\DDR4_CHN_C_DQ_DQS_BYTE6\" )
			)
			( classClass "@sapphirecity_baseboard_lib.sapphirecity_baseboard(sch_1):\CC451\"
				( spacingCSetRef "@sapphirecity_baseboard_lib.sapphirecity_baseboard(sch_1):\DQ_TO_DQ\" )
				( netClassRef "@sapphirecity_baseboard_lib.sapphirecity_baseboard(sch_1):\DDR4_CHN_C_CLK\" )
				( netClassRef "@sapphirecity_baseboard_lib.sapphirecity_baseboard(sch_1):\DDR4_CHN_C_DQ_DQS_BYTE6\" )
			)
			( classClass "@sapphirecity_baseboard_lib.sapphirecity_baseboard(sch_1):\CC463\"
				( spacingCSetRef "@sapphirecity_baseboard_lib.sapphirecity_baseboard(sch_1):\DQ_TO_DQ\" )
				( netClassRef "@sapphirecity_baseboard_lib.sapphirecity_baseboard(sch_1):\DDR4_CHN_C_CMD_ADD\" )
				( netClassRef "@sapphirecity_baseboard_lib.sapphirecity_baseboard(sch_1):\DDR4_CHN_C_DQ_DQS_BYTE6\" )
			)
			( classClass "@sapphirecity_baseboard_lib.sapphirecity_baseboard(sch_1):\CC474\"
				( spacingCSetRef "@sapphirecity_baseboard_lib.sapphirecity_baseboard(sch_1):\DQ_TO_DQ\" )
				( netClassRef "@sapphirecity_baseboard_lib.sapphirecity_baseboard(sch_1):\DDR4_CHN_C_CTRL\" )
				( netClassRef "@sapphirecity_baseboard_lib.sapphirecity_baseboard(sch_1):\DDR4_CHN_C_DQ_DQS_BYTE6\" )
			)
			( classClass "@sapphirecity_baseboard_lib.sapphirecity_baseboard(sch_1):\CC484\"
				( spacingCSetRef "@sapphirecity_baseboard_lib.sapphirecity_baseboard(sch_1):\DQ_TO_DQ\" )
				( netClassRef "@sapphirecity_baseboard_lib.sapphirecity_baseboard(sch_1):\DDR4_CHN_C_DQ_DQS_BYTE6\" )
				( netClassRef "@sapphirecity_baseboard_lib.sapphirecity_baseboard(sch_1):\DDR4_CHN_C_ECC\" )
			)
			( classClass "@sapphirecity_baseboard_lib.sapphirecity_baseboard(sch_1):\CC619\"
				( spacingCSetRef "@sapphirecity_baseboard_lib.sapphirecity_baseboard(sch_1):\DQ_TO_DQ\" )
				( netClassRef "@sapphirecity_baseboard_lib.sapphirecity_baseboard(sch_1):\DDR4_CHN_C_DQ_DQS_BYTE0\" )
				( netClassRef "@sapphirecity_baseboard_lib.sapphirecity_baseboard(sch_1):\DDR4_CHN_C_DQ_DQS_BYTE6\" )
			)
			( classClass "@sapphirecity_baseboard_lib.sapphirecity_baseboard(sch_1):\CC628\"
				( spacingCSetRef "@sapphirecity_baseboard_lib.sapphirecity_baseboard(sch_1):\DQ_TO_DQ\" )
				( netClassRef "@sapphirecity_baseboard_lib.sapphirecity_baseboard(sch_1):\DDR4_CHN_C_DQ_DQS_BYTE1\" )
				( netClassRef "@sapphirecity_baseboard_lib.sapphirecity_baseboard(sch_1):\DDR4_CHN_C_DQ_DQS_BYTE6\" )
			)
			( classClass "@sapphirecity_baseboard_lib.sapphirecity_baseboard(sch_1):\CC636\"
				( spacingCSetRef "@sapphirecity_baseboard_lib.sapphirecity_baseboard(sch_1):\DQ_TO_DQ\" )
				( netClassRef "@sapphirecity_baseboard_lib.sapphirecity_baseboard(sch_1):\DDR4_CHN_C_DQ_DQS_BYTE2\" )
				( netClassRef "@sapphirecity_baseboard_lib.sapphirecity_baseboard(sch_1):\DDR4_CHN_C_DQ_DQS_BYTE6\" )
			)
			( classClass "@sapphirecity_baseboard_lib.sapphirecity_baseboard(sch_1):\CC643\"
				( spacingCSetRef "@sapphirecity_baseboard_lib.sapphirecity_baseboard(sch_1):\DQ_TO_DQ\" )
				( netClassRef "@sapphirecity_baseboard_lib.sapphirecity_baseboard(sch_1):\DDR4_CHN_C_DQ_DQS_BYTE3\" )
				( netClassRef "@sapphirecity_baseboard_lib.sapphirecity_baseboard(sch_1):\DDR4_CHN_C_DQ_DQS_BYTE6\" )
			)
			( classClass "@sapphirecity_baseboard_lib.sapphirecity_baseboard(sch_1):\CC649\"
				( spacingCSetRef "@sapphirecity_baseboard_lib.sapphirecity_baseboard(sch_1):\DQ_TO_DQ\" )
				( netClassRef "@sapphirecity_baseboard_lib.sapphirecity_baseboard(sch_1):\DDR4_CHN_C_DQ_DQS_BYTE4\" )
				( netClassRef "@sapphirecity_baseboard_lib.sapphirecity_baseboard(sch_1):\DDR4_CHN_C_DQ_DQS_BYTE6\" )
			)
			( classClass "@sapphirecity_baseboard_lib.sapphirecity_baseboard(sch_1):\CC654\"
				( spacingCSetRef "@sapphirecity_baseboard_lib.sapphirecity_baseboard(sch_1):\DQ_TO_DQ\" )
				( netClassRef "@sapphirecity_baseboard_lib.sapphirecity_baseboard(sch_1):\DDR4_CHN_C_DQ_DQS_BYTE5\" )
				( netClassRef "@sapphirecity_baseboard_lib.sapphirecity_baseboard(sch_1):\DDR4_CHN_C_DQ_DQS_BYTE6\" )
			)
			( classClass "@sapphirecity_baseboard_lib.sapphirecity_baseboard(sch_1):\CC655\"
				( spacingCSetRef "@sapphirecity_baseboard_lib.sapphirecity_baseboard(sch_1):\DDR4_2SPC_DQ/DQS\" )
				( netClassRef "@sapphirecity_baseboard_lib.sapphirecity_baseboard(sch_1):\DDR4_CHN_C_DQ_DQS_BYTE6\" )
				( netClassRef "@sapphirecity_baseboard_lib.sapphirecity_baseboard(sch_1):\DDR4_CHN_C_DQ_DQS_BYTE6\" )
			)
			( classClass "@crescent_city_bb_fab1_lib.crescent_city_bb_fab1(sch_1):\CC23\"
				( spacingCSetRef "@crescent_city_bb_fab1_lib.crescent_city_bb_fab1(sch_1):\DEFAULT\" )
				( netClassRef "@sapphirecity_baseboard_lib.sapphirecity_baseboard(sch_1):\POWER\" )
				( netClassRef "@sapphirecity_baseboard_lib.sapphirecity_baseboard(sch_1):\DDR4_CHN_C_DQ_DQS_BYTE6\" )
			)
			( classClass "@sapphirecity_baseboard_lib.sapphirecity_baseboard(sch_1):\CC74\"
				( spacingCSetRef "@crescent_city_bb_fab1_lib.crescent_city_bb_fab1(sch_1):\DEFAULT\" )
				( netClassRef "@sapphirecity_baseboard_lib.sapphirecity_baseboard(sch_1):\GND\" )
				( netClassRef "@sapphirecity_baseboard_lib.sapphirecity_baseboard(sch_1):\DDR4_CHN_C_DQ_DQS_BYTE5\" )
			)
			( classClass "@sapphirecity_baseboard_lib.sapphirecity_baseboard(sch_1):\CC450\"
				( spacingCSetRef "@sapphirecity_baseboard_lib.sapphirecity_baseboard(sch_1):\DQ_TO_DQ\" )
				( netClassRef "@sapphirecity_baseboard_lib.sapphirecity_baseboard(sch_1):\DDR4_CHN_C_CLK\" )
				( netClassRef "@sapphirecity_baseboard_lib.sapphirecity_baseboard(sch_1):\DDR4_CHN_C_DQ_DQS_BYTE5\" )
			)
			( classClass "@sapphirecity_baseboard_lib.sapphirecity_baseboard(sch_1):\CC462\"
				( spacingCSetRef "@sapphirecity_baseboard_lib.sapphirecity_baseboard(sch_1):\DQ_TO_DQ\" )
				( netClassRef "@sapphirecity_baseboard_lib.sapphirecity_baseboard(sch_1):\DDR4_CHN_C_CMD_ADD\" )
				( netClassRef "@sapphirecity_baseboard_lib.sapphirecity_baseboard(sch_1):\DDR4_CHN_C_DQ_DQS_BYTE5\" )
			)
			( classClass "@sapphirecity_baseboard_lib.sapphirecity_baseboard(sch_1):\CC473\"
				( spacingCSetRef "@sapphirecity_baseboard_lib.sapphirecity_baseboard(sch_1):\DQ_TO_DQ\" )
				( netClassRef "@sapphirecity_baseboard_lib.sapphirecity_baseboard(sch_1):\DDR4_CHN_C_CTRL\" )
				( netClassRef "@sapphirecity_baseboard_lib.sapphirecity_baseboard(sch_1):\DDR4_CHN_C_DQ_DQS_BYTE5\" )
			)
			( classClass "@sapphirecity_baseboard_lib.sapphirecity_baseboard(sch_1):\CC483\"
				( spacingCSetRef "@sapphirecity_baseboard_lib.sapphirecity_baseboard(sch_1):\DQ_TO_DQ\" )
				( netClassRef "@sapphirecity_baseboard_lib.sapphirecity_baseboard(sch_1):\DDR4_CHN_C_DQ_DQS_BYTE5\" )
				( netClassRef "@sapphirecity_baseboard_lib.sapphirecity_baseboard(sch_1):\DDR4_CHN_C_ECC\" )
			)
			( classClass "@sapphirecity_baseboard_lib.sapphirecity_baseboard(sch_1):\CC620\"
				( spacingCSetRef "@sapphirecity_baseboard_lib.sapphirecity_baseboard(sch_1):\DQ_TO_DQ\" )
				( netClassRef "@sapphirecity_baseboard_lib.sapphirecity_baseboard(sch_1):\DDR4_CHN_C_DQ_DQS_BYTE0\" )
				( netClassRef "@sapphirecity_baseboard_lib.sapphirecity_baseboard(sch_1):\DDR4_CHN_C_DQ_DQS_BYTE5\" )
			)
			( classClass "@sapphirecity_baseboard_lib.sapphirecity_baseboard(sch_1):\CC629\"
				( spacingCSetRef "@sapphirecity_baseboard_lib.sapphirecity_baseboard(sch_1):\DQ_TO_DQ\" )
				( netClassRef "@sapphirecity_baseboard_lib.sapphirecity_baseboard(sch_1):\DDR4_CHN_C_DQ_DQS_BYTE1\" )
				( netClassRef "@sapphirecity_baseboard_lib.sapphirecity_baseboard(sch_1):\DDR4_CHN_C_DQ_DQS_BYTE5\" )
			)
			( classClass "@sapphirecity_baseboard_lib.sapphirecity_baseboard(sch_1):\CC637\"
				( spacingCSetRef "@sapphirecity_baseboard_lib.sapphirecity_baseboard(sch_1):\DQ_TO_DQ\" )
				( netClassRef "@sapphirecity_baseboard_lib.sapphirecity_baseboard(sch_1):\DDR4_CHN_C_DQ_DQS_BYTE2\" )
				( netClassRef "@sapphirecity_baseboard_lib.sapphirecity_baseboard(sch_1):\DDR4_CHN_C_DQ_DQS_BYTE5\" )
			)
			( classClass "@sapphirecity_baseboard_lib.sapphirecity_baseboard(sch_1):\CC644\"
				( spacingCSetRef "@sapphirecity_baseboard_lib.sapphirecity_baseboard(sch_1):\DQ_TO_DQ\" )
				( netClassRef "@sapphirecity_baseboard_lib.sapphirecity_baseboard(sch_1):\DDR4_CHN_C_DQ_DQS_BYTE3\" )
				( netClassRef "@sapphirecity_baseboard_lib.sapphirecity_baseboard(sch_1):\DDR4_CHN_C_DQ_DQS_BYTE5\" )
			)
			( classClass "@sapphirecity_baseboard_lib.sapphirecity_baseboard(sch_1):\CC650\"
				( spacingCSetRef "@sapphirecity_baseboard_lib.sapphirecity_baseboard(sch_1):\DQ_TO_DQ\" )
				( netClassRef "@sapphirecity_baseboard_lib.sapphirecity_baseboard(sch_1):\DDR4_CHN_C_DQ_DQS_BYTE4\" )
				( netClassRef "@sapphirecity_baseboard_lib.sapphirecity_baseboard(sch_1):\DDR4_CHN_C_DQ_DQS_BYTE5\" )
			)
			( classClass "@sapphirecity_baseboard_lib.sapphirecity_baseboard(sch_1):\CC651\"
				( spacingCSetRef "@sapphirecity_baseboard_lib.sapphirecity_baseboard(sch_1):\DDR4_2SPC_DQ/DQS\" )
				( netClassRef "@sapphirecity_baseboard_lib.sapphirecity_baseboard(sch_1):\DDR4_CHN_C_DQ_DQS_BYTE5\" )
				( netClassRef "@sapphirecity_baseboard_lib.sapphirecity_baseboard(sch_1):\DDR4_CHN_C_DQ_DQS_BYTE5\" )
			)
			( classClass "@crescent_city_bb_fab1_lib.crescent_city_bb_fab1(sch_1):\CC22\"
				( spacingCSetRef "@crescent_city_bb_fab1_lib.crescent_city_bb_fab1(sch_1):\DEFAULT\" )
				( netClassRef "@sapphirecity_baseboard_lib.sapphirecity_baseboard(sch_1):\POWER\" )
				( netClassRef "@sapphirecity_baseboard_lib.sapphirecity_baseboard(sch_1):\DDR4_CHN_C_DQ_DQS_BYTE5\" )
			)
			( classClass "@sapphirecity_baseboard_lib.sapphirecity_baseboard(sch_1):\CC75\"
				( spacingCSetRef "@crescent_city_bb_fab1_lib.crescent_city_bb_fab1(sch_1):\DEFAULT\" )
				( netClassRef "@sapphirecity_baseboard_lib.sapphirecity_baseboard(sch_1):\GND\" )
				( netClassRef "@sapphirecity_baseboard_lib.sapphirecity_baseboard(sch_1):\DDR4_CHN_C_DQ_DQS_BYTE4\" )
			)
			( classClass "@sapphirecity_baseboard_lib.sapphirecity_baseboard(sch_1):\CC449\"
				( spacingCSetRef "@sapphirecity_baseboard_lib.sapphirecity_baseboard(sch_1):\DQ_TO_DQ\" )
				( netClassRef "@sapphirecity_baseboard_lib.sapphirecity_baseboard(sch_1):\DDR4_CHN_C_CLK\" )
				( netClassRef "@sapphirecity_baseboard_lib.sapphirecity_baseboard(sch_1):\DDR4_CHN_C_DQ_DQS_BYTE4\" )
			)
			( classClass "@sapphirecity_baseboard_lib.sapphirecity_baseboard(sch_1):\CC461\"
				( spacingCSetRef "@sapphirecity_baseboard_lib.sapphirecity_baseboard(sch_1):\DQ_TO_DQ\" )
				( netClassRef "@sapphirecity_baseboard_lib.sapphirecity_baseboard(sch_1):\DDR4_CHN_C_CMD_ADD\" )
				( netClassRef "@sapphirecity_baseboard_lib.sapphirecity_baseboard(sch_1):\DDR4_CHN_C_DQ_DQS_BYTE4\" )
			)
			( classClass "@sapphirecity_baseboard_lib.sapphirecity_baseboard(sch_1):\CC472\"
				( spacingCSetRef "@sapphirecity_baseboard_lib.sapphirecity_baseboard(sch_1):\DQ_TO_DQ\" )
				( netClassRef "@sapphirecity_baseboard_lib.sapphirecity_baseboard(sch_1):\DDR4_CHN_C_CTRL\" )
				( netClassRef "@sapphirecity_baseboard_lib.sapphirecity_baseboard(sch_1):\DDR4_CHN_C_DQ_DQS_BYTE4\" )
			)
			( classClass "@sapphirecity_baseboard_lib.sapphirecity_baseboard(sch_1):\CC482\"
				( spacingCSetRef "@sapphirecity_baseboard_lib.sapphirecity_baseboard(sch_1):\DQ_TO_DQ\" )
				( netClassRef "@sapphirecity_baseboard_lib.sapphirecity_baseboard(sch_1):\DDR4_CHN_C_DQ_DQS_BYTE4\" )
				( netClassRef "@sapphirecity_baseboard_lib.sapphirecity_baseboard(sch_1):\DDR4_CHN_C_ECC\" )
			)
			( classClass "@sapphirecity_baseboard_lib.sapphirecity_baseboard(sch_1):\CC621\"
				( spacingCSetRef "@sapphirecity_baseboard_lib.sapphirecity_baseboard(sch_1):\DQ_TO_DQ\" )
				( netClassRef "@sapphirecity_baseboard_lib.sapphirecity_baseboard(sch_1):\DDR4_CHN_C_DQ_DQS_BYTE0\" )
				( netClassRef "@sapphirecity_baseboard_lib.sapphirecity_baseboard(sch_1):\DDR4_CHN_C_DQ_DQS_BYTE4\" )
			)
			( classClass "@sapphirecity_baseboard_lib.sapphirecity_baseboard(sch_1):\CC630\"
				( spacingCSetRef "@sapphirecity_baseboard_lib.sapphirecity_baseboard(sch_1):\DQ_TO_DQ\" )
				( netClassRef "@sapphirecity_baseboard_lib.sapphirecity_baseboard(sch_1):\DDR4_CHN_C_DQ_DQS_BYTE1\" )
				( netClassRef "@sapphirecity_baseboard_lib.sapphirecity_baseboard(sch_1):\DDR4_CHN_C_DQ_DQS_BYTE4\" )
			)
			( classClass "@sapphirecity_baseboard_lib.sapphirecity_baseboard(sch_1):\CC638\"
				( spacingCSetRef "@sapphirecity_baseboard_lib.sapphirecity_baseboard(sch_1):\DQ_TO_DQ\" )
				( netClassRef "@sapphirecity_baseboard_lib.sapphirecity_baseboard(sch_1):\DDR4_CHN_C_DQ_DQS_BYTE2\" )
				( netClassRef "@sapphirecity_baseboard_lib.sapphirecity_baseboard(sch_1):\DDR4_CHN_C_DQ_DQS_BYTE4\" )
			)
			( classClass "@sapphirecity_baseboard_lib.sapphirecity_baseboard(sch_1):\CC645\"
				( spacingCSetRef "@sapphirecity_baseboard_lib.sapphirecity_baseboard(sch_1):\DQ_TO_DQ\" )
				( netClassRef "@sapphirecity_baseboard_lib.sapphirecity_baseboard(sch_1):\DDR4_CHN_C_DQ_DQS_BYTE3\" )
				( netClassRef "@sapphirecity_baseboard_lib.sapphirecity_baseboard(sch_1):\DDR4_CHN_C_DQ_DQS_BYTE4\" )
			)
			( classClass "@sapphirecity_baseboard_lib.sapphirecity_baseboard(sch_1):\CC646\"
				( spacingCSetRef "@sapphirecity_baseboard_lib.sapphirecity_baseboard(sch_1):\DDR4_2SPC_DQ/DQS\" )
				( netClassRef "@sapphirecity_baseboard_lib.sapphirecity_baseboard(sch_1):\DDR4_CHN_C_DQ_DQS_BYTE4\" )
				( netClassRef "@sapphirecity_baseboard_lib.sapphirecity_baseboard(sch_1):\DDR4_CHN_C_DQ_DQS_BYTE4\" )
			)
			( classClass "@crescent_city_bb_fab1_lib.crescent_city_bb_fab1(sch_1):\CC21\"
				( spacingCSetRef "@crescent_city_bb_fab1_lib.crescent_city_bb_fab1(sch_1):\DEFAULT\" )
				( netClassRef "@sapphirecity_baseboard_lib.sapphirecity_baseboard(sch_1):\POWER\" )
				( netClassRef "@sapphirecity_baseboard_lib.sapphirecity_baseboard(sch_1):\DDR4_CHN_C_DQ_DQS_BYTE4\" )
			)
			( classClass "@sapphirecity_baseboard_lib.sapphirecity_baseboard(sch_1):\CC76\"
				( spacingCSetRef "@crescent_city_bb_fab1_lib.crescent_city_bb_fab1(sch_1):\DEFAULT\" )
				( netClassRef "@sapphirecity_baseboard_lib.sapphirecity_baseboard(sch_1):\GND\" )
				( netClassRef "@sapphirecity_baseboard_lib.sapphirecity_baseboard(sch_1):\DDR4_CHN_C_DQ_DQS_BYTE3\" )
			)
			( classClass "@sapphirecity_baseboard_lib.sapphirecity_baseboard(sch_1):\CC448\"
				( spacingCSetRef "@sapphirecity_baseboard_lib.sapphirecity_baseboard(sch_1):\DQ_TO_DQ\" )
				( netClassRef "@sapphirecity_baseboard_lib.sapphirecity_baseboard(sch_1):\DDR4_CHN_C_CLK\" )
				( netClassRef "@sapphirecity_baseboard_lib.sapphirecity_baseboard(sch_1):\DDR4_CHN_C_DQ_DQS_BYTE3\" )
			)
			( classClass "@sapphirecity_baseboard_lib.sapphirecity_baseboard(sch_1):\CC460\"
				( spacingCSetRef "@sapphirecity_baseboard_lib.sapphirecity_baseboard(sch_1):\DQ_TO_DQ\" )
				( netClassRef "@sapphirecity_baseboard_lib.sapphirecity_baseboard(sch_1):\DDR4_CHN_C_CMD_ADD\" )
				( netClassRef "@sapphirecity_baseboard_lib.sapphirecity_baseboard(sch_1):\DDR4_CHN_C_DQ_DQS_BYTE3\" )
			)
			( classClass "@sapphirecity_baseboard_lib.sapphirecity_baseboard(sch_1):\CC471\"
				( spacingCSetRef "@sapphirecity_baseboard_lib.sapphirecity_baseboard(sch_1):\DQ_TO_DQ\" )
				( netClassRef "@sapphirecity_baseboard_lib.sapphirecity_baseboard(sch_1):\DDR4_CHN_C_CTRL\" )
				( netClassRef "@sapphirecity_baseboard_lib.sapphirecity_baseboard(sch_1):\DDR4_CHN_C_DQ_DQS_BYTE3\" )
			)
			( classClass "@sapphirecity_baseboard_lib.sapphirecity_baseboard(sch_1):\CC481\"
				( spacingCSetRef "@sapphirecity_baseboard_lib.sapphirecity_baseboard(sch_1):\DQ_TO_DQ\" )
				( netClassRef "@sapphirecity_baseboard_lib.sapphirecity_baseboard(sch_1):\DDR4_CHN_C_DQ_DQS_BYTE3\" )
				( netClassRef "@sapphirecity_baseboard_lib.sapphirecity_baseboard(sch_1):\DDR4_CHN_C_ECC\" )
			)
			( classClass "@sapphirecity_baseboard_lib.sapphirecity_baseboard(sch_1):\CC622\"
				( spacingCSetRef "@sapphirecity_baseboard_lib.sapphirecity_baseboard(sch_1):\DQ_TO_DQ\" )
				( netClassRef "@sapphirecity_baseboard_lib.sapphirecity_baseboard(sch_1):\DDR4_CHN_C_DQ_DQS_BYTE0\" )
				( netClassRef "@sapphirecity_baseboard_lib.sapphirecity_baseboard(sch_1):\DDR4_CHN_C_DQ_DQS_BYTE3\" )
			)
			( classClass "@sapphirecity_baseboard_lib.sapphirecity_baseboard(sch_1):\CC631\"
				( spacingCSetRef "@sapphirecity_baseboard_lib.sapphirecity_baseboard(sch_1):\DQ_TO_DQ\" )
				( netClassRef "@sapphirecity_baseboard_lib.sapphirecity_baseboard(sch_1):\DDR4_CHN_C_DQ_DQS_BYTE1\" )
				( netClassRef "@sapphirecity_baseboard_lib.sapphirecity_baseboard(sch_1):\DDR4_CHN_C_DQ_DQS_BYTE3\" )
			)
			( classClass "@sapphirecity_baseboard_lib.sapphirecity_baseboard(sch_1):\CC639\"
				( spacingCSetRef "@sapphirecity_baseboard_lib.sapphirecity_baseboard(sch_1):\DQ_TO_DQ\" )
				( netClassRef "@sapphirecity_baseboard_lib.sapphirecity_baseboard(sch_1):\DDR4_CHN_C_DQ_DQS_BYTE2\" )
				( netClassRef "@sapphirecity_baseboard_lib.sapphirecity_baseboard(sch_1):\DDR4_CHN_C_DQ_DQS_BYTE3\" )
			)
			( classClass "@sapphirecity_baseboard_lib.sapphirecity_baseboard(sch_1):\CC640\"
				( spacingCSetRef "@sapphirecity_baseboard_lib.sapphirecity_baseboard(sch_1):\DDR4_2SPC_DQ/DQS\" )
				( netClassRef "@sapphirecity_baseboard_lib.sapphirecity_baseboard(sch_1):\DDR4_CHN_C_DQ_DQS_BYTE3\" )
				( netClassRef "@sapphirecity_baseboard_lib.sapphirecity_baseboard(sch_1):\DDR4_CHN_C_DQ_DQS_BYTE3\" )
			)
			( classClass "@crescent_city_bb_fab1_lib.crescent_city_bb_fab1(sch_1):\CC20\"
				( spacingCSetRef "@crescent_city_bb_fab1_lib.crescent_city_bb_fab1(sch_1):\DEFAULT\" )
				( netClassRef "@sapphirecity_baseboard_lib.sapphirecity_baseboard(sch_1):\POWER\" )
				( netClassRef "@sapphirecity_baseboard_lib.sapphirecity_baseboard(sch_1):\DDR4_CHN_C_DQ_DQS_BYTE3\" )
			)
			( classClass "@sapphirecity_baseboard_lib.sapphirecity_baseboard(sch_1):\CC77\"
				( spacingCSetRef "@crescent_city_bb_fab1_lib.crescent_city_bb_fab1(sch_1):\DEFAULT\" )
				( netClassRef "@sapphirecity_baseboard_lib.sapphirecity_baseboard(sch_1):\GND\" )
				( netClassRef "@sapphirecity_baseboard_lib.sapphirecity_baseboard(sch_1):\DDR4_CHN_C_DQ_DQS_BYTE2\" )
			)
			( classClass "@sapphirecity_baseboard_lib.sapphirecity_baseboard(sch_1):\CC447\"
				( spacingCSetRef "@sapphirecity_baseboard_lib.sapphirecity_baseboard(sch_1):\DQ_TO_DQ\" )
				( netClassRef "@sapphirecity_baseboard_lib.sapphirecity_baseboard(sch_1):\DDR4_CHN_C_CLK\" )
				( netClassRef "@sapphirecity_baseboard_lib.sapphirecity_baseboard(sch_1):\DDR4_CHN_C_DQ_DQS_BYTE2\" )
			)
			( classClass "@sapphirecity_baseboard_lib.sapphirecity_baseboard(sch_1):\CC459\"
				( spacingCSetRef "@sapphirecity_baseboard_lib.sapphirecity_baseboard(sch_1):\DQ_TO_DQ\" )
				( netClassRef "@sapphirecity_baseboard_lib.sapphirecity_baseboard(sch_1):\DDR4_CHN_C_CMD_ADD\" )
				( netClassRef "@sapphirecity_baseboard_lib.sapphirecity_baseboard(sch_1):\DDR4_CHN_C_DQ_DQS_BYTE2\" )
			)
			( classClass "@sapphirecity_baseboard_lib.sapphirecity_baseboard(sch_1):\CC470\"
				( spacingCSetRef "@sapphirecity_baseboard_lib.sapphirecity_baseboard(sch_1):\DQ_TO_DQ\" )
				( netClassRef "@sapphirecity_baseboard_lib.sapphirecity_baseboard(sch_1):\DDR4_CHN_C_CTRL\" )
				( netClassRef "@sapphirecity_baseboard_lib.sapphirecity_baseboard(sch_1):\DDR4_CHN_C_DQ_DQS_BYTE2\" )
			)
			( classClass "@sapphirecity_baseboard_lib.sapphirecity_baseboard(sch_1):\CC480\"
				( spacingCSetRef "@sapphirecity_baseboard_lib.sapphirecity_baseboard(sch_1):\DQ_TO_DQ\" )
				( netClassRef "@sapphirecity_baseboard_lib.sapphirecity_baseboard(sch_1):\DDR4_CHN_C_DQ_DQS_BYTE2\" )
				( netClassRef "@sapphirecity_baseboard_lib.sapphirecity_baseboard(sch_1):\DDR4_CHN_C_ECC\" )
			)
			( classClass "@sapphirecity_baseboard_lib.sapphirecity_baseboard(sch_1):\CC623\"
				( spacingCSetRef "@sapphirecity_baseboard_lib.sapphirecity_baseboard(sch_1):\DQ_TO_DQ\" )
				( netClassRef "@sapphirecity_baseboard_lib.sapphirecity_baseboard(sch_1):\DDR4_CHN_C_DQ_DQS_BYTE0\" )
				( netClassRef "@sapphirecity_baseboard_lib.sapphirecity_baseboard(sch_1):\DDR4_CHN_C_DQ_DQS_BYTE2\" )
			)
			( classClass "@sapphirecity_baseboard_lib.sapphirecity_baseboard(sch_1):\CC632\"
				( spacingCSetRef "@sapphirecity_baseboard_lib.sapphirecity_baseboard(sch_1):\DQ_TO_DQ\" )
				( netClassRef "@sapphirecity_baseboard_lib.sapphirecity_baseboard(sch_1):\DDR4_CHN_C_DQ_DQS_BYTE1\" )
				( netClassRef "@sapphirecity_baseboard_lib.sapphirecity_baseboard(sch_1):\DDR4_CHN_C_DQ_DQS_BYTE2\" )
			)
			( classClass "@sapphirecity_baseboard_lib.sapphirecity_baseboard(sch_1):\CC633\"
				( spacingCSetRef "@sapphirecity_baseboard_lib.sapphirecity_baseboard(sch_1):\DDR4_2SPC_DQ/DQS\" )
				( netClassRef "@sapphirecity_baseboard_lib.sapphirecity_baseboard(sch_1):\DDR4_CHN_C_DQ_DQS_BYTE2\" )
				( netClassRef "@sapphirecity_baseboard_lib.sapphirecity_baseboard(sch_1):\DDR4_CHN_C_DQ_DQS_BYTE2\" )
			)
			( classClass "@crescent_city_bb_fab1_lib.crescent_city_bb_fab1(sch_1):\CC19\"
				( spacingCSetRef "@crescent_city_bb_fab1_lib.crescent_city_bb_fab1(sch_1):\DEFAULT\" )
				( netClassRef "@sapphirecity_baseboard_lib.sapphirecity_baseboard(sch_1):\POWER\" )
				( netClassRef "@sapphirecity_baseboard_lib.sapphirecity_baseboard(sch_1):\DDR4_CHN_C_DQ_DQS_BYTE2\" )
			)
			( classClass "@sapphirecity_baseboard_lib.sapphirecity_baseboard(sch_1):\CC78\"
				( spacingCSetRef "@crescent_city_bb_fab1_lib.crescent_city_bb_fab1(sch_1):\DEFAULT\" )
				( netClassRef "@sapphirecity_baseboard_lib.sapphirecity_baseboard(sch_1):\GND\" )
				( netClassRef "@sapphirecity_baseboard_lib.sapphirecity_baseboard(sch_1):\DDR4_CHN_C_DQ_DQS_BYTE1\" )
			)
			( classClass "@sapphirecity_baseboard_lib.sapphirecity_baseboard(sch_1):\CC446\"
				( spacingCSetRef "@sapphirecity_baseboard_lib.sapphirecity_baseboard(sch_1):\DQ_TO_DQ\" )
				( netClassRef "@sapphirecity_baseboard_lib.sapphirecity_baseboard(sch_1):\DDR4_CHN_C_CLK\" )
				( netClassRef "@sapphirecity_baseboard_lib.sapphirecity_baseboard(sch_1):\DDR4_CHN_C_DQ_DQS_BYTE1\" )
			)
			( classClass "@sapphirecity_baseboard_lib.sapphirecity_baseboard(sch_1):\CC458\"
				( spacingCSetRef "@sapphirecity_baseboard_lib.sapphirecity_baseboard(sch_1):\DQ_TO_DQ\" )
				( netClassRef "@sapphirecity_baseboard_lib.sapphirecity_baseboard(sch_1):\DDR4_CHN_C_CMD_ADD\" )
				( netClassRef "@sapphirecity_baseboard_lib.sapphirecity_baseboard(sch_1):\DDR4_CHN_C_DQ_DQS_BYTE1\" )
			)
			( classClass "@sapphirecity_baseboard_lib.sapphirecity_baseboard(sch_1):\CC469\"
				( spacingCSetRef "@sapphirecity_baseboard_lib.sapphirecity_baseboard(sch_1):\DQ_TO_DQ\" )
				( netClassRef "@sapphirecity_baseboard_lib.sapphirecity_baseboard(sch_1):\DDR4_CHN_C_CTRL\" )
				( netClassRef "@sapphirecity_baseboard_lib.sapphirecity_baseboard(sch_1):\DDR4_CHN_C_DQ_DQS_BYTE1\" )
			)
			( classClass "@sapphirecity_baseboard_lib.sapphirecity_baseboard(sch_1):\CC479\"
				( spacingCSetRef "@sapphirecity_baseboard_lib.sapphirecity_baseboard(sch_1):\DQ_TO_DQ\" )
				( netClassRef "@sapphirecity_baseboard_lib.sapphirecity_baseboard(sch_1):\DDR4_CHN_C_DQ_DQS_BYTE1\" )
				( netClassRef "@sapphirecity_baseboard_lib.sapphirecity_baseboard(sch_1):\DDR4_CHN_C_ECC\" )
			)
			( classClass "@sapphirecity_baseboard_lib.sapphirecity_baseboard(sch_1):\CC624\"
				( spacingCSetRef "@sapphirecity_baseboard_lib.sapphirecity_baseboard(sch_1):\DQ_TO_DQ\" )
				( netClassRef "@sapphirecity_baseboard_lib.sapphirecity_baseboard(sch_1):\DDR4_CHN_C_DQ_DQS_BYTE0\" )
				( netClassRef "@sapphirecity_baseboard_lib.sapphirecity_baseboard(sch_1):\DDR4_CHN_C_DQ_DQS_BYTE1\" )
			)
			( classClass "@sapphirecity_baseboard_lib.sapphirecity_baseboard(sch_1):\CC625\"
				( spacingCSetRef "@sapphirecity_baseboard_lib.sapphirecity_baseboard(sch_1):\DDR4_2SPC_DQ/DQS\" )
				( netClassRef "@sapphirecity_baseboard_lib.sapphirecity_baseboard(sch_1):\DDR4_CHN_C_DQ_DQS_BYTE1\" )
				( netClassRef "@sapphirecity_baseboard_lib.sapphirecity_baseboard(sch_1):\DDR4_CHN_C_DQ_DQS_BYTE1\" )
			)
			( classClass "@crescent_city_bb_fab1_lib.crescent_city_bb_fab1(sch_1):\CC18\"
				( spacingCSetRef "@crescent_city_bb_fab1_lib.crescent_city_bb_fab1(sch_1):\DEFAULT\" )
				( netClassRef "@sapphirecity_baseboard_lib.sapphirecity_baseboard(sch_1):\POWER\" )
				( netClassRef "@sapphirecity_baseboard_lib.sapphirecity_baseboard(sch_1):\DDR4_CHN_C_DQ_DQS_BYTE1\" )
			)
			( classClass "@sapphirecity_baseboard_lib.sapphirecity_baseboard(sch_1):\CC79\"
				( spacingCSetRef "@crescent_city_bb_fab1_lib.crescent_city_bb_fab1(sch_1):\DEFAULT\" )
				( netClassRef "@sapphirecity_baseboard_lib.sapphirecity_baseboard(sch_1):\GND\" )
				( netClassRef "@sapphirecity_baseboard_lib.sapphirecity_baseboard(sch_1):\DDR4_CHN_C_DQ_DQS_BYTE0\" )
			)
			( classClass "@sapphirecity_baseboard_lib.sapphirecity_baseboard(sch_1):\CC445\"
				( spacingCSetRef "@sapphirecity_baseboard_lib.sapphirecity_baseboard(sch_1):\DQ_TO_DQ\" )
				( netClassRef "@sapphirecity_baseboard_lib.sapphirecity_baseboard(sch_1):\DDR4_CHN_C_CLK\" )
				( netClassRef "@sapphirecity_baseboard_lib.sapphirecity_baseboard(sch_1):\DDR4_CHN_C_DQ_DQS_BYTE0\" )
			)
			( classClass "@sapphirecity_baseboard_lib.sapphirecity_baseboard(sch_1):\CC457\"
				( spacingCSetRef "@sapphirecity_baseboard_lib.sapphirecity_baseboard(sch_1):\DQ_TO_DQ\" )
				( netClassRef "@sapphirecity_baseboard_lib.sapphirecity_baseboard(sch_1):\DDR4_CHN_C_CMD_ADD\" )
				( netClassRef "@sapphirecity_baseboard_lib.sapphirecity_baseboard(sch_1):\DDR4_CHN_C_DQ_DQS_BYTE0\" )
			)
			( classClass "@sapphirecity_baseboard_lib.sapphirecity_baseboard(sch_1):\CC468\"
				( spacingCSetRef "@sapphirecity_baseboard_lib.sapphirecity_baseboard(sch_1):\DQ_TO_DQ\" )
				( netClassRef "@sapphirecity_baseboard_lib.sapphirecity_baseboard(sch_1):\DDR4_CHN_C_CTRL\" )
				( netClassRef "@sapphirecity_baseboard_lib.sapphirecity_baseboard(sch_1):\DDR4_CHN_C_DQ_DQS_BYTE0\" )
			)
			( classClass "@sapphirecity_baseboard_lib.sapphirecity_baseboard(sch_1):\CC478\"
				( spacingCSetRef "@sapphirecity_baseboard_lib.sapphirecity_baseboard(sch_1):\DQ_TO_DQ\" )
				( netClassRef "@sapphirecity_baseboard_lib.sapphirecity_baseboard(sch_1):\DDR4_CHN_C_DQ_DQS_BYTE0\" )
				( netClassRef "@sapphirecity_baseboard_lib.sapphirecity_baseboard(sch_1):\DDR4_CHN_C_ECC\" )
			)
			( classClass "@sapphirecity_baseboard_lib.sapphirecity_baseboard(sch_1):\CC615\"
				( spacingCSetRef "@sapphirecity_baseboard_lib.sapphirecity_baseboard(sch_1):\DDR4_2SPC_DQ/DQS\" )
				( netClassRef "@sapphirecity_baseboard_lib.sapphirecity_baseboard(sch_1):\DDR4_CHN_C_DQ_DQS_BYTE0\" )
				( netClassRef "@sapphirecity_baseboard_lib.sapphirecity_baseboard(sch_1):\DDR4_CHN_C_DQ_DQS_BYTE0\" )
			)
			( classClass "@crescent_city_bb_fab1_lib.crescent_city_bb_fab1(sch_1):\CC17\"
				( spacingCSetRef "@crescent_city_bb_fab1_lib.crescent_city_bb_fab1(sch_1):\DEFAULT\" )
				( netClassRef "@sapphirecity_baseboard_lib.sapphirecity_baseboard(sch_1):\POWER\" )
				( netClassRef "@sapphirecity_baseboard_lib.sapphirecity_baseboard(sch_1):\DDR4_CHN_C_DQ_DQS_BYTE0\" )
			)
			( classClass "@sapphirecity_baseboard_lib.sapphirecity_baseboard(sch_1):\CC614\"
				( spacingCSetRef "@sapphirecity_baseboard_lib.sapphirecity_baseboard(sch_1):\DDR4_2SPC_DQ/DQS\" )
				( netClassRef "@sapphirecity_baseboard_lib.sapphirecity_baseboard(sch_1):\DDR4_CHN_D_DQ_DQS_BYTE0\" )
				( netClassRef "@sapphirecity_baseboard_lib.sapphirecity_baseboard(sch_1):\DDR4_CHN_D_DQ_DQS_BYTE0\" )
			)
			( classClass "@crescent_city_bb_fab1_lib.crescent_city_bb_fab1(sch_1):\CC87\"
				( spacingCSetRef "@sapphirecity_baseboard_lib.sapphirecity_baseboard(sch_1):\DQ_TO_DQ\" )
				( netClassRef "@sapphirecity_baseboard_lib.sapphirecity_baseboard(sch_1):\DDR4_CHN_D_CLK\" )
				( netClassRef "@sapphirecity_baseboard_lib.sapphirecity_baseboard(sch_1):\DDR4_CHN_D_DQ_DQS_BYTE0\" )
			)
			( classClass "@crescent_city_bb_fab1_lib.crescent_city_bb_fab1(sch_1):\CC88\"
				( spacingCSetRef "@sapphirecity_baseboard_lib.sapphirecity_baseboard(sch_1):\DQ_TO_DQ\" )
				( netClassRef "@sapphirecity_baseboard_lib.sapphirecity_baseboard(sch_1):\DDR4_CHN_D_CMD_ADD\" )
				( netClassRef "@sapphirecity_baseboard_lib.sapphirecity_baseboard(sch_1):\DDR4_CHN_D_DQ_DQS_BYTE0\" )
			)
			( classClass "@crescent_city_bb_fab1_lib.crescent_city_bb_fab1(sch_1):\CC89\"
				( spacingCSetRef "@sapphirecity_baseboard_lib.sapphirecity_baseboard(sch_1):\10H_SL_12H_MS\" )
				( netClassRef "@sapphirecity_baseboard_lib.sapphirecity_baseboard(sch_1):\DDR4_CHN_D_CTRL\" )
				( netClassRef "@sapphirecity_baseboard_lib.sapphirecity_baseboard(sch_1):\DDR4_CHN_D_DQ_DQS_BYTE0\" )
			)
			( classClass "@crescent_city_bb_fab1_lib.crescent_city_bb_fab1(sch_1):\CC90\"
				( spacingCSetRef "@sapphirecity_baseboard_lib.sapphirecity_baseboard(sch_1):\DQ_TO_DQ\" )
				( netClassRef "@sapphirecity_baseboard_lib.sapphirecity_baseboard(sch_1):\DDR4_CHN_D_DQ_DQS_BYTE0\" )
				( netClassRef "@sapphirecity_baseboard_lib.sapphirecity_baseboard(sch_1):\DDR4_CHN_D_DQ_DQS_BYTE1\" )
			)
			( classClass "@crescent_city_bb_fab1_lib.crescent_city_bb_fab1(sch_1):\CC91\"
				( spacingCSetRef "@sapphirecity_baseboard_lib.sapphirecity_baseboard(sch_1):\DQ_TO_DQ\" )
				( netClassRef "@sapphirecity_baseboard_lib.sapphirecity_baseboard(sch_1):\DDR4_CHN_D_DQ_DQS_BYTE0\" )
				( netClassRef "@sapphirecity_baseboard_lib.sapphirecity_baseboard(sch_1):\DDR4_CHN_D_DQ_DQS_BYTE2\" )
			)
			( classClass "@crescent_city_bb_fab1_lib.crescent_city_bb_fab1(sch_1):\CC92\"
				( spacingCSetRef "@sapphirecity_baseboard_lib.sapphirecity_baseboard(sch_1):\DQ_TO_DQ\" )
				( netClassRef "@sapphirecity_baseboard_lib.sapphirecity_baseboard(sch_1):\DDR4_CHN_D_DQ_DQS_BYTE0\" )
				( netClassRef "@sapphirecity_baseboard_lib.sapphirecity_baseboard(sch_1):\DDR4_CHN_D_DQ_DQS_BYTE3\" )
			)
			( classClass "@crescent_city_bb_fab1_lib.crescent_city_bb_fab1(sch_1):\CC93\"
				( spacingCSetRef "@sapphirecity_baseboard_lib.sapphirecity_baseboard(sch_1):\DQ_TO_DQ\" )
				( netClassRef "@sapphirecity_baseboard_lib.sapphirecity_baseboard(sch_1):\DDR4_CHN_D_DQ_DQS_BYTE0\" )
				( netClassRef "@sapphirecity_baseboard_lib.sapphirecity_baseboard(sch_1):\DDR4_CHN_D_DQ_DQS_BYTE4\" )
			)
			( classClass "@crescent_city_bb_fab1_lib.crescent_city_bb_fab1(sch_1):\CC75\"
				( spacingCSetRef "@sapphirecity_baseboard_lib.sapphirecity_baseboard(sch_1):\DQ_TO_DQ\" )
				( netClassRef "@sapphirecity_baseboard_lib.sapphirecity_baseboard(sch_1):\DDR4_CHN_D_DQ_DQS_BYTE0\" )
				( netClassRef "@sapphirecity_baseboard_lib.sapphirecity_baseboard(sch_1):\DDR4_CHN_D_DQ_DQS_BYTE5\" )
			)
			( classClass "@crescent_city_bb_fab1_lib.crescent_city_bb_fab1(sch_1):\CC94\"
				( spacingCSetRef "@sapphirecity_baseboard_lib.sapphirecity_baseboard(sch_1):\DQ_TO_DQ\" )
				( netClassRef "@sapphirecity_baseboard_lib.sapphirecity_baseboard(sch_1):\DDR4_CHN_D_DQ_DQS_BYTE0\" )
				( netClassRef "@sapphirecity_baseboard_lib.sapphirecity_baseboard(sch_1):\DDR4_CHN_D_DQ_DQS_BYTE6\" )
			)
			( classClass "@crescent_city_bb_fab1_lib.crescent_city_bb_fab1(sch_1):\CC95\"
				( spacingCSetRef "@sapphirecity_baseboard_lib.sapphirecity_baseboard(sch_1):\DQ_TO_DQ\" )
				( netClassRef "@sapphirecity_baseboard_lib.sapphirecity_baseboard(sch_1):\DDR4_CHN_D_DQ_DQS_BYTE0\" )
				( netClassRef "@sapphirecity_baseboard_lib.sapphirecity_baseboard(sch_1):\DDR4_CHN_D_DQ_DQS_BYTE7\" )
			)
			( classClass "@crescent_city_bb_fab1_lib.crescent_city_bb_fab1(sch_1):\CC96\"
				( spacingCSetRef "@sapphirecity_baseboard_lib.sapphirecity_baseboard(sch_1):\DQ_TO_DQ\" )
				( netClassRef "@sapphirecity_baseboard_lib.sapphirecity_baseboard(sch_1):\DDR4_CHN_D_DQ_DQS_BYTE0\" )
				( netClassRef "@sapphirecity_baseboard_lib.sapphirecity_baseboard(sch_1):\DDR4_CHN_D_ECC\" )
			)
			( classClass "@crescent_city_bb_fab1_lib.crescent_city_bb_fab1(sch_1):\CC97\"
				( spacingCSetRef "@crescent_city_bb_fab1_lib.crescent_city_bb_fab1(sch_1):\DEFAULT\" )
				( netClassRef "@sapphirecity_baseboard_lib.sapphirecity_baseboard(sch_1):\GND\" )
				( netClassRef "@sapphirecity_baseboard_lib.sapphirecity_baseboard(sch_1):\DDR4_CHN_D_DQ_DQS_BYTE0\" )
			)
			( classClass "@crescent_city_bb_fab1_lib.crescent_city_bb_fab1(sch_1):\CC27\"
				( spacingCSetRef "@crescent_city_bb_fab1_lib.crescent_city_bb_fab1(sch_1):\DEFAULT\" )
				( netClassRef "@sapphirecity_baseboard_lib.sapphirecity_baseboard(sch_1):\POWER\" )
				( netClassRef "@sapphirecity_baseboard_lib.sapphirecity_baseboard(sch_1):\DDR4_CHN_D_DQ_DQS_BYTE0\" )
			)
			( classClass "@sapphirecity_baseboard_lib.sapphirecity_baseboard(sch_1):\CC613\"
				( spacingCSetRef "@sapphirecity_baseboard_lib.sapphirecity_baseboard(sch_1):\DDR4_2SPC_DQ/DQS\" )
				( netClassRef "@sapphirecity_baseboard_lib.sapphirecity_baseboard(sch_1):\DDR4_CHN_D_DQ_DQS_BYTE1\" )
				( netClassRef "@sapphirecity_baseboard_lib.sapphirecity_baseboard(sch_1):\DDR4_CHN_D_DQ_DQS_BYTE1\" )
			)
			( classClass "@crescent_city_bb_fab1_lib.crescent_city_bb_fab1(sch_1):\CC98\"
				( spacingCSetRef "@sapphirecity_baseboard_lib.sapphirecity_baseboard(sch_1):\DQ_TO_DQ\" )
				( netClassRef "@sapphirecity_baseboard_lib.sapphirecity_baseboard(sch_1):\DDR4_CHN_D_CLK\" )
				( netClassRef "@sapphirecity_baseboard_lib.sapphirecity_baseboard(sch_1):\DDR4_CHN_D_DQ_DQS_BYTE1\" )
			)
			( classClass "@crescent_city_bb_fab1_lib.crescent_city_bb_fab1(sch_1):\CC99\"
				( spacingCSetRef "@sapphirecity_baseboard_lib.sapphirecity_baseboard(sch_1):\DQ_TO_DQ\" )
				( netClassRef "@sapphirecity_baseboard_lib.sapphirecity_baseboard(sch_1):\DDR4_CHN_D_CMD_ADD\" )
				( netClassRef "@sapphirecity_baseboard_lib.sapphirecity_baseboard(sch_1):\DDR4_CHN_D_DQ_DQS_BYTE1\" )
			)
			( classClass "@crescent_city_bb_fab1_lib.crescent_city_bb_fab1(sch_1):\CC100\"
				( spacingCSetRef "@sapphirecity_baseboard_lib.sapphirecity_baseboard(sch_1):\10H_SL_12H_MS\" )
				( netClassRef "@sapphirecity_baseboard_lib.sapphirecity_baseboard(sch_1):\DDR4_CHN_D_CTRL\" )
				( netClassRef "@sapphirecity_baseboard_lib.sapphirecity_baseboard(sch_1):\DDR4_CHN_D_DQ_DQS_BYTE1\" )
			)
			( classClass "@crescent_city_bb_fab1_lib.crescent_city_bb_fab1(sch_1):\CC101\"
				( spacingCSetRef "@sapphirecity_baseboard_lib.sapphirecity_baseboard(sch_1):\DQ_TO_DQ\" )
				( netClassRef "@sapphirecity_baseboard_lib.sapphirecity_baseboard(sch_1):\DDR4_CHN_D_DQ_DQS_BYTE1\" )
				( netClassRef "@sapphirecity_baseboard_lib.sapphirecity_baseboard(sch_1):\DDR4_CHN_D_DQ_DQS_BYTE2\" )
			)
			( classClass "@crescent_city_bb_fab1_lib.crescent_city_bb_fab1(sch_1):\CC102\"
				( spacingCSetRef "@sapphirecity_baseboard_lib.sapphirecity_baseboard(sch_1):\DQ_TO_DQ\" )
				( netClassRef "@sapphirecity_baseboard_lib.sapphirecity_baseboard(sch_1):\DDR4_CHN_D_DQ_DQS_BYTE1\" )
				( netClassRef "@sapphirecity_baseboard_lib.sapphirecity_baseboard(sch_1):\DDR4_CHN_D_DQ_DQS_BYTE3\" )
			)
			( classClass "@crescent_city_bb_fab1_lib.crescent_city_bb_fab1(sch_1):\CC103\"
				( spacingCSetRef "@sapphirecity_baseboard_lib.sapphirecity_baseboard(sch_1):\DQ_TO_DQ\" )
				( netClassRef "@sapphirecity_baseboard_lib.sapphirecity_baseboard(sch_1):\DDR4_CHN_D_DQ_DQS_BYTE1\" )
				( netClassRef "@sapphirecity_baseboard_lib.sapphirecity_baseboard(sch_1):\DDR4_CHN_D_DQ_DQS_BYTE4\" )
			)
			( classClass "@crescent_city_bb_fab1_lib.crescent_city_bb_fab1(sch_1):\CC76\"
				( spacingCSetRef "@sapphirecity_baseboard_lib.sapphirecity_baseboard(sch_1):\DQ_TO_DQ\" )
				( netClassRef "@sapphirecity_baseboard_lib.sapphirecity_baseboard(sch_1):\DDR4_CHN_D_DQ_DQS_BYTE1\" )
				( netClassRef "@sapphirecity_baseboard_lib.sapphirecity_baseboard(sch_1):\DDR4_CHN_D_DQ_DQS_BYTE5\" )
			)
			( classClass "@crescent_city_bb_fab1_lib.crescent_city_bb_fab1(sch_1):\CC104\"
				( spacingCSetRef "@sapphirecity_baseboard_lib.sapphirecity_baseboard(sch_1):\DQ_TO_DQ\" )
				( netClassRef "@sapphirecity_baseboard_lib.sapphirecity_baseboard(sch_1):\DDR4_CHN_D_DQ_DQS_BYTE1\" )
				( netClassRef "@sapphirecity_baseboard_lib.sapphirecity_baseboard(sch_1):\DDR4_CHN_D_DQ_DQS_BYTE6\" )
			)
			( classClass "@crescent_city_bb_fab1_lib.crescent_city_bb_fab1(sch_1):\CC105\"
				( spacingCSetRef "@sapphirecity_baseboard_lib.sapphirecity_baseboard(sch_1):\DQ_TO_DQ\" )
				( netClassRef "@sapphirecity_baseboard_lib.sapphirecity_baseboard(sch_1):\DDR4_CHN_D_DQ_DQS_BYTE1\" )
				( netClassRef "@sapphirecity_baseboard_lib.sapphirecity_baseboard(sch_1):\DDR4_CHN_D_DQ_DQS_BYTE7\" )
			)
			( classClass "@crescent_city_bb_fab1_lib.crescent_city_bb_fab1(sch_1):\CC106\"
				( spacingCSetRef "@sapphirecity_baseboard_lib.sapphirecity_baseboard(sch_1):\DQ_TO_DQ\" )
				( netClassRef "@sapphirecity_baseboard_lib.sapphirecity_baseboard(sch_1):\DDR4_CHN_D_DQ_DQS_BYTE1\" )
				( netClassRef "@sapphirecity_baseboard_lib.sapphirecity_baseboard(sch_1):\DDR4_CHN_D_ECC\" )
			)
			( classClass "@crescent_city_bb_fab1_lib.crescent_city_bb_fab1(sch_1):\CC107\"
				( spacingCSetRef "@crescent_city_bb_fab1_lib.crescent_city_bb_fab1(sch_1):\DEFAULT\" )
				( netClassRef "@sapphirecity_baseboard_lib.sapphirecity_baseboard(sch_1):\GND\" )
				( netClassRef "@sapphirecity_baseboard_lib.sapphirecity_baseboard(sch_1):\DDR4_CHN_D_DQ_DQS_BYTE1\" )
			)
			( classClass "@crescent_city_bb_fab1_lib.crescent_city_bb_fab1(sch_1):\CC28\"
				( spacingCSetRef "@crescent_city_bb_fab1_lib.crescent_city_bb_fab1(sch_1):\DEFAULT\" )
				( netClassRef "@sapphirecity_baseboard_lib.sapphirecity_baseboard(sch_1):\POWER\" )
				( netClassRef "@sapphirecity_baseboard_lib.sapphirecity_baseboard(sch_1):\DDR4_CHN_D_DQ_DQS_BYTE1\" )
			)
			( classClass "@sapphirecity_baseboard_lib.sapphirecity_baseboard(sch_1):\CC612\"
				( spacingCSetRef "@sapphirecity_baseboard_lib.sapphirecity_baseboard(sch_1):\DDR4_2SPC_DQ/DQS\" )
				( netClassRef "@sapphirecity_baseboard_lib.sapphirecity_baseboard(sch_1):\DDR4_CHN_D_DQ_DQS_BYTE2\" )
				( netClassRef "@sapphirecity_baseboard_lib.sapphirecity_baseboard(sch_1):\DDR4_CHN_D_DQ_DQS_BYTE2\" )
			)
			( classClass "@crescent_city_bb_fab1_lib.crescent_city_bb_fab1(sch_1):\CC108\"
				( spacingCSetRef "@sapphirecity_baseboard_lib.sapphirecity_baseboard(sch_1):\DQ_TO_DQ\" )
				( netClassRef "@sapphirecity_baseboard_lib.sapphirecity_baseboard(sch_1):\DDR4_CHN_D_CLK\" )
				( netClassRef "@sapphirecity_baseboard_lib.sapphirecity_baseboard(sch_1):\DDR4_CHN_D_DQ_DQS_BYTE2\" )
			)
			( classClass "@crescent_city_bb_fab1_lib.crescent_city_bb_fab1(sch_1):\CC109\"
				( spacingCSetRef "@sapphirecity_baseboard_lib.sapphirecity_baseboard(sch_1):\DQ_TO_DQ\" )
				( netClassRef "@sapphirecity_baseboard_lib.sapphirecity_baseboard(sch_1):\DDR4_CHN_D_CMD_ADD\" )
				( netClassRef "@sapphirecity_baseboard_lib.sapphirecity_baseboard(sch_1):\DDR4_CHN_D_DQ_DQS_BYTE2\" )
			)
			( classClass "@crescent_city_bb_fab1_lib.crescent_city_bb_fab1(sch_1):\CC110\"
				( spacingCSetRef "@sapphirecity_baseboard_lib.sapphirecity_baseboard(sch_1):\10H_SL_12H_MS\" )
				( netClassRef "@sapphirecity_baseboard_lib.sapphirecity_baseboard(sch_1):\DDR4_CHN_D_CTRL\" )
				( netClassRef "@sapphirecity_baseboard_lib.sapphirecity_baseboard(sch_1):\DDR4_CHN_D_DQ_DQS_BYTE2\" )
			)
			( classClass "@crescent_city_bb_fab1_lib.crescent_city_bb_fab1(sch_1):\CC111\"
				( spacingCSetRef "@sapphirecity_baseboard_lib.sapphirecity_baseboard(sch_1):\DQ_TO_DQ\" )
				( netClassRef "@sapphirecity_baseboard_lib.sapphirecity_baseboard(sch_1):\DDR4_CHN_D_DQ_DQS_BYTE2\" )
				( netClassRef "@sapphirecity_baseboard_lib.sapphirecity_baseboard(sch_1):\DDR4_CHN_D_DQ_DQS_BYTE3\" )
			)
			( classClass "@crescent_city_bb_fab1_lib.crescent_city_bb_fab1(sch_1):\CC112\"
				( spacingCSetRef "@sapphirecity_baseboard_lib.sapphirecity_baseboard(sch_1):\DQ_TO_DQ\" )
				( netClassRef "@sapphirecity_baseboard_lib.sapphirecity_baseboard(sch_1):\DDR4_CHN_D_DQ_DQS_BYTE2\" )
				( netClassRef "@sapphirecity_baseboard_lib.sapphirecity_baseboard(sch_1):\DDR4_CHN_D_DQ_DQS_BYTE4\" )
			)
			( classClass "@crescent_city_bb_fab1_lib.crescent_city_bb_fab1(sch_1):\CC77\"
				( spacingCSetRef "@sapphirecity_baseboard_lib.sapphirecity_baseboard(sch_1):\DQ_TO_DQ\" )
				( netClassRef "@sapphirecity_baseboard_lib.sapphirecity_baseboard(sch_1):\DDR4_CHN_D_DQ_DQS_BYTE2\" )
				( netClassRef "@sapphirecity_baseboard_lib.sapphirecity_baseboard(sch_1):\DDR4_CHN_D_DQ_DQS_BYTE5\" )
			)
			( classClass "@crescent_city_bb_fab1_lib.crescent_city_bb_fab1(sch_1):\CC113\"
				( spacingCSetRef "@sapphirecity_baseboard_lib.sapphirecity_baseboard(sch_1):\DQ_TO_DQ\" )
				( netClassRef "@sapphirecity_baseboard_lib.sapphirecity_baseboard(sch_1):\DDR4_CHN_D_DQ_DQS_BYTE2\" )
				( netClassRef "@sapphirecity_baseboard_lib.sapphirecity_baseboard(sch_1):\DDR4_CHN_D_DQ_DQS_BYTE6\" )
			)
			( classClass "@crescent_city_bb_fab1_lib.crescent_city_bb_fab1(sch_1):\CC114\"
				( spacingCSetRef "@sapphirecity_baseboard_lib.sapphirecity_baseboard(sch_1):\DQ_TO_DQ\" )
				( netClassRef "@sapphirecity_baseboard_lib.sapphirecity_baseboard(sch_1):\DDR4_CHN_D_DQ_DQS_BYTE2\" )
				( netClassRef "@sapphirecity_baseboard_lib.sapphirecity_baseboard(sch_1):\DDR4_CHN_D_DQ_DQS_BYTE7\" )
			)
			( classClass "@crescent_city_bb_fab1_lib.crescent_city_bb_fab1(sch_1):\CC115\"
				( spacingCSetRef "@sapphirecity_baseboard_lib.sapphirecity_baseboard(sch_1):\DQ_TO_DQ\" )
				( netClassRef "@sapphirecity_baseboard_lib.sapphirecity_baseboard(sch_1):\DDR4_CHN_D_DQ_DQS_BYTE2\" )
				( netClassRef "@sapphirecity_baseboard_lib.sapphirecity_baseboard(sch_1):\DDR4_CHN_D_ECC\" )
			)
			( classClass "@crescent_city_bb_fab1_lib.crescent_city_bb_fab1(sch_1):\CC116\"
				( spacingCSetRef "@crescent_city_bb_fab1_lib.crescent_city_bb_fab1(sch_1):\DEFAULT\" )
				( netClassRef "@sapphirecity_baseboard_lib.sapphirecity_baseboard(sch_1):\GND\" )
				( netClassRef "@sapphirecity_baseboard_lib.sapphirecity_baseboard(sch_1):\DDR4_CHN_D_DQ_DQS_BYTE2\" )
			)
			( classClass "@crescent_city_bb_fab1_lib.crescent_city_bb_fab1(sch_1):\CC29\"
				( spacingCSetRef "@crescent_city_bb_fab1_lib.crescent_city_bb_fab1(sch_1):\DEFAULT\" )
				( netClassRef "@sapphirecity_baseboard_lib.sapphirecity_baseboard(sch_1):\POWER\" )
				( netClassRef "@sapphirecity_baseboard_lib.sapphirecity_baseboard(sch_1):\DDR4_CHN_D_DQ_DQS_BYTE2\" )
			)
			( classClass "@sapphirecity_baseboard_lib.sapphirecity_baseboard(sch_1):\CC611\"
				( spacingCSetRef "@sapphirecity_baseboard_lib.sapphirecity_baseboard(sch_1):\DDR4_2SPC_DQ/DQS\" )
				( netClassRef "@sapphirecity_baseboard_lib.sapphirecity_baseboard(sch_1):\DDR4_CHN_D_DQ_DQS_BYTE3\" )
				( netClassRef "@sapphirecity_baseboard_lib.sapphirecity_baseboard(sch_1):\DDR4_CHN_D_DQ_DQS_BYTE3\" )
			)
			( classClass "@crescent_city_bb_fab1_lib.crescent_city_bb_fab1(sch_1):\CC117\"
				( spacingCSetRef "@sapphirecity_baseboard_lib.sapphirecity_baseboard(sch_1):\DQ_TO_DQ\" )
				( netClassRef "@sapphirecity_baseboard_lib.sapphirecity_baseboard(sch_1):\DDR4_CHN_D_CLK\" )
				( netClassRef "@sapphirecity_baseboard_lib.sapphirecity_baseboard(sch_1):\DDR4_CHN_D_DQ_DQS_BYTE3\" )
			)
			( classClass "@crescent_city_bb_fab1_lib.crescent_city_bb_fab1(sch_1):\CC118\"
				( spacingCSetRef "@sapphirecity_baseboard_lib.sapphirecity_baseboard(sch_1):\DQ_TO_DQ\" )
				( netClassRef "@sapphirecity_baseboard_lib.sapphirecity_baseboard(sch_1):\DDR4_CHN_D_CMD_ADD\" )
				( netClassRef "@sapphirecity_baseboard_lib.sapphirecity_baseboard(sch_1):\DDR4_CHN_D_DQ_DQS_BYTE3\" )
			)
			( classClass "@crescent_city_bb_fab1_lib.crescent_city_bb_fab1(sch_1):\CC119\"
				( spacingCSetRef "@sapphirecity_baseboard_lib.sapphirecity_baseboard(sch_1):\10H_SL_12H_MS\" )
				( netClassRef "@sapphirecity_baseboard_lib.sapphirecity_baseboard(sch_1):\DDR4_CHN_D_CTRL\" )
				( netClassRef "@sapphirecity_baseboard_lib.sapphirecity_baseboard(sch_1):\DDR4_CHN_D_DQ_DQS_BYTE3\" )
			)
			( classClass "@crescent_city_bb_fab1_lib.crescent_city_bb_fab1(sch_1):\CC120\"
				( spacingCSetRef "@sapphirecity_baseboard_lib.sapphirecity_baseboard(sch_1):\DQ_TO_DQ\" )
				( netClassRef "@sapphirecity_baseboard_lib.sapphirecity_baseboard(sch_1):\DDR4_CHN_D_DQ_DQS_BYTE3\" )
				( netClassRef "@sapphirecity_baseboard_lib.sapphirecity_baseboard(sch_1):\DDR4_CHN_D_DQ_DQS_BYTE4\" )
			)
			( classClass "@crescent_city_bb_fab1_lib.crescent_city_bb_fab1(sch_1):\CC78\"
				( spacingCSetRef "@sapphirecity_baseboard_lib.sapphirecity_baseboard(sch_1):\DQ_TO_DQ\" )
				( netClassRef "@sapphirecity_baseboard_lib.sapphirecity_baseboard(sch_1):\DDR4_CHN_D_DQ_DQS_BYTE3\" )
				( netClassRef "@sapphirecity_baseboard_lib.sapphirecity_baseboard(sch_1):\DDR4_CHN_D_DQ_DQS_BYTE5\" )
			)
			( classClass "@crescent_city_bb_fab1_lib.crescent_city_bb_fab1(sch_1):\CC121\"
				( spacingCSetRef "@sapphirecity_baseboard_lib.sapphirecity_baseboard(sch_1):\DQ_TO_DQ\" )
				( netClassRef "@sapphirecity_baseboard_lib.sapphirecity_baseboard(sch_1):\DDR4_CHN_D_DQ_DQS_BYTE3\" )
				( netClassRef "@sapphirecity_baseboard_lib.sapphirecity_baseboard(sch_1):\DDR4_CHN_D_DQ_DQS_BYTE6\" )
			)
			( classClass "@crescent_city_bb_fab1_lib.crescent_city_bb_fab1(sch_1):\CC122\"
				( spacingCSetRef "@sapphirecity_baseboard_lib.sapphirecity_baseboard(sch_1):\DQ_TO_DQ\" )
				( netClassRef "@sapphirecity_baseboard_lib.sapphirecity_baseboard(sch_1):\DDR4_CHN_D_DQ_DQS_BYTE3\" )
				( netClassRef "@sapphirecity_baseboard_lib.sapphirecity_baseboard(sch_1):\DDR4_CHN_D_DQ_DQS_BYTE7\" )
			)
			( classClass "@crescent_city_bb_fab1_lib.crescent_city_bb_fab1(sch_1):\CC123\"
				( spacingCSetRef "@sapphirecity_baseboard_lib.sapphirecity_baseboard(sch_1):\DQ_TO_DQ\" )
				( netClassRef "@sapphirecity_baseboard_lib.sapphirecity_baseboard(sch_1):\DDR4_CHN_D_DQ_DQS_BYTE3\" )
				( netClassRef "@sapphirecity_baseboard_lib.sapphirecity_baseboard(sch_1):\DDR4_CHN_D_ECC\" )
			)
			( classClass "@crescent_city_bb_fab1_lib.crescent_city_bb_fab1(sch_1):\CC124\"
				( spacingCSetRef "@crescent_city_bb_fab1_lib.crescent_city_bb_fab1(sch_1):\DEFAULT\" )
				( netClassRef "@sapphirecity_baseboard_lib.sapphirecity_baseboard(sch_1):\GND\" )
				( netClassRef "@sapphirecity_baseboard_lib.sapphirecity_baseboard(sch_1):\DDR4_CHN_D_DQ_DQS_BYTE3\" )
			)
			( classClass "@crescent_city_bb_fab1_lib.crescent_city_bb_fab1(sch_1):\CC30\"
				( spacingCSetRef "@crescent_city_bb_fab1_lib.crescent_city_bb_fab1(sch_1):\DEFAULT\" )
				( netClassRef "@sapphirecity_baseboard_lib.sapphirecity_baseboard(sch_1):\POWER\" )
				( netClassRef "@sapphirecity_baseboard_lib.sapphirecity_baseboard(sch_1):\DDR4_CHN_D_DQ_DQS_BYTE3\" )
			)
			( classClass "@sapphirecity_baseboard_lib.sapphirecity_baseboard(sch_1):\CC610\"
				( spacingCSetRef "@sapphirecity_baseboard_lib.sapphirecity_baseboard(sch_1):\DDR4_2SPC_DQ/DQS\" )
				( netClassRef "@sapphirecity_baseboard_lib.sapphirecity_baseboard(sch_1):\DDR4_CHN_D_DQ_DQS_BYTE4\" )
				( netClassRef "@sapphirecity_baseboard_lib.sapphirecity_baseboard(sch_1):\DDR4_CHN_D_DQ_DQS_BYTE4\" )
			)
			( classClass "@crescent_city_bb_fab1_lib.crescent_city_bb_fab1(sch_1):\CC125\"
				( spacingCSetRef "@sapphirecity_baseboard_lib.sapphirecity_baseboard(sch_1):\DQ_TO_DQ\" )
				( netClassRef "@sapphirecity_baseboard_lib.sapphirecity_baseboard(sch_1):\DDR4_CHN_D_CLK\" )
				( netClassRef "@sapphirecity_baseboard_lib.sapphirecity_baseboard(sch_1):\DDR4_CHN_D_DQ_DQS_BYTE4\" )
			)
			( classClass "@crescent_city_bb_fab1_lib.crescent_city_bb_fab1(sch_1):\CC126\"
				( spacingCSetRef "@sapphirecity_baseboard_lib.sapphirecity_baseboard(sch_1):\DQ_TO_DQ\" )
				( netClassRef "@sapphirecity_baseboard_lib.sapphirecity_baseboard(sch_1):\DDR4_CHN_D_CMD_ADD\" )
				( netClassRef "@sapphirecity_baseboard_lib.sapphirecity_baseboard(sch_1):\DDR4_CHN_D_DQ_DQS_BYTE4\" )
			)
			( classClass "@crescent_city_bb_fab1_lib.crescent_city_bb_fab1(sch_1):\CC127\"
				( spacingCSetRef "@sapphirecity_baseboard_lib.sapphirecity_baseboard(sch_1):\10H_SL_12H_MS\" )
				( netClassRef "@sapphirecity_baseboard_lib.sapphirecity_baseboard(sch_1):\DDR4_CHN_D_CTRL\" )
				( netClassRef "@sapphirecity_baseboard_lib.sapphirecity_baseboard(sch_1):\DDR4_CHN_D_DQ_DQS_BYTE4\" )
			)
			( classClass "@crescent_city_bb_fab1_lib.crescent_city_bb_fab1(sch_1):\CC79\"
				( spacingCSetRef "@sapphirecity_baseboard_lib.sapphirecity_baseboard(sch_1):\DQ_TO_DQ\" )
				( netClassRef "@sapphirecity_baseboard_lib.sapphirecity_baseboard(sch_1):\DDR4_CHN_D_DQ_DQS_BYTE4\" )
				( netClassRef "@sapphirecity_baseboard_lib.sapphirecity_baseboard(sch_1):\DDR4_CHN_D_DQ_DQS_BYTE5\" )
			)
			( classClass "@crescent_city_bb_fab1_lib.crescent_city_bb_fab1(sch_1):\CC128\"
				( spacingCSetRef "@sapphirecity_baseboard_lib.sapphirecity_baseboard(sch_1):\DQ_TO_DQ\" )
				( netClassRef "@sapphirecity_baseboard_lib.sapphirecity_baseboard(sch_1):\DDR4_CHN_D_DQ_DQS_BYTE4\" )
				( netClassRef "@sapphirecity_baseboard_lib.sapphirecity_baseboard(sch_1):\DDR4_CHN_D_DQ_DQS_BYTE6\" )
			)
			( classClass "@crescent_city_bb_fab1_lib.crescent_city_bb_fab1(sch_1):\CC129\"
				( spacingCSetRef "@sapphirecity_baseboard_lib.sapphirecity_baseboard(sch_1):\DQ_TO_DQ\" )
				( netClassRef "@sapphirecity_baseboard_lib.sapphirecity_baseboard(sch_1):\DDR4_CHN_D_DQ_DQS_BYTE4\" )
				( netClassRef "@sapphirecity_baseboard_lib.sapphirecity_baseboard(sch_1):\DDR4_CHN_D_DQ_DQS_BYTE7\" )
			)
			( classClass "@crescent_city_bb_fab1_lib.crescent_city_bb_fab1(sch_1):\CC130\"
				( spacingCSetRef "@sapphirecity_baseboard_lib.sapphirecity_baseboard(sch_1):\DQ_TO_DQ\" )
				( netClassRef "@sapphirecity_baseboard_lib.sapphirecity_baseboard(sch_1):\DDR4_CHN_D_DQ_DQS_BYTE4\" )
				( netClassRef "@sapphirecity_baseboard_lib.sapphirecity_baseboard(sch_1):\DDR4_CHN_D_ECC\" )
			)
			( classClass "@crescent_city_bb_fab1_lib.crescent_city_bb_fab1(sch_1):\CC131\"
				( spacingCSetRef "@crescent_city_bb_fab1_lib.crescent_city_bb_fab1(sch_1):\DEFAULT\" )
				( netClassRef "@sapphirecity_baseboard_lib.sapphirecity_baseboard(sch_1):\GND\" )
				( netClassRef "@sapphirecity_baseboard_lib.sapphirecity_baseboard(sch_1):\DDR4_CHN_D_DQ_DQS_BYTE4\" )
			)
			( classClass "@crescent_city_bb_fab1_lib.crescent_city_bb_fab1(sch_1):\CC31\"
				( spacingCSetRef "@crescent_city_bb_fab1_lib.crescent_city_bb_fab1(sch_1):\DEFAULT\" )
				( netClassRef "@sapphirecity_baseboard_lib.sapphirecity_baseboard(sch_1):\POWER\" )
				( netClassRef "@sapphirecity_baseboard_lib.sapphirecity_baseboard(sch_1):\DDR4_CHN_D_DQ_DQS_BYTE4\" )
			)
			( classClass "@sapphirecity_baseboard_lib.sapphirecity_baseboard(sch_1):\CC609\"
				( spacingCSetRef "@sapphirecity_baseboard_lib.sapphirecity_baseboard(sch_1):\DDR4_2SPC_DQ/DQS\" )
				( netClassRef "@sapphirecity_baseboard_lib.sapphirecity_baseboard(sch_1):\DDR4_CHN_D_DQ_DQS_BYTE5\" )
				( netClassRef "@sapphirecity_baseboard_lib.sapphirecity_baseboard(sch_1):\DDR4_CHN_D_DQ_DQS_BYTE5\" )
			)
			( classClass "@crescent_city_bb_fab1_lib.crescent_city_bb_fab1(sch_1):\CC80\"
				( spacingCSetRef "@sapphirecity_baseboard_lib.sapphirecity_baseboard(sch_1):\DQ_TO_DQ\" )
				( netClassRef "@sapphirecity_baseboard_lib.sapphirecity_baseboard(sch_1):\DDR4_CHN_D_CLK\" )
				( netClassRef "@sapphirecity_baseboard_lib.sapphirecity_baseboard(sch_1):\DDR4_CHN_D_DQ_DQS_BYTE5\" )
			)
			( classClass "@crescent_city_bb_fab1_lib.crescent_city_bb_fab1(sch_1):\CC81\"
				( spacingCSetRef "@sapphirecity_baseboard_lib.sapphirecity_baseboard(sch_1):\DQ_TO_DQ\" )
				( netClassRef "@sapphirecity_baseboard_lib.sapphirecity_baseboard(sch_1):\DDR4_CHN_D_CMD_ADD\" )
				( netClassRef "@sapphirecity_baseboard_lib.sapphirecity_baseboard(sch_1):\DDR4_CHN_D_DQ_DQS_BYTE5\" )
			)
			( classClass "@crescent_city_bb_fab1_lib.crescent_city_bb_fab1(sch_1):\CC82\"
				( spacingCSetRef "@sapphirecity_baseboard_lib.sapphirecity_baseboard(sch_1):\10H_SL_12H_MS\" )
				( netClassRef "@sapphirecity_baseboard_lib.sapphirecity_baseboard(sch_1):\DDR4_CHN_D_CTRL\" )
				( netClassRef "@sapphirecity_baseboard_lib.sapphirecity_baseboard(sch_1):\DDR4_CHN_D_DQ_DQS_BYTE5\" )
			)
			( classClass "@crescent_city_bb_fab1_lib.crescent_city_bb_fab1(sch_1):\CC83\"
				( spacingCSetRef "@sapphirecity_baseboard_lib.sapphirecity_baseboard(sch_1):\DQ_TO_DQ\" )
				( netClassRef "@sapphirecity_baseboard_lib.sapphirecity_baseboard(sch_1):\DDR4_CHN_D_DQ_DQS_BYTE5\" )
				( netClassRef "@sapphirecity_baseboard_lib.sapphirecity_baseboard(sch_1):\DDR4_CHN_D_DQ_DQS_BYTE6\" )
			)
			( classClass "@crescent_city_bb_fab1_lib.crescent_city_bb_fab1(sch_1):\CC84\"
				( spacingCSetRef "@sapphirecity_baseboard_lib.sapphirecity_baseboard(sch_1):\DQ_TO_DQ\" )
				( netClassRef "@sapphirecity_baseboard_lib.sapphirecity_baseboard(sch_1):\DDR4_CHN_D_DQ_DQS_BYTE5\" )
				( netClassRef "@sapphirecity_baseboard_lib.sapphirecity_baseboard(sch_1):\DDR4_CHN_D_DQ_DQS_BYTE7\" )
			)
			( classClass "@crescent_city_bb_fab1_lib.crescent_city_bb_fab1(sch_1):\CC85\"
				( spacingCSetRef "@sapphirecity_baseboard_lib.sapphirecity_baseboard(sch_1):\DQ_TO_DQ\" )
				( netClassRef "@sapphirecity_baseboard_lib.sapphirecity_baseboard(sch_1):\DDR4_CHN_D_DQ_DQS_BYTE5\" )
				( netClassRef "@sapphirecity_baseboard_lib.sapphirecity_baseboard(sch_1):\DDR4_CHN_D_ECC\" )
			)
			( classClass "@crescent_city_bb_fab1_lib.crescent_city_bb_fab1(sch_1):\CC86\"
				( spacingCSetRef "@crescent_city_bb_fab1_lib.crescent_city_bb_fab1(sch_1):\DEFAULT\" )
				( netClassRef "@sapphirecity_baseboard_lib.sapphirecity_baseboard(sch_1):\GND\" )
				( netClassRef "@sapphirecity_baseboard_lib.sapphirecity_baseboard(sch_1):\DDR4_CHN_D_DQ_DQS_BYTE5\" )
			)
			( classClass "@crescent_city_bb_fab1_lib.crescent_city_bb_fab1(sch_1):\CC32\"
				( spacingCSetRef "@crescent_city_bb_fab1_lib.crescent_city_bb_fab1(sch_1):\DEFAULT\" )
				( netClassRef "@sapphirecity_baseboard_lib.sapphirecity_baseboard(sch_1):\POWER\" )
				( netClassRef "@sapphirecity_baseboard_lib.sapphirecity_baseboard(sch_1):\DDR4_CHN_D_DQ_DQS_BYTE5\" )
			)
			( classClass "@sapphirecity_baseboard_lib.sapphirecity_baseboard(sch_1):\CC608\"
				( spacingCSetRef "@sapphirecity_baseboard_lib.sapphirecity_baseboard(sch_1):\DDR4_2SPC_DQ/DQS\" )
				( netClassRef "@sapphirecity_baseboard_lib.sapphirecity_baseboard(sch_1):\DDR4_CHN_D_DQ_DQS_BYTE6\" )
				( netClassRef "@sapphirecity_baseboard_lib.sapphirecity_baseboard(sch_1):\DDR4_CHN_D_DQ_DQS_BYTE6\" )
			)
			( classClass "@crescent_city_bb_fab1_lib.crescent_city_bb_fab1(sch_1):\CC132\"
				( spacingCSetRef "@sapphirecity_baseboard_lib.sapphirecity_baseboard(sch_1):\DQ_TO_DQ\" )
				( netClassRef "@sapphirecity_baseboard_lib.sapphirecity_baseboard(sch_1):\DDR4_CHN_D_CLK\" )
				( netClassRef "@sapphirecity_baseboard_lib.sapphirecity_baseboard(sch_1):\DDR4_CHN_D_DQ_DQS_BYTE6\" )
			)
			( classClass "@crescent_city_bb_fab1_lib.crescent_city_bb_fab1(sch_1):\CC133\"
				( spacingCSetRef "@sapphirecity_baseboard_lib.sapphirecity_baseboard(sch_1):\DQ_TO_DQ\" )
				( netClassRef "@sapphirecity_baseboard_lib.sapphirecity_baseboard(sch_1):\DDR4_CHN_D_CMD_ADD\" )
				( netClassRef "@sapphirecity_baseboard_lib.sapphirecity_baseboard(sch_1):\DDR4_CHN_D_DQ_DQS_BYTE6\" )
			)
			( classClass "@crescent_city_bb_fab1_lib.crescent_city_bb_fab1(sch_1):\CC134\"
				( spacingCSetRef "@sapphirecity_baseboard_lib.sapphirecity_baseboard(sch_1):\10H_SL_12H_MS\" )
				( netClassRef "@sapphirecity_baseboard_lib.sapphirecity_baseboard(sch_1):\DDR4_CHN_D_CTRL\" )
				( netClassRef "@sapphirecity_baseboard_lib.sapphirecity_baseboard(sch_1):\DDR4_CHN_D_DQ_DQS_BYTE6\" )
			)
			( classClass "@crescent_city_bb_fab1_lib.crescent_city_bb_fab1(sch_1):\CC135\"
				( spacingCSetRef "@sapphirecity_baseboard_lib.sapphirecity_baseboard(sch_1):\DQ_TO_DQ\" )
				( netClassRef "@sapphirecity_baseboard_lib.sapphirecity_baseboard(sch_1):\DDR4_CHN_D_DQ_DQS_BYTE6\" )
				( netClassRef "@sapphirecity_baseboard_lib.sapphirecity_baseboard(sch_1):\DDR4_CHN_D_DQ_DQS_BYTE7\" )
			)
			( classClass "@crescent_city_bb_fab1_lib.crescent_city_bb_fab1(sch_1):\CC136\"
				( spacingCSetRef "@crescent_city_bb_fab1_lib.crescent_city_bb_fab1(sch_1):\DEFAULT\" )
				( netClassRef "@sapphirecity_baseboard_lib.sapphirecity_baseboard(sch_1):\GND\" )
				( netClassRef "@sapphirecity_baseboard_lib.sapphirecity_baseboard(sch_1):\DDR4_CHN_D_DQ_DQS_BYTE6\" )
			)
			( classClass "@crescent_city_bb_fab1_lib.crescent_city_bb_fab1(sch_1):\CC33\"
				( spacingCSetRef "@crescent_city_bb_fab1_lib.crescent_city_bb_fab1(sch_1):\DEFAULT\" )
				( netClassRef "@sapphirecity_baseboard_lib.sapphirecity_baseboard(sch_1):\POWER\" )
				( netClassRef "@sapphirecity_baseboard_lib.sapphirecity_baseboard(sch_1):\DDR4_CHN_D_DQ_DQS_BYTE6\" )
			)
			( classClass "@crescent_city_bb_fab1_lib.crescent_city_bb_fab1(sch_1):\CC137\"
				( spacingCSetRef "@sapphirecity_baseboard_lib.sapphirecity_baseboard(sch_1):\DQ_TO_DQ\" )
				( netClassRef "@sapphirecity_baseboard_lib.sapphirecity_baseboard(sch_1):\DDR4_CHN_D_DQ_DQS_BYTE6\" )
				( netClassRef "@sapphirecity_baseboard_lib.sapphirecity_baseboard(sch_1):\DDR4_CHN_D_ECC\" )
			)
			( classClass "@sapphirecity_baseboard_lib.sapphirecity_baseboard(sch_1):\CC607\"
				( spacingCSetRef "@sapphirecity_baseboard_lib.sapphirecity_baseboard(sch_1):\DDR4_2SPC_DQ/DQS\" )
				( netClassRef "@sapphirecity_baseboard_lib.sapphirecity_baseboard(sch_1):\DDR4_CHN_D_DQ_DQS_BYTE7\" )
				( netClassRef "@sapphirecity_baseboard_lib.sapphirecity_baseboard(sch_1):\DDR4_CHN_D_DQ_DQS_BYTE7\" )
			)
			( classClass "@crescent_city_bb_fab1_lib.crescent_city_bb_fab1(sch_1):\CC138\"
				( spacingCSetRef "@sapphirecity_baseboard_lib.sapphirecity_baseboard(sch_1):\DQ_TO_DQ\" )
				( netClassRef "@sapphirecity_baseboard_lib.sapphirecity_baseboard(sch_1):\DDR4_CHN_D_CLK\" )
				( netClassRef "@sapphirecity_baseboard_lib.sapphirecity_baseboard(sch_1):\DDR4_CHN_D_DQ_DQS_BYTE7\" )
			)
			( classClass "@crescent_city_bb_fab1_lib.crescent_city_bb_fab1(sch_1):\CC139\"
				( spacingCSetRef "@sapphirecity_baseboard_lib.sapphirecity_baseboard(sch_1):\DQ_TO_DQ\" )
				( netClassRef "@sapphirecity_baseboard_lib.sapphirecity_baseboard(sch_1):\DDR4_CHN_D_CMD_ADD\" )
				( netClassRef "@sapphirecity_baseboard_lib.sapphirecity_baseboard(sch_1):\DDR4_CHN_D_DQ_DQS_BYTE7\" )
			)
			( classClass "@crescent_city_bb_fab1_lib.crescent_city_bb_fab1(sch_1):\CC140\"
				( spacingCSetRef "@sapphirecity_baseboard_lib.sapphirecity_baseboard(sch_1):\10H_SL_12H_MS\" )
				( netClassRef "@sapphirecity_baseboard_lib.sapphirecity_baseboard(sch_1):\DDR4_CHN_D_CTRL\" )
				( netClassRef "@sapphirecity_baseboard_lib.sapphirecity_baseboard(sch_1):\DDR4_CHN_D_DQ_DQS_BYTE7\" )
			)
			( classClass "@crescent_city_bb_fab1_lib.crescent_city_bb_fab1(sch_1):\CC141\"
				( spacingCSetRef "@sapphirecity_baseboard_lib.sapphirecity_baseboard(sch_1):\DQ_TO_DQ\" )
				( netClassRef "@sapphirecity_baseboard_lib.sapphirecity_baseboard(sch_1):\DDR4_CHN_D_DQ_DQS_BYTE7\" )
				( netClassRef "@sapphirecity_baseboard_lib.sapphirecity_baseboard(sch_1):\DDR4_CHN_D_ECC\" )
			)
			( classClass "@crescent_city_bb_fab1_lib.crescent_city_bb_fab1(sch_1):\CC142\"
				( spacingCSetRef "@crescent_city_bb_fab1_lib.crescent_city_bb_fab1(sch_1):\DEFAULT\" )
				( netClassRef "@sapphirecity_baseboard_lib.sapphirecity_baseboard(sch_1):\GND\" )
				( netClassRef "@sapphirecity_baseboard_lib.sapphirecity_baseboard(sch_1):\DDR4_CHN_D_DQ_DQS_BYTE7\" )
			)
			( classClass "@crescent_city_bb_fab1_lib.crescent_city_bb_fab1(sch_1):\CC34\"
				( spacingCSetRef "@crescent_city_bb_fab1_lib.crescent_city_bb_fab1(sch_1):\DEFAULT\" )
				( netClassRef "@sapphirecity_baseboard_lib.sapphirecity_baseboard(sch_1):\POWER\" )
				( netClassRef "@sapphirecity_baseboard_lib.sapphirecity_baseboard(sch_1):\DDR4_CHN_D_DQ_DQS_BYTE7\" )
			)
			( classClass "@crescent_city_bb_fab1_lib.crescent_city_bb_fab1(sch_1):\CC981\"
				( spacingCSetRef "@crescent_city_bb_fab1_lib.crescent_city_bb_fab1(sch_1):\4_MILS\" )
				( netClassRef "@sapphirecity_baseboard_lib.sapphirecity_baseboard(sch_1):\MISC_INTEL_STATIC\" )
				( netClassRef "@sapphirecity_baseboard_lib.sapphirecity_baseboard(sch_1):\RGMII_TX\" )
			)
			( classClass "@sapphirecity_baseboard_lib.sapphirecity_baseboard(sch_1):\CC597\"
				( spacingCSetRef "@sapphirecity_baseboard_lib.sapphirecity_baseboard(sch_1):\8MIL_SL_10MIL_MS\" )
				( netClassRef "@sapphirecity_baseboard_lib.sapphirecity_baseboard(sch_1):\RGMII_TX\" )
				( netClassRef "@sapphirecity_baseboard_lib.sapphirecity_baseboard(sch_1):\RGMII_TX\" )
			)
			( classClass "@crescent_city_bb_fab1_lib.crescent_city_bb_fab1(sch_1):\CC970\"
				( spacingCSetRef "@crescent_city_bb_fab1_lib.crescent_city_bb_fab1(sch_1):\4_MILS\" )
				( netClassRef "@sapphirecity_baseboard_lib.sapphirecity_baseboard(sch_1):\GND\" )
				( netClassRef "@sapphirecity_baseboard_lib.sapphirecity_baseboard(sch_1):\RGMII_TX\" )
			)
			( classClass "@crescent_city_bb_fab1_lib.crescent_city_bb_fab1(sch_1):\CC946\"
				( spacingCSetRef "@crescent_city_bb_fab1_lib.crescent_city_bb_fab1(sch_1):\4_MILS\" )
				( netClassRef "@sapphirecity_baseboard_lib.sapphirecity_baseboard(sch_1):\POWER\" )
				( netClassRef "@sapphirecity_baseboard_lib.sapphirecity_baseboard(sch_1):\RGMII_TX\" )
			)
			( classClass "@sapphirecity_baseboard_lib.sapphirecity_baseboard(sch_1):\CC44\"
				( spacingCSetRef "@sapphirecity_baseboard_lib.sapphirecity_baseboard(sch_1):\20_MILS\" )
				( netClassRef "@sapphirecity_baseboard_lib.sapphirecity_baseboard(sch_1):\V_M_BMC_DDR3_CLK\" )
				( netClassRef "@sapphirecity_baseboard_lib.sapphirecity_baseboard(sch_1):\V_M_BMC_DDR3_MA\" )
			)
			( classClass "@sapphirecity_baseboard_lib.sapphirecity_baseboard(sch_1):\CC84\"
				( spacingCSetRef "@crescent_city_bb_fab1_lib.crescent_city_bb_fab1(sch_1):\DEFAULT\" )
				( netClassRef "@sapphirecity_baseboard_lib.sapphirecity_baseboard(sch_1):\GND\" )
				( netClassRef "@sapphirecity_baseboard_lib.sapphirecity_baseboard(sch_1):\V_M_BMC_DDR3_CLK\" )
			)
			( classClass "@sapphirecity_baseboard_lib.sapphirecity_baseboard(sch_1):\CC590\"
				( spacingCSetRef "@sapphirecity_baseboard_lib.sapphirecity_baseboard(sch_1):\20_MILS\" )
				( netClassRef "@sapphirecity_baseboard_lib.sapphirecity_baseboard(sch_1):\V_M_BMC_DDR3_CLK\" )
				( netClassRef "@sapphirecity_baseboard_lib.sapphirecity_baseboard(sch_1):\V_M_BMC_DDR3_DQ\" )
			)
			( classClass "@sapphirecity_baseboard_lib.sapphirecity_baseboard(sch_1):\CC593\"
				( spacingCSetRef "@sapphirecity_baseboard_lib.sapphirecity_baseboard(sch_1):\20_MILS\" )
				( netClassRef "@sapphirecity_baseboard_lib.sapphirecity_baseboard(sch_1):\V_M_BMC_DDR3_CLK\" )
				( netClassRef "@sapphirecity_baseboard_lib.sapphirecity_baseboard(sch_1):\V_M_BMC_DDR3_DQS\" )
			)
			( classClass "@sapphirecity_baseboard_lib.sapphirecity_baseboard(sch_1):\CC43\"
				( spacingCSetRef "@sapphirecity_baseboard_lib.sapphirecity_baseboard(sch_1):\20_MILS\" )
				( netClassRef "@sapphirecity_baseboard_lib.sapphirecity_baseboard(sch_1):\V_M_BMC_DDR3_DQS\" )
				( netClassRef "@sapphirecity_baseboard_lib.sapphirecity_baseboard(sch_1):\V_M_BMC_DDR3_MA\" )
			)
			( classClass "@sapphirecity_baseboard_lib.sapphirecity_baseboard(sch_1):\CC82\"
				( spacingCSetRef "@crescent_city_bb_fab1_lib.crescent_city_bb_fab1(sch_1):\DEFAULT\" )
				( netClassRef "@sapphirecity_baseboard_lib.sapphirecity_baseboard(sch_1):\GND\" )
				( netClassRef "@sapphirecity_baseboard_lib.sapphirecity_baseboard(sch_1):\V_M_BMC_DDR3_DQS\" )
			)
			( classClass "@sapphirecity_baseboard_lib.sapphirecity_baseboard(sch_1):\CC592\"
				( spacingCSetRef "@sapphirecity_baseboard_lib.sapphirecity_baseboard(sch_1):\20_MILS\" )
				( netClassRef "@sapphirecity_baseboard_lib.sapphirecity_baseboard(sch_1):\V_M_BMC_DDR3_DQ\" )
				( netClassRef "@sapphirecity_baseboard_lib.sapphirecity_baseboard(sch_1):\V_M_BMC_DDR3_DQS\" )
			)
			( classClass "@sapphirecity_baseboard_lib.sapphirecity_baseboard(sch_1):\CC594\"
				( spacingCSetRef "@sapphirecity_baseboard_lib.sapphirecity_baseboard(sch_1):\20_MILS\" )
				( netClassRef "@sapphirecity_baseboard_lib.sapphirecity_baseboard(sch_1):\V_M_BMC_DDR3_DQS\" )
				( netClassRef "@sapphirecity_baseboard_lib.sapphirecity_baseboard(sch_1):\V_M_BMC_DDR3_DQS\" )
			)
			( classClass "@sapphirecity_baseboard_lib.sapphirecity_baseboard(sch_1):\CC42\"
				( spacingCSetRef "@sapphirecity_baseboard_lib.sapphirecity_baseboard(sch_1):\15MIL\" )
				( netClassRef "@sapphirecity_baseboard_lib.sapphirecity_baseboard(sch_1):\V_M_BMC_DDR3_DQ\" )
				( netClassRef "@sapphirecity_baseboard_lib.sapphirecity_baseboard(sch_1):\V_M_BMC_DDR3_MA\" )
			)
			( classClass "@sapphirecity_baseboard_lib.sapphirecity_baseboard(sch_1):\CC81\"
				( spacingCSetRef "@crescent_city_bb_fab1_lib.crescent_city_bb_fab1(sch_1):\DEFAULT\" )
				( netClassRef "@sapphirecity_baseboard_lib.sapphirecity_baseboard(sch_1):\GND\" )
				( netClassRef "@sapphirecity_baseboard_lib.sapphirecity_baseboard(sch_1):\V_M_BMC_DDR3_DQ\" )
			)
			( classClass "@sapphirecity_baseboard_lib.sapphirecity_baseboard(sch_1):\CC591\"
				( spacingCSetRef "@sapphirecity_baseboard_lib.sapphirecity_baseboard(sch_1):\10MIL\" )
				( netClassRef "@sapphirecity_baseboard_lib.sapphirecity_baseboard(sch_1):\V_M_BMC_DDR3_DQ\" )
				( netClassRef "@sapphirecity_baseboard_lib.sapphirecity_baseboard(sch_1):\V_M_BMC_DDR3_DQ\" )
			)
			( classClass "@sapphirecity_baseboard_lib.sapphirecity_baseboard(sch_1):\CC45\"
				( spacingCSetRef "@sapphirecity_baseboard_lib.sapphirecity_baseboard(sch_1):\10MIL\" )
				( netClassRef "@sapphirecity_baseboard_lib.sapphirecity_baseboard(sch_1):\V_M_BMC_DDR3_MA\" )
				( netClassRef "@sapphirecity_baseboard_lib.sapphirecity_baseboard(sch_1):\V_M_BMC_DDR3_MA\" )
			)
			( classClass "@sapphirecity_baseboard_lib.sapphirecity_baseboard(sch_1):\CC46\"
				( spacingCSetRef "@crescent_city_bb_fab1_lib.crescent_city_bb_fab1(sch_1):\DEFAULT\" )
				( netClassRef "@sapphirecity_baseboard_lib.sapphirecity_baseboard(sch_1):\GND\" )
				( netClassRef "@sapphirecity_baseboard_lib.sapphirecity_baseboard(sch_1):\V_M_BMC_DDR3_MA\" )
			)
			( classClass "@crescent_city_bb_fab1_lib.crescent_city_bb_fab1(sch_1):\CC942\"
				( spacingCSetRef "@crescent_city_bb_fab1_lib.crescent_city_bb_fab1(sch_1):\DEFAULT\" )
				( netClassRef "@sapphirecity_baseboard_lib.sapphirecity_baseboard(sch_1):\POWER\" )
				( netClassRef "@sapphirecity_baseboard_lib.sapphirecity_baseboard(sch_1):\XDP_CPU_TCK\" )
			)
			( classClass "@sapphirecity_baseboard_lib.sapphirecity_baseboard(sch_1):\CC83\"
				( spacingCSetRef "@crescent_city_bb_fab1_lib.crescent_city_bb_fab1(sch_1):\DEFAULT\" )
				( netClassRef "@sapphirecity_baseboard_lib.sapphirecity_baseboard(sch_1):\GND\" )
				( netClassRef "@sapphirecity_baseboard_lib.sapphirecity_baseboard(sch_1):\XDP_CPU_TCK\" )
			)
			( classClass "@sapphirecity_baseboard_lib.sapphirecity_baseboard(sch_1):\CC41\"
				( spacingCSetRef "@crescent_city_bb_fab1_lib.crescent_city_bb_fab1(sch_1):\DEFAULT\" )
				( netClassRef "@sapphirecity_baseboard_lib.sapphirecity_baseboard(sch_1):\GND\" )
				( netClassRef "@sapphirecity_baseboard_lib.sapphirecity_baseboard(sch_1):\RCOMP\" )
			)
			( classClass "@sapphirecity_baseboard_lib.sapphirecity_baseboard(sch_1):\CC85\"
				( spacingCSetRef "@crescent_city_bb_fab1_lib.crescent_city_bb_fab1(sch_1):\DEFAULT\" )
				( netClassRef "@sapphirecity_baseboard_lib.sapphirecity_baseboard(sch_1):\GND\" )
				( netClassRef "@sapphirecity_baseboard_lib.sapphirecity_baseboard(sch_1):\XTAL\" )
			)
			( classClass "@sapphirecity_baseboard_lib.sapphirecity_baseboard(sch_1):\CC589\"
				( spacingCSetRef "@crescent_city_bb_fab1_lib.crescent_city_bb_fab1(sch_1):\24MIL_US_&_21MIL_SL\" )
				( netClassRef "@sapphirecity_baseboard_lib.sapphirecity_baseboard(sch_1):\XTAL\" )
				( netClassRef "@sapphirecity_baseboard_lib.sapphirecity_baseboard(sch_1):\XTAL\" )
			)
			( classClass "@sapphirecity_baseboard_lib.sapphirecity_baseboard(sch_1):\CC171\"
				( spacingCSetRef "@crescent_city_bb_fab1_lib.crescent_city_bb_fab1(sch_1):\DEFAULT\" )
				( netClassRef "@sapphirecity_baseboard_lib.sapphirecity_baseboard(sch_1):\GND\" )
				( netClassRef "@sapphirecity_baseboard_lib.sapphirecity_baseboard(sch_1):\VR_PVDDQ_GH\" )
			)
			( classClass "@sapphirecity_baseboard_lib.sapphirecity_baseboard(sch_1):\CC172\"
				( spacingCSetRef "@crescent_city_bb_fab1_lib.crescent_city_bb_fab1(sch_1):\DEFAULT\" )
				( netClassRef "@sapphirecity_baseboard_lib.sapphirecity_baseboard(sch_1):\GND\" )
				( netClassRef "@sapphirecity_baseboard_lib.sapphirecity_baseboard(sch_1):\VR_PVDDQ_EF\" )
			)
			( classClass "@sapphirecity_baseboard_lib.sapphirecity_baseboard(sch_1):\CC150\"
				( spacingCSetRef "@crescent_city_bb_fab1_lib.crescent_city_bb_fab1(sch_1):\DEFAULT\" )
				( netClassRef "@sapphirecity_baseboard_lib.sapphirecity_baseboard(sch_1):\GND\" )
				( netClassRef "@sapphirecity_baseboard_lib.sapphirecity_baseboard(sch_1):\VR_P3V3\" )
			)
			( classClass "@sapphirecity_baseboard_lib.sapphirecity_baseboard(sch_1):\CC175\"
				( spacingCSetRef "@crescent_city_bb_fab1_lib.crescent_city_bb_fab1(sch_1):\DEFAULT\" )
				( netClassRef "@sapphirecity_baseboard_lib.sapphirecity_baseboard(sch_1):\GND\" )
				( netClassRef "@sapphirecity_baseboard_lib.sapphirecity_baseboard(sch_1):\VR_PVCCIO\" )
			)
			( classClass "@sapphirecity_baseboard_lib.sapphirecity_baseboard(sch_1):\CC156\"
				( spacingCSetRef "@crescent_city_bb_fab1_lib.crescent_city_bb_fab1(sch_1):\DEFAULT\" )
				( netClassRef "@sapphirecity_baseboard_lib.sapphirecity_baseboard(sch_1):\GND\" )
				( netClassRef "@sapphirecity_baseboard_lib.sapphirecity_baseboard(sch_1):\VR_P1V5_AUX\" )
			)
			( classClass "@sapphirecity_baseboard_lib.sapphirecity_baseboard(sch_1):\CC154\"
				( spacingCSetRef "@crescent_city_bb_fab1_lib.crescent_city_bb_fab1(sch_1):\DEFAULT\" )
				( netClassRef "@sapphirecity_baseboard_lib.sapphirecity_baseboard(sch_1):\GND\" )
				( netClassRef "@sapphirecity_baseboard_lib.sapphirecity_baseboard(sch_1):\VR_P1V8_AUX\" )
			)
			( classClass "@sapphirecity_baseboard_lib.sapphirecity_baseboard(sch_1):\CC158\"
				( spacingCSetRef "@crescent_city_bb_fab1_lib.crescent_city_bb_fab1(sch_1):\DEFAULT\" )
				( netClassRef "@sapphirecity_baseboard_lib.sapphirecity_baseboard(sch_1):\GND\" )
				( netClassRef "@sapphirecity_baseboard_lib.sapphirecity_baseboard(sch_1):\VR_P1V0_AUX\" )
			)
			( classClass "@sapphirecity_baseboard_lib.sapphirecity_baseboard(sch_1):\CC147\"
				( spacingCSetRef "@crescent_city_bb_fab1_lib.crescent_city_bb_fab1(sch_1):\DEFAULT\" )
				( netClassRef "@sapphirecity_baseboard_lib.sapphirecity_baseboard(sch_1):\GND\" )
				( netClassRef "@sapphirecity_baseboard_lib.sapphirecity_baseboard(sch_1):\VR_P5V_AUX\" )
			)
			( classClass "@sapphirecity_baseboard_lib.sapphirecity_baseboard(sch_1):\CC148\"
				( spacingCSetRef "@crescent_city_bb_fab1_lib.crescent_city_bb_fab1(sch_1):\DEFAULT\" )
				( netClassRef "@sapphirecity_baseboard_lib.sapphirecity_baseboard(sch_1):\GND\" )
				( netClassRef "@sapphirecity_baseboard_lib.sapphirecity_baseboard(sch_1):\VR_P5V\" )
			)
			( classClass "@sapphirecity_baseboard_lib.sapphirecity_baseboard(sch_1):\CC155\"
				( spacingCSetRef "@crescent_city_bb_fab1_lib.crescent_city_bb_fab1(sch_1):\DEFAULT\" )
				( netClassRef "@sapphirecity_baseboard_lib.sapphirecity_baseboard(sch_1):\GND\" )
				( netClassRef "@sapphirecity_baseboard_lib.sapphirecity_baseboard(sch_1):\VR_P1V5_PCH\" )
			)
			( classClass "@sapphirecity_baseboard_lib.sapphirecity_baseboard(sch_1):\CC152\"
				( spacingCSetRef "@crescent_city_bb_fab1_lib.crescent_city_bb_fab1(sch_1):\DEFAULT\" )
				( netClassRef "@sapphirecity_baseboard_lib.sapphirecity_baseboard(sch_1):\GND\" )
				( netClassRef "@sapphirecity_baseboard_lib.sapphirecity_baseboard(sch_1):\VR_P1V05_STBY_PCH\" )
			)
			( classClass "@sapphirecity_baseboard_lib.sapphirecity_baseboard(sch_1):\CC153\"
				( spacingCSetRef "@crescent_city_bb_fab1_lib.crescent_city_bb_fab1(sch_1):\DEFAULT\" )
				( netClassRef "@sapphirecity_baseboard_lib.sapphirecity_baseboard(sch_1):\GND\" )
				( netClassRef "@sapphirecity_baseboard_lib.sapphirecity_baseboard(sch_1):\VR_P1V05_PCH\" )
			)
			( classClass "@sapphirecity_baseboard_lib.sapphirecity_baseboard(sch_1):\CC149\"
				( spacingCSetRef "@crescent_city_bb_fab1_lib.crescent_city_bb_fab1(sch_1):\DEFAULT\" )
				( netClassRef "@sapphirecity_baseboard_lib.sapphirecity_baseboard(sch_1):\GND\" )
				( netClassRef "@sapphirecity_baseboard_lib.sapphirecity_baseboard(sch_1):\VR_P3V3_AUX\" )
			)
			( classClass "@sapphirecity_baseboard_lib.sapphirecity_baseboard(sch_1):\CC163\"
				( spacingCSetRef "@crescent_city_bb_fab1_lib.crescent_city_bb_fab1(sch_1):\DEFAULT\" )
				( netClassRef "@sapphirecity_baseboard_lib.sapphirecity_baseboard(sch_1):\GND\" )
				( netClassRef "@sapphirecity_baseboard_lib.sapphirecity_baseboard(sch_1):\VR_PVTT_GH\" )
			)
			( classClass "@sapphirecity_baseboard_lib.sapphirecity_baseboard(sch_1):\CC164\"
				( spacingCSetRef "@crescent_city_bb_fab1_lib.crescent_city_bb_fab1(sch_1):\DEFAULT\" )
				( netClassRef "@sapphirecity_baseboard_lib.sapphirecity_baseboard(sch_1):\GND\" )
				( netClassRef "@sapphirecity_baseboard_lib.sapphirecity_baseboard(sch_1):\VR_PVTT_EF\" )
			)
			( classClass "@sapphirecity_baseboard_lib.sapphirecity_baseboard(sch_1):\CC165\"
				( spacingCSetRef "@crescent_city_bb_fab1_lib.crescent_city_bb_fab1(sch_1):\DEFAULT\" )
				( netClassRef "@sapphirecity_baseboard_lib.sapphirecity_baseboard(sch_1):\GND\" )
				( netClassRef "@sapphirecity_baseboard_lib.sapphirecity_baseboard(sch_1):\VR_PVTT_CD\" )
			)
			( classClass "@sapphirecity_baseboard_lib.sapphirecity_baseboard(sch_1):\CC166\"
				( spacingCSetRef "@crescent_city_bb_fab1_lib.crescent_city_bb_fab1(sch_1):\DEFAULT\" )
				( netClassRef "@sapphirecity_baseboard_lib.sapphirecity_baseboard(sch_1):\GND\" )
				( netClassRef "@sapphirecity_baseboard_lib.sapphirecity_baseboard(sch_1):\VR_PVTT_AB\" )
			)
			( classClass "@sapphirecity_baseboard_lib.sapphirecity_baseboard(sch_1):\CC176\"
				( spacingCSetRef "@crescent_city_bb_fab1_lib.crescent_city_bb_fab1(sch_1):\DEFAULT\" )
				( netClassRef "@sapphirecity_baseboard_lib.sapphirecity_baseboard(sch_1):\GND\" )
				( netClassRef "@sapphirecity_baseboard_lib.sapphirecity_baseboard(sch_1):\VR_PVCCIN_CPU1\" )
			)
			( classClass "@crescent_city_bb_fab1_lib.crescent_city_bb_fab1(sch_1):\CC935\"
				( spacingCSetRef "@sapphirecity_baseboard_lib.sapphirecity_baseboard(sch_1):\13.5MIL_SL_12MIL_MS\" )
				( netClassRef "@sapphirecity_baseboard_lib.sapphirecity_baseboard(sch_1):\SVID\" )
				( netClassRef "@sapphirecity_baseboard_lib.sapphirecity_baseboard(sch_1):\SVID\" )
			)
			( classClass "@sapphirecity_baseboard_lib.sapphirecity_baseboard(sch_1):\CC180\"
				( spacingCSetRef "@crescent_city_bb_fab1_lib.crescent_city_bb_fab1(sch_1):\5MIL_US_&_4MIL_SL\" )
				( netClassRef "@sapphirecity_baseboard_lib.sapphirecity_baseboard(sch_1):\GND\" )
				( netClassRef "@sapphirecity_baseboard_lib.sapphirecity_baseboard(sch_1):\SPI\" )
			)
			( classClass "@crescent_city_bb_fab1_lib.crescent_city_bb_fab1(sch_1):\CC947\"
				( spacingCSetRef "@crescent_city_bb_fab1_lib.crescent_city_bb_fab1(sch_1):\5MIL_US_&_4MIL_SL\" )
				( netClassRef "@sapphirecity_baseboard_lib.sapphirecity_baseboard(sch_1):\POWER\" )
				( netClassRef "@sapphirecity_baseboard_lib.sapphirecity_baseboard(sch_1):\SPI\" )
			)
			( classClass "@crescent_city_bb_fab1_lib.crescent_city_bb_fab1(sch_1):\CC982\"
				( spacingCSetRef "@crescent_city_bb_fab1_lib.crescent_city_bb_fab1(sch_1):\5MIL_US_&_4MIL_SL\" )
				( netClassRef "@sapphirecity_baseboard_lib.sapphirecity_baseboard(sch_1):\MISC_INTEL_STATIC\" )
				( netClassRef "@sapphirecity_baseboard_lib.sapphirecity_baseboard(sch_1):\SPI\" )
			)
			( classClass "@crescent_city_bb_fab1_lib.crescent_city_bb_fab1(sch_1):\CC971\"
				( spacingCSetRef "@crescent_city_bb_fab1_lib.crescent_city_bb_fab1(sch_1):\DEFAULT\" )
				( netClassRef "@sapphirecity_baseboard_lib.sapphirecity_baseboard(sch_1):\GND\" )
				( netClassRef "@sapphirecity_baseboard_lib.sapphirecity_baseboard(sch_1):\SGPIO_SATA\" )
			)
			( classClass "@sapphirecity_baseboard_lib.sapphirecity_baseboard(sch_1):\CC184\"
				( spacingCSetRef "@crescent_city_bb_fab1_lib.crescent_city_bb_fab1(sch_1):\DEFAULT\" )
				( netClassRef "@sapphirecity_baseboard_lib.sapphirecity_baseboard(sch_1):\GND\" )
				( netClassRef "@sapphirecity_baseboard_lib.sapphirecity_baseboard(sch_1):\SGPIO\" )
			)
			( classClass "@sapphirecity_baseboard_lib.sapphirecity_baseboard(sch_1):\CC251\"
				( spacingCSetRef "@crescent_city_bb_fab1_lib.crescent_city_bb_fab1(sch_1):\DEFAULT\" )
				( netClassRef "@sapphirecity_baseboard_lib.sapphirecity_baseboard(sch_1):\GND\" )
				( netClassRef "@sapphirecity_baseboard_lib.sapphirecity_baseboard(sch_1):\NOA\" )
			)
			( classClass "@crescent_city_bb_fab1_lib.crescent_city_bb_fab1(sch_1):\CC928\"
				( spacingCSetRef "@crescent_city_bb_fab1_lib.crescent_city_bb_fab1(sch_1):\DEFAULT\" )
				( netClassRef "@sapphirecity_baseboard_lib.sapphirecity_baseboard(sch_1):\GND\" )
				( netClassRef "@sapphirecity_baseboard_lib.sapphirecity_baseboard(sch_1):\RESET_IRQ_PWRGD\" )
			)
			( classClass "@crescent_city_bb_fab1_lib.crescent_city_bb_fab1(sch_1):\CC940\"
				( spacingCSetRef "@crescent_city_bb_fab1_lib.crescent_city_bb_fab1(sch_1):\DEFAULT\" )
				( netClassRef "@sapphirecity_baseboard_lib.sapphirecity_baseboard(sch_1):\POWER\" )
				( netClassRef "@sapphirecity_baseboard_lib.sapphirecity_baseboard(sch_1):\RESET_IRQ_PWRGD\" )
			)
			( classClass "@sapphirecity_baseboard_lib.sapphirecity_baseboard(sch_1):\CC200\"
				( spacingCSetRef "@crescent_city_bb_fab1_lib.crescent_city_bb_fab1(sch_1):\DEFAULT\" )
				( netClassRef "@sapphirecity_baseboard_lib.sapphirecity_baseboard(sch_1):\GND\" )
				( netClassRef "@sapphirecity_baseboard_lib.sapphirecity_baseboard(sch_1):\LPC\" )
			)
			( classClass "@sapphirecity_baseboard_lib.sapphirecity_baseboard(sch_1):\CC586\"
				( spacingCSetRef "@sapphirecity_baseboard_lib.sapphirecity_baseboard(sch_1):\13.5MIL_SL_12MIL_MS\" )
				( netClassRef "@sapphirecity_baseboard_lib.sapphirecity_baseboard(sch_1):\LPC\" )
				( netClassRef "@sapphirecity_baseboard_lib.sapphirecity_baseboard(sch_1):\LPC\" )
			)
			( classClass "@sapphirecity_baseboard_lib.sapphirecity_baseboard(sch_1):\CC88\"
				( spacingCSetRef "@crescent_city_bb_fab1_lib.crescent_city_bb_fab1(sch_1):\DEFAULT\" )
				( netClassRef "@sapphirecity_baseboard_lib.sapphirecity_baseboard(sch_1):\GND\" )
				( netClassRef "@sapphirecity_baseboard_lib.sapphirecity_baseboard(sch_1):\JTAG_XDP\" )
			)
			( classClass "@sapphirecity_baseboard_lib.sapphirecity_baseboard(sch_1):\CC585\"
				( netClassRef "@sapphirecity_baseboard_lib.sapphirecity_baseboard(sch_1):\JTAG_XDP\" )
				( netClassRef "@sapphirecity_baseboard_lib.sapphirecity_baseboard(sch_1):\JTAG_XDP\" )
			)
			( classClass "@sapphirecity_baseboard_lib.sapphirecity_baseboard(sch_1):\CC248\"
				( spacingCSetRef "@crescent_city_bb_fab1_lib.crescent_city_bb_fab1(sch_1):\DEFAULT\" )
				( netClassRef "@sapphirecity_baseboard_lib.sapphirecity_baseboard(sch_1):\GND\" )
				( netClassRef "@sapphirecity_baseboard_lib.sapphirecity_baseboard(sch_1):\FAN\" )
			)
			( classClass "@sapphirecity_baseboard_lib.sapphirecity_baseboard(sch_1):\CC584\"
				( netClassRef "@sapphirecity_baseboard_lib.sapphirecity_baseboard(sch_1):\FAN\" )
				( netClassRef "@sapphirecity_baseboard_lib.sapphirecity_baseboard(sch_1):\FAN\" )
			)
			( classClass "@sapphirecity_baseboard_lib.sapphirecity_baseboard(sch_1):\CC40\"
				( spacingCSetRef "@crescent_city_bb_fab1_lib.crescent_city_bb_fab1(sch_1):\DEFAULT\" )
				( netClassRef "@sapphirecity_baseboard_lib.sapphirecity_baseboard(sch_1):\GND\" )
				( netClassRef "@sapphirecity_baseboard_lib.sapphirecity_baseboard(sch_1):\ISENSE\" )
			)
			( classClass "@sapphirecity_baseboard_lib.sapphirecity_baseboard(sch_1):\CC583\"
				( spacingCSetRef "@sapphirecity_baseboard_lib.sapphirecity_baseboard(sch_1):\8MIL\" )
				( netClassRef "@sapphirecity_baseboard_lib.sapphirecity_baseboard(sch_1):\V_BMC_DDC\" )
				( netClassRef "@sapphirecity_baseboard_lib.sapphirecity_baseboard(sch_1):\V_BMC_DDC\" )
			)
			( classClass "@sapphirecity_baseboard_lib.sapphirecity_baseboard(sch_1):\CC38\"
				( spacingCSetRef "@sapphirecity_baseboard_lib.sapphirecity_baseboard(sch_1):\20MIL_VIA_2H+A\" )
				( netClassRef "@sapphirecity_baseboard_lib.sapphirecity_baseboard(sch_1):\V_BMC_RGB\" )
				( netClassRef "@sapphirecity_baseboard_lib.sapphirecity_baseboard(sch_1):\V_BMC_RGB\" )
			)
			( classClass "@sapphirecity_baseboard_lib.sapphirecity_baseboard(sch_1):\CC39\"
				( spacingCSetRef "@crescent_city_bb_fab1_lib.crescent_city_bb_fab1(sch_1):\DEFAULT\" )
				( netClassRef "@sapphirecity_baseboard_lib.sapphirecity_baseboard(sch_1):\GND\" )
				( netClassRef "@sapphirecity_baseboard_lib.sapphirecity_baseboard(sch_1):\V_BMC_RGB\" )
			)
			( classClass "@sapphirecity_baseboard_lib.sapphirecity_baseboard(sch_1):\CC95\"
				( spacingCSetRef "@crescent_city_bb_fab1_lib.crescent_city_bb_fab1(sch_1):\DEFAULT\" )
				( netClassRef "@sapphirecity_baseboard_lib.sapphirecity_baseboard(sch_1):\GND\" )
				( netClassRef "@sapphirecity_baseboard_lib.sapphirecity_baseboard(sch_1):\PE_PCH_BMC\" )
			)
			( classClass "@sapphirecity_baseboard_lib.sapphirecity_baseboard(sch_1):\CC98\"
				( spacingCSetRef "@crescent_city_bb_fab1_lib.crescent_city_bb_fab1(sch_1):\DEFAULT\" )
				( netClassRef "@sapphirecity_baseboard_lib.sapphirecity_baseboard(sch_1):\GND\" )
				( netClassRef "@sapphirecity_baseboard_lib.sapphirecity_baseboard(sch_1):\USB2\" )
			)
			( classClass "@crescent_city_bb_fab1_lib.crescent_city_bb_fab1(sch_1):\CC956\"
				( spacingCSetRef "@sapphirecity_baseboard_lib.sapphirecity_baseboard(sch_1):\35MIL\" )
				( netClassRef "@sapphirecity_baseboard_lib.sapphirecity_baseboard(sch_1):\CLK_DIFF_100M\" )
				( netClassRef "@sapphirecity_baseboard_lib.sapphirecity_baseboard(sch_1):\USB2\" )
			)
			( classClass "@crescent_city_bb_fab1_lib.crescent_city_bb_fab1(sch_1):\CC960\"
				( spacingCSetRef "@sapphirecity_baseboard_lib.sapphirecity_baseboard(sch_1):\35MIL\" )
				( netClassRef "@sapphirecity_baseboard_lib.sapphirecity_baseboard(sch_1):\CLK_SE_48_50M\" )
				( netClassRef "@sapphirecity_baseboard_lib.sapphirecity_baseboard(sch_1):\USB2\" )
			)
			( classClass "@crescent_city_bb_fab1_lib.crescent_city_bb_fab1(sch_1):\CC961\"
				( spacingCSetRef "@crescent_city_bb_fab1_lib.crescent_city_bb_fab1(sch_1):\DEFAULT\" )
				( netClassRef "@sapphirecity_baseboard_lib.sapphirecity_baseboard(sch_1):\POWER\" )
				( netClassRef "@sapphirecity_baseboard_lib.sapphirecity_baseboard(sch_1):\USB2\" )
			)
			( classClass "@sapphirecity_baseboard_lib.sapphirecity_baseboard(sch_1):\CC99\"
				( spacingCSetRef "@crescent_city_bb_fab1_lib.crescent_city_bb_fab1(sch_1):\DEFAULT\" )
				( netClassRef "@sapphirecity_baseboard_lib.sapphirecity_baseboard(sch_1):\GND\" )
				( netClassRef "@sapphirecity_baseboard_lib.sapphirecity_baseboard(sch_1):\SATA6G_TX\" )
			)
			( classClass "@sapphirecity_baseboard_lib.sapphirecity_baseboard(sch_1):\CC582\"
				( spacingCSetRef "@crescent_city_bb_fab1_lib.crescent_city_bb_fab1(sch_1):\19MIL_US_&_15MIL_SL\" )
				( netClassRef "@sapphirecity_baseboard_lib.sapphirecity_baseboard(sch_1):\SATA6G_TX\" )
				( netClassRef "@sapphirecity_baseboard_lib.sapphirecity_baseboard(sch_1):\SATA6G_TX\" )
			)
			( classClass "@sapphirecity_baseboard_lib.sapphirecity_baseboard(sch_1):\CC107\"
				( spacingCSetRef "@crescent_city_bb_fab1_lib.crescent_city_bb_fab1(sch_1):\DEFAULT\" )
				( netClassRef "@sapphirecity_baseboard_lib.sapphirecity_baseboard(sch_1):\GND\" )
				( netClassRef "@sapphirecity_baseboard_lib.sapphirecity_baseboard(sch_1):\USB3_RX\" )
			)
			( classClass "@sapphirecity_baseboard_lib.sapphirecity_baseboard(sch_1):\CC580\"
				( spacingCSetRef "@crescent_city_bb_fab1_lib.crescent_city_bb_fab1(sch_1):\9H_US_&_5H_SL_VIA+3H_A\" )
				( netClassRef "@sapphirecity_baseboard_lib.sapphirecity_baseboard(sch_1):\USB3_RX\" )
				( netClassRef "@sapphirecity_baseboard_lib.sapphirecity_baseboard(sch_1):\USB3_RX\" )
			)
			( classClass "@crescent_city_bb_fab1_lib.crescent_city_bb_fab1(sch_1):\CC967\"
				( spacingCSetRef "@crescent_city_bb_fab1_lib.crescent_city_bb_fab1(sch_1):\DEFAULT\" )
				( netClassRef "@sapphirecity_baseboard_lib.sapphirecity_baseboard(sch_1):\POWER\" )
				( netClassRef "@sapphirecity_baseboard_lib.sapphirecity_baseboard(sch_1):\USB3_RX\" )
			)
			( classClass "@sapphirecity_baseboard_lib.sapphirecity_baseboard(sch_1):\CC110\"
				( spacingCSetRef "@crescent_city_bb_fab1_lib.crescent_city_bb_fab1(sch_1):\DEFAULT\" )
				( netClassRef "@sapphirecity_baseboard_lib.sapphirecity_baseboard(sch_1):\GND\" )
				( netClassRef "@sapphirecity_baseboard_lib.sapphirecity_baseboard(sch_1):\SATA6G_RX\" )
			)
			( classClass "@sapphirecity_baseboard_lib.sapphirecity_baseboard(sch_1):\CC579\"
				( spacingCSetRef "@crescent_city_bb_fab1_lib.crescent_city_bb_fab1(sch_1):\19MIL_US_&_15MIL_SL\" )
				( netClassRef "@sapphirecity_baseboard_lib.sapphirecity_baseboard(sch_1):\SATA6G_RX\" )
				( netClassRef "@sapphirecity_baseboard_lib.sapphirecity_baseboard(sch_1):\SATA6G_RX\" )
			)
			( classClass "@crescent_city_bb_fab1_lib.crescent_city_bb_fab1(sch_1):\CC73\"
				( spacingCSetRef "@crescent_city_bb_fab1_lib.crescent_city_bb_fab1(sch_1):\DEFAULT\" )
				( netClassRef "@sapphirecity_baseboard_lib.sapphirecity_baseboard(sch_1):\POWER\" )
				( netClassRef "@sapphirecity_baseboard_lib.sapphirecity_baseboard(sch_1):\P3E_CPU1_PE3D_RISER2_TX\" )
			)
			( classClass "@sapphirecity_baseboard_lib.sapphirecity_baseboard(sch_1):\CC269\"
				( spacingCSetRef "@crescent_city_bb_fab1_lib.crescent_city_bb_fab1(sch_1):\DEFAULT\" )
				( netClassRef "@sapphirecity_baseboard_lib.sapphirecity_baseboard(sch_1):\GND\" )
				( netClassRef "@sapphirecity_baseboard_lib.sapphirecity_baseboard(sch_1):\P3E_CPU1_PE3D_RISER2_TX\" )
			)
			( classClass "@sapphirecity_baseboard_lib.sapphirecity_baseboard(sch_1):\CC577\"
				( spacingCSetRef "@sapphirecity_baseboard_lib.sapphirecity_baseboard(sch_1):\3H_SL_9H_MS_VIA_3H+A\" )
				( netClassRef "@sapphirecity_baseboard_lib.sapphirecity_baseboard(sch_1):\P3E_CPU1_PE3D_RISER2_TX\" )
				( netClassRef "@sapphirecity_baseboard_lib.sapphirecity_baseboard(sch_1):\P3E_CPU1_PE3D_RISER2_TX\" )
			)
			( classClass "@crescent_city_bb_fab1_lib.crescent_city_bb_fab1(sch_1):\CC72\"
				( spacingCSetRef "@crescent_city_bb_fab1_lib.crescent_city_bb_fab1(sch_1):\DEFAULT\" )
				( netClassRef "@sapphirecity_baseboard_lib.sapphirecity_baseboard(sch_1):\POWER\" )
				( netClassRef "@sapphirecity_baseboard_lib.sapphirecity_baseboard(sch_1):\P3E_CPU1_PE3D_RISER2_RX\" )
			)
			( classClass "@sapphirecity_baseboard_lib.sapphirecity_baseboard(sch_1):\CC268\"
				( spacingCSetRef "@crescent_city_bb_fab1_lib.crescent_city_bb_fab1(sch_1):\DEFAULT\" )
				( netClassRef "@sapphirecity_baseboard_lib.sapphirecity_baseboard(sch_1):\GND\" )
				( netClassRef "@sapphirecity_baseboard_lib.sapphirecity_baseboard(sch_1):\P3E_CPU1_PE3D_RISER2_RX\" )
			)
			( classClass "@sapphirecity_baseboard_lib.sapphirecity_baseboard(sch_1):\CC576\"
				( spacingCSetRef "@sapphirecity_baseboard_lib.sapphirecity_baseboard(sch_1):\3H_SL_9H_MS_VIA_3H+A\" )
				( netClassRef "@sapphirecity_baseboard_lib.sapphirecity_baseboard(sch_1):\P3E_CPU1_PE3D_RISER2_RX\" )
				( netClassRef "@sapphirecity_baseboard_lib.sapphirecity_baseboard(sch_1):\P3E_CPU1_PE3D_RISER2_RX\" )
			)
			( classClass "@crescent_city_bb_fab1_lib.crescent_city_bb_fab1(sch_1):\CC293\"
				( spacingCSetRef "@crescent_city_bb_fab1_lib.crescent_city_bb_fab1(sch_1):\DEFAULT\" )
				( netClassRef "@sapphirecity_baseboard_lib.sapphirecity_baseboard(sch_1):\POWER\" )
				( netClassRef "@sapphirecity_baseboard_lib.sapphirecity_baseboard(sch_1):\P3E_CPU1_PE3C_RISER2_TX\" )
			)
			( classClass "@sapphirecity_baseboard_lib.sapphirecity_baseboard(sch_1):\CC267\"
				( spacingCSetRef "@crescent_city_bb_fab1_lib.crescent_city_bb_fab1(sch_1):\DEFAULT\" )
				( netClassRef "@sapphirecity_baseboard_lib.sapphirecity_baseboard(sch_1):\GND\" )
				( netClassRef "@sapphirecity_baseboard_lib.sapphirecity_baseboard(sch_1):\P3E_CPU1_PE3C_RISER2_TX\" )
			)
			( classClass "@sapphirecity_baseboard_lib.sapphirecity_baseboard(sch_1):\CC575\"
				( spacingCSetRef "@sapphirecity_baseboard_lib.sapphirecity_baseboard(sch_1):\3H_SL_9H_MS_VIA_3H+A\" )
				( netClassRef "@sapphirecity_baseboard_lib.sapphirecity_baseboard(sch_1):\P3E_CPU1_PE3C_RISER2_TX\" )
				( netClassRef "@sapphirecity_baseboard_lib.sapphirecity_baseboard(sch_1):\P3E_CPU1_PE3C_RISER2_TX\" )
			)
			( classClass "@crescent_city_bb_fab1_lib.crescent_city_bb_fab1(sch_1):\CC74\"
				( spacingCSetRef "@crescent_city_bb_fab1_lib.crescent_city_bb_fab1(sch_1):\DEFAULT\" )
				( netClassRef "@sapphirecity_baseboard_lib.sapphirecity_baseboard(sch_1):\POWER\" )
				( netClassRef "@sapphirecity_baseboard_lib.sapphirecity_baseboard(sch_1):\P3E_CPU1_PE3C_RISER_RX\" )
			)
			( classClass "@sapphirecity_baseboard_lib.sapphirecity_baseboard(sch_1):\CC266\"
				( spacingCSetRef "@crescent_city_bb_fab1_lib.crescent_city_bb_fab1(sch_1):\DEFAULT\" )
				( netClassRef "@sapphirecity_baseboard_lib.sapphirecity_baseboard(sch_1):\GND\" )
				( netClassRef "@sapphirecity_baseboard_lib.sapphirecity_baseboard(sch_1):\P3E_CPU1_PE3C_RISER_RX\" )
			)
			( classClass "@sapphirecity_baseboard_lib.sapphirecity_baseboard(sch_1):\CC574\"
				( spacingCSetRef "@sapphirecity_baseboard_lib.sapphirecity_baseboard(sch_1):\3H_SL_9H_MS_VIA_3H+A\" )
				( netClassRef "@sapphirecity_baseboard_lib.sapphirecity_baseboard(sch_1):\P3E_CPU1_PE3C_RISER_RX\" )
				( netClassRef "@sapphirecity_baseboard_lib.sapphirecity_baseboard(sch_1):\P3E_CPU1_PE3C_RISER_RX\" )
			)
			( classClass "@crescent_city_bb_fab1_lib.crescent_city_bb_fab1(sch_1):\CC923\"
				( spacingCSetRef "@crescent_city_bb_fab1_lib.crescent_city_bb_fab1(sch_1):\DEFAULT\" )
				( netClassRef "@sapphirecity_baseboard_lib.sapphirecity_baseboard(sch_1):\POWER\" )
				( netClassRef "@sapphirecity_baseboard_lib.sapphirecity_baseboard(sch_1):\P3E_CPU1_PE3AB_SLOTE_TX\" )
			)
			( classClass "@sapphirecity_baseboard_lib.sapphirecity_baseboard(sch_1):\CC265\"
				( spacingCSetRef "@crescent_city_bb_fab1_lib.crescent_city_bb_fab1(sch_1):\DEFAULT\" )
				( netClassRef "@sapphirecity_baseboard_lib.sapphirecity_baseboard(sch_1):\GND\" )
				( netClassRef "@sapphirecity_baseboard_lib.sapphirecity_baseboard(sch_1):\P3E_CPU1_PE3AB_SLOTE_TX\" )
			)
			( classClass "@sapphirecity_baseboard_lib.sapphirecity_baseboard(sch_1):\CC573\"
				( spacingCSetRef "@sapphirecity_baseboard_lib.sapphirecity_baseboard(sch_1):\3H_SL_9H_MS_VIA_3H+A\" )
				( netClassRef "@sapphirecity_baseboard_lib.sapphirecity_baseboard(sch_1):\P3E_CPU1_PE3AB_SLOTE_TX\" )
				( netClassRef "@sapphirecity_baseboard_lib.sapphirecity_baseboard(sch_1):\P3E_CPU1_PE3AB_SLOTE_TX\" )
			)
			( classClass "@crescent_city_bb_fab1_lib.crescent_city_bb_fab1(sch_1):\CC922\"
				( spacingCSetRef "@crescent_city_bb_fab1_lib.crescent_city_bb_fab1(sch_1):\DEFAULT\" )
				( netClassRef "@sapphirecity_baseboard_lib.sapphirecity_baseboard(sch_1):\POWER\" )
				( netClassRef "@sapphirecity_baseboard_lib.sapphirecity_baseboard(sch_1):\P3E_CPU1_PE3AB_SLOTE_RX\" )
			)
			( classClass "@sapphirecity_baseboard_lib.sapphirecity_baseboard(sch_1):\CC264\"
				( spacingCSetRef "@crescent_city_bb_fab1_lib.crescent_city_bb_fab1(sch_1):\DEFAULT\" )
				( netClassRef "@sapphirecity_baseboard_lib.sapphirecity_baseboard(sch_1):\GND\" )
				( netClassRef "@sapphirecity_baseboard_lib.sapphirecity_baseboard(sch_1):\P3E_CPU1_PE3AB_SLOTE_RX\" )
			)
			( classClass "@sapphirecity_baseboard_lib.sapphirecity_baseboard(sch_1):\CC572\"
				( spacingCSetRef "@sapphirecity_baseboard_lib.sapphirecity_baseboard(sch_1):\3H_SL_9H_MS_VIA_3H+A\" )
				( netClassRef "@sapphirecity_baseboard_lib.sapphirecity_baseboard(sch_1):\P3E_CPU1_PE3AB_SLOTE_RX\" )
				( netClassRef "@sapphirecity_baseboard_lib.sapphirecity_baseboard(sch_1):\P3E_CPU1_PE3AB_SLOTE_RX\" )
			)
			( classClass "@crescent_city_bb_fab1_lib.crescent_city_bb_fab1(sch_1):\CC295\"
				( spacingCSetRef "@crescent_city_bb_fab1_lib.crescent_city_bb_fab1(sch_1):\DEFAULT\" )
				( netClassRef "@sapphirecity_baseboard_lib.sapphirecity_baseboard(sch_1):\POWER\" )
				( netClassRef "@sapphirecity_baseboard_lib.sapphirecity_baseboard(sch_1):\P3E_CPU1_PE2_RISER2_TX\" )
			)
			( classClass "@sapphirecity_baseboard_lib.sapphirecity_baseboard(sch_1):\CC263\"
				( spacingCSetRef "@crescent_city_bb_fab1_lib.crescent_city_bb_fab1(sch_1):\DEFAULT\" )
				( netClassRef "@sapphirecity_baseboard_lib.sapphirecity_baseboard(sch_1):\GND\" )
				( netClassRef "@sapphirecity_baseboard_lib.sapphirecity_baseboard(sch_1):\P3E_CPU1_PE2_RISER2_TX\" )
			)
			( classClass "@sapphirecity_baseboard_lib.sapphirecity_baseboard(sch_1):\CC571\"
				( spacingCSetRef "@sapphirecity_baseboard_lib.sapphirecity_baseboard(sch_1):\3H_SL_9H_MS_VIA_3H+A\" )
				( netClassRef "@sapphirecity_baseboard_lib.sapphirecity_baseboard(sch_1):\P3E_CPU1_PE2_RISER2_TX\" )
				( netClassRef "@sapphirecity_baseboard_lib.sapphirecity_baseboard(sch_1):\P3E_CPU1_PE2_RISER2_TX\" )
			)
			( classClass "@crescent_city_bb_fab1_lib.crescent_city_bb_fab1(sch_1):\CC294\"
				( spacingCSetRef "@crescent_city_bb_fab1_lib.crescent_city_bb_fab1(sch_1):\DEFAULT\" )
				( netClassRef "@sapphirecity_baseboard_lib.sapphirecity_baseboard(sch_1):\POWER\" )
				( netClassRef "@sapphirecity_baseboard_lib.sapphirecity_baseboard(sch_1):\P3E_CPU1_PE2_RISER2_RX\" )
			)
			( classClass "@sapphirecity_baseboard_lib.sapphirecity_baseboard(sch_1):\CC262\"
				( spacingCSetRef "@crescent_city_bb_fab1_lib.crescent_city_bb_fab1(sch_1):\DEFAULT\" )
				( netClassRef "@sapphirecity_baseboard_lib.sapphirecity_baseboard(sch_1):\GND\" )
				( netClassRef "@sapphirecity_baseboard_lib.sapphirecity_baseboard(sch_1):\P3E_CPU1_PE2_RISER2_RX\" )
			)
			( classClass "@sapphirecity_baseboard_lib.sapphirecity_baseboard(sch_1):\CC570\"
				( spacingCSetRef "@sapphirecity_baseboard_lib.sapphirecity_baseboard(sch_1):\3H_SL_9H_MS_VIA_3H+A\" )
				( netClassRef "@sapphirecity_baseboard_lib.sapphirecity_baseboard(sch_1):\P3E_CPU1_PE2_RISER2_RX\" )
				( netClassRef "@sapphirecity_baseboard_lib.sapphirecity_baseboard(sch_1):\P3E_CPU1_PE2_RISER2_RX\" )
			)
			( classClass "@crescent_city_bb_fab1_lib.crescent_city_bb_fab1(sch_1):\CC927\"
				( spacingCSetRef "@crescent_city_bb_fab1_lib.crescent_city_bb_fab1(sch_1):\DEFAULT\" )
				( netClassRef "@sapphirecity_baseboard_lib.sapphirecity_baseboard(sch_1):\POWER\" )
				( netClassRef "@sapphirecity_baseboard_lib.sapphirecity_baseboard(sch_1):\P3E_CPU1_PE1B_RISER1_TX\" )
			)
			( classClass "@sapphirecity_baseboard_lib.sapphirecity_baseboard(sch_1):\CC261\"
				( spacingCSetRef "@crescent_city_bb_fab1_lib.crescent_city_bb_fab1(sch_1):\DEFAULT\" )
				( netClassRef "@sapphirecity_baseboard_lib.sapphirecity_baseboard(sch_1):\GND\" )
				( netClassRef "@sapphirecity_baseboard_lib.sapphirecity_baseboard(sch_1):\P3E_CPU1_PE1B_RISER1_TX\" )
			)
			( classClass "@sapphirecity_baseboard_lib.sapphirecity_baseboard(sch_1):\CC569\"
				( spacingCSetRef "@sapphirecity_baseboard_lib.sapphirecity_baseboard(sch_1):\3H_SL_9H_MS_VIA_3H+A\" )
				( netClassRef "@sapphirecity_baseboard_lib.sapphirecity_baseboard(sch_1):\P3E_CPU1_PE1B_RISER1_TX\" )
				( netClassRef "@sapphirecity_baseboard_lib.sapphirecity_baseboard(sch_1):\P3E_CPU1_PE1B_RISER1_TX\" )
			)
			( classClass "@crescent_city_bb_fab1_lib.crescent_city_bb_fab1(sch_1):\CC926\"
				( spacingCSetRef "@crescent_city_bb_fab1_lib.crescent_city_bb_fab1(sch_1):\DEFAULT\" )
				( netClassRef "@sapphirecity_baseboard_lib.sapphirecity_baseboard(sch_1):\POWER\" )
				( netClassRef "@sapphirecity_baseboard_lib.sapphirecity_baseboard(sch_1):\P3E_CPU1_PE1B_RISER1_RX\" )
			)
			( classClass "@sapphirecity_baseboard_lib.sapphirecity_baseboard(sch_1):\CC260\"
				( spacingCSetRef "@crescent_city_bb_fab1_lib.crescent_city_bb_fab1(sch_1):\DEFAULT\" )
				( netClassRef "@sapphirecity_baseboard_lib.sapphirecity_baseboard(sch_1):\GND\" )
				( netClassRef "@sapphirecity_baseboard_lib.sapphirecity_baseboard(sch_1):\P3E_CPU1_PE1B_RISER1_RX\" )
			)
			( classClass "@sapphirecity_baseboard_lib.sapphirecity_baseboard(sch_1):\CC568\"
				( spacingCSetRef "@sapphirecity_baseboard_lib.sapphirecity_baseboard(sch_1):\3H_SL_9H_MS_VIA_3H+A\" )
				( netClassRef "@sapphirecity_baseboard_lib.sapphirecity_baseboard(sch_1):\P3E_CPU1_PE1B_RISER1_RX\" )
				( netClassRef "@sapphirecity_baseboard_lib.sapphirecity_baseboard(sch_1):\P3E_CPU1_PE1B_RISER1_RX\" )
			)
			( classClass "@crescent_city_bb_fab1_lib.crescent_city_bb_fab1(sch_1):\CC925\"
				( spacingCSetRef "@crescent_city_bb_fab1_lib.crescent_city_bb_fab1(sch_1):\DEFAULT\" )
				( netClassRef "@sapphirecity_baseboard_lib.sapphirecity_baseboard(sch_1):\POWER\" )
				( netClassRef "@sapphirecity_baseboard_lib.sapphirecity_baseboard(sch_1):\P3E_CPU1_PE1A_RISER1_TX\" )
			)
			( classClass "@sapphirecity_baseboard_lib.sapphirecity_baseboard(sch_1):\CC259\"
				( spacingCSetRef "@crescent_city_bb_fab1_lib.crescent_city_bb_fab1(sch_1):\DEFAULT\" )
				( netClassRef "@sapphirecity_baseboard_lib.sapphirecity_baseboard(sch_1):\GND\" )
				( netClassRef "@sapphirecity_baseboard_lib.sapphirecity_baseboard(sch_1):\P3E_CPU1_PE1A_RISER1_TX\" )
			)
			( classClass "@sapphirecity_baseboard_lib.sapphirecity_baseboard(sch_1):\CC567\"
				( spacingCSetRef "@sapphirecity_baseboard_lib.sapphirecity_baseboard(sch_1):\3H_SL_9H_MS_VIA_3H+A\" )
				( netClassRef "@sapphirecity_baseboard_lib.sapphirecity_baseboard(sch_1):\P3E_CPU1_PE1A_RISER1_TX\" )
				( netClassRef "@sapphirecity_baseboard_lib.sapphirecity_baseboard(sch_1):\P3E_CPU1_PE1A_RISER1_TX\" )
			)
			( classClass "@crescent_city_bb_fab1_lib.crescent_city_bb_fab1(sch_1):\CC924\"
				( spacingCSetRef "@crescent_city_bb_fab1_lib.crescent_city_bb_fab1(sch_1):\DEFAULT\" )
				( netClassRef "@sapphirecity_baseboard_lib.sapphirecity_baseboard(sch_1):\POWER\" )
				( netClassRef "@sapphirecity_baseboard_lib.sapphirecity_baseboard(sch_1):\P3E_CPU1_PE1A_RISER1_RX\" )
			)
			( classClass "@sapphirecity_baseboard_lib.sapphirecity_baseboard(sch_1):\CC258\"
				( spacingCSetRef "@crescent_city_bb_fab1_lib.crescent_city_bb_fab1(sch_1):\DEFAULT\" )
				( netClassRef "@sapphirecity_baseboard_lib.sapphirecity_baseboard(sch_1):\GND\" )
				( netClassRef "@sapphirecity_baseboard_lib.sapphirecity_baseboard(sch_1):\P3E_CPU1_PE1A_RISER1_RX\" )
			)
			( classClass "@sapphirecity_baseboard_lib.sapphirecity_baseboard(sch_1):\CC566\"
				( spacingCSetRef "@sapphirecity_baseboard_lib.sapphirecity_baseboard(sch_1):\3H_SL_9H_MS_VIA_3H+A\" )
				( netClassRef "@sapphirecity_baseboard_lib.sapphirecity_baseboard(sch_1):\P3E_CPU1_PE1A_RISER1_RX\" )
				( netClassRef "@sapphirecity_baseboard_lib.sapphirecity_baseboard(sch_1):\P3E_CPU1_PE1A_RISER1_RX\" )
			)
			( classClass "@crescent_city_bb_fab1_lib.crescent_city_bb_fab1(sch_1):\CC921\"
				( spacingCSetRef "@crescent_city_bb_fab1_lib.crescent_city_bb_fab1(sch_1):\DEFAULT\" )
				( netClassRef "@sapphirecity_baseboard_lib.sapphirecity_baseboard(sch_1):\POWER\" )
				( netClassRef "@sapphirecity_baseboard_lib.sapphirecity_baseboard(sch_1):\P3E_CPU0_PE1AB_SLOTB_TX\" )
			)
			( classClass "@sapphirecity_baseboard_lib.sapphirecity_baseboard(sch_1):\CC255\"
				( spacingCSetRef "@crescent_city_bb_fab1_lib.crescent_city_bb_fab1(sch_1):\DEFAULT\" )
				( netClassRef "@sapphirecity_baseboard_lib.sapphirecity_baseboard(sch_1):\GND\" )
				( netClassRef "@sapphirecity_baseboard_lib.sapphirecity_baseboard(sch_1):\P3E_CPU0_PE1AB_SLOTB_TX\" )
			)
			( classClass "@sapphirecity_baseboard_lib.sapphirecity_baseboard(sch_1):\CC563\"
				( spacingCSetRef "@sapphirecity_baseboard_lib.sapphirecity_baseboard(sch_1):\3H_SL_9H_MS_VIA_3H+A\" )
				( netClassRef "@sapphirecity_baseboard_lib.sapphirecity_baseboard(sch_1):\P3E_CPU0_PE1AB_SLOTB_TX\" )
				( netClassRef "@sapphirecity_baseboard_lib.sapphirecity_baseboard(sch_1):\P3E_CPU0_PE1AB_SLOTB_TX\" )
			)
			( classClass "@crescent_city_bb_fab1_lib.crescent_city_bb_fab1(sch_1):\CC920\"
				( spacingCSetRef "@crescent_city_bb_fab1_lib.crescent_city_bb_fab1(sch_1):\DEFAULT\" )
				( netClassRef "@sapphirecity_baseboard_lib.sapphirecity_baseboard(sch_1):\POWER\" )
				( netClassRef "@sapphirecity_baseboard_lib.sapphirecity_baseboard(sch_1):\P3E_CPU0_PE1AB_SLOTB_RX\" )
			)
			( classClass "@sapphirecity_baseboard_lib.sapphirecity_baseboard(sch_1):\CC254\"
				( spacingCSetRef "@crescent_city_bb_fab1_lib.crescent_city_bb_fab1(sch_1):\DEFAULT\" )
				( netClassRef "@sapphirecity_baseboard_lib.sapphirecity_baseboard(sch_1):\GND\" )
				( netClassRef "@sapphirecity_baseboard_lib.sapphirecity_baseboard(sch_1):\P3E_CPU0_PE1AB_SLOTB_RX\" )
			)
			( classClass "@sapphirecity_baseboard_lib.sapphirecity_baseboard(sch_1):\CC562\"
				( spacingCSetRef "@sapphirecity_baseboard_lib.sapphirecity_baseboard(sch_1):\3H_SL_9H_MS_VIA_3H+A\" )
				( netClassRef "@sapphirecity_baseboard_lib.sapphirecity_baseboard(sch_1):\P3E_CPU0_PE1AB_SLOTB_RX\" )
				( netClassRef "@sapphirecity_baseboard_lib.sapphirecity_baseboard(sch_1):\P3E_CPU0_PE1AB_SLOTB_RX\" )
			)
			( classClass "@sapphirecity_baseboard_lib.sapphirecity_baseboard(sch_1):\CC553\"
				( spacingCSetRef "@sapphirecity_baseboard_lib.sapphirecity_baseboard(sch_1):\DDR4_2SPC_DQ/DQS\" )
				( netClassRef "@sapphirecity_baseboard_lib.sapphirecity_baseboard(sch_1):\DDR4_CHN_H_ECC\" )
				( netClassRef "@sapphirecity_baseboard_lib.sapphirecity_baseboard(sch_1):\DDR4_CHN_H_ECC\" )
			)
			( classClass "@crescent_city_bb_fab1_lib.crescent_city_bb_fab1(sch_1):\CC345\"
				( spacingCSetRef "@sapphirecity_baseboard_lib.sapphirecity_baseboard(sch_1):\DQ_TO_DQ\" )
				( netClassRef "@sapphirecity_baseboard_lib.sapphirecity_baseboard(sch_1):\DDR4_CHN_H_CLK\" )
				( netClassRef "@sapphirecity_baseboard_lib.sapphirecity_baseboard(sch_1):\DDR4_CHN_H_ECC\" )
			)
			( classClass "@crescent_city_bb_fab1_lib.crescent_city_bb_fab1(sch_1):\CC355\"
				( spacingCSetRef "@sapphirecity_baseboard_lib.sapphirecity_baseboard(sch_1):\DQ_TO_DQ\" )
				( netClassRef "@sapphirecity_baseboard_lib.sapphirecity_baseboard(sch_1):\DDR4_CHN_H_CMD_ADD\" )
				( netClassRef "@sapphirecity_baseboard_lib.sapphirecity_baseboard(sch_1):\DDR4_CHN_H_ECC\" )
			)
			( classClass "@crescent_city_bb_fab1_lib.crescent_city_bb_fab1(sch_1):\CC305\"
				( spacingCSetRef "@sapphirecity_baseboard_lib.sapphirecity_baseboard(sch_1):\DQ_TO_DQ\" )
				( netClassRef "@sapphirecity_baseboard_lib.sapphirecity_baseboard(sch_1):\DDR4_CHN_H_CTRL\" )
				( netClassRef "@sapphirecity_baseboard_lib.sapphirecity_baseboard(sch_1):\DDR4_CHN_H_ECC\" )
			)
			( classClass "@crescent_city_bb_fab1_lib.crescent_city_bb_fab1(sch_1):\CC613\"
				( spacingCSetRef "@crescent_city_bb_fab1_lib.crescent_city_bb_fab1(sch_1):\DEFAULT\" )
				( netClassRef "@sapphirecity_baseboard_lib.sapphirecity_baseboard(sch_1):\GND\" )
				( netClassRef "@sapphirecity_baseboard_lib.sapphirecity_baseboard(sch_1):\DDR4_CHN_H_ECC\" )
			)
			( classClass "@crescent_city_bb_fab1_lib.crescent_city_bb_fab1(sch_1):\CC667\"
				( spacingCSetRef "@crescent_city_bb_fab1_lib.crescent_city_bb_fab1(sch_1):\DEFAULT\" )
				( netClassRef "@sapphirecity_baseboard_lib.sapphirecity_baseboard(sch_1):\POWER\" )
				( netClassRef "@sapphirecity_baseboard_lib.sapphirecity_baseboard(sch_1):\DDR4_CHN_H_ECC\" )
			)
			( classClass "@crescent_city_bb_fab1_lib.crescent_city_bb_fab1(sch_1):\CC747\"
				( spacingCSetRef "@sapphirecity_baseboard_lib.sapphirecity_baseboard(sch_1):\DQ_TO_DQ\" )
				( netClassRef "@sapphirecity_baseboard_lib.sapphirecity_baseboard(sch_1):\DDR4_CHN_H_DQ_DQS_BYTE0\" )
				( netClassRef "@sapphirecity_baseboard_lib.sapphirecity_baseboard(sch_1):\DDR4_CHN_H_ECC\" )
			)
			( classClass "@crescent_city_bb_fab1_lib.crescent_city_bb_fab1(sch_1):\CC754\"
				( spacingCSetRef "@sapphirecity_baseboard_lib.sapphirecity_baseboard(sch_1):\DQ_TO_DQ\" )
				( netClassRef "@sapphirecity_baseboard_lib.sapphirecity_baseboard(sch_1):\DDR4_CHN_H_DQ_DQS_BYTE1\" )
				( netClassRef "@sapphirecity_baseboard_lib.sapphirecity_baseboard(sch_1):\DDR4_CHN_H_ECC\" )
			)
			( classClass "@crescent_city_bb_fab1_lib.crescent_city_bb_fab1(sch_1):\CC760\"
				( spacingCSetRef "@sapphirecity_baseboard_lib.sapphirecity_baseboard(sch_1):\DQ_TO_DQ\" )
				( netClassRef "@sapphirecity_baseboard_lib.sapphirecity_baseboard(sch_1):\DDR4_CHN_H_DQ_DQS_BYTE2\" )
				( netClassRef "@sapphirecity_baseboard_lib.sapphirecity_baseboard(sch_1):\DDR4_CHN_H_ECC\" )
			)
			( classClass "@crescent_city_bb_fab1_lib.crescent_city_bb_fab1(sch_1):\CC765\"
				( spacingCSetRef "@sapphirecity_baseboard_lib.sapphirecity_baseboard(sch_1):\DQ_TO_DQ\" )
				( netClassRef "@sapphirecity_baseboard_lib.sapphirecity_baseboard(sch_1):\DDR4_CHN_H_DQ_DQS_BYTE3\" )
				( netClassRef "@sapphirecity_baseboard_lib.sapphirecity_baseboard(sch_1):\DDR4_CHN_H_ECC\" )
			)
			( classClass "@crescent_city_bb_fab1_lib.crescent_city_bb_fab1(sch_1):\CC769\"
				( spacingCSetRef "@sapphirecity_baseboard_lib.sapphirecity_baseboard(sch_1):\DQ_TO_DQ\" )
				( netClassRef "@sapphirecity_baseboard_lib.sapphirecity_baseboard(sch_1):\DDR4_CHN_H_DQ_DQS_BYTE4\" )
				( netClassRef "@sapphirecity_baseboard_lib.sapphirecity_baseboard(sch_1):\DDR4_CHN_H_ECC\" )
			)
			( classClass "@crescent_city_bb_fab1_lib.crescent_city_bb_fab1(sch_1):\CC772\"
				( spacingCSetRef "@sapphirecity_baseboard_lib.sapphirecity_baseboard(sch_1):\DQ_TO_DQ\" )
				( netClassRef "@sapphirecity_baseboard_lib.sapphirecity_baseboard(sch_1):\DDR4_CHN_H_DQ_DQS_BYTE5\" )
				( netClassRef "@sapphirecity_baseboard_lib.sapphirecity_baseboard(sch_1):\DDR4_CHN_H_ECC\" )
			)
			( classClass "@crescent_city_bb_fab1_lib.crescent_city_bb_fab1(sch_1):\CC774\"
				( spacingCSetRef "@sapphirecity_baseboard_lib.sapphirecity_baseboard(sch_1):\DQ_TO_DQ\" )
				( netClassRef "@sapphirecity_baseboard_lib.sapphirecity_baseboard(sch_1):\DDR4_CHN_H_DQ_DQS_BYTE6\" )
				( netClassRef "@sapphirecity_baseboard_lib.sapphirecity_baseboard(sch_1):\DDR4_CHN_H_ECC\" )
			)
			( classClass "@crescent_city_bb_fab1_lib.crescent_city_bb_fab1(sch_1):\CC775\"
				( spacingCSetRef "@sapphirecity_baseboard_lib.sapphirecity_baseboard(sch_1):\DQ_TO_DQ\" )
				( netClassRef "@sapphirecity_baseboard_lib.sapphirecity_baseboard(sch_1):\DDR4_CHN_H_DQ_DQS_BYTE7\" )
				( netClassRef "@sapphirecity_baseboard_lib.sapphirecity_baseboard(sch_1):\DDR4_CHN_H_ECC\" )
			)
			( classClass "@sapphirecity_baseboard_lib.sapphirecity_baseboard(sch_1):\CC552\"
				( spacingCSetRef "@sapphirecity_baseboard_lib.sapphirecity_baseboard(sch_1):\DDR4_2SPC_DQ/DQS\" )
				( netClassRef "@sapphirecity_baseboard_lib.sapphirecity_baseboard(sch_1):\DDR4_CHN_H_DQ_DQS_BYTE7\" )
				( netClassRef "@sapphirecity_baseboard_lib.sapphirecity_baseboard(sch_1):\DDR4_CHN_H_DQ_DQS_BYTE7\" )
			)
			( classClass "@crescent_city_bb_fab1_lib.crescent_city_bb_fab1(sch_1):\CC344\"
				( spacingCSetRef "@sapphirecity_baseboard_lib.sapphirecity_baseboard(sch_1):\DQ_TO_DQ\" )
				( netClassRef "@sapphirecity_baseboard_lib.sapphirecity_baseboard(sch_1):\DDR4_CHN_H_CLK\" )
				( netClassRef "@sapphirecity_baseboard_lib.sapphirecity_baseboard(sch_1):\DDR4_CHN_H_DQ_DQS_BYTE7\" )
			)
			( classClass "@crescent_city_bb_fab1_lib.crescent_city_bb_fab1(sch_1):\CC354\"
				( spacingCSetRef "@sapphirecity_baseboard_lib.sapphirecity_baseboard(sch_1):\DQ_TO_DQ\" )
				( netClassRef "@sapphirecity_baseboard_lib.sapphirecity_baseboard(sch_1):\DDR4_CHN_H_CMD_ADD\" )
				( netClassRef "@sapphirecity_baseboard_lib.sapphirecity_baseboard(sch_1):\DDR4_CHN_H_DQ_DQS_BYTE7\" )
			)
			( classClass "@crescent_city_bb_fab1_lib.crescent_city_bb_fab1(sch_1):\CC304\"
				( spacingCSetRef "@sapphirecity_baseboard_lib.sapphirecity_baseboard(sch_1):\DQ_TO_DQ\" )
				( netClassRef "@sapphirecity_baseboard_lib.sapphirecity_baseboard(sch_1):\DDR4_CHN_H_CTRL\" )
				( netClassRef "@sapphirecity_baseboard_lib.sapphirecity_baseboard(sch_1):\DDR4_CHN_H_DQ_DQS_BYTE7\" )
			)
			( classClass "@crescent_city_bb_fab1_lib.crescent_city_bb_fab1(sch_1):\CC612\"
				( spacingCSetRef "@crescent_city_bb_fab1_lib.crescent_city_bb_fab1(sch_1):\DEFAULT\" )
				( netClassRef "@sapphirecity_baseboard_lib.sapphirecity_baseboard(sch_1):\GND\" )
				( netClassRef "@sapphirecity_baseboard_lib.sapphirecity_baseboard(sch_1):\DDR4_CHN_H_DQ_DQS_BYTE7\" )
			)
			( classClass "@crescent_city_bb_fab1_lib.crescent_city_bb_fab1(sch_1):\CC666\"
				( spacingCSetRef "@crescent_city_bb_fab1_lib.crescent_city_bb_fab1(sch_1):\DEFAULT\" )
				( netClassRef "@sapphirecity_baseboard_lib.sapphirecity_baseboard(sch_1):\POWER\" )
				( netClassRef "@sapphirecity_baseboard_lib.sapphirecity_baseboard(sch_1):\DDR4_CHN_H_DQ_DQS_BYTE7\" )
			)
			( classClass "@crescent_city_bb_fab1_lib.crescent_city_bb_fab1(sch_1):\CC746\"
				( spacingCSetRef "@sapphirecity_baseboard_lib.sapphirecity_baseboard(sch_1):\DQ_TO_DQ\" )
				( netClassRef "@sapphirecity_baseboard_lib.sapphirecity_baseboard(sch_1):\DDR4_CHN_H_DQ_DQS_BYTE0\" )
				( netClassRef "@sapphirecity_baseboard_lib.sapphirecity_baseboard(sch_1):\DDR4_CHN_H_DQ_DQS_BYTE7\" )
			)
			( classClass "@crescent_city_bb_fab1_lib.crescent_city_bb_fab1(sch_1):\CC753\"
				( spacingCSetRef "@sapphirecity_baseboard_lib.sapphirecity_baseboard(sch_1):\DQ_TO_DQ\" )
				( netClassRef "@sapphirecity_baseboard_lib.sapphirecity_baseboard(sch_1):\DDR4_CHN_H_DQ_DQS_BYTE1\" )
				( netClassRef "@sapphirecity_baseboard_lib.sapphirecity_baseboard(sch_1):\DDR4_CHN_H_DQ_DQS_BYTE7\" )
			)
			( classClass "@crescent_city_bb_fab1_lib.crescent_city_bb_fab1(sch_1):\CC759\"
				( spacingCSetRef "@sapphirecity_baseboard_lib.sapphirecity_baseboard(sch_1):\DQ_TO_DQ\" )
				( netClassRef "@sapphirecity_baseboard_lib.sapphirecity_baseboard(sch_1):\DDR4_CHN_H_DQ_DQS_BYTE2\" )
				( netClassRef "@sapphirecity_baseboard_lib.sapphirecity_baseboard(sch_1):\DDR4_CHN_H_DQ_DQS_BYTE7\" )
			)
			( classClass "@crescent_city_bb_fab1_lib.crescent_city_bb_fab1(sch_1):\CC764\"
				( spacingCSetRef "@sapphirecity_baseboard_lib.sapphirecity_baseboard(sch_1):\DQ_TO_DQ\" )
				( netClassRef "@sapphirecity_baseboard_lib.sapphirecity_baseboard(sch_1):\DDR4_CHN_H_DQ_DQS_BYTE3\" )
				( netClassRef "@sapphirecity_baseboard_lib.sapphirecity_baseboard(sch_1):\DDR4_CHN_H_DQ_DQS_BYTE7\" )
			)
			( classClass "@crescent_city_bb_fab1_lib.crescent_city_bb_fab1(sch_1):\CC768\"
				( spacingCSetRef "@sapphirecity_baseboard_lib.sapphirecity_baseboard(sch_1):\DQ_TO_DQ\" )
				( netClassRef "@sapphirecity_baseboard_lib.sapphirecity_baseboard(sch_1):\DDR4_CHN_H_DQ_DQS_BYTE4\" )
				( netClassRef "@sapphirecity_baseboard_lib.sapphirecity_baseboard(sch_1):\DDR4_CHN_H_DQ_DQS_BYTE7\" )
			)
			( classClass "@crescent_city_bb_fab1_lib.crescent_city_bb_fab1(sch_1):\CC771\"
				( spacingCSetRef "@sapphirecity_baseboard_lib.sapphirecity_baseboard(sch_1):\DQ_TO_DQ\" )
				( netClassRef "@sapphirecity_baseboard_lib.sapphirecity_baseboard(sch_1):\DDR4_CHN_H_DQ_DQS_BYTE5\" )
				( netClassRef "@sapphirecity_baseboard_lib.sapphirecity_baseboard(sch_1):\DDR4_CHN_H_DQ_DQS_BYTE7\" )
			)
			( classClass "@crescent_city_bb_fab1_lib.crescent_city_bb_fab1(sch_1):\CC773\"
				( spacingCSetRef "@sapphirecity_baseboard_lib.sapphirecity_baseboard(sch_1):\DQ_TO_DQ\" )
				( netClassRef "@sapphirecity_baseboard_lib.sapphirecity_baseboard(sch_1):\DDR4_CHN_H_DQ_DQS_BYTE6\" )
				( netClassRef "@sapphirecity_baseboard_lib.sapphirecity_baseboard(sch_1):\DDR4_CHN_H_DQ_DQS_BYTE7\" )
			)
			( classClass "@sapphirecity_baseboard_lib.sapphirecity_baseboard(sch_1):\CC551\"
				( spacingCSetRef "@sapphirecity_baseboard_lib.sapphirecity_baseboard(sch_1):\DDR4_2SPC_DQ/DQS\" )
				( netClassRef "@sapphirecity_baseboard_lib.sapphirecity_baseboard(sch_1):\DDR4_CHN_H_DQ_DQS_BYTE6\" )
				( netClassRef "@sapphirecity_baseboard_lib.sapphirecity_baseboard(sch_1):\DDR4_CHN_H_DQ_DQS_BYTE6\" )
			)
			( classClass "@crescent_city_bb_fab1_lib.crescent_city_bb_fab1(sch_1):\CC343\"
				( spacingCSetRef "@sapphirecity_baseboard_lib.sapphirecity_baseboard(sch_1):\DQ_TO_DQ\" )
				( netClassRef "@sapphirecity_baseboard_lib.sapphirecity_baseboard(sch_1):\DDR4_CHN_H_CLK\" )
				( netClassRef "@sapphirecity_baseboard_lib.sapphirecity_baseboard(sch_1):\DDR4_CHN_H_DQ_DQS_BYTE6\" )
			)
			( classClass "@crescent_city_bb_fab1_lib.crescent_city_bb_fab1(sch_1):\CC353\"
				( spacingCSetRef "@sapphirecity_baseboard_lib.sapphirecity_baseboard(sch_1):\DQ_TO_DQ\" )
				( netClassRef "@sapphirecity_baseboard_lib.sapphirecity_baseboard(sch_1):\DDR4_CHN_H_CMD_ADD\" )
				( netClassRef "@sapphirecity_baseboard_lib.sapphirecity_baseboard(sch_1):\DDR4_CHN_H_DQ_DQS_BYTE6\" )
			)
			( classClass "@crescent_city_bb_fab1_lib.crescent_city_bb_fab1(sch_1):\CC303\"
				( spacingCSetRef "@sapphirecity_baseboard_lib.sapphirecity_baseboard(sch_1):\DQ_TO_DQ\" )
				( netClassRef "@sapphirecity_baseboard_lib.sapphirecity_baseboard(sch_1):\DDR4_CHN_H_CTRL\" )
				( netClassRef "@sapphirecity_baseboard_lib.sapphirecity_baseboard(sch_1):\DDR4_CHN_H_DQ_DQS_BYTE6\" )
			)
			( classClass "@crescent_city_bb_fab1_lib.crescent_city_bb_fab1(sch_1):\CC611\"
				( spacingCSetRef "@crescent_city_bb_fab1_lib.crescent_city_bb_fab1(sch_1):\DEFAULT\" )
				( netClassRef "@sapphirecity_baseboard_lib.sapphirecity_baseboard(sch_1):\GND\" )
				( netClassRef "@sapphirecity_baseboard_lib.sapphirecity_baseboard(sch_1):\DDR4_CHN_H_DQ_DQS_BYTE6\" )
			)
			( classClass "@crescent_city_bb_fab1_lib.crescent_city_bb_fab1(sch_1):\CC665\"
				( spacingCSetRef "@crescent_city_bb_fab1_lib.crescent_city_bb_fab1(sch_1):\DEFAULT\" )
				( netClassRef "@sapphirecity_baseboard_lib.sapphirecity_baseboard(sch_1):\POWER\" )
				( netClassRef "@sapphirecity_baseboard_lib.sapphirecity_baseboard(sch_1):\DDR4_CHN_H_DQ_DQS_BYTE6\" )
			)
			( classClass "@crescent_city_bb_fab1_lib.crescent_city_bb_fab1(sch_1):\CC745\"
				( spacingCSetRef "@sapphirecity_baseboard_lib.sapphirecity_baseboard(sch_1):\DQ_TO_DQ\" )
				( netClassRef "@sapphirecity_baseboard_lib.sapphirecity_baseboard(sch_1):\DDR4_CHN_H_DQ_DQS_BYTE0\" )
				( netClassRef "@sapphirecity_baseboard_lib.sapphirecity_baseboard(sch_1):\DDR4_CHN_H_DQ_DQS_BYTE6\" )
			)
			( classClass "@crescent_city_bb_fab1_lib.crescent_city_bb_fab1(sch_1):\CC752\"
				( spacingCSetRef "@sapphirecity_baseboard_lib.sapphirecity_baseboard(sch_1):\DQ_TO_DQ\" )
				( netClassRef "@sapphirecity_baseboard_lib.sapphirecity_baseboard(sch_1):\DDR4_CHN_H_DQ_DQS_BYTE1\" )
				( netClassRef "@sapphirecity_baseboard_lib.sapphirecity_baseboard(sch_1):\DDR4_CHN_H_DQ_DQS_BYTE6\" )
			)
			( classClass "@crescent_city_bb_fab1_lib.crescent_city_bb_fab1(sch_1):\CC758\"
				( spacingCSetRef "@sapphirecity_baseboard_lib.sapphirecity_baseboard(sch_1):\DQ_TO_DQ\" )
				( netClassRef "@sapphirecity_baseboard_lib.sapphirecity_baseboard(sch_1):\DDR4_CHN_H_DQ_DQS_BYTE2\" )
				( netClassRef "@sapphirecity_baseboard_lib.sapphirecity_baseboard(sch_1):\DDR4_CHN_H_DQ_DQS_BYTE6\" )
			)
			( classClass "@crescent_city_bb_fab1_lib.crescent_city_bb_fab1(sch_1):\CC763\"
				( spacingCSetRef "@sapphirecity_baseboard_lib.sapphirecity_baseboard(sch_1):\DQ_TO_DQ\" )
				( netClassRef "@sapphirecity_baseboard_lib.sapphirecity_baseboard(sch_1):\DDR4_CHN_H_DQ_DQS_BYTE3\" )
				( netClassRef "@sapphirecity_baseboard_lib.sapphirecity_baseboard(sch_1):\DDR4_CHN_H_DQ_DQS_BYTE6\" )
			)
			( classClass "@crescent_city_bb_fab1_lib.crescent_city_bb_fab1(sch_1):\CC767\"
				( spacingCSetRef "@sapphirecity_baseboard_lib.sapphirecity_baseboard(sch_1):\DQ_TO_DQ\" )
				( netClassRef "@sapphirecity_baseboard_lib.sapphirecity_baseboard(sch_1):\DDR4_CHN_H_DQ_DQS_BYTE4\" )
				( netClassRef "@sapphirecity_baseboard_lib.sapphirecity_baseboard(sch_1):\DDR4_CHN_H_DQ_DQS_BYTE6\" )
			)
			( classClass "@crescent_city_bb_fab1_lib.crescent_city_bb_fab1(sch_1):\CC770\"
				( spacingCSetRef "@sapphirecity_baseboard_lib.sapphirecity_baseboard(sch_1):\DQ_TO_DQ\" )
				( netClassRef "@sapphirecity_baseboard_lib.sapphirecity_baseboard(sch_1):\DDR4_CHN_H_DQ_DQS_BYTE5\" )
				( netClassRef "@sapphirecity_baseboard_lib.sapphirecity_baseboard(sch_1):\DDR4_CHN_H_DQ_DQS_BYTE6\" )
			)
			( classClass "@sapphirecity_baseboard_lib.sapphirecity_baseboard(sch_1):\CC550\"
				( spacingCSetRef "@sapphirecity_baseboard_lib.sapphirecity_baseboard(sch_1):\DDR4_2SPC_DQ/DQS\" )
				( netClassRef "@sapphirecity_baseboard_lib.sapphirecity_baseboard(sch_1):\DDR4_CHN_H_DQ_DQS_BYTE5\" )
				( netClassRef "@sapphirecity_baseboard_lib.sapphirecity_baseboard(sch_1):\DDR4_CHN_H_DQ_DQS_BYTE5\" )
			)
			( classClass "@crescent_city_bb_fab1_lib.crescent_city_bb_fab1(sch_1):\CC342\"
				( spacingCSetRef "@sapphirecity_baseboard_lib.sapphirecity_baseboard(sch_1):\DQ_TO_DQ\" )
				( netClassRef "@sapphirecity_baseboard_lib.sapphirecity_baseboard(sch_1):\DDR4_CHN_H_CLK\" )
				( netClassRef "@sapphirecity_baseboard_lib.sapphirecity_baseboard(sch_1):\DDR4_CHN_H_DQ_DQS_BYTE5\" )
			)
			( classClass "@crescent_city_bb_fab1_lib.crescent_city_bb_fab1(sch_1):\CC352\"
				( spacingCSetRef "@sapphirecity_baseboard_lib.sapphirecity_baseboard(sch_1):\DQ_TO_DQ\" )
				( netClassRef "@sapphirecity_baseboard_lib.sapphirecity_baseboard(sch_1):\DDR4_CHN_H_CMD_ADD\" )
				( netClassRef "@sapphirecity_baseboard_lib.sapphirecity_baseboard(sch_1):\DDR4_CHN_H_DQ_DQS_BYTE5\" )
			)
			( classClass "@crescent_city_bb_fab1_lib.crescent_city_bb_fab1(sch_1):\CC302\"
				( spacingCSetRef "@sapphirecity_baseboard_lib.sapphirecity_baseboard(sch_1):\DQ_TO_DQ\" )
				( netClassRef "@sapphirecity_baseboard_lib.sapphirecity_baseboard(sch_1):\DDR4_CHN_H_CTRL\" )
				( netClassRef "@sapphirecity_baseboard_lib.sapphirecity_baseboard(sch_1):\DDR4_CHN_H_DQ_DQS_BYTE5\" )
			)
			( classClass "@crescent_city_bb_fab1_lib.crescent_city_bb_fab1(sch_1):\CC610\"
				( spacingCSetRef "@crescent_city_bb_fab1_lib.crescent_city_bb_fab1(sch_1):\DEFAULT\" )
				( netClassRef "@sapphirecity_baseboard_lib.sapphirecity_baseboard(sch_1):\GND\" )
				( netClassRef "@sapphirecity_baseboard_lib.sapphirecity_baseboard(sch_1):\DDR4_CHN_H_DQ_DQS_BYTE5\" )
			)
			( classClass "@crescent_city_bb_fab1_lib.crescent_city_bb_fab1(sch_1):\CC664\"
				( spacingCSetRef "@crescent_city_bb_fab1_lib.crescent_city_bb_fab1(sch_1):\DEFAULT\" )
				( netClassRef "@sapphirecity_baseboard_lib.sapphirecity_baseboard(sch_1):\POWER\" )
				( netClassRef "@sapphirecity_baseboard_lib.sapphirecity_baseboard(sch_1):\DDR4_CHN_H_DQ_DQS_BYTE5\" )
			)
			( classClass "@crescent_city_bb_fab1_lib.crescent_city_bb_fab1(sch_1):\CC744\"
				( spacingCSetRef "@sapphirecity_baseboard_lib.sapphirecity_baseboard(sch_1):\DQ_TO_DQ\" )
				( netClassRef "@sapphirecity_baseboard_lib.sapphirecity_baseboard(sch_1):\DDR4_CHN_H_DQ_DQS_BYTE0\" )
				( netClassRef "@sapphirecity_baseboard_lib.sapphirecity_baseboard(sch_1):\DDR4_CHN_H_DQ_DQS_BYTE5\" )
			)
			( classClass "@crescent_city_bb_fab1_lib.crescent_city_bb_fab1(sch_1):\CC751\"
				( spacingCSetRef "@sapphirecity_baseboard_lib.sapphirecity_baseboard(sch_1):\DQ_TO_DQ\" )
				( netClassRef "@sapphirecity_baseboard_lib.sapphirecity_baseboard(sch_1):\DDR4_CHN_H_DQ_DQS_BYTE1\" )
				( netClassRef "@sapphirecity_baseboard_lib.sapphirecity_baseboard(sch_1):\DDR4_CHN_H_DQ_DQS_BYTE5\" )
			)
			( classClass "@crescent_city_bb_fab1_lib.crescent_city_bb_fab1(sch_1):\CC757\"
				( spacingCSetRef "@sapphirecity_baseboard_lib.sapphirecity_baseboard(sch_1):\DQ_TO_DQ\" )
				( netClassRef "@sapphirecity_baseboard_lib.sapphirecity_baseboard(sch_1):\DDR4_CHN_H_DQ_DQS_BYTE2\" )
				( netClassRef "@sapphirecity_baseboard_lib.sapphirecity_baseboard(sch_1):\DDR4_CHN_H_DQ_DQS_BYTE5\" )
			)
			( classClass "@crescent_city_bb_fab1_lib.crescent_city_bb_fab1(sch_1):\CC762\"
				( spacingCSetRef "@sapphirecity_baseboard_lib.sapphirecity_baseboard(sch_1):\DQ_TO_DQ\" )
				( netClassRef "@sapphirecity_baseboard_lib.sapphirecity_baseboard(sch_1):\DDR4_CHN_H_DQ_DQS_BYTE3\" )
				( netClassRef "@sapphirecity_baseboard_lib.sapphirecity_baseboard(sch_1):\DDR4_CHN_H_DQ_DQS_BYTE5\" )
			)
			( classClass "@crescent_city_bb_fab1_lib.crescent_city_bb_fab1(sch_1):\CC766\"
				( spacingCSetRef "@sapphirecity_baseboard_lib.sapphirecity_baseboard(sch_1):\DQ_TO_DQ\" )
				( netClassRef "@sapphirecity_baseboard_lib.sapphirecity_baseboard(sch_1):\DDR4_CHN_H_DQ_DQS_BYTE4\" )
				( netClassRef "@sapphirecity_baseboard_lib.sapphirecity_baseboard(sch_1):\DDR4_CHN_H_DQ_DQS_BYTE5\" )
			)
			( classClass "@sapphirecity_baseboard_lib.sapphirecity_baseboard(sch_1):\CC549\"
				( spacingCSetRef "@sapphirecity_baseboard_lib.sapphirecity_baseboard(sch_1):\DDR4_2SPC_DQ/DQS\" )
				( netClassRef "@sapphirecity_baseboard_lib.sapphirecity_baseboard(sch_1):\DDR4_CHN_H_DQ_DQS_BYTE4\" )
				( netClassRef "@sapphirecity_baseboard_lib.sapphirecity_baseboard(sch_1):\DDR4_CHN_H_DQ_DQS_BYTE4\" )
			)
			( classClass "@crescent_city_bb_fab1_lib.crescent_city_bb_fab1(sch_1):\CC341\"
				( spacingCSetRef "@sapphirecity_baseboard_lib.sapphirecity_baseboard(sch_1):\DQ_TO_DQ\" )
				( netClassRef "@sapphirecity_baseboard_lib.sapphirecity_baseboard(sch_1):\DDR4_CHN_H_CLK\" )
				( netClassRef "@sapphirecity_baseboard_lib.sapphirecity_baseboard(sch_1):\DDR4_CHN_H_DQ_DQS_BYTE4\" )
			)
			( classClass "@crescent_city_bb_fab1_lib.crescent_city_bb_fab1(sch_1):\CC351\"
				( spacingCSetRef "@sapphirecity_baseboard_lib.sapphirecity_baseboard(sch_1):\DQ_TO_DQ\" )
				( netClassRef "@sapphirecity_baseboard_lib.sapphirecity_baseboard(sch_1):\DDR4_CHN_H_CMD_ADD\" )
				( netClassRef "@sapphirecity_baseboard_lib.sapphirecity_baseboard(sch_1):\DDR4_CHN_H_DQ_DQS_BYTE4\" )
			)
			( classClass "@crescent_city_bb_fab1_lib.crescent_city_bb_fab1(sch_1):\CC301\"
				( spacingCSetRef "@sapphirecity_baseboard_lib.sapphirecity_baseboard(sch_1):\DQ_TO_DQ\" )
				( netClassRef "@sapphirecity_baseboard_lib.sapphirecity_baseboard(sch_1):\DDR4_CHN_H_CTRL\" )
				( netClassRef "@sapphirecity_baseboard_lib.sapphirecity_baseboard(sch_1):\DDR4_CHN_H_DQ_DQS_BYTE4\" )
			)
			( classClass "@crescent_city_bb_fab1_lib.crescent_city_bb_fab1(sch_1):\CC609\"
				( spacingCSetRef "@crescent_city_bb_fab1_lib.crescent_city_bb_fab1(sch_1):\DEFAULT\" )
				( netClassRef "@sapphirecity_baseboard_lib.sapphirecity_baseboard(sch_1):\GND\" )
				( netClassRef "@sapphirecity_baseboard_lib.sapphirecity_baseboard(sch_1):\DDR4_CHN_H_DQ_DQS_BYTE4\" )
			)
			( classClass "@crescent_city_bb_fab1_lib.crescent_city_bb_fab1(sch_1):\CC663\"
				( spacingCSetRef "@crescent_city_bb_fab1_lib.crescent_city_bb_fab1(sch_1):\DEFAULT\" )
				( netClassRef "@sapphirecity_baseboard_lib.sapphirecity_baseboard(sch_1):\POWER\" )
				( netClassRef "@sapphirecity_baseboard_lib.sapphirecity_baseboard(sch_1):\DDR4_CHN_H_DQ_DQS_BYTE4\" )
			)
			( classClass "@crescent_city_bb_fab1_lib.crescent_city_bb_fab1(sch_1):\CC743\"
				( spacingCSetRef "@sapphirecity_baseboard_lib.sapphirecity_baseboard(sch_1):\DQ_TO_DQ\" )
				( netClassRef "@sapphirecity_baseboard_lib.sapphirecity_baseboard(sch_1):\DDR4_CHN_H_DQ_DQS_BYTE0\" )
				( netClassRef "@sapphirecity_baseboard_lib.sapphirecity_baseboard(sch_1):\DDR4_CHN_H_DQ_DQS_BYTE4\" )
			)
			( classClass "@crescent_city_bb_fab1_lib.crescent_city_bb_fab1(sch_1):\CC750\"
				( spacingCSetRef "@sapphirecity_baseboard_lib.sapphirecity_baseboard(sch_1):\DQ_TO_DQ\" )
				( netClassRef "@sapphirecity_baseboard_lib.sapphirecity_baseboard(sch_1):\DDR4_CHN_H_DQ_DQS_BYTE1\" )
				( netClassRef "@sapphirecity_baseboard_lib.sapphirecity_baseboard(sch_1):\DDR4_CHN_H_DQ_DQS_BYTE4\" )
			)
			( classClass "@crescent_city_bb_fab1_lib.crescent_city_bb_fab1(sch_1):\CC756\"
				( spacingCSetRef "@sapphirecity_baseboard_lib.sapphirecity_baseboard(sch_1):\DQ_TO_DQ\" )
				( netClassRef "@sapphirecity_baseboard_lib.sapphirecity_baseboard(sch_1):\DDR4_CHN_H_DQ_DQS_BYTE2\" )
				( netClassRef "@sapphirecity_baseboard_lib.sapphirecity_baseboard(sch_1):\DDR4_CHN_H_DQ_DQS_BYTE4\" )
			)
			( classClass "@crescent_city_bb_fab1_lib.crescent_city_bb_fab1(sch_1):\CC761\"
				( spacingCSetRef "@sapphirecity_baseboard_lib.sapphirecity_baseboard(sch_1):\DQ_TO_DQ\" )
				( netClassRef "@sapphirecity_baseboard_lib.sapphirecity_baseboard(sch_1):\DDR4_CHN_H_DQ_DQS_BYTE3\" )
				( netClassRef "@sapphirecity_baseboard_lib.sapphirecity_baseboard(sch_1):\DDR4_CHN_H_DQ_DQS_BYTE4\" )
			)
			( classClass "@sapphirecity_baseboard_lib.sapphirecity_baseboard(sch_1):\CC548\"
				( spacingCSetRef "@sapphirecity_baseboard_lib.sapphirecity_baseboard(sch_1):\DDR4_2SPC_DQ/DQS\" )
				( netClassRef "@sapphirecity_baseboard_lib.sapphirecity_baseboard(sch_1):\DDR4_CHN_H_DQ_DQS_BYTE3\" )
				( netClassRef "@sapphirecity_baseboard_lib.sapphirecity_baseboard(sch_1):\DDR4_CHN_H_DQ_DQS_BYTE3\" )
			)
			( classClass "@crescent_city_bb_fab1_lib.crescent_city_bb_fab1(sch_1):\CC340\"
				( spacingCSetRef "@sapphirecity_baseboard_lib.sapphirecity_baseboard(sch_1):\DQ_TO_DQ\" )
				( netClassRef "@sapphirecity_baseboard_lib.sapphirecity_baseboard(sch_1):\DDR4_CHN_H_CLK\" )
				( netClassRef "@sapphirecity_baseboard_lib.sapphirecity_baseboard(sch_1):\DDR4_CHN_H_DQ_DQS_BYTE3\" )
			)
			( classClass "@crescent_city_bb_fab1_lib.crescent_city_bb_fab1(sch_1):\CC350\"
				( spacingCSetRef "@sapphirecity_baseboard_lib.sapphirecity_baseboard(sch_1):\DQ_TO_DQ\" )
				( netClassRef "@sapphirecity_baseboard_lib.sapphirecity_baseboard(sch_1):\DDR4_CHN_H_CMD_ADD\" )
				( netClassRef "@sapphirecity_baseboard_lib.sapphirecity_baseboard(sch_1):\DDR4_CHN_H_DQ_DQS_BYTE3\" )
			)
			( classClass "@crescent_city_bb_fab1_lib.crescent_city_bb_fab1(sch_1):\CC300\"
				( spacingCSetRef "@sapphirecity_baseboard_lib.sapphirecity_baseboard(sch_1):\DQ_TO_DQ\" )
				( netClassRef "@sapphirecity_baseboard_lib.sapphirecity_baseboard(sch_1):\DDR4_CHN_H_CTRL\" )
				( netClassRef "@sapphirecity_baseboard_lib.sapphirecity_baseboard(sch_1):\DDR4_CHN_H_DQ_DQS_BYTE3\" )
			)
			( classClass "@crescent_city_bb_fab1_lib.crescent_city_bb_fab1(sch_1):\CC608\"
				( spacingCSetRef "@crescent_city_bb_fab1_lib.crescent_city_bb_fab1(sch_1):\DEFAULT\" )
				( netClassRef "@sapphirecity_baseboard_lib.sapphirecity_baseboard(sch_1):\GND\" )
				( netClassRef "@sapphirecity_baseboard_lib.sapphirecity_baseboard(sch_1):\DDR4_CHN_H_DQ_DQS_BYTE3\" )
			)
			( classClass "@crescent_city_bb_fab1_lib.crescent_city_bb_fab1(sch_1):\CC662\"
				( spacingCSetRef "@crescent_city_bb_fab1_lib.crescent_city_bb_fab1(sch_1):\DEFAULT\" )
				( netClassRef "@sapphirecity_baseboard_lib.sapphirecity_baseboard(sch_1):\POWER\" )
				( netClassRef "@sapphirecity_baseboard_lib.sapphirecity_baseboard(sch_1):\DDR4_CHN_H_DQ_DQS_BYTE3\" )
			)
			( classClass "@crescent_city_bb_fab1_lib.crescent_city_bb_fab1(sch_1):\CC742\"
				( spacingCSetRef "@sapphirecity_baseboard_lib.sapphirecity_baseboard(sch_1):\DQ_TO_DQ\" )
				( netClassRef "@sapphirecity_baseboard_lib.sapphirecity_baseboard(sch_1):\DDR4_CHN_H_DQ_DQS_BYTE0\" )
				( netClassRef "@sapphirecity_baseboard_lib.sapphirecity_baseboard(sch_1):\DDR4_CHN_H_DQ_DQS_BYTE3\" )
			)
			( classClass "@crescent_city_bb_fab1_lib.crescent_city_bb_fab1(sch_1):\CC749\"
				( spacingCSetRef "@sapphirecity_baseboard_lib.sapphirecity_baseboard(sch_1):\DQ_TO_DQ\" )
				( netClassRef "@sapphirecity_baseboard_lib.sapphirecity_baseboard(sch_1):\DDR4_CHN_H_DQ_DQS_BYTE1\" )
				( netClassRef "@sapphirecity_baseboard_lib.sapphirecity_baseboard(sch_1):\DDR4_CHN_H_DQ_DQS_BYTE3\" )
			)
			( classClass "@crescent_city_bb_fab1_lib.crescent_city_bb_fab1(sch_1):\CC755\"
				( spacingCSetRef "@sapphirecity_baseboard_lib.sapphirecity_baseboard(sch_1):\DQ_TO_DQ\" )
				( netClassRef "@sapphirecity_baseboard_lib.sapphirecity_baseboard(sch_1):\DDR4_CHN_H_DQ_DQS_BYTE2\" )
				( netClassRef "@sapphirecity_baseboard_lib.sapphirecity_baseboard(sch_1):\DDR4_CHN_H_DQ_DQS_BYTE3\" )
			)
			( classClass "@sapphirecity_baseboard_lib.sapphirecity_baseboard(sch_1):\CC547\"
				( spacingCSetRef "@sapphirecity_baseboard_lib.sapphirecity_baseboard(sch_1):\DDR4_2SPC_DQ/DQS\" )
				( netClassRef "@sapphirecity_baseboard_lib.sapphirecity_baseboard(sch_1):\DDR4_CHN_H_DQ_DQS_BYTE2\" )
				( netClassRef "@sapphirecity_baseboard_lib.sapphirecity_baseboard(sch_1):\DDR4_CHN_H_DQ_DQS_BYTE2\" )
			)
			( classClass "@crescent_city_bb_fab1_lib.crescent_city_bb_fab1(sch_1):\CC339\"
				( spacingCSetRef "@sapphirecity_baseboard_lib.sapphirecity_baseboard(sch_1):\DQ_TO_DQ\" )
				( netClassRef "@sapphirecity_baseboard_lib.sapphirecity_baseboard(sch_1):\DDR4_CHN_H_CLK\" )
				( netClassRef "@sapphirecity_baseboard_lib.sapphirecity_baseboard(sch_1):\DDR4_CHN_H_DQ_DQS_BYTE2\" )
			)
			( classClass "@crescent_city_bb_fab1_lib.crescent_city_bb_fab1(sch_1):\CC349\"
				( spacingCSetRef "@sapphirecity_baseboard_lib.sapphirecity_baseboard(sch_1):\DQ_TO_DQ\" )
				( netClassRef "@sapphirecity_baseboard_lib.sapphirecity_baseboard(sch_1):\DDR4_CHN_H_CMD_ADD\" )
				( netClassRef "@sapphirecity_baseboard_lib.sapphirecity_baseboard(sch_1):\DDR4_CHN_H_DQ_DQS_BYTE2\" )
			)
			( classClass "@crescent_city_bb_fab1_lib.crescent_city_bb_fab1(sch_1):\CC299\"
				( spacingCSetRef "@sapphirecity_baseboard_lib.sapphirecity_baseboard(sch_1):\DQ_TO_DQ\" )
				( netClassRef "@sapphirecity_baseboard_lib.sapphirecity_baseboard(sch_1):\DDR4_CHN_H_CTRL\" )
				( netClassRef "@sapphirecity_baseboard_lib.sapphirecity_baseboard(sch_1):\DDR4_CHN_H_DQ_DQS_BYTE2\" )
			)
			( classClass "@crescent_city_bb_fab1_lib.crescent_city_bb_fab1(sch_1):\CC607\"
				( spacingCSetRef "@crescent_city_bb_fab1_lib.crescent_city_bb_fab1(sch_1):\DEFAULT\" )
				( netClassRef "@sapphirecity_baseboard_lib.sapphirecity_baseboard(sch_1):\GND\" )
				( netClassRef "@sapphirecity_baseboard_lib.sapphirecity_baseboard(sch_1):\DDR4_CHN_H_DQ_DQS_BYTE2\" )
			)
			( classClass "@crescent_city_bb_fab1_lib.crescent_city_bb_fab1(sch_1):\CC661\"
				( spacingCSetRef "@crescent_city_bb_fab1_lib.crescent_city_bb_fab1(sch_1):\DEFAULT\" )
				( netClassRef "@sapphirecity_baseboard_lib.sapphirecity_baseboard(sch_1):\POWER\" )
				( netClassRef "@sapphirecity_baseboard_lib.sapphirecity_baseboard(sch_1):\DDR4_CHN_H_DQ_DQS_BYTE2\" )
			)
			( classClass "@crescent_city_bb_fab1_lib.crescent_city_bb_fab1(sch_1):\CC741\"
				( spacingCSetRef "@sapphirecity_baseboard_lib.sapphirecity_baseboard(sch_1):\DQ_TO_DQ\" )
				( netClassRef "@sapphirecity_baseboard_lib.sapphirecity_baseboard(sch_1):\DDR4_CHN_H_DQ_DQS_BYTE0\" )
				( netClassRef "@sapphirecity_baseboard_lib.sapphirecity_baseboard(sch_1):\DDR4_CHN_H_DQ_DQS_BYTE2\" )
			)
			( classClass "@crescent_city_bb_fab1_lib.crescent_city_bb_fab1(sch_1):\CC748\"
				( spacingCSetRef "@sapphirecity_baseboard_lib.sapphirecity_baseboard(sch_1):\DQ_TO_DQ\" )
				( netClassRef "@sapphirecity_baseboard_lib.sapphirecity_baseboard(sch_1):\DDR4_CHN_H_DQ_DQS_BYTE1\" )
				( netClassRef "@sapphirecity_baseboard_lib.sapphirecity_baseboard(sch_1):\DDR4_CHN_H_DQ_DQS_BYTE2\" )
			)
			( classClass "@sapphirecity_baseboard_lib.sapphirecity_baseboard(sch_1):\CC546\"
				( spacingCSetRef "@sapphirecity_baseboard_lib.sapphirecity_baseboard(sch_1):\DDR4_2SPC_DQ/DQS\" )
				( netClassRef "@sapphirecity_baseboard_lib.sapphirecity_baseboard(sch_1):\DDR4_CHN_H_DQ_DQS_BYTE1\" )
				( netClassRef "@sapphirecity_baseboard_lib.sapphirecity_baseboard(sch_1):\DDR4_CHN_H_DQ_DQS_BYTE1\" )
			)
			( classClass "@crescent_city_bb_fab1_lib.crescent_city_bb_fab1(sch_1):\CC338\"
				( spacingCSetRef "@sapphirecity_baseboard_lib.sapphirecity_baseboard(sch_1):\DQ_TO_DQ\" )
				( netClassRef "@sapphirecity_baseboard_lib.sapphirecity_baseboard(sch_1):\DDR4_CHN_H_CLK\" )
				( netClassRef "@sapphirecity_baseboard_lib.sapphirecity_baseboard(sch_1):\DDR4_CHN_H_DQ_DQS_BYTE1\" )
			)
			( classClass "@crescent_city_bb_fab1_lib.crescent_city_bb_fab1(sch_1):\CC348\"
				( spacingCSetRef "@sapphirecity_baseboard_lib.sapphirecity_baseboard(sch_1):\DQ_TO_DQ\" )
				( netClassRef "@sapphirecity_baseboard_lib.sapphirecity_baseboard(sch_1):\DDR4_CHN_H_CMD_ADD\" )
				( netClassRef "@sapphirecity_baseboard_lib.sapphirecity_baseboard(sch_1):\DDR4_CHN_H_DQ_DQS_BYTE1\" )
			)
			( classClass "@crescent_city_bb_fab1_lib.crescent_city_bb_fab1(sch_1):\CC298\"
				( spacingCSetRef "@sapphirecity_baseboard_lib.sapphirecity_baseboard(sch_1):\DQ_TO_DQ\" )
				( netClassRef "@sapphirecity_baseboard_lib.sapphirecity_baseboard(sch_1):\DDR4_CHN_H_CTRL\" )
				( netClassRef "@sapphirecity_baseboard_lib.sapphirecity_baseboard(sch_1):\DDR4_CHN_H_DQ_DQS_BYTE1\" )
			)
			( classClass "@crescent_city_bb_fab1_lib.crescent_city_bb_fab1(sch_1):\CC606\"
				( spacingCSetRef "@crescent_city_bb_fab1_lib.crescent_city_bb_fab1(sch_1):\DEFAULT\" )
				( netClassRef "@sapphirecity_baseboard_lib.sapphirecity_baseboard(sch_1):\GND\" )
				( netClassRef "@sapphirecity_baseboard_lib.sapphirecity_baseboard(sch_1):\DDR4_CHN_H_DQ_DQS_BYTE1\" )
			)
			( classClass "@crescent_city_bb_fab1_lib.crescent_city_bb_fab1(sch_1):\CC660\"
				( spacingCSetRef "@crescent_city_bb_fab1_lib.crescent_city_bb_fab1(sch_1):\DEFAULT\" )
				( netClassRef "@sapphirecity_baseboard_lib.sapphirecity_baseboard(sch_1):\POWER\" )
				( netClassRef "@sapphirecity_baseboard_lib.sapphirecity_baseboard(sch_1):\DDR4_CHN_H_DQ_DQS_BYTE1\" )
			)
			( classClass "@crescent_city_bb_fab1_lib.crescent_city_bb_fab1(sch_1):\CC740\"
				( spacingCSetRef "@sapphirecity_baseboard_lib.sapphirecity_baseboard(sch_1):\DQ_TO_DQ\" )
				( netClassRef "@sapphirecity_baseboard_lib.sapphirecity_baseboard(sch_1):\DDR4_CHN_H_DQ_DQS_BYTE0\" )
				( netClassRef "@sapphirecity_baseboard_lib.sapphirecity_baseboard(sch_1):\DDR4_CHN_H_DQ_DQS_BYTE1\" )
			)
			( classClass "@sapphirecity_baseboard_lib.sapphirecity_baseboard(sch_1):\CC545\"
				( spacingCSetRef "@sapphirecity_baseboard_lib.sapphirecity_baseboard(sch_1):\DDR4_2SPC_DQ/DQS\" )
				( netClassRef "@sapphirecity_baseboard_lib.sapphirecity_baseboard(sch_1):\DDR4_CHN_H_DQ_DQS_BYTE0\" )
				( netClassRef "@sapphirecity_baseboard_lib.sapphirecity_baseboard(sch_1):\DDR4_CHN_H_DQ_DQS_BYTE0\" )
			)
			( classClass "@crescent_city_bb_fab1_lib.crescent_city_bb_fab1(sch_1):\CC337\"
				( spacingCSetRef "@sapphirecity_baseboard_lib.sapphirecity_baseboard(sch_1):\DQ_TO_DQ\" )
				( netClassRef "@sapphirecity_baseboard_lib.sapphirecity_baseboard(sch_1):\DDR4_CHN_H_CLK\" )
				( netClassRef "@sapphirecity_baseboard_lib.sapphirecity_baseboard(sch_1):\DDR4_CHN_H_DQ_DQS_BYTE0\" )
			)
			( classClass "@crescent_city_bb_fab1_lib.crescent_city_bb_fab1(sch_1):\CC347\"
				( spacingCSetRef "@sapphirecity_baseboard_lib.sapphirecity_baseboard(sch_1):\DQ_TO_DQ\" )
				( netClassRef "@sapphirecity_baseboard_lib.sapphirecity_baseboard(sch_1):\DDR4_CHN_H_CMD_ADD\" )
				( netClassRef "@sapphirecity_baseboard_lib.sapphirecity_baseboard(sch_1):\DDR4_CHN_H_DQ_DQS_BYTE0\" )
			)
			( classClass "@crescent_city_bb_fab1_lib.crescent_city_bb_fab1(sch_1):\CC297\"
				( spacingCSetRef "@sapphirecity_baseboard_lib.sapphirecity_baseboard(sch_1):\DQ_TO_DQ\" )
				( netClassRef "@sapphirecity_baseboard_lib.sapphirecity_baseboard(sch_1):\DDR4_CHN_H_CTRL\" )
				( netClassRef "@sapphirecity_baseboard_lib.sapphirecity_baseboard(sch_1):\DDR4_CHN_H_DQ_DQS_BYTE0\" )
			)
			( classClass "@crescent_city_bb_fab1_lib.crescent_city_bb_fab1(sch_1):\CC605\"
				( spacingCSetRef "@crescent_city_bb_fab1_lib.crescent_city_bb_fab1(sch_1):\DEFAULT\" )
				( netClassRef "@sapphirecity_baseboard_lib.sapphirecity_baseboard(sch_1):\GND\" )
				( netClassRef "@sapphirecity_baseboard_lib.sapphirecity_baseboard(sch_1):\DDR4_CHN_H_DQ_DQS_BYTE0\" )
			)
			( classClass "@crescent_city_bb_fab1_lib.crescent_city_bb_fab1(sch_1):\CC659\"
				( spacingCSetRef "@crescent_city_bb_fab1_lib.crescent_city_bb_fab1(sch_1):\DEFAULT\" )
				( netClassRef "@sapphirecity_baseboard_lib.sapphirecity_baseboard(sch_1):\POWER\" )
				( netClassRef "@sapphirecity_baseboard_lib.sapphirecity_baseboard(sch_1):\DDR4_CHN_H_DQ_DQS_BYTE0\" )
			)
			( classClass "@sapphirecity_baseboard_lib.sapphirecity_baseboard(sch_1):\CC245\"
				( spacingCSetRef "@crescent_city_bb_fab1_lib.crescent_city_bb_fab1(sch_1):\DEFAULT\" )
				( netClassRef "@sapphirecity_baseboard_lib.sapphirecity_baseboard(sch_1):\GND\" )
				( netClassRef "@sapphirecity_baseboard_lib.sapphirecity_baseboard(sch_1):\DDR4_CHN_H_CTRL\" )
			)
			( classClass "@sapphirecity_baseboard_lib.sapphirecity_baseboard(sch_1):\CC539\"
				( spacingCSetRef "@sapphirecity_baseboard_lib.sapphirecity_baseboard(sch_1):\DDR4_2SPC_CAC\" )
				( netClassRef "@sapphirecity_baseboard_lib.sapphirecity_baseboard(sch_1):\DDR4_CHN_H_CLK\" )
				( netClassRef "@sapphirecity_baseboard_lib.sapphirecity_baseboard(sch_1):\DDR4_CHN_H_CTRL\" )
			)
			( classClass "@sapphirecity_baseboard_lib.sapphirecity_baseboard(sch_1):\CC542\"
				( spacingCSetRef "@sapphirecity_baseboard_lib.sapphirecity_baseboard(sch_1):\DDR4_2SPC_CAC\" )
				( netClassRef "@sapphirecity_baseboard_lib.sapphirecity_baseboard(sch_1):\DDR4_CHN_H_CMD_ADD\" )
				( netClassRef "@sapphirecity_baseboard_lib.sapphirecity_baseboard(sch_1):\DDR4_CHN_H_CTRL\" )
			)
			( classClass "@sapphirecity_baseboard_lib.sapphirecity_baseboard(sch_1):\CC544\"
				( spacingCSetRef "@sapphirecity_baseboard_lib.sapphirecity_baseboard(sch_1):\DDR4_2SPC_CAC\" )
				( netClassRef "@sapphirecity_baseboard_lib.sapphirecity_baseboard(sch_1):\DDR4_CHN_H_CTRL\" )
				( netClassRef "@sapphirecity_baseboard_lib.sapphirecity_baseboard(sch_1):\DDR4_CHN_H_CTRL\" )
			)
			( classClass "@crescent_city_bb_fab1_lib.crescent_city_bb_fab1(sch_1):\CC306\"
				( spacingCSetRef "@crescent_city_bb_fab1_lib.crescent_city_bb_fab1(sch_1):\DEFAULT\" )
				( netClassRef "@sapphirecity_baseboard_lib.sapphirecity_baseboard(sch_1):\POWER\" )
				( netClassRef "@sapphirecity_baseboard_lib.sapphirecity_baseboard(sch_1):\DDR4_CHN_H_CTRL\" )
			)
			( classClass "@sapphirecity_baseboard_lib.sapphirecity_baseboard(sch_1):\CC244\"
				( spacingCSetRef "@crescent_city_bb_fab1_lib.crescent_city_bb_fab1(sch_1):\DEFAULT\" )
				( netClassRef "@sapphirecity_baseboard_lib.sapphirecity_baseboard(sch_1):\GND\" )
				( netClassRef "@sapphirecity_baseboard_lib.sapphirecity_baseboard(sch_1):\DDR4_CHN_H_CMD_ADD\" )
			)
			( classClass "@sapphirecity_baseboard_lib.sapphirecity_baseboard(sch_1):\CC540\"
				( spacingCSetRef "@sapphirecity_baseboard_lib.sapphirecity_baseboard(sch_1):\DDR4_2SPC_CAC\" )
				( netClassRef "@sapphirecity_baseboard_lib.sapphirecity_baseboard(sch_1):\DDR4_CHN_H_CLK\" )
				( netClassRef "@sapphirecity_baseboard_lib.sapphirecity_baseboard(sch_1):\DDR4_CHN_H_CMD_ADD\" )
			)
			( classClass "@sapphirecity_baseboard_lib.sapphirecity_baseboard(sch_1):\CC543\"
				( spacingCSetRef "@sapphirecity_baseboard_lib.sapphirecity_baseboard(sch_1):\DDR4_2SPC_CAC\" )
				( netClassRef "@sapphirecity_baseboard_lib.sapphirecity_baseboard(sch_1):\DDR4_CHN_H_CMD_ADD\" )
				( netClassRef "@sapphirecity_baseboard_lib.sapphirecity_baseboard(sch_1):\DDR4_CHN_H_CMD_ADD\" )
			)
			( classClass "@crescent_city_bb_fab1_lib.crescent_city_bb_fab1(sch_1):\CC356\"
				( spacingCSetRef "@crescent_city_bb_fab1_lib.crescent_city_bb_fab1(sch_1):\DEFAULT\" )
				( netClassRef "@sapphirecity_baseboard_lib.sapphirecity_baseboard(sch_1):\POWER\" )
				( netClassRef "@sapphirecity_baseboard_lib.sapphirecity_baseboard(sch_1):\DDR4_CHN_H_CMD_ADD\" )
			)
			( classClass "@sapphirecity_baseboard_lib.sapphirecity_baseboard(sch_1):\CC243\"
				( spacingCSetRef "@crescent_city_bb_fab1_lib.crescent_city_bb_fab1(sch_1):\DEFAULT\" )
				( netClassRef "@sapphirecity_baseboard_lib.sapphirecity_baseboard(sch_1):\GND\" )
				( netClassRef "@sapphirecity_baseboard_lib.sapphirecity_baseboard(sch_1):\DDR4_CHN_H_CLK\" )
			)
			( classClass "@sapphirecity_baseboard_lib.sapphirecity_baseboard(sch_1):\CC541\"
				( spacingCSetRef "@sapphirecity_baseboard_lib.sapphirecity_baseboard(sch_1):\DDR4_2SPC_CAC\" )
				( netClassRef "@sapphirecity_baseboard_lib.sapphirecity_baseboard(sch_1):\DDR4_CHN_H_CLK\" )
				( netClassRef "@sapphirecity_baseboard_lib.sapphirecity_baseboard(sch_1):\DDR4_CHN_H_CLK\" )
			)
			( classClass "@crescent_city_bb_fab1_lib.crescent_city_bb_fab1(sch_1):\CC346\"
				( spacingCSetRef "@crescent_city_bb_fab1_lib.crescent_city_bb_fab1(sch_1):\DEFAULT\" )
				( netClassRef "@sapphirecity_baseboard_lib.sapphirecity_baseboard(sch_1):\POWER\" )
				( netClassRef "@sapphirecity_baseboard_lib.sapphirecity_baseboard(sch_1):\DDR4_CHN_H_CLK\" )
			)
			( classClass "@sapphirecity_baseboard_lib.sapphirecity_baseboard(sch_1):\CC538\"
				( spacingCSetRef "@sapphirecity_baseboard_lib.sapphirecity_baseboard(sch_1):\DDR4_2SPC_DQ/DQS\" )
				( netClassRef "@sapphirecity_baseboard_lib.sapphirecity_baseboard(sch_1):\DDR4_CHN_G_ECC\" )
				( netClassRef "@sapphirecity_baseboard_lib.sapphirecity_baseboard(sch_1):\DDR4_CHN_G_ECC\" )
			)
			( classClass "@crescent_city_bb_fab1_lib.crescent_city_bb_fab1(sch_1):\CC315\"
				( spacingCSetRef "@sapphirecity_baseboard_lib.sapphirecity_baseboard(sch_1):\DQ_TO_DQ\" )
				( netClassRef "@sapphirecity_baseboard_lib.sapphirecity_baseboard(sch_1):\DDR4_CHN_G_CLK\" )
				( netClassRef "@sapphirecity_baseboard_lib.sapphirecity_baseboard(sch_1):\DDR4_CHN_G_ECC\" )
			)
			( classClass "@crescent_city_bb_fab1_lib.crescent_city_bb_fab1(sch_1):\CC325\"
				( spacingCSetRef "@sapphirecity_baseboard_lib.sapphirecity_baseboard(sch_1):\DQ_TO_DQ\" )
				( netClassRef "@sapphirecity_baseboard_lib.sapphirecity_baseboard(sch_1):\DDR4_CHN_G_CMD_ADD\" )
				( netClassRef "@sapphirecity_baseboard_lib.sapphirecity_baseboard(sch_1):\DDR4_CHN_G_ECC\" )
			)
			( classClass "@crescent_city_bb_fab1_lib.crescent_city_bb_fab1(sch_1):\CC335\"
				( spacingCSetRef "@sapphirecity_baseboard_lib.sapphirecity_baseboard(sch_1):\DQ_TO_DQ\" )
				( netClassRef "@sapphirecity_baseboard_lib.sapphirecity_baseboard(sch_1):\DDR4_CHN_G_CTRL\" )
				( netClassRef "@sapphirecity_baseboard_lib.sapphirecity_baseboard(sch_1):\DDR4_CHN_G_ECC\" )
			)
			( classClass "@crescent_city_bb_fab1_lib.crescent_city_bb_fab1(sch_1):\CC604\"
				( spacingCSetRef "@crescent_city_bb_fab1_lib.crescent_city_bb_fab1(sch_1):\DEFAULT\" )
				( netClassRef "@sapphirecity_baseboard_lib.sapphirecity_baseboard(sch_1):\GND\" )
				( netClassRef "@sapphirecity_baseboard_lib.sapphirecity_baseboard(sch_1):\DDR4_CHN_G_ECC\" )
			)
			( classClass "@crescent_city_bb_fab1_lib.crescent_city_bb_fab1(sch_1):\CC658\"
				( spacingCSetRef "@crescent_city_bb_fab1_lib.crescent_city_bb_fab1(sch_1):\DEFAULT\" )
				( netClassRef "@sapphirecity_baseboard_lib.sapphirecity_baseboard(sch_1):\POWER\" )
				( netClassRef "@sapphirecity_baseboard_lib.sapphirecity_baseboard(sch_1):\DDR4_CHN_G_ECC\" )
			)
			( classClass "@crescent_city_bb_fab1_lib.crescent_city_bb_fab1(sch_1):\CC711\"
				( spacingCSetRef "@sapphirecity_baseboard_lib.sapphirecity_baseboard(sch_1):\DQ_TO_DQ\" )
				( netClassRef "@sapphirecity_baseboard_lib.sapphirecity_baseboard(sch_1):\DDR4_CHN_G_DQ_DQS_BYTE0\" )
				( netClassRef "@sapphirecity_baseboard_lib.sapphirecity_baseboard(sch_1):\DDR4_CHN_G_ECC\" )
			)
			( classClass "@crescent_city_bb_fab1_lib.crescent_city_bb_fab1(sch_1):\CC718\"
				( spacingCSetRef "@sapphirecity_baseboard_lib.sapphirecity_baseboard(sch_1):\DQ_TO_DQ\" )
				( netClassRef "@sapphirecity_baseboard_lib.sapphirecity_baseboard(sch_1):\DDR4_CHN_G_DQ_DQS_BYTE1\" )
				( netClassRef "@sapphirecity_baseboard_lib.sapphirecity_baseboard(sch_1):\DDR4_CHN_G_ECC\" )
			)
			( classClass "@crescent_city_bb_fab1_lib.crescent_city_bb_fab1(sch_1):\CC724\"
				( spacingCSetRef "@sapphirecity_baseboard_lib.sapphirecity_baseboard(sch_1):\DQ_TO_DQ\" )
				( netClassRef "@sapphirecity_baseboard_lib.sapphirecity_baseboard(sch_1):\DDR4_CHN_G_DQ_DQS_BYTE2\" )
				( netClassRef "@sapphirecity_baseboard_lib.sapphirecity_baseboard(sch_1):\DDR4_CHN_G_ECC\" )
			)
			( classClass "@crescent_city_bb_fab1_lib.crescent_city_bb_fab1(sch_1):\CC729\"
				( spacingCSetRef "@sapphirecity_baseboard_lib.sapphirecity_baseboard(sch_1):\DQ_TO_DQ\" )
				( netClassRef "@sapphirecity_baseboard_lib.sapphirecity_baseboard(sch_1):\DDR4_CHN_G_DQ_DQS_BYTE3\" )
				( netClassRef "@sapphirecity_baseboard_lib.sapphirecity_baseboard(sch_1):\DDR4_CHN_G_ECC\" )
			)
			( classClass "@crescent_city_bb_fab1_lib.crescent_city_bb_fab1(sch_1):\CC733\"
				( spacingCSetRef "@sapphirecity_baseboard_lib.sapphirecity_baseboard(sch_1):\DQ_TO_DQ\" )
				( netClassRef "@sapphirecity_baseboard_lib.sapphirecity_baseboard(sch_1):\DDR4_CHN_G_DQ_DQS_BYTE4\" )
				( netClassRef "@sapphirecity_baseboard_lib.sapphirecity_baseboard(sch_1):\DDR4_CHN_G_ECC\" )
			)
			( classClass "@crescent_city_bb_fab1_lib.crescent_city_bb_fab1(sch_1):\CC736\"
				( spacingCSetRef "@sapphirecity_baseboard_lib.sapphirecity_baseboard(sch_1):\DQ_TO_DQ\" )
				( netClassRef "@sapphirecity_baseboard_lib.sapphirecity_baseboard(sch_1):\DDR4_CHN_G_DQ_DQS_BYTE5\" )
				( netClassRef "@sapphirecity_baseboard_lib.sapphirecity_baseboard(sch_1):\DDR4_CHN_G_ECC\" )
			)
			( classClass "@crescent_city_bb_fab1_lib.crescent_city_bb_fab1(sch_1):\CC738\"
				( spacingCSetRef "@sapphirecity_baseboard_lib.sapphirecity_baseboard(sch_1):\DQ_TO_DQ\" )
				( netClassRef "@sapphirecity_baseboard_lib.sapphirecity_baseboard(sch_1):\DDR4_CHN_G_DQ_DQS_BYTE6\" )
				( netClassRef "@sapphirecity_baseboard_lib.sapphirecity_baseboard(sch_1):\DDR4_CHN_G_ECC\" )
			)
			( classClass "@crescent_city_bb_fab1_lib.crescent_city_bb_fab1(sch_1):\CC739\"
				( spacingCSetRef "@sapphirecity_baseboard_lib.sapphirecity_baseboard(sch_1):\DQ_TO_DQ\" )
				( netClassRef "@sapphirecity_baseboard_lib.sapphirecity_baseboard(sch_1):\DDR4_CHN_G_DQ_DQS_BYTE7\" )
				( netClassRef "@sapphirecity_baseboard_lib.sapphirecity_baseboard(sch_1):\DDR4_CHN_G_ECC\" )
			)
			( classClass "@sapphirecity_baseboard_lib.sapphirecity_baseboard(sch_1):\CC537\"
				( spacingCSetRef "@sapphirecity_baseboard_lib.sapphirecity_baseboard(sch_1):\DDR4_2SPC_DQ/DQS\" )
				( netClassRef "@sapphirecity_baseboard_lib.sapphirecity_baseboard(sch_1):\DDR4_CHN_G_DQ_DQS_BYTE7\" )
				( netClassRef "@sapphirecity_baseboard_lib.sapphirecity_baseboard(sch_1):\DDR4_CHN_G_DQ_DQS_BYTE7\" )
			)
			( classClass "@crescent_city_bb_fab1_lib.crescent_city_bb_fab1(sch_1):\CC314\"
				( spacingCSetRef "@sapphirecity_baseboard_lib.sapphirecity_baseboard(sch_1):\DQ_TO_DQ\" )
				( netClassRef "@sapphirecity_baseboard_lib.sapphirecity_baseboard(sch_1):\DDR4_CHN_G_CLK\" )
				( netClassRef "@sapphirecity_baseboard_lib.sapphirecity_baseboard(sch_1):\DDR4_CHN_G_DQ_DQS_BYTE7\" )
			)
			( classClass "@crescent_city_bb_fab1_lib.crescent_city_bb_fab1(sch_1):\CC324\"
				( spacingCSetRef "@sapphirecity_baseboard_lib.sapphirecity_baseboard(sch_1):\DQ_TO_DQ\" )
				( netClassRef "@sapphirecity_baseboard_lib.sapphirecity_baseboard(sch_1):\DDR4_CHN_G_CMD_ADD\" )
				( netClassRef "@sapphirecity_baseboard_lib.sapphirecity_baseboard(sch_1):\DDR4_CHN_G_DQ_DQS_BYTE7\" )
			)
			( classClass "@crescent_city_bb_fab1_lib.crescent_city_bb_fab1(sch_1):\CC334\"
				( spacingCSetRef "@sapphirecity_baseboard_lib.sapphirecity_baseboard(sch_1):\DQ_TO_DQ\" )
				( netClassRef "@sapphirecity_baseboard_lib.sapphirecity_baseboard(sch_1):\DDR4_CHN_G_CTRL\" )
				( netClassRef "@sapphirecity_baseboard_lib.sapphirecity_baseboard(sch_1):\DDR4_CHN_G_DQ_DQS_BYTE7\" )
			)
			( classClass "@crescent_city_bb_fab1_lib.crescent_city_bb_fab1(sch_1):\CC603\"
				( spacingCSetRef "@crescent_city_bb_fab1_lib.crescent_city_bb_fab1(sch_1):\DEFAULT\" )
				( netClassRef "@sapphirecity_baseboard_lib.sapphirecity_baseboard(sch_1):\GND\" )
				( netClassRef "@sapphirecity_baseboard_lib.sapphirecity_baseboard(sch_1):\DDR4_CHN_G_DQ_DQS_BYTE7\" )
			)
			( classClass "@crescent_city_bb_fab1_lib.crescent_city_bb_fab1(sch_1):\CC657\"
				( spacingCSetRef "@crescent_city_bb_fab1_lib.crescent_city_bb_fab1(sch_1):\DEFAULT\" )
				( netClassRef "@sapphirecity_baseboard_lib.sapphirecity_baseboard(sch_1):\POWER\" )
				( netClassRef "@sapphirecity_baseboard_lib.sapphirecity_baseboard(sch_1):\DDR4_CHN_G_DQ_DQS_BYTE7\" )
			)
			( classClass "@crescent_city_bb_fab1_lib.crescent_city_bb_fab1(sch_1):\CC710\"
				( spacingCSetRef "@sapphirecity_baseboard_lib.sapphirecity_baseboard(sch_1):\DQ_TO_DQ\" )
				( netClassRef "@sapphirecity_baseboard_lib.sapphirecity_baseboard(sch_1):\DDR4_CHN_G_DQ_DQS_BYTE0\" )
				( netClassRef "@sapphirecity_baseboard_lib.sapphirecity_baseboard(sch_1):\DDR4_CHN_G_DQ_DQS_BYTE7\" )
			)
			( classClass "@crescent_city_bb_fab1_lib.crescent_city_bb_fab1(sch_1):\CC717\"
				( spacingCSetRef "@sapphirecity_baseboard_lib.sapphirecity_baseboard(sch_1):\DQ_TO_DQ\" )
				( netClassRef "@sapphirecity_baseboard_lib.sapphirecity_baseboard(sch_1):\DDR4_CHN_G_DQ_DQS_BYTE1\" )
				( netClassRef "@sapphirecity_baseboard_lib.sapphirecity_baseboard(sch_1):\DDR4_CHN_G_DQ_DQS_BYTE7\" )
			)
			( classClass "@crescent_city_bb_fab1_lib.crescent_city_bb_fab1(sch_1):\CC723\"
				( spacingCSetRef "@sapphirecity_baseboard_lib.sapphirecity_baseboard(sch_1):\DQ_TO_DQ\" )
				( netClassRef "@sapphirecity_baseboard_lib.sapphirecity_baseboard(sch_1):\DDR4_CHN_G_DQ_DQS_BYTE2\" )
				( netClassRef "@sapphirecity_baseboard_lib.sapphirecity_baseboard(sch_1):\DDR4_CHN_G_DQ_DQS_BYTE7\" )
			)
			( classClass "@crescent_city_bb_fab1_lib.crescent_city_bb_fab1(sch_1):\CC728\"
				( spacingCSetRef "@sapphirecity_baseboard_lib.sapphirecity_baseboard(sch_1):\DQ_TO_DQ\" )
				( netClassRef "@sapphirecity_baseboard_lib.sapphirecity_baseboard(sch_1):\DDR4_CHN_G_DQ_DQS_BYTE3\" )
				( netClassRef "@sapphirecity_baseboard_lib.sapphirecity_baseboard(sch_1):\DDR4_CHN_G_DQ_DQS_BYTE7\" )
			)
			( classClass "@crescent_city_bb_fab1_lib.crescent_city_bb_fab1(sch_1):\CC732\"
				( spacingCSetRef "@sapphirecity_baseboard_lib.sapphirecity_baseboard(sch_1):\DQ_TO_DQ\" )
				( netClassRef "@sapphirecity_baseboard_lib.sapphirecity_baseboard(sch_1):\DDR4_CHN_G_DQ_DQS_BYTE4\" )
				( netClassRef "@sapphirecity_baseboard_lib.sapphirecity_baseboard(sch_1):\DDR4_CHN_G_DQ_DQS_BYTE7\" )
			)
			( classClass "@crescent_city_bb_fab1_lib.crescent_city_bb_fab1(sch_1):\CC735\"
				( spacingCSetRef "@sapphirecity_baseboard_lib.sapphirecity_baseboard(sch_1):\DQ_TO_DQ\" )
				( netClassRef "@sapphirecity_baseboard_lib.sapphirecity_baseboard(sch_1):\DDR4_CHN_G_DQ_DQS_BYTE5\" )
				( netClassRef "@sapphirecity_baseboard_lib.sapphirecity_baseboard(sch_1):\DDR4_CHN_G_DQ_DQS_BYTE7\" )
			)
			( classClass "@crescent_city_bb_fab1_lib.crescent_city_bb_fab1(sch_1):\CC737\"
				( spacingCSetRef "@sapphirecity_baseboard_lib.sapphirecity_baseboard(sch_1):\DQ_TO_DQ\" )
				( netClassRef "@sapphirecity_baseboard_lib.sapphirecity_baseboard(sch_1):\DDR4_CHN_G_DQ_DQS_BYTE6\" )
				( netClassRef "@sapphirecity_baseboard_lib.sapphirecity_baseboard(sch_1):\DDR4_CHN_G_DQ_DQS_BYTE7\" )
			)
			( classClass "@sapphirecity_baseboard_lib.sapphirecity_baseboard(sch_1):\CC536\"
				( spacingCSetRef "@sapphirecity_baseboard_lib.sapphirecity_baseboard(sch_1):\DDR4_2SPC_DQ/DQS\" )
				( netClassRef "@sapphirecity_baseboard_lib.sapphirecity_baseboard(sch_1):\DDR4_CHN_G_DQ_DQS_BYTE6\" )
				( netClassRef "@sapphirecity_baseboard_lib.sapphirecity_baseboard(sch_1):\DDR4_CHN_G_DQ_DQS_BYTE6\" )
			)
			( classClass "@crescent_city_bb_fab1_lib.crescent_city_bb_fab1(sch_1):\CC313\"
				( spacingCSetRef "@sapphirecity_baseboard_lib.sapphirecity_baseboard(sch_1):\DQ_TO_DQ\" )
				( netClassRef "@sapphirecity_baseboard_lib.sapphirecity_baseboard(sch_1):\DDR4_CHN_G_CLK\" )
				( netClassRef "@sapphirecity_baseboard_lib.sapphirecity_baseboard(sch_1):\DDR4_CHN_G_DQ_DQS_BYTE6\" )
			)
			( classClass "@crescent_city_bb_fab1_lib.crescent_city_bb_fab1(sch_1):\CC323\"
				( spacingCSetRef "@sapphirecity_baseboard_lib.sapphirecity_baseboard(sch_1):\DQ_TO_DQ\" )
				( netClassRef "@sapphirecity_baseboard_lib.sapphirecity_baseboard(sch_1):\DDR4_CHN_G_CMD_ADD\" )
				( netClassRef "@sapphirecity_baseboard_lib.sapphirecity_baseboard(sch_1):\DDR4_CHN_G_DQ_DQS_BYTE6\" )
			)
			( classClass "@crescent_city_bb_fab1_lib.crescent_city_bb_fab1(sch_1):\CC333\"
				( spacingCSetRef "@sapphirecity_baseboard_lib.sapphirecity_baseboard(sch_1):\DQ_TO_DQ\" )
				( netClassRef "@sapphirecity_baseboard_lib.sapphirecity_baseboard(sch_1):\DDR4_CHN_G_CTRL\" )
				( netClassRef "@sapphirecity_baseboard_lib.sapphirecity_baseboard(sch_1):\DDR4_CHN_G_DQ_DQS_BYTE6\" )
			)
			( classClass "@crescent_city_bb_fab1_lib.crescent_city_bb_fab1(sch_1):\CC602\"
				( spacingCSetRef "@crescent_city_bb_fab1_lib.crescent_city_bb_fab1(sch_1):\DEFAULT\" )
				( netClassRef "@sapphirecity_baseboard_lib.sapphirecity_baseboard(sch_1):\GND\" )
				( netClassRef "@sapphirecity_baseboard_lib.sapphirecity_baseboard(sch_1):\DDR4_CHN_G_DQ_DQS_BYTE6\" )
			)
			( classClass "@crescent_city_bb_fab1_lib.crescent_city_bb_fab1(sch_1):\CC656\"
				( spacingCSetRef "@crescent_city_bb_fab1_lib.crescent_city_bb_fab1(sch_1):\DEFAULT\" )
				( netClassRef "@sapphirecity_baseboard_lib.sapphirecity_baseboard(sch_1):\POWER\" )
				( netClassRef "@sapphirecity_baseboard_lib.sapphirecity_baseboard(sch_1):\DDR4_CHN_G_DQ_DQS_BYTE6\" )
			)
			( classClass "@crescent_city_bb_fab1_lib.crescent_city_bb_fab1(sch_1):\CC709\"
				( spacingCSetRef "@sapphirecity_baseboard_lib.sapphirecity_baseboard(sch_1):\DQ_TO_DQ\" )
				( netClassRef "@sapphirecity_baseboard_lib.sapphirecity_baseboard(sch_1):\DDR4_CHN_G_DQ_DQS_BYTE0\" )
				( netClassRef "@sapphirecity_baseboard_lib.sapphirecity_baseboard(sch_1):\DDR4_CHN_G_DQ_DQS_BYTE6\" )
			)
			( classClass "@crescent_city_bb_fab1_lib.crescent_city_bb_fab1(sch_1):\CC716\"
				( spacingCSetRef "@sapphirecity_baseboard_lib.sapphirecity_baseboard(sch_1):\DQ_TO_DQ\" )
				( netClassRef "@sapphirecity_baseboard_lib.sapphirecity_baseboard(sch_1):\DDR4_CHN_G_DQ_DQS_BYTE1\" )
				( netClassRef "@sapphirecity_baseboard_lib.sapphirecity_baseboard(sch_1):\DDR4_CHN_G_DQ_DQS_BYTE6\" )
			)
			( classClass "@crescent_city_bb_fab1_lib.crescent_city_bb_fab1(sch_1):\CC722\"
				( spacingCSetRef "@sapphirecity_baseboard_lib.sapphirecity_baseboard(sch_1):\DQ_TO_DQ\" )
				( netClassRef "@sapphirecity_baseboard_lib.sapphirecity_baseboard(sch_1):\DDR4_CHN_G_DQ_DQS_BYTE2\" )
				( netClassRef "@sapphirecity_baseboard_lib.sapphirecity_baseboard(sch_1):\DDR4_CHN_G_DQ_DQS_BYTE6\" )
			)
			( classClass "@crescent_city_bb_fab1_lib.crescent_city_bb_fab1(sch_1):\CC727\"
				( spacingCSetRef "@sapphirecity_baseboard_lib.sapphirecity_baseboard(sch_1):\DQ_TO_DQ\" )
				( netClassRef "@sapphirecity_baseboard_lib.sapphirecity_baseboard(sch_1):\DDR4_CHN_G_DQ_DQS_BYTE3\" )
				( netClassRef "@sapphirecity_baseboard_lib.sapphirecity_baseboard(sch_1):\DDR4_CHN_G_DQ_DQS_BYTE6\" )
			)
			( classClass "@crescent_city_bb_fab1_lib.crescent_city_bb_fab1(sch_1):\CC731\"
				( spacingCSetRef "@sapphirecity_baseboard_lib.sapphirecity_baseboard(sch_1):\DQ_TO_DQ\" )
				( netClassRef "@sapphirecity_baseboard_lib.sapphirecity_baseboard(sch_1):\DDR4_CHN_G_DQ_DQS_BYTE4\" )
				( netClassRef "@sapphirecity_baseboard_lib.sapphirecity_baseboard(sch_1):\DDR4_CHN_G_DQ_DQS_BYTE6\" )
			)
			( classClass "@crescent_city_bb_fab1_lib.crescent_city_bb_fab1(sch_1):\CC734\"
				( spacingCSetRef "@sapphirecity_baseboard_lib.sapphirecity_baseboard(sch_1):\DQ_TO_DQ\" )
				( netClassRef "@sapphirecity_baseboard_lib.sapphirecity_baseboard(sch_1):\DDR4_CHN_G_DQ_DQS_BYTE5\" )
				( netClassRef "@sapphirecity_baseboard_lib.sapphirecity_baseboard(sch_1):\DDR4_CHN_G_DQ_DQS_BYTE6\" )
			)
			( classClass "@sapphirecity_baseboard_lib.sapphirecity_baseboard(sch_1):\CC535\"
				( spacingCSetRef "@sapphirecity_baseboard_lib.sapphirecity_baseboard(sch_1):\DDR4_2SPC_DQ/DQS\" )
				( netClassRef "@sapphirecity_baseboard_lib.sapphirecity_baseboard(sch_1):\DDR4_CHN_G_DQ_DQS_BYTE5\" )
				( netClassRef "@sapphirecity_baseboard_lib.sapphirecity_baseboard(sch_1):\DDR4_CHN_G_DQ_DQS_BYTE5\" )
			)
			( classClass "@crescent_city_bb_fab1_lib.crescent_city_bb_fab1(sch_1):\CC312\"
				( spacingCSetRef "@sapphirecity_baseboard_lib.sapphirecity_baseboard(sch_1):\DQ_TO_DQ\" )
				( netClassRef "@sapphirecity_baseboard_lib.sapphirecity_baseboard(sch_1):\DDR4_CHN_G_CLK\" )
				( netClassRef "@sapphirecity_baseboard_lib.sapphirecity_baseboard(sch_1):\DDR4_CHN_G_DQ_DQS_BYTE5\" )
			)
			( classClass "@crescent_city_bb_fab1_lib.crescent_city_bb_fab1(sch_1):\CC322\"
				( spacingCSetRef "@sapphirecity_baseboard_lib.sapphirecity_baseboard(sch_1):\DQ_TO_DQ\" )
				( netClassRef "@sapphirecity_baseboard_lib.sapphirecity_baseboard(sch_1):\DDR4_CHN_G_CMD_ADD\" )
				( netClassRef "@sapphirecity_baseboard_lib.sapphirecity_baseboard(sch_1):\DDR4_CHN_G_DQ_DQS_BYTE5\" )
			)
			( classClass "@crescent_city_bb_fab1_lib.crescent_city_bb_fab1(sch_1):\CC332\"
				( spacingCSetRef "@sapphirecity_baseboard_lib.sapphirecity_baseboard(sch_1):\DQ_TO_DQ\" )
				( netClassRef "@sapphirecity_baseboard_lib.sapphirecity_baseboard(sch_1):\DDR4_CHN_G_CTRL\" )
				( netClassRef "@sapphirecity_baseboard_lib.sapphirecity_baseboard(sch_1):\DDR4_CHN_G_DQ_DQS_BYTE5\" )
			)
			( classClass "@crescent_city_bb_fab1_lib.crescent_city_bb_fab1(sch_1):\CC601\"
				( spacingCSetRef "@crescent_city_bb_fab1_lib.crescent_city_bb_fab1(sch_1):\DEFAULT\" )
				( netClassRef "@sapphirecity_baseboard_lib.sapphirecity_baseboard(sch_1):\GND\" )
				( netClassRef "@sapphirecity_baseboard_lib.sapphirecity_baseboard(sch_1):\DDR4_CHN_G_DQ_DQS_BYTE5\" )
			)
			( classClass "@crescent_city_bb_fab1_lib.crescent_city_bb_fab1(sch_1):\CC655\"
				( spacingCSetRef "@crescent_city_bb_fab1_lib.crescent_city_bb_fab1(sch_1):\DEFAULT\" )
				( netClassRef "@sapphirecity_baseboard_lib.sapphirecity_baseboard(sch_1):\POWER\" )
				( netClassRef "@sapphirecity_baseboard_lib.sapphirecity_baseboard(sch_1):\DDR4_CHN_G_DQ_DQS_BYTE5\" )
			)
			( classClass "@crescent_city_bb_fab1_lib.crescent_city_bb_fab1(sch_1):\CC708\"
				( spacingCSetRef "@sapphirecity_baseboard_lib.sapphirecity_baseboard(sch_1):\DQ_TO_DQ\" )
				( netClassRef "@sapphirecity_baseboard_lib.sapphirecity_baseboard(sch_1):\DDR4_CHN_G_DQ_DQS_BYTE0\" )
				( netClassRef "@sapphirecity_baseboard_lib.sapphirecity_baseboard(sch_1):\DDR4_CHN_G_DQ_DQS_BYTE5\" )
			)
			( classClass "@crescent_city_bb_fab1_lib.crescent_city_bb_fab1(sch_1):\CC715\"
				( spacingCSetRef "@sapphirecity_baseboard_lib.sapphirecity_baseboard(sch_1):\DQ_TO_DQ\" )
				( netClassRef "@sapphirecity_baseboard_lib.sapphirecity_baseboard(sch_1):\DDR4_CHN_G_DQ_DQS_BYTE1\" )
				( netClassRef "@sapphirecity_baseboard_lib.sapphirecity_baseboard(sch_1):\DDR4_CHN_G_DQ_DQS_BYTE5\" )
			)
			( classClass "@crescent_city_bb_fab1_lib.crescent_city_bb_fab1(sch_1):\CC721\"
				( spacingCSetRef "@sapphirecity_baseboard_lib.sapphirecity_baseboard(sch_1):\DQ_TO_DQ\" )
				( netClassRef "@sapphirecity_baseboard_lib.sapphirecity_baseboard(sch_1):\DDR4_CHN_G_DQ_DQS_BYTE2\" )
				( netClassRef "@sapphirecity_baseboard_lib.sapphirecity_baseboard(sch_1):\DDR4_CHN_G_DQ_DQS_BYTE5\" )
			)
			( classClass "@crescent_city_bb_fab1_lib.crescent_city_bb_fab1(sch_1):\CC726\"
				( spacingCSetRef "@sapphirecity_baseboard_lib.sapphirecity_baseboard(sch_1):\DQ_TO_DQ\" )
				( netClassRef "@sapphirecity_baseboard_lib.sapphirecity_baseboard(sch_1):\DDR4_CHN_G_DQ_DQS_BYTE3\" )
				( netClassRef "@sapphirecity_baseboard_lib.sapphirecity_baseboard(sch_1):\DDR4_CHN_G_DQ_DQS_BYTE5\" )
			)
			( classClass "@crescent_city_bb_fab1_lib.crescent_city_bb_fab1(sch_1):\CC730\"
				( spacingCSetRef "@sapphirecity_baseboard_lib.sapphirecity_baseboard(sch_1):\DQ_TO_DQ\" )
				( netClassRef "@sapphirecity_baseboard_lib.sapphirecity_baseboard(sch_1):\DDR4_CHN_G_DQ_DQS_BYTE4\" )
				( netClassRef "@sapphirecity_baseboard_lib.sapphirecity_baseboard(sch_1):\DDR4_CHN_G_DQ_DQS_BYTE5\" )
			)
			( classClass "@sapphirecity_baseboard_lib.sapphirecity_baseboard(sch_1):\CC534\"
				( spacingCSetRef "@sapphirecity_baseboard_lib.sapphirecity_baseboard(sch_1):\DDR4_2SPC_DQ/DQS\" )
				( netClassRef "@sapphirecity_baseboard_lib.sapphirecity_baseboard(sch_1):\DDR4_CHN_G_DQ_DQS_BYTE4\" )
				( netClassRef "@sapphirecity_baseboard_lib.sapphirecity_baseboard(sch_1):\DDR4_CHN_G_DQ_DQS_BYTE4\" )
			)
			( classClass "@crescent_city_bb_fab1_lib.crescent_city_bb_fab1(sch_1):\CC311\"
				( spacingCSetRef "@sapphirecity_baseboard_lib.sapphirecity_baseboard(sch_1):\DQ_TO_DQ\" )
				( netClassRef "@sapphirecity_baseboard_lib.sapphirecity_baseboard(sch_1):\DDR4_CHN_G_CLK\" )
				( netClassRef "@sapphirecity_baseboard_lib.sapphirecity_baseboard(sch_1):\DDR4_CHN_G_DQ_DQS_BYTE4\" )
			)
			( classClass "@crescent_city_bb_fab1_lib.crescent_city_bb_fab1(sch_1):\CC321\"
				( spacingCSetRef "@sapphirecity_baseboard_lib.sapphirecity_baseboard(sch_1):\DQ_TO_DQ\" )
				( netClassRef "@sapphirecity_baseboard_lib.sapphirecity_baseboard(sch_1):\DDR4_CHN_G_CMD_ADD\" )
				( netClassRef "@sapphirecity_baseboard_lib.sapphirecity_baseboard(sch_1):\DDR4_CHN_G_DQ_DQS_BYTE4\" )
			)
			( classClass "@crescent_city_bb_fab1_lib.crescent_city_bb_fab1(sch_1):\CC331\"
				( spacingCSetRef "@sapphirecity_baseboard_lib.sapphirecity_baseboard(sch_1):\DQ_TO_DQ\" )
				( netClassRef "@sapphirecity_baseboard_lib.sapphirecity_baseboard(sch_1):\DDR4_CHN_G_CTRL\" )
				( netClassRef "@sapphirecity_baseboard_lib.sapphirecity_baseboard(sch_1):\DDR4_CHN_G_DQ_DQS_BYTE4\" )
			)
			( classClass "@crescent_city_bb_fab1_lib.crescent_city_bb_fab1(sch_1):\CC600\"
				( spacingCSetRef "@crescent_city_bb_fab1_lib.crescent_city_bb_fab1(sch_1):\DEFAULT\" )
				( netClassRef "@sapphirecity_baseboard_lib.sapphirecity_baseboard(sch_1):\GND\" )
				( netClassRef "@sapphirecity_baseboard_lib.sapphirecity_baseboard(sch_1):\DDR4_CHN_G_DQ_DQS_BYTE4\" )
			)
			( classClass "@crescent_city_bb_fab1_lib.crescent_city_bb_fab1(sch_1):\CC654\"
				( spacingCSetRef "@crescent_city_bb_fab1_lib.crescent_city_bb_fab1(sch_1):\DEFAULT\" )
				( netClassRef "@sapphirecity_baseboard_lib.sapphirecity_baseboard(sch_1):\POWER\" )
				( netClassRef "@sapphirecity_baseboard_lib.sapphirecity_baseboard(sch_1):\DDR4_CHN_G_DQ_DQS_BYTE4\" )
			)
			( classClass "@crescent_city_bb_fab1_lib.crescent_city_bb_fab1(sch_1):\CC707\"
				( spacingCSetRef "@sapphirecity_baseboard_lib.sapphirecity_baseboard(sch_1):\DQ_TO_DQ\" )
				( netClassRef "@sapphirecity_baseboard_lib.sapphirecity_baseboard(sch_1):\DDR4_CHN_G_DQ_DQS_BYTE0\" )
				( netClassRef "@sapphirecity_baseboard_lib.sapphirecity_baseboard(sch_1):\DDR4_CHN_G_DQ_DQS_BYTE4\" )
			)
			( classClass "@crescent_city_bb_fab1_lib.crescent_city_bb_fab1(sch_1):\CC714\"
				( spacingCSetRef "@sapphirecity_baseboard_lib.sapphirecity_baseboard(sch_1):\DQ_TO_DQ\" )
				( netClassRef "@sapphirecity_baseboard_lib.sapphirecity_baseboard(sch_1):\DDR4_CHN_G_DQ_DQS_BYTE1\" )
				( netClassRef "@sapphirecity_baseboard_lib.sapphirecity_baseboard(sch_1):\DDR4_CHN_G_DQ_DQS_BYTE4\" )
			)
			( classClass "@crescent_city_bb_fab1_lib.crescent_city_bb_fab1(sch_1):\CC720\"
				( spacingCSetRef "@sapphirecity_baseboard_lib.sapphirecity_baseboard(sch_1):\DQ_TO_DQ\" )
				( netClassRef "@sapphirecity_baseboard_lib.sapphirecity_baseboard(sch_1):\DDR4_CHN_G_DQ_DQS_BYTE2\" )
				( netClassRef "@sapphirecity_baseboard_lib.sapphirecity_baseboard(sch_1):\DDR4_CHN_G_DQ_DQS_BYTE4\" )
			)
			( classClass "@crescent_city_bb_fab1_lib.crescent_city_bb_fab1(sch_1):\CC725\"
				( spacingCSetRef "@sapphirecity_baseboard_lib.sapphirecity_baseboard(sch_1):\DQ_TO_DQ\" )
				( netClassRef "@sapphirecity_baseboard_lib.sapphirecity_baseboard(sch_1):\DDR4_CHN_G_DQ_DQS_BYTE3\" )
				( netClassRef "@sapphirecity_baseboard_lib.sapphirecity_baseboard(sch_1):\DDR4_CHN_G_DQ_DQS_BYTE4\" )
			)
			( classClass "@sapphirecity_baseboard_lib.sapphirecity_baseboard(sch_1):\CC533\"
				( spacingCSetRef "@sapphirecity_baseboard_lib.sapphirecity_baseboard(sch_1):\DDR4_2SPC_DQ/DQS\" )
				( netClassRef "@sapphirecity_baseboard_lib.sapphirecity_baseboard(sch_1):\DDR4_CHN_G_DQ_DQS_BYTE3\" )
				( netClassRef "@sapphirecity_baseboard_lib.sapphirecity_baseboard(sch_1):\DDR4_CHN_G_DQ_DQS_BYTE3\" )
			)
			( classClass "@crescent_city_bb_fab1_lib.crescent_city_bb_fab1(sch_1):\CC310\"
				( spacingCSetRef "@sapphirecity_baseboard_lib.sapphirecity_baseboard(sch_1):\DQ_TO_DQ\" )
				( netClassRef "@sapphirecity_baseboard_lib.sapphirecity_baseboard(sch_1):\DDR4_CHN_G_CLK\" )
				( netClassRef "@sapphirecity_baseboard_lib.sapphirecity_baseboard(sch_1):\DDR4_CHN_G_DQ_DQS_BYTE3\" )
			)
			( classClass "@crescent_city_bb_fab1_lib.crescent_city_bb_fab1(sch_1):\CC320\"
				( spacingCSetRef "@sapphirecity_baseboard_lib.sapphirecity_baseboard(sch_1):\DQ_TO_DQ\" )
				( netClassRef "@sapphirecity_baseboard_lib.sapphirecity_baseboard(sch_1):\DDR4_CHN_G_CMD_ADD\" )
				( netClassRef "@sapphirecity_baseboard_lib.sapphirecity_baseboard(sch_1):\DDR4_CHN_G_DQ_DQS_BYTE3\" )
			)
			( classClass "@crescent_city_bb_fab1_lib.crescent_city_bb_fab1(sch_1):\CC330\"
				( spacingCSetRef "@sapphirecity_baseboard_lib.sapphirecity_baseboard(sch_1):\DQ_TO_DQ\" )
				( netClassRef "@sapphirecity_baseboard_lib.sapphirecity_baseboard(sch_1):\DDR4_CHN_G_CTRL\" )
				( netClassRef "@sapphirecity_baseboard_lib.sapphirecity_baseboard(sch_1):\DDR4_CHN_G_DQ_DQS_BYTE3\" )
			)
			( classClass "@crescent_city_bb_fab1_lib.crescent_city_bb_fab1(sch_1):\CC599\"
				( spacingCSetRef "@crescent_city_bb_fab1_lib.crescent_city_bb_fab1(sch_1):\DEFAULT\" )
				( netClassRef "@sapphirecity_baseboard_lib.sapphirecity_baseboard(sch_1):\GND\" )
				( netClassRef "@sapphirecity_baseboard_lib.sapphirecity_baseboard(sch_1):\DDR4_CHN_G_DQ_DQS_BYTE3\" )
			)
			( classClass "@crescent_city_bb_fab1_lib.crescent_city_bb_fab1(sch_1):\CC653\"
				( spacingCSetRef "@crescent_city_bb_fab1_lib.crescent_city_bb_fab1(sch_1):\DEFAULT\" )
				( netClassRef "@sapphirecity_baseboard_lib.sapphirecity_baseboard(sch_1):\POWER\" )
				( netClassRef "@sapphirecity_baseboard_lib.sapphirecity_baseboard(sch_1):\DDR4_CHN_G_DQ_DQS_BYTE3\" )
			)
			( classClass "@crescent_city_bb_fab1_lib.crescent_city_bb_fab1(sch_1):\CC706\"
				( spacingCSetRef "@sapphirecity_baseboard_lib.sapphirecity_baseboard(sch_1):\DQ_TO_DQ\" )
				( netClassRef "@sapphirecity_baseboard_lib.sapphirecity_baseboard(sch_1):\DDR4_CHN_G_DQ_DQS_BYTE0\" )
				( netClassRef "@sapphirecity_baseboard_lib.sapphirecity_baseboard(sch_1):\DDR4_CHN_G_DQ_DQS_BYTE3\" )
			)
			( classClass "@crescent_city_bb_fab1_lib.crescent_city_bb_fab1(sch_1):\CC713\"
				( spacingCSetRef "@sapphirecity_baseboard_lib.sapphirecity_baseboard(sch_1):\DQ_TO_DQ\" )
				( netClassRef "@sapphirecity_baseboard_lib.sapphirecity_baseboard(sch_1):\DDR4_CHN_G_DQ_DQS_BYTE1\" )
				( netClassRef "@sapphirecity_baseboard_lib.sapphirecity_baseboard(sch_1):\DDR4_CHN_G_DQ_DQS_BYTE3\" )
			)
			( classClass "@crescent_city_bb_fab1_lib.crescent_city_bb_fab1(sch_1):\CC719\"
				( spacingCSetRef "@sapphirecity_baseboard_lib.sapphirecity_baseboard(sch_1):\DQ_TO_DQ\" )
				( netClassRef "@sapphirecity_baseboard_lib.sapphirecity_baseboard(sch_1):\DDR4_CHN_G_DQ_DQS_BYTE2\" )
				( netClassRef "@sapphirecity_baseboard_lib.sapphirecity_baseboard(sch_1):\DDR4_CHN_G_DQ_DQS_BYTE3\" )
			)
			( classClass "@sapphirecity_baseboard_lib.sapphirecity_baseboard(sch_1):\CC532\"
				( spacingCSetRef "@sapphirecity_baseboard_lib.sapphirecity_baseboard(sch_1):\DDR4_2SPC_DQ/DQS\" )
				( netClassRef "@sapphirecity_baseboard_lib.sapphirecity_baseboard(sch_1):\DDR4_CHN_G_DQ_DQS_BYTE2\" )
				( netClassRef "@sapphirecity_baseboard_lib.sapphirecity_baseboard(sch_1):\DDR4_CHN_G_DQ_DQS_BYTE2\" )
			)
			( classClass "@crescent_city_bb_fab1_lib.crescent_city_bb_fab1(sch_1):\CC309\"
				( spacingCSetRef "@sapphirecity_baseboard_lib.sapphirecity_baseboard(sch_1):\DQ_TO_DQ\" )
				( netClassRef "@sapphirecity_baseboard_lib.sapphirecity_baseboard(sch_1):\DDR4_CHN_G_CLK\" )
				( netClassRef "@sapphirecity_baseboard_lib.sapphirecity_baseboard(sch_1):\DDR4_CHN_G_DQ_DQS_BYTE2\" )
			)
			( classClass "@crescent_city_bb_fab1_lib.crescent_city_bb_fab1(sch_1):\CC319\"
				( spacingCSetRef "@sapphirecity_baseboard_lib.sapphirecity_baseboard(sch_1):\DQ_TO_DQ\" )
				( netClassRef "@sapphirecity_baseboard_lib.sapphirecity_baseboard(sch_1):\DDR4_CHN_G_CMD_ADD\" )
				( netClassRef "@sapphirecity_baseboard_lib.sapphirecity_baseboard(sch_1):\DDR4_CHN_G_DQ_DQS_BYTE2\" )
			)
			( classClass "@crescent_city_bb_fab1_lib.crescent_city_bb_fab1(sch_1):\CC329\"
				( spacingCSetRef "@sapphirecity_baseboard_lib.sapphirecity_baseboard(sch_1):\DQ_TO_DQ\" )
				( netClassRef "@sapphirecity_baseboard_lib.sapphirecity_baseboard(sch_1):\DDR4_CHN_G_CTRL\" )
				( netClassRef "@sapphirecity_baseboard_lib.sapphirecity_baseboard(sch_1):\DDR4_CHN_G_DQ_DQS_BYTE2\" )
			)
			( classClass "@crescent_city_bb_fab1_lib.crescent_city_bb_fab1(sch_1):\CC598\"
				( spacingCSetRef "@crescent_city_bb_fab1_lib.crescent_city_bb_fab1(sch_1):\DEFAULT\" )
				( netClassRef "@sapphirecity_baseboard_lib.sapphirecity_baseboard(sch_1):\GND\" )
				( netClassRef "@sapphirecity_baseboard_lib.sapphirecity_baseboard(sch_1):\DDR4_CHN_G_DQ_DQS_BYTE2\" )
			)
			( classClass "@crescent_city_bb_fab1_lib.crescent_city_bb_fab1(sch_1):\CC652\"
				( spacingCSetRef "@crescent_city_bb_fab1_lib.crescent_city_bb_fab1(sch_1):\DEFAULT\" )
				( netClassRef "@sapphirecity_baseboard_lib.sapphirecity_baseboard(sch_1):\POWER\" )
				( netClassRef "@sapphirecity_baseboard_lib.sapphirecity_baseboard(sch_1):\DDR4_CHN_G_DQ_DQS_BYTE2\" )
			)
			( classClass "@crescent_city_bb_fab1_lib.crescent_city_bb_fab1(sch_1):\CC705\"
				( spacingCSetRef "@sapphirecity_baseboard_lib.sapphirecity_baseboard(sch_1):\DQ_TO_DQ\" )
				( netClassRef "@sapphirecity_baseboard_lib.sapphirecity_baseboard(sch_1):\DDR4_CHN_G_DQ_DQS_BYTE0\" )
				( netClassRef "@sapphirecity_baseboard_lib.sapphirecity_baseboard(sch_1):\DDR4_CHN_G_DQ_DQS_BYTE2\" )
			)
			( classClass "@crescent_city_bb_fab1_lib.crescent_city_bb_fab1(sch_1):\CC712\"
				( spacingCSetRef "@sapphirecity_baseboard_lib.sapphirecity_baseboard(sch_1):\DQ_TO_DQ\" )
				( netClassRef "@sapphirecity_baseboard_lib.sapphirecity_baseboard(sch_1):\DDR4_CHN_G_DQ_DQS_BYTE1\" )
				( netClassRef "@sapphirecity_baseboard_lib.sapphirecity_baseboard(sch_1):\DDR4_CHN_G_DQ_DQS_BYTE2\" )
			)
			( classClass "@sapphirecity_baseboard_lib.sapphirecity_baseboard(sch_1):\CC531\"
				( spacingCSetRef "@sapphirecity_baseboard_lib.sapphirecity_baseboard(sch_1):\DDR4_2SPC_DQ/DQS\" )
				( netClassRef "@sapphirecity_baseboard_lib.sapphirecity_baseboard(sch_1):\DDR4_CHN_G_DQ_DQS_BYTE1\" )
				( netClassRef "@sapphirecity_baseboard_lib.sapphirecity_baseboard(sch_1):\DDR4_CHN_G_DQ_DQS_BYTE1\" )
			)
			( classClass "@crescent_city_bb_fab1_lib.crescent_city_bb_fab1(sch_1):\CC308\"
				( spacingCSetRef "@sapphirecity_baseboard_lib.sapphirecity_baseboard(sch_1):\DQ_TO_DQ\" )
				( netClassRef "@sapphirecity_baseboard_lib.sapphirecity_baseboard(sch_1):\DDR4_CHN_G_CLK\" )
				( netClassRef "@sapphirecity_baseboard_lib.sapphirecity_baseboard(sch_1):\DDR4_CHN_G_DQ_DQS_BYTE1\" )
			)
			( classClass "@crescent_city_bb_fab1_lib.crescent_city_bb_fab1(sch_1):\CC318\"
				( spacingCSetRef "@sapphirecity_baseboard_lib.sapphirecity_baseboard(sch_1):\DQ_TO_DQ\" )
				( netClassRef "@sapphirecity_baseboard_lib.sapphirecity_baseboard(sch_1):\DDR4_CHN_G_CMD_ADD\" )
				( netClassRef "@sapphirecity_baseboard_lib.sapphirecity_baseboard(sch_1):\DDR4_CHN_G_DQ_DQS_BYTE1\" )
			)
			( classClass "@crescent_city_bb_fab1_lib.crescent_city_bb_fab1(sch_1):\CC328\"
				( spacingCSetRef "@sapphirecity_baseboard_lib.sapphirecity_baseboard(sch_1):\DQ_TO_DQ\" )
				( netClassRef "@sapphirecity_baseboard_lib.sapphirecity_baseboard(sch_1):\DDR4_CHN_G_CTRL\" )
				( netClassRef "@sapphirecity_baseboard_lib.sapphirecity_baseboard(sch_1):\DDR4_CHN_G_DQ_DQS_BYTE1\" )
			)
			( classClass "@crescent_city_bb_fab1_lib.crescent_city_bb_fab1(sch_1):\CC597\"
				( spacingCSetRef "@crescent_city_bb_fab1_lib.crescent_city_bb_fab1(sch_1):\DEFAULT\" )
				( netClassRef "@sapphirecity_baseboard_lib.sapphirecity_baseboard(sch_1):\GND\" )
				( netClassRef "@sapphirecity_baseboard_lib.sapphirecity_baseboard(sch_1):\DDR4_CHN_G_DQ_DQS_BYTE1\" )
			)
			( classClass "@crescent_city_bb_fab1_lib.crescent_city_bb_fab1(sch_1):\CC651\"
				( spacingCSetRef "@crescent_city_bb_fab1_lib.crescent_city_bb_fab1(sch_1):\DEFAULT\" )
				( netClassRef "@sapphirecity_baseboard_lib.sapphirecity_baseboard(sch_1):\POWER\" )
				( netClassRef "@sapphirecity_baseboard_lib.sapphirecity_baseboard(sch_1):\DDR4_CHN_G_DQ_DQS_BYTE1\" )
			)
			( classClass "@crescent_city_bb_fab1_lib.crescent_city_bb_fab1(sch_1):\CC704\"
				( spacingCSetRef "@sapphirecity_baseboard_lib.sapphirecity_baseboard(sch_1):\DQ_TO_DQ\" )
				( netClassRef "@sapphirecity_baseboard_lib.sapphirecity_baseboard(sch_1):\DDR4_CHN_G_DQ_DQS_BYTE0\" )
				( netClassRef "@sapphirecity_baseboard_lib.sapphirecity_baseboard(sch_1):\DDR4_CHN_G_DQ_DQS_BYTE1\" )
			)
			( classClass "@sapphirecity_baseboard_lib.sapphirecity_baseboard(sch_1):\CC530\"
				( spacingCSetRef "@sapphirecity_baseboard_lib.sapphirecity_baseboard(sch_1):\DDR4_2SPC_DQ/DQS\" )
				( netClassRef "@sapphirecity_baseboard_lib.sapphirecity_baseboard(sch_1):\DDR4_CHN_G_DQ_DQS_BYTE0\" )
				( netClassRef "@sapphirecity_baseboard_lib.sapphirecity_baseboard(sch_1):\DDR4_CHN_G_DQ_DQS_BYTE0\" )
			)
			( classClass "@crescent_city_bb_fab1_lib.crescent_city_bb_fab1(sch_1):\CC307\"
				( spacingCSetRef "@sapphirecity_baseboard_lib.sapphirecity_baseboard(sch_1):\DQ_TO_DQ\" )
				( netClassRef "@sapphirecity_baseboard_lib.sapphirecity_baseboard(sch_1):\DDR4_CHN_G_CLK\" )
				( netClassRef "@sapphirecity_baseboard_lib.sapphirecity_baseboard(sch_1):\DDR4_CHN_G_DQ_DQS_BYTE0\" )
			)
			( classClass "@crescent_city_bb_fab1_lib.crescent_city_bb_fab1(sch_1):\CC317\"
				( spacingCSetRef "@sapphirecity_baseboard_lib.sapphirecity_baseboard(sch_1):\DQ_TO_DQ\" )
				( netClassRef "@sapphirecity_baseboard_lib.sapphirecity_baseboard(sch_1):\DDR4_CHN_G_CMD_ADD\" )
				( netClassRef "@sapphirecity_baseboard_lib.sapphirecity_baseboard(sch_1):\DDR4_CHN_G_DQ_DQS_BYTE0\" )
			)
			( classClass "@crescent_city_bb_fab1_lib.crescent_city_bb_fab1(sch_1):\CC327\"
				( spacingCSetRef "@sapphirecity_baseboard_lib.sapphirecity_baseboard(sch_1):\DQ_TO_DQ\" )
				( netClassRef "@sapphirecity_baseboard_lib.sapphirecity_baseboard(sch_1):\DDR4_CHN_G_CTRL\" )
				( netClassRef "@sapphirecity_baseboard_lib.sapphirecity_baseboard(sch_1):\DDR4_CHN_G_DQ_DQS_BYTE0\" )
			)
			( classClass "@crescent_city_bb_fab1_lib.crescent_city_bb_fab1(sch_1):\CC596\"
				( spacingCSetRef "@crescent_city_bb_fab1_lib.crescent_city_bb_fab1(sch_1):\DEFAULT\" )
				( netClassRef "@sapphirecity_baseboard_lib.sapphirecity_baseboard(sch_1):\GND\" )
				( netClassRef "@sapphirecity_baseboard_lib.sapphirecity_baseboard(sch_1):\DDR4_CHN_G_DQ_DQS_BYTE0\" )
			)
			( classClass "@crescent_city_bb_fab1_lib.crescent_city_bb_fab1(sch_1):\CC650\"
				( spacingCSetRef "@crescent_city_bb_fab1_lib.crescent_city_bb_fab1(sch_1):\DEFAULT\" )
				( netClassRef "@sapphirecity_baseboard_lib.sapphirecity_baseboard(sch_1):\POWER\" )
				( netClassRef "@sapphirecity_baseboard_lib.sapphirecity_baseboard(sch_1):\DDR4_CHN_G_DQ_DQS_BYTE0\" )
			)
			( classClass "@sapphirecity_baseboard_lib.sapphirecity_baseboard(sch_1):\CC242\"
				( spacingCSetRef "@crescent_city_bb_fab1_lib.crescent_city_bb_fab1(sch_1):\DEFAULT\" )
				( netClassRef "@sapphirecity_baseboard_lib.sapphirecity_baseboard(sch_1):\GND\" )
				( netClassRef "@sapphirecity_baseboard_lib.sapphirecity_baseboard(sch_1):\DDR4_CHN_G_CTRL\" )
			)
			( classClass "@sapphirecity_baseboard_lib.sapphirecity_baseboard(sch_1):\CC524\"
				( spacingCSetRef "@sapphirecity_baseboard_lib.sapphirecity_baseboard(sch_1):\DDR4_2SPC_CAC\" )
				( netClassRef "@sapphirecity_baseboard_lib.sapphirecity_baseboard(sch_1):\DDR4_CHN_G_CLK\" )
				( netClassRef "@sapphirecity_baseboard_lib.sapphirecity_baseboard(sch_1):\DDR4_CHN_G_CTRL\" )
			)
			( classClass "@sapphirecity_baseboard_lib.sapphirecity_baseboard(sch_1):\CC527\"
				( spacingCSetRef "@sapphirecity_baseboard_lib.sapphirecity_baseboard(sch_1):\DDR4_2SPC_CAC\" )
				( netClassRef "@sapphirecity_baseboard_lib.sapphirecity_baseboard(sch_1):\DDR4_CHN_G_CMD_ADD\" )
				( netClassRef "@sapphirecity_baseboard_lib.sapphirecity_baseboard(sch_1):\DDR4_CHN_G_CTRL\" )
			)
			( classClass "@sapphirecity_baseboard_lib.sapphirecity_baseboard(sch_1):\CC529\"
				( spacingCSetRef "@sapphirecity_baseboard_lib.sapphirecity_baseboard(sch_1):\DDR4_2SPC_CAC\" )
				( netClassRef "@sapphirecity_baseboard_lib.sapphirecity_baseboard(sch_1):\DDR4_CHN_G_CTRL\" )
				( netClassRef "@sapphirecity_baseboard_lib.sapphirecity_baseboard(sch_1):\DDR4_CHN_G_CTRL\" )
			)
			( classClass "@crescent_city_bb_fab1_lib.crescent_city_bb_fab1(sch_1):\CC336\"
				( spacingCSetRef "@crescent_city_bb_fab1_lib.crescent_city_bb_fab1(sch_1):\DEFAULT\" )
				( netClassRef "@sapphirecity_baseboard_lib.sapphirecity_baseboard(sch_1):\POWER\" )
				( netClassRef "@sapphirecity_baseboard_lib.sapphirecity_baseboard(sch_1):\DDR4_CHN_G_CTRL\" )
			)
			( classClass "@sapphirecity_baseboard_lib.sapphirecity_baseboard(sch_1):\CC241\"
				( spacingCSetRef "@crescent_city_bb_fab1_lib.crescent_city_bb_fab1(sch_1):\DEFAULT\" )
				( netClassRef "@sapphirecity_baseboard_lib.sapphirecity_baseboard(sch_1):\GND\" )
				( netClassRef "@sapphirecity_baseboard_lib.sapphirecity_baseboard(sch_1):\DDR4_CHN_G_CMD_ADD\" )
			)
			( classClass "@sapphirecity_baseboard_lib.sapphirecity_baseboard(sch_1):\CC525\"
				( spacingCSetRef "@sapphirecity_baseboard_lib.sapphirecity_baseboard(sch_1):\DDR4_2SPC_CAC\" )
				( netClassRef "@sapphirecity_baseboard_lib.sapphirecity_baseboard(sch_1):\DDR4_CHN_G_CLK\" )
				( netClassRef "@sapphirecity_baseboard_lib.sapphirecity_baseboard(sch_1):\DDR4_CHN_G_CMD_ADD\" )
			)
			( classClass "@sapphirecity_baseboard_lib.sapphirecity_baseboard(sch_1):\CC528\"
				( spacingCSetRef "@sapphirecity_baseboard_lib.sapphirecity_baseboard(sch_1):\DDR4_2SPC_CAC\" )
				( netClassRef "@sapphirecity_baseboard_lib.sapphirecity_baseboard(sch_1):\DDR4_CHN_G_CMD_ADD\" )
				( netClassRef "@sapphirecity_baseboard_lib.sapphirecity_baseboard(sch_1):\DDR4_CHN_G_CMD_ADD\" )
			)
			( classClass "@crescent_city_bb_fab1_lib.crescent_city_bb_fab1(sch_1):\CC326\"
				( spacingCSetRef "@crescent_city_bb_fab1_lib.crescent_city_bb_fab1(sch_1):\DEFAULT\" )
				( netClassRef "@sapphirecity_baseboard_lib.sapphirecity_baseboard(sch_1):\POWER\" )
				( netClassRef "@sapphirecity_baseboard_lib.sapphirecity_baseboard(sch_1):\DDR4_CHN_G_CMD_ADD\" )
			)
			( classClass "@sapphirecity_baseboard_lib.sapphirecity_baseboard(sch_1):\CC240\"
				( spacingCSetRef "@crescent_city_bb_fab1_lib.crescent_city_bb_fab1(sch_1):\DEFAULT\" )
				( netClassRef "@sapphirecity_baseboard_lib.sapphirecity_baseboard(sch_1):\GND\" )
				( netClassRef "@sapphirecity_baseboard_lib.sapphirecity_baseboard(sch_1):\DDR4_CHN_G_CLK\" )
			)
			( classClass "@sapphirecity_baseboard_lib.sapphirecity_baseboard(sch_1):\CC526\"
				( spacingCSetRef "@sapphirecity_baseboard_lib.sapphirecity_baseboard(sch_1):\DDR4_2SPC_CAC\" )
				( netClassRef "@sapphirecity_baseboard_lib.sapphirecity_baseboard(sch_1):\DDR4_CHN_G_CLK\" )
				( netClassRef "@sapphirecity_baseboard_lib.sapphirecity_baseboard(sch_1):\DDR4_CHN_G_CLK\" )
			)
			( classClass "@crescent_city_bb_fab1_lib.crescent_city_bb_fab1(sch_1):\CC316\"
				( spacingCSetRef "@crescent_city_bb_fab1_lib.crescent_city_bb_fab1(sch_1):\DEFAULT\" )
				( netClassRef "@sapphirecity_baseboard_lib.sapphirecity_baseboard(sch_1):\POWER\" )
				( netClassRef "@sapphirecity_baseboard_lib.sapphirecity_baseboard(sch_1):\DDR4_CHN_G_CLK\" )
			)
			( classClass "@sapphirecity_baseboard_lib.sapphirecity_baseboard(sch_1):\CC523\"
				( spacingCSetRef "@sapphirecity_baseboard_lib.sapphirecity_baseboard(sch_1):\DDR4_2SPC_DQ/DQS\" )
				( netClassRef "@sapphirecity_baseboard_lib.sapphirecity_baseboard(sch_1):\DDR4_CHN_F_ECC\" )
				( netClassRef "@sapphirecity_baseboard_lib.sapphirecity_baseboard(sch_1):\DDR4_CHN_F_ECC\" )
			)
			( classClass "@crescent_city_bb_fab1_lib.crescent_city_bb_fab1(sch_1):\CC229\"
				( spacingCSetRef "@sapphirecity_baseboard_lib.sapphirecity_baseboard(sch_1):\DQ_TO_DQ\" )
				( netClassRef "@sapphirecity_baseboard_lib.sapphirecity_baseboard(sch_1):\DDR4_CHN_F_DQ_DQS_BYTE0\" )
				( netClassRef "@sapphirecity_baseboard_lib.sapphirecity_baseboard(sch_1):\DDR4_CHN_F_ECC\" )
			)
			( classClass "@crescent_city_bb_fab1_lib.crescent_city_bb_fab1(sch_1):\CC240\"
				( spacingCSetRef "@sapphirecity_baseboard_lib.sapphirecity_baseboard(sch_1):\DQ_TO_DQ\" )
				( netClassRef "@sapphirecity_baseboard_lib.sapphirecity_baseboard(sch_1):\DDR4_CHN_F_DQ_DQS_BYTE1\" )
				( netClassRef "@sapphirecity_baseboard_lib.sapphirecity_baseboard(sch_1):\DDR4_CHN_F_ECC\" )
			)
			( classClass "@crescent_city_bb_fab1_lib.crescent_city_bb_fab1(sch_1):\CC250\"
				( spacingCSetRef "@sapphirecity_baseboard_lib.sapphirecity_baseboard(sch_1):\DQ_TO_DQ\" )
				( netClassRef "@sapphirecity_baseboard_lib.sapphirecity_baseboard(sch_1):\DDR4_CHN_F_DQ_DQS_BYTE2\" )
				( netClassRef "@sapphirecity_baseboard_lib.sapphirecity_baseboard(sch_1):\DDR4_CHN_F_ECC\" )
			)
			( classClass "@crescent_city_bb_fab1_lib.crescent_city_bb_fab1(sch_1):\CC259\"
				( spacingCSetRef "@sapphirecity_baseboard_lib.sapphirecity_baseboard(sch_1):\DQ_TO_DQ\" )
				( netClassRef "@sapphirecity_baseboard_lib.sapphirecity_baseboard(sch_1):\DDR4_CHN_F_DQ_DQS_BYTE3\" )
				( netClassRef "@sapphirecity_baseboard_lib.sapphirecity_baseboard(sch_1):\DDR4_CHN_F_ECC\" )
			)
			( classClass "@crescent_city_bb_fab1_lib.crescent_city_bb_fab1(sch_1):\CC267\"
				( spacingCSetRef "@sapphirecity_baseboard_lib.sapphirecity_baseboard(sch_1):\DQ_TO_DQ\" )
				( netClassRef "@sapphirecity_baseboard_lib.sapphirecity_baseboard(sch_1):\DDR4_CHN_F_DQ_DQS_BYTE4\" )
				( netClassRef "@sapphirecity_baseboard_lib.sapphirecity_baseboard(sch_1):\DDR4_CHN_F_ECC\" )
			)
			( classClass "@crescent_city_bb_fab1_lib.crescent_city_bb_fab1(sch_1):\CC274\"
				( spacingCSetRef "@sapphirecity_baseboard_lib.sapphirecity_baseboard(sch_1):\DQ_TO_DQ\" )
				( netClassRef "@sapphirecity_baseboard_lib.sapphirecity_baseboard(sch_1):\DDR4_CHN_F_DQ_DQS_BYTE5\" )
				( netClassRef "@sapphirecity_baseboard_lib.sapphirecity_baseboard(sch_1):\DDR4_CHN_F_ECC\" )
			)
			( classClass "@crescent_city_bb_fab1_lib.crescent_city_bb_fab1(sch_1):\CC280\"
				( spacingCSetRef "@sapphirecity_baseboard_lib.sapphirecity_baseboard(sch_1):\DQ_TO_DQ\" )
				( netClassRef "@sapphirecity_baseboard_lib.sapphirecity_baseboard(sch_1):\DDR4_CHN_F_DQ_DQS_BYTE6\" )
				( netClassRef "@sapphirecity_baseboard_lib.sapphirecity_baseboard(sch_1):\DDR4_CHN_F_ECC\" )
			)
			( classClass "@crescent_city_bb_fab1_lib.crescent_city_bb_fab1(sch_1):\CC285\"
				( spacingCSetRef "@sapphirecity_baseboard_lib.sapphirecity_baseboard(sch_1):\DQ_TO_DQ\" )
				( netClassRef "@sapphirecity_baseboard_lib.sapphirecity_baseboard(sch_1):\DDR4_CHN_F_DQ_DQS_BYTE7\" )
				( netClassRef "@sapphirecity_baseboard_lib.sapphirecity_baseboard(sch_1):\DDR4_CHN_F_ECC\" )
			)
			( classClass "@crescent_city_bb_fab1_lib.crescent_city_bb_fab1(sch_1):\CC287\"
				( spacingCSetRef "@sapphirecity_baseboard_lib.sapphirecity_baseboard(sch_1):\DQ_TO_DQ\" )
				( netClassRef "@sapphirecity_baseboard_lib.sapphirecity_baseboard(sch_1):\DDR4_CHN_F_CLK\" )
				( netClassRef "@sapphirecity_baseboard_lib.sapphirecity_baseboard(sch_1):\DDR4_CHN_F_ECC\" )
			)
			( classClass "@crescent_city_bb_fab1_lib.crescent_city_bb_fab1(sch_1):\CC288\"
				( spacingCSetRef "@sapphirecity_baseboard_lib.sapphirecity_baseboard(sch_1):\DQ_TO_DQ\" )
				( netClassRef "@sapphirecity_baseboard_lib.sapphirecity_baseboard(sch_1):\DDR4_CHN_F_CMD_ADD\" )
				( netClassRef "@sapphirecity_baseboard_lib.sapphirecity_baseboard(sch_1):\DDR4_CHN_F_ECC\" )
			)
			( classClass "@crescent_city_bb_fab1_lib.crescent_city_bb_fab1(sch_1):\CC289\"
				( spacingCSetRef "@sapphirecity_baseboard_lib.sapphirecity_baseboard(sch_1):\DQ_TO_DQ\" )
				( netClassRef "@sapphirecity_baseboard_lib.sapphirecity_baseboard(sch_1):\DDR4_CHN_F_CTRL\" )
				( netClassRef "@sapphirecity_baseboard_lib.sapphirecity_baseboard(sch_1):\DDR4_CHN_F_ECC\" )
			)
			( classClass "@crescent_city_bb_fab1_lib.crescent_city_bb_fab1(sch_1):\CC290\"
				( spacingCSetRef "@crescent_city_bb_fab1_lib.crescent_city_bb_fab1(sch_1):\DEFAULT\" )
				( netClassRef "@sapphirecity_baseboard_lib.sapphirecity_baseboard(sch_1):\GND\" )
				( netClassRef "@sapphirecity_baseboard_lib.sapphirecity_baseboard(sch_1):\DDR4_CHN_F_ECC\" )
			)
			( classClass "@crescent_city_bb_fab1_lib.crescent_city_bb_fab1(sch_1):\CC53\"
				( spacingCSetRef "@crescent_city_bb_fab1_lib.crescent_city_bb_fab1(sch_1):\DEFAULT\" )
				( netClassRef "@sapphirecity_baseboard_lib.sapphirecity_baseboard(sch_1):\POWER\" )
				( netClassRef "@sapphirecity_baseboard_lib.sapphirecity_baseboard(sch_1):\DDR4_CHN_F_ECC\" )
			)
			( classClass "@sapphirecity_baseboard_lib.sapphirecity_baseboard(sch_1):\CC522\"
				( spacingCSetRef "@sapphirecity_baseboard_lib.sapphirecity_baseboard(sch_1):\DDR4_2SPC_DQ/DQS\" )
				( netClassRef "@sapphirecity_baseboard_lib.sapphirecity_baseboard(sch_1):\DDR4_CHN_F_DQ_DQS_BYTE7\" )
				( netClassRef "@sapphirecity_baseboard_lib.sapphirecity_baseboard(sch_1):\DDR4_CHN_F_DQ_DQS_BYTE7\" )
			)
			( classClass "@crescent_city_bb_fab1_lib.crescent_city_bb_fab1(sch_1):\CC228\"
				( spacingCSetRef "@sapphirecity_baseboard_lib.sapphirecity_baseboard(sch_1):\DQ_TO_DQ\" )
				( netClassRef "@sapphirecity_baseboard_lib.sapphirecity_baseboard(sch_1):\DDR4_CHN_F_DQ_DQS_BYTE0\" )
				( netClassRef "@sapphirecity_baseboard_lib.sapphirecity_baseboard(sch_1):\DDR4_CHN_F_DQ_DQS_BYTE7\" )
			)
			( classClass "@crescent_city_bb_fab1_lib.crescent_city_bb_fab1(sch_1):\CC239\"
				( spacingCSetRef "@sapphirecity_baseboard_lib.sapphirecity_baseboard(sch_1):\DQ_TO_DQ\" )
				( netClassRef "@sapphirecity_baseboard_lib.sapphirecity_baseboard(sch_1):\DDR4_CHN_F_DQ_DQS_BYTE1\" )
				( netClassRef "@sapphirecity_baseboard_lib.sapphirecity_baseboard(sch_1):\DDR4_CHN_F_DQ_DQS_BYTE7\" )
			)
			( classClass "@crescent_city_bb_fab1_lib.crescent_city_bb_fab1(sch_1):\CC249\"
				( spacingCSetRef "@sapphirecity_baseboard_lib.sapphirecity_baseboard(sch_1):\DQ_TO_DQ\" )
				( netClassRef "@sapphirecity_baseboard_lib.sapphirecity_baseboard(sch_1):\DDR4_CHN_F_DQ_DQS_BYTE2\" )
				( netClassRef "@sapphirecity_baseboard_lib.sapphirecity_baseboard(sch_1):\DDR4_CHN_F_DQ_DQS_BYTE7\" )
			)
			( classClass "@crescent_city_bb_fab1_lib.crescent_city_bb_fab1(sch_1):\CC258\"
				( spacingCSetRef "@sapphirecity_baseboard_lib.sapphirecity_baseboard(sch_1):\DQ_TO_DQ\" )
				( netClassRef "@sapphirecity_baseboard_lib.sapphirecity_baseboard(sch_1):\DDR4_CHN_F_DQ_DQS_BYTE3\" )
				( netClassRef "@sapphirecity_baseboard_lib.sapphirecity_baseboard(sch_1):\DDR4_CHN_F_DQ_DQS_BYTE7\" )
			)
			( classClass "@crescent_city_bb_fab1_lib.crescent_city_bb_fab1(sch_1):\CC266\"
				( spacingCSetRef "@sapphirecity_baseboard_lib.sapphirecity_baseboard(sch_1):\DQ_TO_DQ\" )
				( netClassRef "@sapphirecity_baseboard_lib.sapphirecity_baseboard(sch_1):\DDR4_CHN_F_DQ_DQS_BYTE4\" )
				( netClassRef "@sapphirecity_baseboard_lib.sapphirecity_baseboard(sch_1):\DDR4_CHN_F_DQ_DQS_BYTE7\" )
			)
			( classClass "@crescent_city_bb_fab1_lib.crescent_city_bb_fab1(sch_1):\CC273\"
				( spacingCSetRef "@sapphirecity_baseboard_lib.sapphirecity_baseboard(sch_1):\DQ_TO_DQ\" )
				( netClassRef "@sapphirecity_baseboard_lib.sapphirecity_baseboard(sch_1):\DDR4_CHN_F_DQ_DQS_BYTE5\" )
				( netClassRef "@sapphirecity_baseboard_lib.sapphirecity_baseboard(sch_1):\DDR4_CHN_F_DQ_DQS_BYTE7\" )
			)
			( classClass "@crescent_city_bb_fab1_lib.crescent_city_bb_fab1(sch_1):\CC279\"
				( spacingCSetRef "@sapphirecity_baseboard_lib.sapphirecity_baseboard(sch_1):\DQ_TO_DQ\" )
				( netClassRef "@sapphirecity_baseboard_lib.sapphirecity_baseboard(sch_1):\DDR4_CHN_F_DQ_DQS_BYTE6\" )
				( netClassRef "@sapphirecity_baseboard_lib.sapphirecity_baseboard(sch_1):\DDR4_CHN_F_DQ_DQS_BYTE7\" )
			)
			( classClass "@crescent_city_bb_fab1_lib.crescent_city_bb_fab1(sch_1):\CC282\"
				( spacingCSetRef "@sapphirecity_baseboard_lib.sapphirecity_baseboard(sch_1):\DQ_TO_DQ\" )
				( netClassRef "@sapphirecity_baseboard_lib.sapphirecity_baseboard(sch_1):\DDR4_CHN_F_CLK\" )
				( netClassRef "@sapphirecity_baseboard_lib.sapphirecity_baseboard(sch_1):\DDR4_CHN_F_DQ_DQS_BYTE7\" )
			)
			( classClass "@crescent_city_bb_fab1_lib.crescent_city_bb_fab1(sch_1):\CC283\"
				( spacingCSetRef "@sapphirecity_baseboard_lib.sapphirecity_baseboard(sch_1):\DQ_TO_DQ\" )
				( netClassRef "@sapphirecity_baseboard_lib.sapphirecity_baseboard(sch_1):\DDR4_CHN_F_CMD_ADD\" )
				( netClassRef "@sapphirecity_baseboard_lib.sapphirecity_baseboard(sch_1):\DDR4_CHN_F_DQ_DQS_BYTE7\" )
			)
			( classClass "@crescent_city_bb_fab1_lib.crescent_city_bb_fab1(sch_1):\CC284\"
				( spacingCSetRef "@sapphirecity_baseboard_lib.sapphirecity_baseboard(sch_1):\DQ_TO_DQ\" )
				( netClassRef "@sapphirecity_baseboard_lib.sapphirecity_baseboard(sch_1):\DDR4_CHN_F_CTRL\" )
				( netClassRef "@sapphirecity_baseboard_lib.sapphirecity_baseboard(sch_1):\DDR4_CHN_F_DQ_DQS_BYTE7\" )
			)
			( classClass "@crescent_city_bb_fab1_lib.crescent_city_bb_fab1(sch_1):\CC286\"
				( spacingCSetRef "@crescent_city_bb_fab1_lib.crescent_city_bb_fab1(sch_1):\DEFAULT\" )
				( netClassRef "@sapphirecity_baseboard_lib.sapphirecity_baseboard(sch_1):\GND\" )
				( netClassRef "@sapphirecity_baseboard_lib.sapphirecity_baseboard(sch_1):\DDR4_CHN_F_DQ_DQS_BYTE7\" )
			)
			( classClass "@crescent_city_bb_fab1_lib.crescent_city_bb_fab1(sch_1):\CC52\"
				( spacingCSetRef "@crescent_city_bb_fab1_lib.crescent_city_bb_fab1(sch_1):\DEFAULT\" )
				( netClassRef "@sapphirecity_baseboard_lib.sapphirecity_baseboard(sch_1):\POWER\" )
				( netClassRef "@sapphirecity_baseboard_lib.sapphirecity_baseboard(sch_1):\DDR4_CHN_F_DQ_DQS_BYTE7\" )
			)
			( classClass "@sapphirecity_baseboard_lib.sapphirecity_baseboard(sch_1):\CC521\"
				( spacingCSetRef "@sapphirecity_baseboard_lib.sapphirecity_baseboard(sch_1):\DDR4_2SPC_DQ/DQS\" )
				( netClassRef "@sapphirecity_baseboard_lib.sapphirecity_baseboard(sch_1):\DDR4_CHN_F_DQ_DQS_BYTE6\" )
				( netClassRef "@sapphirecity_baseboard_lib.sapphirecity_baseboard(sch_1):\DDR4_CHN_F_DQ_DQS_BYTE6\" )
			)
			( classClass "@crescent_city_bb_fab1_lib.crescent_city_bb_fab1(sch_1):\CC227\"
				( spacingCSetRef "@sapphirecity_baseboard_lib.sapphirecity_baseboard(sch_1):\DQ_TO_DQ\" )
				( netClassRef "@sapphirecity_baseboard_lib.sapphirecity_baseboard(sch_1):\DDR4_CHN_F_DQ_DQS_BYTE0\" )
				( netClassRef "@sapphirecity_baseboard_lib.sapphirecity_baseboard(sch_1):\DDR4_CHN_F_DQ_DQS_BYTE6\" )
			)
			( classClass "@crescent_city_bb_fab1_lib.crescent_city_bb_fab1(sch_1):\CC238\"
				( spacingCSetRef "@sapphirecity_baseboard_lib.sapphirecity_baseboard(sch_1):\DQ_TO_DQ\" )
				( netClassRef "@sapphirecity_baseboard_lib.sapphirecity_baseboard(sch_1):\DDR4_CHN_F_DQ_DQS_BYTE1\" )
				( netClassRef "@sapphirecity_baseboard_lib.sapphirecity_baseboard(sch_1):\DDR4_CHN_F_DQ_DQS_BYTE6\" )
			)
			( classClass "@crescent_city_bb_fab1_lib.crescent_city_bb_fab1(sch_1):\CC248\"
				( spacingCSetRef "@sapphirecity_baseboard_lib.sapphirecity_baseboard(sch_1):\DQ_TO_DQ\" )
				( netClassRef "@sapphirecity_baseboard_lib.sapphirecity_baseboard(sch_1):\DDR4_CHN_F_DQ_DQS_BYTE2\" )
				( netClassRef "@sapphirecity_baseboard_lib.sapphirecity_baseboard(sch_1):\DDR4_CHN_F_DQ_DQS_BYTE6\" )
			)
			( classClass "@crescent_city_bb_fab1_lib.crescent_city_bb_fab1(sch_1):\CC257\"
				( spacingCSetRef "@sapphirecity_baseboard_lib.sapphirecity_baseboard(sch_1):\DQ_TO_DQ\" )
				( netClassRef "@sapphirecity_baseboard_lib.sapphirecity_baseboard(sch_1):\DDR4_CHN_F_DQ_DQS_BYTE3\" )
				( netClassRef "@sapphirecity_baseboard_lib.sapphirecity_baseboard(sch_1):\DDR4_CHN_F_DQ_DQS_BYTE6\" )
			)
			( classClass "@crescent_city_bb_fab1_lib.crescent_city_bb_fab1(sch_1):\CC265\"
				( spacingCSetRef "@sapphirecity_baseboard_lib.sapphirecity_baseboard(sch_1):\DQ_TO_DQ\" )
				( netClassRef "@sapphirecity_baseboard_lib.sapphirecity_baseboard(sch_1):\DDR4_CHN_F_DQ_DQS_BYTE4\" )
				( netClassRef "@sapphirecity_baseboard_lib.sapphirecity_baseboard(sch_1):\DDR4_CHN_F_DQ_DQS_BYTE6\" )
			)
			( classClass "@crescent_city_bb_fab1_lib.crescent_city_bb_fab1(sch_1):\CC272\"
				( spacingCSetRef "@sapphirecity_baseboard_lib.sapphirecity_baseboard(sch_1):\DQ_TO_DQ\" )
				( netClassRef "@sapphirecity_baseboard_lib.sapphirecity_baseboard(sch_1):\DDR4_CHN_F_DQ_DQS_BYTE5\" )
				( netClassRef "@sapphirecity_baseboard_lib.sapphirecity_baseboard(sch_1):\DDR4_CHN_F_DQ_DQS_BYTE6\" )
			)
			( classClass "@crescent_city_bb_fab1_lib.crescent_city_bb_fab1(sch_1):\CC276\"
				( spacingCSetRef "@sapphirecity_baseboard_lib.sapphirecity_baseboard(sch_1):\DQ_TO_DQ\" )
				( netClassRef "@sapphirecity_baseboard_lib.sapphirecity_baseboard(sch_1):\DDR4_CHN_F_CLK\" )
				( netClassRef "@sapphirecity_baseboard_lib.sapphirecity_baseboard(sch_1):\DDR4_CHN_F_DQ_DQS_BYTE6\" )
			)
			( classClass "@crescent_city_bb_fab1_lib.crescent_city_bb_fab1(sch_1):\CC277\"
				( spacingCSetRef "@sapphirecity_baseboard_lib.sapphirecity_baseboard(sch_1):\DQ_TO_DQ\" )
				( netClassRef "@sapphirecity_baseboard_lib.sapphirecity_baseboard(sch_1):\DDR4_CHN_F_CMD_ADD\" )
				( netClassRef "@sapphirecity_baseboard_lib.sapphirecity_baseboard(sch_1):\DDR4_CHN_F_DQ_DQS_BYTE6\" )
			)
			( classClass "@crescent_city_bb_fab1_lib.crescent_city_bb_fab1(sch_1):\CC278\"
				( spacingCSetRef "@sapphirecity_baseboard_lib.sapphirecity_baseboard(sch_1):\DQ_TO_DQ\" )
				( netClassRef "@sapphirecity_baseboard_lib.sapphirecity_baseboard(sch_1):\DDR4_CHN_F_CTRL\" )
				( netClassRef "@sapphirecity_baseboard_lib.sapphirecity_baseboard(sch_1):\DDR4_CHN_F_DQ_DQS_BYTE6\" )
			)
			( classClass "@crescent_city_bb_fab1_lib.crescent_city_bb_fab1(sch_1):\CC281\"
				( spacingCSetRef "@crescent_city_bb_fab1_lib.crescent_city_bb_fab1(sch_1):\DEFAULT\" )
				( netClassRef "@sapphirecity_baseboard_lib.sapphirecity_baseboard(sch_1):\GND\" )
				( netClassRef "@sapphirecity_baseboard_lib.sapphirecity_baseboard(sch_1):\DDR4_CHN_F_DQ_DQS_BYTE6\" )
			)
			( classClass "@crescent_city_bb_fab1_lib.crescent_city_bb_fab1(sch_1):\CC51\"
				( spacingCSetRef "@crescent_city_bb_fab1_lib.crescent_city_bb_fab1(sch_1):\DEFAULT\" )
				( netClassRef "@sapphirecity_baseboard_lib.sapphirecity_baseboard(sch_1):\POWER\" )
				( netClassRef "@sapphirecity_baseboard_lib.sapphirecity_baseboard(sch_1):\DDR4_CHN_F_DQ_DQS_BYTE6\" )
			)
			( classClass "@sapphirecity_baseboard_lib.sapphirecity_baseboard(sch_1):\CC520\"
				( spacingCSetRef "@sapphirecity_baseboard_lib.sapphirecity_baseboard(sch_1):\DDR4_2SPC_DQ/DQS\" )
				( netClassRef "@sapphirecity_baseboard_lib.sapphirecity_baseboard(sch_1):\DDR4_CHN_F_DQ_DQS_BYTE5\" )
				( netClassRef "@sapphirecity_baseboard_lib.sapphirecity_baseboard(sch_1):\DDR4_CHN_F_DQ_DQS_BYTE5\" )
			)
			( classClass "@crescent_city_bb_fab1_lib.crescent_city_bb_fab1(sch_1):\CC226\"
				( spacingCSetRef "@sapphirecity_baseboard_lib.sapphirecity_baseboard(sch_1):\DQ_TO_DQ\" )
				( netClassRef "@sapphirecity_baseboard_lib.sapphirecity_baseboard(sch_1):\DDR4_CHN_F_DQ_DQS_BYTE0\" )
				( netClassRef "@sapphirecity_baseboard_lib.sapphirecity_baseboard(sch_1):\DDR4_CHN_F_DQ_DQS_BYTE5\" )
			)
			( classClass "@crescent_city_bb_fab1_lib.crescent_city_bb_fab1(sch_1):\CC237\"
				( spacingCSetRef "@sapphirecity_baseboard_lib.sapphirecity_baseboard(sch_1):\DQ_TO_DQ\" )
				( netClassRef "@sapphirecity_baseboard_lib.sapphirecity_baseboard(sch_1):\DDR4_CHN_F_DQ_DQS_BYTE1\" )
				( netClassRef "@sapphirecity_baseboard_lib.sapphirecity_baseboard(sch_1):\DDR4_CHN_F_DQ_DQS_BYTE5\" )
			)
			( classClass "@crescent_city_bb_fab1_lib.crescent_city_bb_fab1(sch_1):\CC247\"
				( spacingCSetRef "@sapphirecity_baseboard_lib.sapphirecity_baseboard(sch_1):\DQ_TO_DQ\" )
				( netClassRef "@sapphirecity_baseboard_lib.sapphirecity_baseboard(sch_1):\DDR4_CHN_F_DQ_DQS_BYTE2\" )
				( netClassRef "@sapphirecity_baseboard_lib.sapphirecity_baseboard(sch_1):\DDR4_CHN_F_DQ_DQS_BYTE5\" )
			)
			( classClass "@crescent_city_bb_fab1_lib.crescent_city_bb_fab1(sch_1):\CC256\"
				( spacingCSetRef "@sapphirecity_baseboard_lib.sapphirecity_baseboard(sch_1):\DQ_TO_DQ\" )
				( netClassRef "@sapphirecity_baseboard_lib.sapphirecity_baseboard(sch_1):\DDR4_CHN_F_DQ_DQS_BYTE3\" )
				( netClassRef "@sapphirecity_baseboard_lib.sapphirecity_baseboard(sch_1):\DDR4_CHN_F_DQ_DQS_BYTE5\" )
			)
			( classClass "@crescent_city_bb_fab1_lib.crescent_city_bb_fab1(sch_1):\CC264\"
				( spacingCSetRef "@sapphirecity_baseboard_lib.sapphirecity_baseboard(sch_1):\DQ_TO_DQ\" )
				( netClassRef "@sapphirecity_baseboard_lib.sapphirecity_baseboard(sch_1):\DDR4_CHN_F_DQ_DQS_BYTE4\" )
				( netClassRef "@sapphirecity_baseboard_lib.sapphirecity_baseboard(sch_1):\DDR4_CHN_F_DQ_DQS_BYTE5\" )
			)
			( classClass "@crescent_city_bb_fab1_lib.crescent_city_bb_fab1(sch_1):\CC269\"
				( spacingCSetRef "@sapphirecity_baseboard_lib.sapphirecity_baseboard(sch_1):\DQ_TO_DQ\" )
				( netClassRef "@sapphirecity_baseboard_lib.sapphirecity_baseboard(sch_1):\DDR4_CHN_F_CLK\" )
				( netClassRef "@sapphirecity_baseboard_lib.sapphirecity_baseboard(sch_1):\DDR4_CHN_F_DQ_DQS_BYTE5\" )
			)
			( classClass "@crescent_city_bb_fab1_lib.crescent_city_bb_fab1(sch_1):\CC270\"
				( spacingCSetRef "@sapphirecity_baseboard_lib.sapphirecity_baseboard(sch_1):\DQ_TO_DQ\" )
				( netClassRef "@sapphirecity_baseboard_lib.sapphirecity_baseboard(sch_1):\DDR4_CHN_F_CMD_ADD\" )
				( netClassRef "@sapphirecity_baseboard_lib.sapphirecity_baseboard(sch_1):\DDR4_CHN_F_DQ_DQS_BYTE5\" )
			)
			( classClass "@crescent_city_bb_fab1_lib.crescent_city_bb_fab1(sch_1):\CC271\"
				( spacingCSetRef "@sapphirecity_baseboard_lib.sapphirecity_baseboard(sch_1):\DQ_TO_DQ\" )
				( netClassRef "@sapphirecity_baseboard_lib.sapphirecity_baseboard(sch_1):\DDR4_CHN_F_CTRL\" )
				( netClassRef "@sapphirecity_baseboard_lib.sapphirecity_baseboard(sch_1):\DDR4_CHN_F_DQ_DQS_BYTE5\" )
			)
			( classClass "@crescent_city_bb_fab1_lib.crescent_city_bb_fab1(sch_1):\CC275\"
				( spacingCSetRef "@crescent_city_bb_fab1_lib.crescent_city_bb_fab1(sch_1):\DEFAULT\" )
				( netClassRef "@sapphirecity_baseboard_lib.sapphirecity_baseboard(sch_1):\GND\" )
				( netClassRef "@sapphirecity_baseboard_lib.sapphirecity_baseboard(sch_1):\DDR4_CHN_F_DQ_DQS_BYTE5\" )
			)
			( classClass "@crescent_city_bb_fab1_lib.crescent_city_bb_fab1(sch_1):\CC50\"
				( spacingCSetRef "@crescent_city_bb_fab1_lib.crescent_city_bb_fab1(sch_1):\DEFAULT\" )
				( netClassRef "@sapphirecity_baseboard_lib.sapphirecity_baseboard(sch_1):\POWER\" )
				( netClassRef "@sapphirecity_baseboard_lib.sapphirecity_baseboard(sch_1):\DDR4_CHN_F_DQ_DQS_BYTE5\" )
			)
			( classClass "@sapphirecity_baseboard_lib.sapphirecity_baseboard(sch_1):\CC519\"
				( spacingCSetRef "@sapphirecity_baseboard_lib.sapphirecity_baseboard(sch_1):\DDR4_2SPC_DQ/DQS\" )
				( netClassRef "@sapphirecity_baseboard_lib.sapphirecity_baseboard(sch_1):\DDR4_CHN_F_DQ_DQS_BYTE4\" )
				( netClassRef "@sapphirecity_baseboard_lib.sapphirecity_baseboard(sch_1):\DDR4_CHN_F_DQ_DQS_BYTE4\" )
			)
			( classClass "@crescent_city_bb_fab1_lib.crescent_city_bb_fab1(sch_1):\CC225\"
				( spacingCSetRef "@sapphirecity_baseboard_lib.sapphirecity_baseboard(sch_1):\DQ_TO_DQ\" )
				( netClassRef "@sapphirecity_baseboard_lib.sapphirecity_baseboard(sch_1):\DDR4_CHN_F_DQ_DQS_BYTE0\" )
				( netClassRef "@sapphirecity_baseboard_lib.sapphirecity_baseboard(sch_1):\DDR4_CHN_F_DQ_DQS_BYTE4\" )
			)
			( classClass "@crescent_city_bb_fab1_lib.crescent_city_bb_fab1(sch_1):\CC236\"
				( spacingCSetRef "@sapphirecity_baseboard_lib.sapphirecity_baseboard(sch_1):\DQ_TO_DQ\" )
				( netClassRef "@sapphirecity_baseboard_lib.sapphirecity_baseboard(sch_1):\DDR4_CHN_F_DQ_DQS_BYTE1\" )
				( netClassRef "@sapphirecity_baseboard_lib.sapphirecity_baseboard(sch_1):\DDR4_CHN_F_DQ_DQS_BYTE4\" )
			)
			( classClass "@crescent_city_bb_fab1_lib.crescent_city_bb_fab1(sch_1):\CC246\"
				( spacingCSetRef "@sapphirecity_baseboard_lib.sapphirecity_baseboard(sch_1):\DQ_TO_DQ\" )
				( netClassRef "@sapphirecity_baseboard_lib.sapphirecity_baseboard(sch_1):\DDR4_CHN_F_DQ_DQS_BYTE2\" )
				( netClassRef "@sapphirecity_baseboard_lib.sapphirecity_baseboard(sch_1):\DDR4_CHN_F_DQ_DQS_BYTE4\" )
			)
			( classClass "@crescent_city_bb_fab1_lib.crescent_city_bb_fab1(sch_1):\CC255\"
				( spacingCSetRef "@sapphirecity_baseboard_lib.sapphirecity_baseboard(sch_1):\DQ_TO_DQ\" )
				( netClassRef "@sapphirecity_baseboard_lib.sapphirecity_baseboard(sch_1):\DDR4_CHN_F_DQ_DQS_BYTE3\" )
				( netClassRef "@sapphirecity_baseboard_lib.sapphirecity_baseboard(sch_1):\DDR4_CHN_F_DQ_DQS_BYTE4\" )
			)
			( classClass "@crescent_city_bb_fab1_lib.crescent_city_bb_fab1(sch_1):\CC261\"
				( spacingCSetRef "@sapphirecity_baseboard_lib.sapphirecity_baseboard(sch_1):\DQ_TO_DQ\" )
				( netClassRef "@sapphirecity_baseboard_lib.sapphirecity_baseboard(sch_1):\DDR4_CHN_F_CLK\" )
				( netClassRef "@sapphirecity_baseboard_lib.sapphirecity_baseboard(sch_1):\DDR4_CHN_F_DQ_DQS_BYTE4\" )
			)
			( classClass "@crescent_city_bb_fab1_lib.crescent_city_bb_fab1(sch_1):\CC262\"
				( spacingCSetRef "@sapphirecity_baseboard_lib.sapphirecity_baseboard(sch_1):\DQ_TO_DQ\" )
				( netClassRef "@sapphirecity_baseboard_lib.sapphirecity_baseboard(sch_1):\DDR4_CHN_F_CMD_ADD\" )
				( netClassRef "@sapphirecity_baseboard_lib.sapphirecity_baseboard(sch_1):\DDR4_CHN_F_DQ_DQS_BYTE4\" )
			)
			( classClass "@crescent_city_bb_fab1_lib.crescent_city_bb_fab1(sch_1):\CC263\"
				( spacingCSetRef "@sapphirecity_baseboard_lib.sapphirecity_baseboard(sch_1):\DQ_TO_DQ\" )
				( netClassRef "@sapphirecity_baseboard_lib.sapphirecity_baseboard(sch_1):\DDR4_CHN_F_CTRL\" )
				( netClassRef "@sapphirecity_baseboard_lib.sapphirecity_baseboard(sch_1):\DDR4_CHN_F_DQ_DQS_BYTE4\" )
			)
			( classClass "@crescent_city_bb_fab1_lib.crescent_city_bb_fab1(sch_1):\CC268\"
				( spacingCSetRef "@crescent_city_bb_fab1_lib.crescent_city_bb_fab1(sch_1):\DEFAULT\" )
				( netClassRef "@sapphirecity_baseboard_lib.sapphirecity_baseboard(sch_1):\GND\" )
				( netClassRef "@sapphirecity_baseboard_lib.sapphirecity_baseboard(sch_1):\DDR4_CHN_F_DQ_DQS_BYTE4\" )
			)
			( classClass "@crescent_city_bb_fab1_lib.crescent_city_bb_fab1(sch_1):\CC49\"
				( spacingCSetRef "@crescent_city_bb_fab1_lib.crescent_city_bb_fab1(sch_1):\DEFAULT\" )
				( netClassRef "@sapphirecity_baseboard_lib.sapphirecity_baseboard(sch_1):\POWER\" )
				( netClassRef "@sapphirecity_baseboard_lib.sapphirecity_baseboard(sch_1):\DDR4_CHN_F_DQ_DQS_BYTE4\" )
			)
			( classClass "@sapphirecity_baseboard_lib.sapphirecity_baseboard(sch_1):\CC518\"
				( spacingCSetRef "@sapphirecity_baseboard_lib.sapphirecity_baseboard(sch_1):\DDR4_2SPC_DQ/DQS\" )
				( netClassRef "@sapphirecity_baseboard_lib.sapphirecity_baseboard(sch_1):\DDR4_CHN_F_DQ_DQS_BYTE3\" )
				( netClassRef "@sapphirecity_baseboard_lib.sapphirecity_baseboard(sch_1):\DDR4_CHN_F_DQ_DQS_BYTE3\" )
			)
			( classClass "@crescent_city_bb_fab1_lib.crescent_city_bb_fab1(sch_1):\CC224\"
				( spacingCSetRef "@sapphirecity_baseboard_lib.sapphirecity_baseboard(sch_1):\DQ_TO_DQ\" )
				( netClassRef "@sapphirecity_baseboard_lib.sapphirecity_baseboard(sch_1):\DDR4_CHN_F_DQ_DQS_BYTE0\" )
				( netClassRef "@sapphirecity_baseboard_lib.sapphirecity_baseboard(sch_1):\DDR4_CHN_F_DQ_DQS_BYTE3\" )
			)
			( classClass "@crescent_city_bb_fab1_lib.crescent_city_bb_fab1(sch_1):\CC235\"
				( spacingCSetRef "@sapphirecity_baseboard_lib.sapphirecity_baseboard(sch_1):\DQ_TO_DQ\" )
				( netClassRef "@sapphirecity_baseboard_lib.sapphirecity_baseboard(sch_1):\DDR4_CHN_F_DQ_DQS_BYTE1\" )
				( netClassRef "@sapphirecity_baseboard_lib.sapphirecity_baseboard(sch_1):\DDR4_CHN_F_DQ_DQS_BYTE3\" )
			)
			( classClass "@crescent_city_bb_fab1_lib.crescent_city_bb_fab1(sch_1):\CC245\"
				( spacingCSetRef "@sapphirecity_baseboard_lib.sapphirecity_baseboard(sch_1):\DQ_TO_DQ\" )
				( netClassRef "@sapphirecity_baseboard_lib.sapphirecity_baseboard(sch_1):\DDR4_CHN_F_DQ_DQS_BYTE2\" )
				( netClassRef "@sapphirecity_baseboard_lib.sapphirecity_baseboard(sch_1):\DDR4_CHN_F_DQ_DQS_BYTE3\" )
			)
			( classClass "@crescent_city_bb_fab1_lib.crescent_city_bb_fab1(sch_1):\CC252\"
				( spacingCSetRef "@sapphirecity_baseboard_lib.sapphirecity_baseboard(sch_1):\DQ_TO_DQ\" )
				( netClassRef "@sapphirecity_baseboard_lib.sapphirecity_baseboard(sch_1):\DDR4_CHN_F_CLK\" )
				( netClassRef "@sapphirecity_baseboard_lib.sapphirecity_baseboard(sch_1):\DDR4_CHN_F_DQ_DQS_BYTE3\" )
			)
			( classClass "@crescent_city_bb_fab1_lib.crescent_city_bb_fab1(sch_1):\CC253\"
				( spacingCSetRef "@sapphirecity_baseboard_lib.sapphirecity_baseboard(sch_1):\DQ_TO_DQ\" )
				( netClassRef "@sapphirecity_baseboard_lib.sapphirecity_baseboard(sch_1):\DDR4_CHN_F_CMD_ADD\" )
				( netClassRef "@sapphirecity_baseboard_lib.sapphirecity_baseboard(sch_1):\DDR4_CHN_F_DQ_DQS_BYTE3\" )
			)
			( classClass "@crescent_city_bb_fab1_lib.crescent_city_bb_fab1(sch_1):\CC254\"
				( spacingCSetRef "@sapphirecity_baseboard_lib.sapphirecity_baseboard(sch_1):\DQ_TO_DQ\" )
				( netClassRef "@sapphirecity_baseboard_lib.sapphirecity_baseboard(sch_1):\DDR4_CHN_F_CTRL\" )
				( netClassRef "@sapphirecity_baseboard_lib.sapphirecity_baseboard(sch_1):\DDR4_CHN_F_DQ_DQS_BYTE3\" )
			)
			( classClass "@crescent_city_bb_fab1_lib.crescent_city_bb_fab1(sch_1):\CC260\"
				( spacingCSetRef "@crescent_city_bb_fab1_lib.crescent_city_bb_fab1(sch_1):\DEFAULT\" )
				( netClassRef "@sapphirecity_baseboard_lib.sapphirecity_baseboard(sch_1):\GND\" )
				( netClassRef "@sapphirecity_baseboard_lib.sapphirecity_baseboard(sch_1):\DDR4_CHN_F_DQ_DQS_BYTE3\" )
			)
			( classClass "@crescent_city_bb_fab1_lib.crescent_city_bb_fab1(sch_1):\CC48\"
				( spacingCSetRef "@crescent_city_bb_fab1_lib.crescent_city_bb_fab1(sch_1):\DEFAULT\" )
				( netClassRef "@sapphirecity_baseboard_lib.sapphirecity_baseboard(sch_1):\POWER\" )
				( netClassRef "@sapphirecity_baseboard_lib.sapphirecity_baseboard(sch_1):\DDR4_CHN_F_DQ_DQS_BYTE3\" )
			)
			( classClass "@sapphirecity_baseboard_lib.sapphirecity_baseboard(sch_1):\CC517\"
				( spacingCSetRef "@sapphirecity_baseboard_lib.sapphirecity_baseboard(sch_1):\DDR4_2SPC_DQ/DQS\" )
				( netClassRef "@sapphirecity_baseboard_lib.sapphirecity_baseboard(sch_1):\DDR4_CHN_F_DQ_DQS_BYTE2\" )
				( netClassRef "@sapphirecity_baseboard_lib.sapphirecity_baseboard(sch_1):\DDR4_CHN_F_DQ_DQS_BYTE2\" )
			)
			( classClass "@crescent_city_bb_fab1_lib.crescent_city_bb_fab1(sch_1):\CC223\"
				( spacingCSetRef "@sapphirecity_baseboard_lib.sapphirecity_baseboard(sch_1):\DQ_TO_DQ\" )
				( netClassRef "@sapphirecity_baseboard_lib.sapphirecity_baseboard(sch_1):\DDR4_CHN_F_DQ_DQS_BYTE0\" )
				( netClassRef "@sapphirecity_baseboard_lib.sapphirecity_baseboard(sch_1):\DDR4_CHN_F_DQ_DQS_BYTE2\" )
			)
			( classClass "@crescent_city_bb_fab1_lib.crescent_city_bb_fab1(sch_1):\CC234\"
				( spacingCSetRef "@sapphirecity_baseboard_lib.sapphirecity_baseboard(sch_1):\DQ_TO_DQ\" )
				( netClassRef "@sapphirecity_baseboard_lib.sapphirecity_baseboard(sch_1):\DDR4_CHN_F_DQ_DQS_BYTE1\" )
				( netClassRef "@sapphirecity_baseboard_lib.sapphirecity_baseboard(sch_1):\DDR4_CHN_F_DQ_DQS_BYTE2\" )
			)
			( classClass "@crescent_city_bb_fab1_lib.crescent_city_bb_fab1(sch_1):\CC242\"
				( spacingCSetRef "@sapphirecity_baseboard_lib.sapphirecity_baseboard(sch_1):\DQ_TO_DQ\" )
				( netClassRef "@sapphirecity_baseboard_lib.sapphirecity_baseboard(sch_1):\DDR4_CHN_F_CLK\" )
				( netClassRef "@sapphirecity_baseboard_lib.sapphirecity_baseboard(sch_1):\DDR4_CHN_F_DQ_DQS_BYTE2\" )
			)
			( classClass "@crescent_city_bb_fab1_lib.crescent_city_bb_fab1(sch_1):\CC243\"
				( spacingCSetRef "@sapphirecity_baseboard_lib.sapphirecity_baseboard(sch_1):\DQ_TO_DQ\" )
				( netClassRef "@sapphirecity_baseboard_lib.sapphirecity_baseboard(sch_1):\DDR4_CHN_F_CMD_ADD\" )
				( netClassRef "@sapphirecity_baseboard_lib.sapphirecity_baseboard(sch_1):\DDR4_CHN_F_DQ_DQS_BYTE2\" )
			)
			( classClass "@crescent_city_bb_fab1_lib.crescent_city_bb_fab1(sch_1):\CC244\"
				( spacingCSetRef "@sapphirecity_baseboard_lib.sapphirecity_baseboard(sch_1):\DQ_TO_DQ\" )
				( netClassRef "@sapphirecity_baseboard_lib.sapphirecity_baseboard(sch_1):\DDR4_CHN_F_CTRL\" )
				( netClassRef "@sapphirecity_baseboard_lib.sapphirecity_baseboard(sch_1):\DDR4_CHN_F_DQ_DQS_BYTE2\" )
			)
			( classClass "@crescent_city_bb_fab1_lib.crescent_city_bb_fab1(sch_1):\CC251\"
				( spacingCSetRef "@crescent_city_bb_fab1_lib.crescent_city_bb_fab1(sch_1):\DEFAULT\" )
				( netClassRef "@sapphirecity_baseboard_lib.sapphirecity_baseboard(sch_1):\GND\" )
				( netClassRef "@sapphirecity_baseboard_lib.sapphirecity_baseboard(sch_1):\DDR4_CHN_F_DQ_DQS_BYTE2\" )
			)
			( classClass "@crescent_city_bb_fab1_lib.crescent_city_bb_fab1(sch_1):\CC47\"
				( spacingCSetRef "@crescent_city_bb_fab1_lib.crescent_city_bb_fab1(sch_1):\DEFAULT\" )
				( netClassRef "@sapphirecity_baseboard_lib.sapphirecity_baseboard(sch_1):\POWER\" )
				( netClassRef "@sapphirecity_baseboard_lib.sapphirecity_baseboard(sch_1):\DDR4_CHN_F_DQ_DQS_BYTE2\" )
			)
			( classClass "@sapphirecity_baseboard_lib.sapphirecity_baseboard(sch_1):\CC516\"
				( spacingCSetRef "@sapphirecity_baseboard_lib.sapphirecity_baseboard(sch_1):\DDR4_2SPC_DQ/DQS\" )
				( netClassRef "@sapphirecity_baseboard_lib.sapphirecity_baseboard(sch_1):\DDR4_CHN_F_DQ_DQS_BYTE1\" )
				( netClassRef "@sapphirecity_baseboard_lib.sapphirecity_baseboard(sch_1):\DDR4_CHN_F_DQ_DQS_BYTE1\" )
			)
			( classClass "@crescent_city_bb_fab1_lib.crescent_city_bb_fab1(sch_1):\CC222\"
				( spacingCSetRef "@sapphirecity_baseboard_lib.sapphirecity_baseboard(sch_1):\DQ_TO_DQ\" )
				( netClassRef "@sapphirecity_baseboard_lib.sapphirecity_baseboard(sch_1):\DDR4_CHN_F_DQ_DQS_BYTE0\" )
				( netClassRef "@sapphirecity_baseboard_lib.sapphirecity_baseboard(sch_1):\DDR4_CHN_F_DQ_DQS_BYTE1\" )
			)
			( classClass "@crescent_city_bb_fab1_lib.crescent_city_bb_fab1(sch_1):\CC231\"
				( spacingCSetRef "@sapphirecity_baseboard_lib.sapphirecity_baseboard(sch_1):\DQ_TO_DQ\" )
				( netClassRef "@sapphirecity_baseboard_lib.sapphirecity_baseboard(sch_1):\DDR4_CHN_F_CLK\" )
				( netClassRef "@sapphirecity_baseboard_lib.sapphirecity_baseboard(sch_1):\DDR4_CHN_F_DQ_DQS_BYTE1\" )
			)
			( classClass "@crescent_city_bb_fab1_lib.crescent_city_bb_fab1(sch_1):\CC232\"
				( spacingCSetRef "@sapphirecity_baseboard_lib.sapphirecity_baseboard(sch_1):\DQ_TO_DQ\" )
				( netClassRef "@sapphirecity_baseboard_lib.sapphirecity_baseboard(sch_1):\DDR4_CHN_F_CMD_ADD\" )
				( netClassRef "@sapphirecity_baseboard_lib.sapphirecity_baseboard(sch_1):\DDR4_CHN_F_DQ_DQS_BYTE1\" )
			)
			( classClass "@crescent_city_bb_fab1_lib.crescent_city_bb_fab1(sch_1):\CC233\"
				( spacingCSetRef "@sapphirecity_baseboard_lib.sapphirecity_baseboard(sch_1):\DQ_TO_DQ\" )
				( netClassRef "@sapphirecity_baseboard_lib.sapphirecity_baseboard(sch_1):\DDR4_CHN_F_CTRL\" )
				( netClassRef "@sapphirecity_baseboard_lib.sapphirecity_baseboard(sch_1):\DDR4_CHN_F_DQ_DQS_BYTE1\" )
			)
			( classClass "@crescent_city_bb_fab1_lib.crescent_city_bb_fab1(sch_1):\CC241\"
				( spacingCSetRef "@crescent_city_bb_fab1_lib.crescent_city_bb_fab1(sch_1):\DEFAULT\" )
				( netClassRef "@sapphirecity_baseboard_lib.sapphirecity_baseboard(sch_1):\GND\" )
				( netClassRef "@sapphirecity_baseboard_lib.sapphirecity_baseboard(sch_1):\DDR4_CHN_F_DQ_DQS_BYTE1\" )
			)
			( classClass "@crescent_city_bb_fab1_lib.crescent_city_bb_fab1(sch_1):\CC46\"
				( spacingCSetRef "@crescent_city_bb_fab1_lib.crescent_city_bb_fab1(sch_1):\DEFAULT\" )
				( netClassRef "@sapphirecity_baseboard_lib.sapphirecity_baseboard(sch_1):\POWER\" )
				( netClassRef "@sapphirecity_baseboard_lib.sapphirecity_baseboard(sch_1):\DDR4_CHN_F_DQ_DQS_BYTE1\" )
			)
			( classClass "@sapphirecity_baseboard_lib.sapphirecity_baseboard(sch_1):\CC515\"
				( spacingCSetRef "@sapphirecity_baseboard_lib.sapphirecity_baseboard(sch_1):\DDR4_2SPC_DQ/DQS\" )
				( netClassRef "@sapphirecity_baseboard_lib.sapphirecity_baseboard(sch_1):\DDR4_CHN_F_DQ_DQS_BYTE0\" )
				( netClassRef "@sapphirecity_baseboard_lib.sapphirecity_baseboard(sch_1):\DDR4_CHN_F_DQ_DQS_BYTE0\" )
			)
			( classClass "@crescent_city_bb_fab1_lib.crescent_city_bb_fab1(sch_1):\CC219\"
				( spacingCSetRef "@sapphirecity_baseboard_lib.sapphirecity_baseboard(sch_1):\DQ_TO_DQ\" )
				( netClassRef "@sapphirecity_baseboard_lib.sapphirecity_baseboard(sch_1):\DDR4_CHN_F_CLK\" )
				( netClassRef "@sapphirecity_baseboard_lib.sapphirecity_baseboard(sch_1):\DDR4_CHN_F_DQ_DQS_BYTE0\" )
			)
			( classClass "@crescent_city_bb_fab1_lib.crescent_city_bb_fab1(sch_1):\CC220\"
				( spacingCSetRef "@sapphirecity_baseboard_lib.sapphirecity_baseboard(sch_1):\DQ_TO_DQ\" )
				( netClassRef "@sapphirecity_baseboard_lib.sapphirecity_baseboard(sch_1):\DDR4_CHN_F_CMD_ADD\" )
				( netClassRef "@sapphirecity_baseboard_lib.sapphirecity_baseboard(sch_1):\DDR4_CHN_F_DQ_DQS_BYTE0\" )
			)
			( classClass "@crescent_city_bb_fab1_lib.crescent_city_bb_fab1(sch_1):\CC221\"
				( spacingCSetRef "@sapphirecity_baseboard_lib.sapphirecity_baseboard(sch_1):\DQ_TO_DQ\" )
				( netClassRef "@sapphirecity_baseboard_lib.sapphirecity_baseboard(sch_1):\DDR4_CHN_F_CTRL\" )
				( netClassRef "@sapphirecity_baseboard_lib.sapphirecity_baseboard(sch_1):\DDR4_CHN_F_DQ_DQS_BYTE0\" )
			)
			( classClass "@crescent_city_bb_fab1_lib.crescent_city_bb_fab1(sch_1):\CC230\"
				( spacingCSetRef "@crescent_city_bb_fab1_lib.crescent_city_bb_fab1(sch_1):\DEFAULT\" )
				( netClassRef "@sapphirecity_baseboard_lib.sapphirecity_baseboard(sch_1):\GND\" )
				( netClassRef "@sapphirecity_baseboard_lib.sapphirecity_baseboard(sch_1):\DDR4_CHN_F_DQ_DQS_BYTE0\" )
			)
			( classClass "@crescent_city_bb_fab1_lib.crescent_city_bb_fab1(sch_1):\CC45\"
				( spacingCSetRef "@crescent_city_bb_fab1_lib.crescent_city_bb_fab1(sch_1):\DEFAULT\" )
				( netClassRef "@sapphirecity_baseboard_lib.sapphirecity_baseboard(sch_1):\POWER\" )
				( netClassRef "@sapphirecity_baseboard_lib.sapphirecity_baseboard(sch_1):\DDR4_CHN_F_DQ_DQS_BYTE0\" )
			)
			( classClass "@sapphirecity_baseboard_lib.sapphirecity_baseboard(sch_1):\CC239\"
				( spacingCSetRef "@crescent_city_bb_fab1_lib.crescent_city_bb_fab1(sch_1):\DEFAULT\" )
				( netClassRef "@sapphirecity_baseboard_lib.sapphirecity_baseboard(sch_1):\GND\" )
				( netClassRef "@sapphirecity_baseboard_lib.sapphirecity_baseboard(sch_1):\DDR4_CHN_F_CTRL\" )
			)
			( classClass "@sapphirecity_baseboard_lib.sapphirecity_baseboard(sch_1):\CC509\"
				( spacingCSetRef "@sapphirecity_baseboard_lib.sapphirecity_baseboard(sch_1):\DDR4_2SPC_CAC\" )
				( netClassRef "@sapphirecity_baseboard_lib.sapphirecity_baseboard(sch_1):\DDR4_CHN_F_CLK\" )
				( netClassRef "@sapphirecity_baseboard_lib.sapphirecity_baseboard(sch_1):\DDR4_CHN_F_CTRL\" )
			)
			( classClass "@sapphirecity_baseboard_lib.sapphirecity_baseboard(sch_1):\CC512\"
				( spacingCSetRef "@sapphirecity_baseboard_lib.sapphirecity_baseboard(sch_1):\DDR4_2SPC_CAC\" )
				( netClassRef "@sapphirecity_baseboard_lib.sapphirecity_baseboard(sch_1):\DDR4_CHN_F_CMD_ADD\" )
				( netClassRef "@sapphirecity_baseboard_lib.sapphirecity_baseboard(sch_1):\DDR4_CHN_F_CTRL\" )
			)
			( classClass "@sapphirecity_baseboard_lib.sapphirecity_baseboard(sch_1):\CC514\"
				( spacingCSetRef "@sapphirecity_baseboard_lib.sapphirecity_baseboard(sch_1):\DDR4_2SPC_CAC\" )
				( netClassRef "@sapphirecity_baseboard_lib.sapphirecity_baseboard(sch_1):\DDR4_CHN_F_CTRL\" )
				( netClassRef "@sapphirecity_baseboard_lib.sapphirecity_baseboard(sch_1):\DDR4_CHN_F_CTRL\" )
			)
			( classClass "@crescent_city_bb_fab1_lib.crescent_city_bb_fab1(sch_1):\CC71\"
				( spacingCSetRef "@crescent_city_bb_fab1_lib.crescent_city_bb_fab1(sch_1):\DEFAULT\" )
				( netClassRef "@sapphirecity_baseboard_lib.sapphirecity_baseboard(sch_1):\POWER\" )
				( netClassRef "@sapphirecity_baseboard_lib.sapphirecity_baseboard(sch_1):\DDR4_CHN_F_CTRL\" )
			)
			( classClass "@sapphirecity_baseboard_lib.sapphirecity_baseboard(sch_1):\CC238\"
				( spacingCSetRef "@crescent_city_bb_fab1_lib.crescent_city_bb_fab1(sch_1):\DEFAULT\" )
				( netClassRef "@sapphirecity_baseboard_lib.sapphirecity_baseboard(sch_1):\GND\" )
				( netClassRef "@sapphirecity_baseboard_lib.sapphirecity_baseboard(sch_1):\DDR4_CHN_F_CMD_ADD\" )
			)
			( classClass "@sapphirecity_baseboard_lib.sapphirecity_baseboard(sch_1):\CC510\"
				( spacingCSetRef "@sapphirecity_baseboard_lib.sapphirecity_baseboard(sch_1):\DDR4_2SPC_CAC\" )
				( netClassRef "@sapphirecity_baseboard_lib.sapphirecity_baseboard(sch_1):\DDR4_CHN_F_CLK\" )
				( netClassRef "@sapphirecity_baseboard_lib.sapphirecity_baseboard(sch_1):\DDR4_CHN_F_CMD_ADD\" )
			)
			( classClass "@sapphirecity_baseboard_lib.sapphirecity_baseboard(sch_1):\CC513\"
				( spacingCSetRef "@sapphirecity_baseboard_lib.sapphirecity_baseboard(sch_1):\DDR4_2SPC_CAC\" )
				( netClassRef "@sapphirecity_baseboard_lib.sapphirecity_baseboard(sch_1):\DDR4_CHN_F_CMD_ADD\" )
				( netClassRef "@sapphirecity_baseboard_lib.sapphirecity_baseboard(sch_1):\DDR4_CHN_F_CMD_ADD\" )
			)
			( classClass "@crescent_city_bb_fab1_lib.crescent_city_bb_fab1(sch_1):\CC70\"
				( spacingCSetRef "@crescent_city_bb_fab1_lib.crescent_city_bb_fab1(sch_1):\DEFAULT\" )
				( netClassRef "@sapphirecity_baseboard_lib.sapphirecity_baseboard(sch_1):\POWER\" )
				( netClassRef "@sapphirecity_baseboard_lib.sapphirecity_baseboard(sch_1):\DDR4_CHN_F_CMD_ADD\" )
			)
			( classClass "@sapphirecity_baseboard_lib.sapphirecity_baseboard(sch_1):\CC237\"
				( spacingCSetRef "@crescent_city_bb_fab1_lib.crescent_city_bb_fab1(sch_1):\DEFAULT\" )
				( netClassRef "@sapphirecity_baseboard_lib.sapphirecity_baseboard(sch_1):\GND\" )
				( netClassRef "@sapphirecity_baseboard_lib.sapphirecity_baseboard(sch_1):\DDR4_CHN_F_CLK\" )
			)
			( classClass "@sapphirecity_baseboard_lib.sapphirecity_baseboard(sch_1):\CC511\"
				( spacingCSetRef "@sapphirecity_baseboard_lib.sapphirecity_baseboard(sch_1):\DDR4_2SPC_CAC\" )
				( netClassRef "@sapphirecity_baseboard_lib.sapphirecity_baseboard(sch_1):\DDR4_CHN_F_CLK\" )
				( netClassRef "@sapphirecity_baseboard_lib.sapphirecity_baseboard(sch_1):\DDR4_CHN_F_CLK\" )
			)
			( classClass "@crescent_city_bb_fab1_lib.crescent_city_bb_fab1(sch_1):\CC26\"
				( spacingCSetRef "@crescent_city_bb_fab1_lib.crescent_city_bb_fab1(sch_1):\DEFAULT\" )
				( netClassRef "@sapphirecity_baseboard_lib.sapphirecity_baseboard(sch_1):\POWER\" )
				( netClassRef "@sapphirecity_baseboard_lib.sapphirecity_baseboard(sch_1):\DDR4_CHN_F_CLK\" )
			)
			( classClass "@sapphirecity_baseboard_lib.sapphirecity_baseboard(sch_1):\CC508\"
				( spacingCSetRef "@sapphirecity_baseboard_lib.sapphirecity_baseboard(sch_1):\DDR4_2SPC_DQ/DQS\" )
				( netClassRef "@sapphirecity_baseboard_lib.sapphirecity_baseboard(sch_1):\DDR4_CHN_E_ECC\" )
				( netClassRef "@sapphirecity_baseboard_lib.sapphirecity_baseboard(sch_1):\DDR4_CHN_E_ECC\" )
			)
			( classClass "@crescent_city_bb_fab1_lib.crescent_city_bb_fab1(sch_1):\CC157\"
				( spacingCSetRef "@sapphirecity_baseboard_lib.sapphirecity_baseboard(sch_1):\DQ_TO_DQ\" )
				( netClassRef "@sapphirecity_baseboard_lib.sapphirecity_baseboard(sch_1):\DDR4_CHN_E_DQ_DQS_BYTE0\" )
				( netClassRef "@sapphirecity_baseboard_lib.sapphirecity_baseboard(sch_1):\DDR4_CHN_E_ECC\" )
			)
			( classClass "@crescent_city_bb_fab1_lib.crescent_city_bb_fab1(sch_1):\CC168\"
				( spacingCSetRef "@sapphirecity_baseboard_lib.sapphirecity_baseboard(sch_1):\DQ_TO_DQ\" )
				( netClassRef "@sapphirecity_baseboard_lib.sapphirecity_baseboard(sch_1):\DDR4_CHN_E_DQ_DQS_BYTE1\" )
				( netClassRef "@sapphirecity_baseboard_lib.sapphirecity_baseboard(sch_1):\DDR4_CHN_E_ECC\" )
			)
			( classClass "@crescent_city_bb_fab1_lib.crescent_city_bb_fab1(sch_1):\CC178\"
				( spacingCSetRef "@sapphirecity_baseboard_lib.sapphirecity_baseboard(sch_1):\DQ_TO_DQ\" )
				( netClassRef "@sapphirecity_baseboard_lib.sapphirecity_baseboard(sch_1):\DDR4_CHN_E_DQ_DQS_BYTE2\" )
				( netClassRef "@sapphirecity_baseboard_lib.sapphirecity_baseboard(sch_1):\DDR4_CHN_E_ECC\" )
			)
			( classClass "@crescent_city_bb_fab1_lib.crescent_city_bb_fab1(sch_1):\CC187\"
				( spacingCSetRef "@sapphirecity_baseboard_lib.sapphirecity_baseboard(sch_1):\DQ_TO_DQ\" )
				( netClassRef "@sapphirecity_baseboard_lib.sapphirecity_baseboard(sch_1):\DDR4_CHN_E_DQ_DQS_BYTE3\" )
				( netClassRef "@sapphirecity_baseboard_lib.sapphirecity_baseboard(sch_1):\DDR4_CHN_E_ECC\" )
			)
			( classClass "@crescent_city_bb_fab1_lib.crescent_city_bb_fab1(sch_1):\CC195\"
				( spacingCSetRef "@sapphirecity_baseboard_lib.sapphirecity_baseboard(sch_1):\DQ_TO_DQ\" )
				( netClassRef "@sapphirecity_baseboard_lib.sapphirecity_baseboard(sch_1):\DDR4_CHN_E_DQ_DQS_BYTE4\" )
				( netClassRef "@sapphirecity_baseboard_lib.sapphirecity_baseboard(sch_1):\DDR4_CHN_E_ECC\" )
			)
			( classClass "@crescent_city_bb_fab1_lib.crescent_city_bb_fab1(sch_1):\CC202\"
				( spacingCSetRef "@sapphirecity_baseboard_lib.sapphirecity_baseboard(sch_1):\DQ_TO_DQ\" )
				( netClassRef "@sapphirecity_baseboard_lib.sapphirecity_baseboard(sch_1):\DDR4_CHN_E_DQ_DQS_BYTE5\" )
				( netClassRef "@sapphirecity_baseboard_lib.sapphirecity_baseboard(sch_1):\DDR4_CHN_E_ECC\" )
			)
			( classClass "@crescent_city_bb_fab1_lib.crescent_city_bb_fab1(sch_1):\CC208\"
				( spacingCSetRef "@sapphirecity_baseboard_lib.sapphirecity_baseboard(sch_1):\DQ_TO_DQ\" )
				( netClassRef "@sapphirecity_baseboard_lib.sapphirecity_baseboard(sch_1):\DDR4_CHN_E_DQ_DQS_BYTE6\" )
				( netClassRef "@sapphirecity_baseboard_lib.sapphirecity_baseboard(sch_1):\DDR4_CHN_E_ECC\" )
			)
			( classClass "@crescent_city_bb_fab1_lib.crescent_city_bb_fab1(sch_1):\CC213\"
				( spacingCSetRef "@sapphirecity_baseboard_lib.sapphirecity_baseboard(sch_1):\DQ_TO_DQ\" )
				( netClassRef "@sapphirecity_baseboard_lib.sapphirecity_baseboard(sch_1):\DDR4_CHN_E_DQ_DQS_BYTE7\" )
				( netClassRef "@sapphirecity_baseboard_lib.sapphirecity_baseboard(sch_1):\DDR4_CHN_E_ECC\" )
			)
			( classClass "@crescent_city_bb_fab1_lib.crescent_city_bb_fab1(sch_1):\CC215\"
				( spacingCSetRef "@sapphirecity_baseboard_lib.sapphirecity_baseboard(sch_1):\DQ_TO_DQ\" )
				( netClassRef "@sapphirecity_baseboard_lib.sapphirecity_baseboard(sch_1):\DDR4_CHN_E_CLK\" )
				( netClassRef "@sapphirecity_baseboard_lib.sapphirecity_baseboard(sch_1):\DDR4_CHN_E_ECC\" )
			)
			( classClass "@crescent_city_bb_fab1_lib.crescent_city_bb_fab1(sch_1):\CC216\"
				( spacingCSetRef "@sapphirecity_baseboard_lib.sapphirecity_baseboard(sch_1):\DQ_TO_DQ\" )
				( netClassRef "@sapphirecity_baseboard_lib.sapphirecity_baseboard(sch_1):\DDR4_CHN_E_CMD_ADD\" )
				( netClassRef "@sapphirecity_baseboard_lib.sapphirecity_baseboard(sch_1):\DDR4_CHN_E_ECC\" )
			)
			( classClass "@crescent_city_bb_fab1_lib.crescent_city_bb_fab1(sch_1):\CC217\"
				( spacingCSetRef "@sapphirecity_baseboard_lib.sapphirecity_baseboard(sch_1):\DQ_TO_DQ\" )
				( netClassRef "@sapphirecity_baseboard_lib.sapphirecity_baseboard(sch_1):\DDR4_CHN_E_CTRL\" )
				( netClassRef "@sapphirecity_baseboard_lib.sapphirecity_baseboard(sch_1):\DDR4_CHN_E_ECC\" )
			)
			( classClass "@crescent_city_bb_fab1_lib.crescent_city_bb_fab1(sch_1):\CC218\"
				( spacingCSetRef "@crescent_city_bb_fab1_lib.crescent_city_bb_fab1(sch_1):\DEFAULT\" )
				( netClassRef "@sapphirecity_baseboard_lib.sapphirecity_baseboard(sch_1):\GND\" )
				( netClassRef "@sapphirecity_baseboard_lib.sapphirecity_baseboard(sch_1):\DDR4_CHN_E_ECC\" )
			)
			( classClass "@crescent_city_bb_fab1_lib.crescent_city_bb_fab1(sch_1):\CC44\"
				( spacingCSetRef "@crescent_city_bb_fab1_lib.crescent_city_bb_fab1(sch_1):\DEFAULT\" )
				( netClassRef "@sapphirecity_baseboard_lib.sapphirecity_baseboard(sch_1):\POWER\" )
				( netClassRef "@sapphirecity_baseboard_lib.sapphirecity_baseboard(sch_1):\DDR4_CHN_E_ECC\" )
			)
			( classClass "@sapphirecity_baseboard_lib.sapphirecity_baseboard(sch_1):\CC507\"
				( spacingCSetRef "@sapphirecity_baseboard_lib.sapphirecity_baseboard(sch_1):\DDR4_2SPC_DQ/DQS\" )
				( netClassRef "@sapphirecity_baseboard_lib.sapphirecity_baseboard(sch_1):\DDR4_CHN_E_DQ_DQS_BYTE7\" )
				( netClassRef "@sapphirecity_baseboard_lib.sapphirecity_baseboard(sch_1):\DDR4_CHN_E_DQ_DQS_BYTE7\" )
			)
			( classClass "@crescent_city_bb_fab1_lib.crescent_city_bb_fab1(sch_1):\CC156\"
				( spacingCSetRef "@sapphirecity_baseboard_lib.sapphirecity_baseboard(sch_1):\DQ_TO_DQ\" )
				( netClassRef "@sapphirecity_baseboard_lib.sapphirecity_baseboard(sch_1):\DDR4_CHN_E_DQ_DQS_BYTE0\" )
				( netClassRef "@sapphirecity_baseboard_lib.sapphirecity_baseboard(sch_1):\DDR4_CHN_E_DQ_DQS_BYTE7\" )
			)
			( classClass "@crescent_city_bb_fab1_lib.crescent_city_bb_fab1(sch_1):\CC167\"
				( spacingCSetRef "@sapphirecity_baseboard_lib.sapphirecity_baseboard(sch_1):\DQ_TO_DQ\" )
				( netClassRef "@sapphirecity_baseboard_lib.sapphirecity_baseboard(sch_1):\DDR4_CHN_E_DQ_DQS_BYTE1\" )
				( netClassRef "@sapphirecity_baseboard_lib.sapphirecity_baseboard(sch_1):\DDR4_CHN_E_DQ_DQS_BYTE7\" )
			)
			( classClass "@crescent_city_bb_fab1_lib.crescent_city_bb_fab1(sch_1):\CC177\"
				( spacingCSetRef "@sapphirecity_baseboard_lib.sapphirecity_baseboard(sch_1):\DQ_TO_DQ\" )
				( netClassRef "@sapphirecity_baseboard_lib.sapphirecity_baseboard(sch_1):\DDR4_CHN_E_DQ_DQS_BYTE2\" )
				( netClassRef "@sapphirecity_baseboard_lib.sapphirecity_baseboard(sch_1):\DDR4_CHN_E_DQ_DQS_BYTE7\" )
			)
			( classClass "@crescent_city_bb_fab1_lib.crescent_city_bb_fab1(sch_1):\CC186\"
				( spacingCSetRef "@sapphirecity_baseboard_lib.sapphirecity_baseboard(sch_1):\DQ_TO_DQ\" )
				( netClassRef "@sapphirecity_baseboard_lib.sapphirecity_baseboard(sch_1):\DDR4_CHN_E_DQ_DQS_BYTE3\" )
				( netClassRef "@sapphirecity_baseboard_lib.sapphirecity_baseboard(sch_1):\DDR4_CHN_E_DQ_DQS_BYTE7\" )
			)
			( classClass "@crescent_city_bb_fab1_lib.crescent_city_bb_fab1(sch_1):\CC194\"
				( spacingCSetRef "@sapphirecity_baseboard_lib.sapphirecity_baseboard(sch_1):\DQ_TO_DQ\" )
				( netClassRef "@sapphirecity_baseboard_lib.sapphirecity_baseboard(sch_1):\DDR4_CHN_E_DQ_DQS_BYTE4\" )
				( netClassRef "@sapphirecity_baseboard_lib.sapphirecity_baseboard(sch_1):\DDR4_CHN_E_DQ_DQS_BYTE7\" )
			)
			( classClass "@crescent_city_bb_fab1_lib.crescent_city_bb_fab1(sch_1):\CC201\"
				( spacingCSetRef "@sapphirecity_baseboard_lib.sapphirecity_baseboard(sch_1):\DQ_TO_DQ\" )
				( netClassRef "@sapphirecity_baseboard_lib.sapphirecity_baseboard(sch_1):\DDR4_CHN_E_DQ_DQS_BYTE5\" )
				( netClassRef "@sapphirecity_baseboard_lib.sapphirecity_baseboard(sch_1):\DDR4_CHN_E_DQ_DQS_BYTE7\" )
			)
			( classClass "@crescent_city_bb_fab1_lib.crescent_city_bb_fab1(sch_1):\CC207\"
				( spacingCSetRef "@sapphirecity_baseboard_lib.sapphirecity_baseboard(sch_1):\DQ_TO_DQ\" )
				( netClassRef "@sapphirecity_baseboard_lib.sapphirecity_baseboard(sch_1):\DDR4_CHN_E_DQ_DQS_BYTE6\" )
				( netClassRef "@sapphirecity_baseboard_lib.sapphirecity_baseboard(sch_1):\DDR4_CHN_E_DQ_DQS_BYTE7\" )
			)
			( classClass "@crescent_city_bb_fab1_lib.crescent_city_bb_fab1(sch_1):\CC210\"
				( spacingCSetRef "@sapphirecity_baseboard_lib.sapphirecity_baseboard(sch_1):\DQ_TO_DQ\" )
				( netClassRef "@sapphirecity_baseboard_lib.sapphirecity_baseboard(sch_1):\DDR4_CHN_E_CLK\" )
				( netClassRef "@sapphirecity_baseboard_lib.sapphirecity_baseboard(sch_1):\DDR4_CHN_E_DQ_DQS_BYTE7\" )
			)
			( classClass "@crescent_city_bb_fab1_lib.crescent_city_bb_fab1(sch_1):\CC211\"
				( spacingCSetRef "@sapphirecity_baseboard_lib.sapphirecity_baseboard(sch_1):\DQ_TO_DQ\" )
				( netClassRef "@sapphirecity_baseboard_lib.sapphirecity_baseboard(sch_1):\DDR4_CHN_E_CMD_ADD\" )
				( netClassRef "@sapphirecity_baseboard_lib.sapphirecity_baseboard(sch_1):\DDR4_CHN_E_DQ_DQS_BYTE7\" )
			)
			( classClass "@crescent_city_bb_fab1_lib.crescent_city_bb_fab1(sch_1):\CC212\"
				( spacingCSetRef "@sapphirecity_baseboard_lib.sapphirecity_baseboard(sch_1):\DQ_TO_DQ\" )
				( netClassRef "@sapphirecity_baseboard_lib.sapphirecity_baseboard(sch_1):\DDR4_CHN_E_CTRL\" )
				( netClassRef "@sapphirecity_baseboard_lib.sapphirecity_baseboard(sch_1):\DDR4_CHN_E_DQ_DQS_BYTE7\" )
			)
			( classClass "@crescent_city_bb_fab1_lib.crescent_city_bb_fab1(sch_1):\CC214\"
				( spacingCSetRef "@crescent_city_bb_fab1_lib.crescent_city_bb_fab1(sch_1):\DEFAULT\" )
				( netClassRef "@sapphirecity_baseboard_lib.sapphirecity_baseboard(sch_1):\GND\" )
				( netClassRef "@sapphirecity_baseboard_lib.sapphirecity_baseboard(sch_1):\DDR4_CHN_E_DQ_DQS_BYTE7\" )
			)
			( classClass "@crescent_city_bb_fab1_lib.crescent_city_bb_fab1(sch_1):\CC43\"
				( spacingCSetRef "@crescent_city_bb_fab1_lib.crescent_city_bb_fab1(sch_1):\DEFAULT\" )
				( netClassRef "@sapphirecity_baseboard_lib.sapphirecity_baseboard(sch_1):\POWER\" )
				( netClassRef "@sapphirecity_baseboard_lib.sapphirecity_baseboard(sch_1):\DDR4_CHN_E_DQ_DQS_BYTE7\" )
			)
			( classClass "@sapphirecity_baseboard_lib.sapphirecity_baseboard(sch_1):\CC506\"
				( spacingCSetRef "@sapphirecity_baseboard_lib.sapphirecity_baseboard(sch_1):\DDR4_2SPC_DQ/DQS\" )
				( netClassRef "@sapphirecity_baseboard_lib.sapphirecity_baseboard(sch_1):\DDR4_CHN_E_DQ_DQS_BYTE6\" )
				( netClassRef "@sapphirecity_baseboard_lib.sapphirecity_baseboard(sch_1):\DDR4_CHN_E_DQ_DQS_BYTE6\" )
			)
			( classClass "@crescent_city_bb_fab1_lib.crescent_city_bb_fab1(sch_1):\CC155\"
				( spacingCSetRef "@sapphirecity_baseboard_lib.sapphirecity_baseboard(sch_1):\DQ_TO_DQ\" )
				( netClassRef "@sapphirecity_baseboard_lib.sapphirecity_baseboard(sch_1):\DDR4_CHN_E_DQ_DQS_BYTE0\" )
				( netClassRef "@sapphirecity_baseboard_lib.sapphirecity_baseboard(sch_1):\DDR4_CHN_E_DQ_DQS_BYTE6\" )
			)
			( classClass "@crescent_city_bb_fab1_lib.crescent_city_bb_fab1(sch_1):\CC166\"
				( spacingCSetRef "@sapphirecity_baseboard_lib.sapphirecity_baseboard(sch_1):\DQ_TO_DQ\" )
				( netClassRef "@sapphirecity_baseboard_lib.sapphirecity_baseboard(sch_1):\DDR4_CHN_E_DQ_DQS_BYTE1\" )
				( netClassRef "@sapphirecity_baseboard_lib.sapphirecity_baseboard(sch_1):\DDR4_CHN_E_DQ_DQS_BYTE6\" )
			)
			( classClass "@crescent_city_bb_fab1_lib.crescent_city_bb_fab1(sch_1):\CC176\"
				( spacingCSetRef "@sapphirecity_baseboard_lib.sapphirecity_baseboard(sch_1):\DQ_TO_DQ\" )
				( netClassRef "@sapphirecity_baseboard_lib.sapphirecity_baseboard(sch_1):\DDR4_CHN_E_DQ_DQS_BYTE2\" )
				( netClassRef "@sapphirecity_baseboard_lib.sapphirecity_baseboard(sch_1):\DDR4_CHN_E_DQ_DQS_BYTE6\" )
			)
			( classClass "@crescent_city_bb_fab1_lib.crescent_city_bb_fab1(sch_1):\CC185\"
				( spacingCSetRef "@sapphirecity_baseboard_lib.sapphirecity_baseboard(sch_1):\DQ_TO_DQ\" )
				( netClassRef "@sapphirecity_baseboard_lib.sapphirecity_baseboard(sch_1):\DDR4_CHN_E_DQ_DQS_BYTE3\" )
				( netClassRef "@sapphirecity_baseboard_lib.sapphirecity_baseboard(sch_1):\DDR4_CHN_E_DQ_DQS_BYTE6\" )
			)
			( classClass "@crescent_city_bb_fab1_lib.crescent_city_bb_fab1(sch_1):\CC193\"
				( spacingCSetRef "@sapphirecity_baseboard_lib.sapphirecity_baseboard(sch_1):\DQ_TO_DQ\" )
				( netClassRef "@sapphirecity_baseboard_lib.sapphirecity_baseboard(sch_1):\DDR4_CHN_E_DQ_DQS_BYTE4\" )
				( netClassRef "@sapphirecity_baseboard_lib.sapphirecity_baseboard(sch_1):\DDR4_CHN_E_DQ_DQS_BYTE6\" )
			)
			( classClass "@crescent_city_bb_fab1_lib.crescent_city_bb_fab1(sch_1):\CC200\"
				( spacingCSetRef "@sapphirecity_baseboard_lib.sapphirecity_baseboard(sch_1):\DQ_TO_DQ\" )
				( netClassRef "@sapphirecity_baseboard_lib.sapphirecity_baseboard(sch_1):\DDR4_CHN_E_DQ_DQS_BYTE5\" )
				( netClassRef "@sapphirecity_baseboard_lib.sapphirecity_baseboard(sch_1):\DDR4_CHN_E_DQ_DQS_BYTE6\" )
			)
			( classClass "@crescent_city_bb_fab1_lib.crescent_city_bb_fab1(sch_1):\CC204\"
				( spacingCSetRef "@sapphirecity_baseboard_lib.sapphirecity_baseboard(sch_1):\DQ_TO_DQ\" )
				( netClassRef "@sapphirecity_baseboard_lib.sapphirecity_baseboard(sch_1):\DDR4_CHN_E_CLK\" )
				( netClassRef "@sapphirecity_baseboard_lib.sapphirecity_baseboard(sch_1):\DDR4_CHN_E_DQ_DQS_BYTE6\" )
			)
			( classClass "@crescent_city_bb_fab1_lib.crescent_city_bb_fab1(sch_1):\CC205\"
				( spacingCSetRef "@sapphirecity_baseboard_lib.sapphirecity_baseboard(sch_1):\DQ_TO_DQ\" )
				( netClassRef "@sapphirecity_baseboard_lib.sapphirecity_baseboard(sch_1):\DDR4_CHN_E_CMD_ADD\" )
				( netClassRef "@sapphirecity_baseboard_lib.sapphirecity_baseboard(sch_1):\DDR4_CHN_E_DQ_DQS_BYTE6\" )
			)
			( classClass "@crescent_city_bb_fab1_lib.crescent_city_bb_fab1(sch_1):\CC206\"
				( spacingCSetRef "@sapphirecity_baseboard_lib.sapphirecity_baseboard(sch_1):\DQ_TO_DQ\" )
				( netClassRef "@sapphirecity_baseboard_lib.sapphirecity_baseboard(sch_1):\DDR4_CHN_E_CTRL\" )
				( netClassRef "@sapphirecity_baseboard_lib.sapphirecity_baseboard(sch_1):\DDR4_CHN_E_DQ_DQS_BYTE6\" )
			)
			( classClass "@crescent_city_bb_fab1_lib.crescent_city_bb_fab1(sch_1):\CC209\"
				( spacingCSetRef "@crescent_city_bb_fab1_lib.crescent_city_bb_fab1(sch_1):\DEFAULT\" )
				( netClassRef "@sapphirecity_baseboard_lib.sapphirecity_baseboard(sch_1):\GND\" )
				( netClassRef "@sapphirecity_baseboard_lib.sapphirecity_baseboard(sch_1):\DDR4_CHN_E_DQ_DQS_BYTE6\" )
			)
			( classClass "@crescent_city_bb_fab1_lib.crescent_city_bb_fab1(sch_1):\CC42\"
				( spacingCSetRef "@crescent_city_bb_fab1_lib.crescent_city_bb_fab1(sch_1):\DEFAULT\" )
				( netClassRef "@sapphirecity_baseboard_lib.sapphirecity_baseboard(sch_1):\POWER\" )
				( netClassRef "@sapphirecity_baseboard_lib.sapphirecity_baseboard(sch_1):\DDR4_CHN_E_DQ_DQS_BYTE6\" )
			)
			( classClass "@sapphirecity_baseboard_lib.sapphirecity_baseboard(sch_1):\CC505\"
				( spacingCSetRef "@sapphirecity_baseboard_lib.sapphirecity_baseboard(sch_1):\DDR4_2SPC_DQ/DQS\" )
				( netClassRef "@sapphirecity_baseboard_lib.sapphirecity_baseboard(sch_1):\DDR4_CHN_E_DQ_DQS_BYTE5\" )
				( netClassRef "@sapphirecity_baseboard_lib.sapphirecity_baseboard(sch_1):\DDR4_CHN_E_DQ_DQS_BYTE5\" )
			)
			( classClass "@crescent_city_bb_fab1_lib.crescent_city_bb_fab1(sch_1):\CC154\"
				( spacingCSetRef "@sapphirecity_baseboard_lib.sapphirecity_baseboard(sch_1):\DQ_TO_DQ\" )
				( netClassRef "@sapphirecity_baseboard_lib.sapphirecity_baseboard(sch_1):\DDR4_CHN_E_DQ_DQS_BYTE0\" )
				( netClassRef "@sapphirecity_baseboard_lib.sapphirecity_baseboard(sch_1):\DDR4_CHN_E_DQ_DQS_BYTE5\" )
			)
			( classClass "@crescent_city_bb_fab1_lib.crescent_city_bb_fab1(sch_1):\CC165\"
				( spacingCSetRef "@sapphirecity_baseboard_lib.sapphirecity_baseboard(sch_1):\DQ_TO_DQ\" )
				( netClassRef "@sapphirecity_baseboard_lib.sapphirecity_baseboard(sch_1):\DDR4_CHN_E_DQ_DQS_BYTE1\" )
				( netClassRef "@sapphirecity_baseboard_lib.sapphirecity_baseboard(sch_1):\DDR4_CHN_E_DQ_DQS_BYTE5\" )
			)
			( classClass "@crescent_city_bb_fab1_lib.crescent_city_bb_fab1(sch_1):\CC175\"
				( spacingCSetRef "@sapphirecity_baseboard_lib.sapphirecity_baseboard(sch_1):\DQ_TO_DQ\" )
				( netClassRef "@sapphirecity_baseboard_lib.sapphirecity_baseboard(sch_1):\DDR4_CHN_E_DQ_DQS_BYTE2\" )
				( netClassRef "@sapphirecity_baseboard_lib.sapphirecity_baseboard(sch_1):\DDR4_CHN_E_DQ_DQS_BYTE5\" )
			)
			( classClass "@crescent_city_bb_fab1_lib.crescent_city_bb_fab1(sch_1):\CC184\"
				( spacingCSetRef "@sapphirecity_baseboard_lib.sapphirecity_baseboard(sch_1):\DQ_TO_DQ\" )
				( netClassRef "@sapphirecity_baseboard_lib.sapphirecity_baseboard(sch_1):\DDR4_CHN_E_DQ_DQS_BYTE3\" )
				( netClassRef "@sapphirecity_baseboard_lib.sapphirecity_baseboard(sch_1):\DDR4_CHN_E_DQ_DQS_BYTE5\" )
			)
			( classClass "@crescent_city_bb_fab1_lib.crescent_city_bb_fab1(sch_1):\CC192\"
				( spacingCSetRef "@sapphirecity_baseboard_lib.sapphirecity_baseboard(sch_1):\DQ_TO_DQ\" )
				( netClassRef "@sapphirecity_baseboard_lib.sapphirecity_baseboard(sch_1):\DDR4_CHN_E_DQ_DQS_BYTE4\" )
				( netClassRef "@sapphirecity_baseboard_lib.sapphirecity_baseboard(sch_1):\DDR4_CHN_E_DQ_DQS_BYTE5\" )
			)
			( classClass "@crescent_city_bb_fab1_lib.crescent_city_bb_fab1(sch_1):\CC197\"
				( spacingCSetRef "@sapphirecity_baseboard_lib.sapphirecity_baseboard(sch_1):\DQ_TO_DQ\" )
				( netClassRef "@sapphirecity_baseboard_lib.sapphirecity_baseboard(sch_1):\DDR4_CHN_E_CLK\" )
				( netClassRef "@sapphirecity_baseboard_lib.sapphirecity_baseboard(sch_1):\DDR4_CHN_E_DQ_DQS_BYTE5\" )
			)
			( classClass "@crescent_city_bb_fab1_lib.crescent_city_bb_fab1(sch_1):\CC198\"
				( spacingCSetRef "@sapphirecity_baseboard_lib.sapphirecity_baseboard(sch_1):\DQ_TO_DQ\" )
				( netClassRef "@sapphirecity_baseboard_lib.sapphirecity_baseboard(sch_1):\DDR4_CHN_E_CMD_ADD\" )
				( netClassRef "@sapphirecity_baseboard_lib.sapphirecity_baseboard(sch_1):\DDR4_CHN_E_DQ_DQS_BYTE5\" )
			)
			( classClass "@crescent_city_bb_fab1_lib.crescent_city_bb_fab1(sch_1):\CC199\"
				( spacingCSetRef "@sapphirecity_baseboard_lib.sapphirecity_baseboard(sch_1):\DQ_TO_DQ\" )
				( netClassRef "@sapphirecity_baseboard_lib.sapphirecity_baseboard(sch_1):\DDR4_CHN_E_CTRL\" )
				( netClassRef "@sapphirecity_baseboard_lib.sapphirecity_baseboard(sch_1):\DDR4_CHN_E_DQ_DQS_BYTE5\" )
			)
			( classClass "@crescent_city_bb_fab1_lib.crescent_city_bb_fab1(sch_1):\CC203\"
				( spacingCSetRef "@crescent_city_bb_fab1_lib.crescent_city_bb_fab1(sch_1):\DEFAULT\" )
				( netClassRef "@sapphirecity_baseboard_lib.sapphirecity_baseboard(sch_1):\GND\" )
				( netClassRef "@sapphirecity_baseboard_lib.sapphirecity_baseboard(sch_1):\DDR4_CHN_E_DQ_DQS_BYTE5\" )
			)
			( classClass "@crescent_city_bb_fab1_lib.crescent_city_bb_fab1(sch_1):\CC41\"
				( spacingCSetRef "@crescent_city_bb_fab1_lib.crescent_city_bb_fab1(sch_1):\DEFAULT\" )
				( netClassRef "@sapphirecity_baseboard_lib.sapphirecity_baseboard(sch_1):\POWER\" )
				( netClassRef "@sapphirecity_baseboard_lib.sapphirecity_baseboard(sch_1):\DDR4_CHN_E_DQ_DQS_BYTE5\" )
			)
			( classClass "@sapphirecity_baseboard_lib.sapphirecity_baseboard(sch_1):\CC504\"
				( spacingCSetRef "@sapphirecity_baseboard_lib.sapphirecity_baseboard(sch_1):\DDR4_2SPC_DQ/DQS\" )
				( netClassRef "@sapphirecity_baseboard_lib.sapphirecity_baseboard(sch_1):\DDR4_CHN_E_DQ_DQS_BYTE4\" )
				( netClassRef "@sapphirecity_baseboard_lib.sapphirecity_baseboard(sch_1):\DDR4_CHN_E_DQ_DQS_BYTE4\" )
			)
			( classClass "@crescent_city_bb_fab1_lib.crescent_city_bb_fab1(sch_1):\CC153\"
				( spacingCSetRef "@sapphirecity_baseboard_lib.sapphirecity_baseboard(sch_1):\DQ_TO_DQ\" )
				( netClassRef "@sapphirecity_baseboard_lib.sapphirecity_baseboard(sch_1):\DDR4_CHN_E_DQ_DQS_BYTE0\" )
				( netClassRef "@sapphirecity_baseboard_lib.sapphirecity_baseboard(sch_1):\DDR4_CHN_E_DQ_DQS_BYTE4\" )
			)
			( classClass "@crescent_city_bb_fab1_lib.crescent_city_bb_fab1(sch_1):\CC164\"
				( spacingCSetRef "@sapphirecity_baseboard_lib.sapphirecity_baseboard(sch_1):\DQ_TO_DQ\" )
				( netClassRef "@sapphirecity_baseboard_lib.sapphirecity_baseboard(sch_1):\DDR4_CHN_E_DQ_DQS_BYTE1\" )
				( netClassRef "@sapphirecity_baseboard_lib.sapphirecity_baseboard(sch_1):\DDR4_CHN_E_DQ_DQS_BYTE4\" )
			)
			( classClass "@crescent_city_bb_fab1_lib.crescent_city_bb_fab1(sch_1):\CC174\"
				( spacingCSetRef "@sapphirecity_baseboard_lib.sapphirecity_baseboard(sch_1):\DQ_TO_DQ\" )
				( netClassRef "@sapphirecity_baseboard_lib.sapphirecity_baseboard(sch_1):\DDR4_CHN_E_DQ_DQS_BYTE2\" )
				( netClassRef "@sapphirecity_baseboard_lib.sapphirecity_baseboard(sch_1):\DDR4_CHN_E_DQ_DQS_BYTE4\" )
			)
			( classClass "@crescent_city_bb_fab1_lib.crescent_city_bb_fab1(sch_1):\CC183\"
				( spacingCSetRef "@sapphirecity_baseboard_lib.sapphirecity_baseboard(sch_1):\DQ_TO_DQ\" )
				( netClassRef "@sapphirecity_baseboard_lib.sapphirecity_baseboard(sch_1):\DDR4_CHN_E_DQ_DQS_BYTE3\" )
				( netClassRef "@sapphirecity_baseboard_lib.sapphirecity_baseboard(sch_1):\DDR4_CHN_E_DQ_DQS_BYTE4\" )
			)
			( classClass "@crescent_city_bb_fab1_lib.crescent_city_bb_fab1(sch_1):\CC189\"
				( spacingCSetRef "@sapphirecity_baseboard_lib.sapphirecity_baseboard(sch_1):\DQ_TO_DQ\" )
				( netClassRef "@sapphirecity_baseboard_lib.sapphirecity_baseboard(sch_1):\DDR4_CHN_E_CLK\" )
				( netClassRef "@sapphirecity_baseboard_lib.sapphirecity_baseboard(sch_1):\DDR4_CHN_E_DQ_DQS_BYTE4\" )
			)
			( classClass "@crescent_city_bb_fab1_lib.crescent_city_bb_fab1(sch_1):\CC190\"
				( spacingCSetRef "@sapphirecity_baseboard_lib.sapphirecity_baseboard(sch_1):\DQ_TO_DQ\" )
				( netClassRef "@sapphirecity_baseboard_lib.sapphirecity_baseboard(sch_1):\DDR4_CHN_E_CMD_ADD\" )
				( netClassRef "@sapphirecity_baseboard_lib.sapphirecity_baseboard(sch_1):\DDR4_CHN_E_DQ_DQS_BYTE4\" )
			)
			( classClass "@crescent_city_bb_fab1_lib.crescent_city_bb_fab1(sch_1):\CC191\"
				( spacingCSetRef "@sapphirecity_baseboard_lib.sapphirecity_baseboard(sch_1):\DQ_TO_DQ\" )
				( netClassRef "@sapphirecity_baseboard_lib.sapphirecity_baseboard(sch_1):\DDR4_CHN_E_CTRL\" )
				( netClassRef "@sapphirecity_baseboard_lib.sapphirecity_baseboard(sch_1):\DDR4_CHN_E_DQ_DQS_BYTE4\" )
			)
			( classClass "@crescent_city_bb_fab1_lib.crescent_city_bb_fab1(sch_1):\CC196\"
				( spacingCSetRef "@crescent_city_bb_fab1_lib.crescent_city_bb_fab1(sch_1):\DEFAULT\" )
				( netClassRef "@sapphirecity_baseboard_lib.sapphirecity_baseboard(sch_1):\GND\" )
				( netClassRef "@sapphirecity_baseboard_lib.sapphirecity_baseboard(sch_1):\DDR4_CHN_E_DQ_DQS_BYTE4\" )
			)
			( classClass "@crescent_city_bb_fab1_lib.crescent_city_bb_fab1(sch_1):\CC40\"
				( spacingCSetRef "@crescent_city_bb_fab1_lib.crescent_city_bb_fab1(sch_1):\DEFAULT\" )
				( netClassRef "@sapphirecity_baseboard_lib.sapphirecity_baseboard(sch_1):\POWER\" )
				( netClassRef "@sapphirecity_baseboard_lib.sapphirecity_baseboard(sch_1):\DDR4_CHN_E_DQ_DQS_BYTE4\" )
			)
			( classClass "@sapphirecity_baseboard_lib.sapphirecity_baseboard(sch_1):\CC503\"
				( spacingCSetRef "@sapphirecity_baseboard_lib.sapphirecity_baseboard(sch_1):\DDR4_2SPC_DQ/DQS\" )
				( netClassRef "@sapphirecity_baseboard_lib.sapphirecity_baseboard(sch_1):\DDR4_CHN_E_DQ_DQS_BYTE3\" )
				( netClassRef "@sapphirecity_baseboard_lib.sapphirecity_baseboard(sch_1):\DDR4_CHN_E_DQ_DQS_BYTE3\" )
			)
			( classClass "@crescent_city_bb_fab1_lib.crescent_city_bb_fab1(sch_1):\CC152\"
				( spacingCSetRef "@sapphirecity_baseboard_lib.sapphirecity_baseboard(sch_1):\DQ_TO_DQ\" )
				( netClassRef "@sapphirecity_baseboard_lib.sapphirecity_baseboard(sch_1):\DDR4_CHN_E_DQ_DQS_BYTE0\" )
				( netClassRef "@sapphirecity_baseboard_lib.sapphirecity_baseboard(sch_1):\DDR4_CHN_E_DQ_DQS_BYTE3\" )
			)
			( classClass "@crescent_city_bb_fab1_lib.crescent_city_bb_fab1(sch_1):\CC163\"
				( spacingCSetRef "@sapphirecity_baseboard_lib.sapphirecity_baseboard(sch_1):\DQ_TO_DQ\" )
				( netClassRef "@sapphirecity_baseboard_lib.sapphirecity_baseboard(sch_1):\DDR4_CHN_E_DQ_DQS_BYTE1\" )
				( netClassRef "@sapphirecity_baseboard_lib.sapphirecity_baseboard(sch_1):\DDR4_CHN_E_DQ_DQS_BYTE3\" )
			)
			( classClass "@crescent_city_bb_fab1_lib.crescent_city_bb_fab1(sch_1):\CC173\"
				( spacingCSetRef "@sapphirecity_baseboard_lib.sapphirecity_baseboard(sch_1):\DQ_TO_DQ\" )
				( netClassRef "@sapphirecity_baseboard_lib.sapphirecity_baseboard(sch_1):\DDR4_CHN_E_DQ_DQS_BYTE2\" )
				( netClassRef "@sapphirecity_baseboard_lib.sapphirecity_baseboard(sch_1):\DDR4_CHN_E_DQ_DQS_BYTE3\" )
			)
			( classClass "@crescent_city_bb_fab1_lib.crescent_city_bb_fab1(sch_1):\CC180\"
				( spacingCSetRef "@sapphirecity_baseboard_lib.sapphirecity_baseboard(sch_1):\DQ_TO_DQ\" )
				( netClassRef "@sapphirecity_baseboard_lib.sapphirecity_baseboard(sch_1):\DDR4_CHN_E_CLK\" )
				( netClassRef "@sapphirecity_baseboard_lib.sapphirecity_baseboard(sch_1):\DDR4_CHN_E_DQ_DQS_BYTE3\" )
			)
			( classClass "@crescent_city_bb_fab1_lib.crescent_city_bb_fab1(sch_1):\CC181\"
				( spacingCSetRef "@sapphirecity_baseboard_lib.sapphirecity_baseboard(sch_1):\DQ_TO_DQ\" )
				( netClassRef "@sapphirecity_baseboard_lib.sapphirecity_baseboard(sch_1):\DDR4_CHN_E_CMD_ADD\" )
				( netClassRef "@sapphirecity_baseboard_lib.sapphirecity_baseboard(sch_1):\DDR4_CHN_E_DQ_DQS_BYTE3\" )
			)
			( classClass "@crescent_city_bb_fab1_lib.crescent_city_bb_fab1(sch_1):\CC182\"
				( spacingCSetRef "@sapphirecity_baseboard_lib.sapphirecity_baseboard(sch_1):\DQ_TO_DQ\" )
				( netClassRef "@sapphirecity_baseboard_lib.sapphirecity_baseboard(sch_1):\DDR4_CHN_E_CTRL\" )
				( netClassRef "@sapphirecity_baseboard_lib.sapphirecity_baseboard(sch_1):\DDR4_CHN_E_DQ_DQS_BYTE3\" )
			)
			( classClass "@crescent_city_bb_fab1_lib.crescent_city_bb_fab1(sch_1):\CC188\"
				( spacingCSetRef "@crescent_city_bb_fab1_lib.crescent_city_bb_fab1(sch_1):\DEFAULT\" )
				( netClassRef "@sapphirecity_baseboard_lib.sapphirecity_baseboard(sch_1):\GND\" )
				( netClassRef "@sapphirecity_baseboard_lib.sapphirecity_baseboard(sch_1):\DDR4_CHN_E_DQ_DQS_BYTE3\" )
			)
			( classClass "@crescent_city_bb_fab1_lib.crescent_city_bb_fab1(sch_1):\CC39\"
				( spacingCSetRef "@crescent_city_bb_fab1_lib.crescent_city_bb_fab1(sch_1):\DEFAULT\" )
				( netClassRef "@sapphirecity_baseboard_lib.sapphirecity_baseboard(sch_1):\POWER\" )
				( netClassRef "@sapphirecity_baseboard_lib.sapphirecity_baseboard(sch_1):\DDR4_CHN_E_DQ_DQS_BYTE3\" )
			)
			( classClass "@sapphirecity_baseboard_lib.sapphirecity_baseboard(sch_1):\CC502\"
				( spacingCSetRef "@sapphirecity_baseboard_lib.sapphirecity_baseboard(sch_1):\DDR4_2SPC_DQ/DQS\" )
				( netClassRef "@sapphirecity_baseboard_lib.sapphirecity_baseboard(sch_1):\DDR4_CHN_E_DQ_DQS_BYTE2\" )
				( netClassRef "@sapphirecity_baseboard_lib.sapphirecity_baseboard(sch_1):\DDR4_CHN_E_DQ_DQS_BYTE2\" )
			)
			( classClass "@crescent_city_bb_fab1_lib.crescent_city_bb_fab1(sch_1):\CC151\"
				( spacingCSetRef "@sapphirecity_baseboard_lib.sapphirecity_baseboard(sch_1):\DQ_TO_DQ\" )
				( netClassRef "@sapphirecity_baseboard_lib.sapphirecity_baseboard(sch_1):\DDR4_CHN_E_DQ_DQS_BYTE0\" )
				( netClassRef "@sapphirecity_baseboard_lib.sapphirecity_baseboard(sch_1):\DDR4_CHN_E_DQ_DQS_BYTE2\" )
			)
			( classClass "@crescent_city_bb_fab1_lib.crescent_city_bb_fab1(sch_1):\CC162\"
				( spacingCSetRef "@sapphirecity_baseboard_lib.sapphirecity_baseboard(sch_1):\DQ_TO_DQ\" )
				( netClassRef "@sapphirecity_baseboard_lib.sapphirecity_baseboard(sch_1):\DDR4_CHN_E_DQ_DQS_BYTE1\" )
				( netClassRef "@sapphirecity_baseboard_lib.sapphirecity_baseboard(sch_1):\DDR4_CHN_E_DQ_DQS_BYTE2\" )
			)
			( classClass "@crescent_city_bb_fab1_lib.crescent_city_bb_fab1(sch_1):\CC170\"
				( spacingCSetRef "@sapphirecity_baseboard_lib.sapphirecity_baseboard(sch_1):\DQ_TO_DQ\" )
				( netClassRef "@sapphirecity_baseboard_lib.sapphirecity_baseboard(sch_1):\DDR4_CHN_E_CLK\" )
				( netClassRef "@sapphirecity_baseboard_lib.sapphirecity_baseboard(sch_1):\DDR4_CHN_E_DQ_DQS_BYTE2\" )
			)
			( classClass "@crescent_city_bb_fab1_lib.crescent_city_bb_fab1(sch_1):\CC171\"
				( spacingCSetRef "@sapphirecity_baseboard_lib.sapphirecity_baseboard(sch_1):\DQ_TO_DQ\" )
				( netClassRef "@sapphirecity_baseboard_lib.sapphirecity_baseboard(sch_1):\DDR4_CHN_E_CMD_ADD\" )
				( netClassRef "@sapphirecity_baseboard_lib.sapphirecity_baseboard(sch_1):\DDR4_CHN_E_DQ_DQS_BYTE2\" )
			)
			( classClass "@crescent_city_bb_fab1_lib.crescent_city_bb_fab1(sch_1):\CC172\"
				( spacingCSetRef "@sapphirecity_baseboard_lib.sapphirecity_baseboard(sch_1):\DQ_TO_DQ\" )
				( netClassRef "@sapphirecity_baseboard_lib.sapphirecity_baseboard(sch_1):\DDR4_CHN_E_CTRL\" )
				( netClassRef "@sapphirecity_baseboard_lib.sapphirecity_baseboard(sch_1):\DDR4_CHN_E_DQ_DQS_BYTE2\" )
			)
			( classClass "@crescent_city_bb_fab1_lib.crescent_city_bb_fab1(sch_1):\CC179\"
				( spacingCSetRef "@crescent_city_bb_fab1_lib.crescent_city_bb_fab1(sch_1):\DEFAULT\" )
				( netClassRef "@sapphirecity_baseboard_lib.sapphirecity_baseboard(sch_1):\GND\" )
				( netClassRef "@sapphirecity_baseboard_lib.sapphirecity_baseboard(sch_1):\DDR4_CHN_E_DQ_DQS_BYTE2\" )
			)
			( classClass "@crescent_city_bb_fab1_lib.crescent_city_bb_fab1(sch_1):\CC38\"
				( spacingCSetRef "@crescent_city_bb_fab1_lib.crescent_city_bb_fab1(sch_1):\DEFAULT\" )
				( netClassRef "@sapphirecity_baseboard_lib.sapphirecity_baseboard(sch_1):\POWER\" )
				( netClassRef "@sapphirecity_baseboard_lib.sapphirecity_baseboard(sch_1):\DDR4_CHN_E_DQ_DQS_BYTE2\" )
			)
			( classClass "@sapphirecity_baseboard_lib.sapphirecity_baseboard(sch_1):\CC501\"
				( spacingCSetRef "@sapphirecity_baseboard_lib.sapphirecity_baseboard(sch_1):\DDR4_2SPC_DQ/DQS\" )
				( netClassRef "@sapphirecity_baseboard_lib.sapphirecity_baseboard(sch_1):\DDR4_CHN_E_DQ_DQS_BYTE1\" )
				( netClassRef "@sapphirecity_baseboard_lib.sapphirecity_baseboard(sch_1):\DDR4_CHN_E_DQ_DQS_BYTE1\" )
			)
			( classClass "@crescent_city_bb_fab1_lib.crescent_city_bb_fab1(sch_1):\CC150\"
				( spacingCSetRef "@sapphirecity_baseboard_lib.sapphirecity_baseboard(sch_1):\DQ_TO_DQ\" )
				( netClassRef "@sapphirecity_baseboard_lib.sapphirecity_baseboard(sch_1):\DDR4_CHN_E_DQ_DQS_BYTE0\" )
				( netClassRef "@sapphirecity_baseboard_lib.sapphirecity_baseboard(sch_1):\DDR4_CHN_E_DQ_DQS_BYTE1\" )
			)
			( classClass "@crescent_city_bb_fab1_lib.crescent_city_bb_fab1(sch_1):\CC159\"
				( spacingCSetRef "@sapphirecity_baseboard_lib.sapphirecity_baseboard(sch_1):\DQ_TO_DQ\" )
				( netClassRef "@sapphirecity_baseboard_lib.sapphirecity_baseboard(sch_1):\DDR4_CHN_E_CLK\" )
				( netClassRef "@sapphirecity_baseboard_lib.sapphirecity_baseboard(sch_1):\DDR4_CHN_E_DQ_DQS_BYTE1\" )
			)
			( classClass "@crescent_city_bb_fab1_lib.crescent_city_bb_fab1(sch_1):\CC160\"
				( spacingCSetRef "@sapphirecity_baseboard_lib.sapphirecity_baseboard(sch_1):\DQ_TO_DQ\" )
				( netClassRef "@sapphirecity_baseboard_lib.sapphirecity_baseboard(sch_1):\DDR4_CHN_E_CMD_ADD\" )
				( netClassRef "@sapphirecity_baseboard_lib.sapphirecity_baseboard(sch_1):\DDR4_CHN_E_DQ_DQS_BYTE1\" )
			)
			( classClass "@crescent_city_bb_fab1_lib.crescent_city_bb_fab1(sch_1):\CC161\"
				( spacingCSetRef "@sapphirecity_baseboard_lib.sapphirecity_baseboard(sch_1):\DQ_TO_DQ\" )
				( netClassRef "@sapphirecity_baseboard_lib.sapphirecity_baseboard(sch_1):\DDR4_CHN_E_CTRL\" )
				( netClassRef "@sapphirecity_baseboard_lib.sapphirecity_baseboard(sch_1):\DDR4_CHN_E_DQ_DQS_BYTE1\" )
			)
			( classClass "@crescent_city_bb_fab1_lib.crescent_city_bb_fab1(sch_1):\CC169\"
				( spacingCSetRef "@crescent_city_bb_fab1_lib.crescent_city_bb_fab1(sch_1):\DEFAULT\" )
				( netClassRef "@sapphirecity_baseboard_lib.sapphirecity_baseboard(sch_1):\GND\" )
				( netClassRef "@sapphirecity_baseboard_lib.sapphirecity_baseboard(sch_1):\DDR4_CHN_E_DQ_DQS_BYTE1\" )
			)
			( classClass "@crescent_city_bb_fab1_lib.crescent_city_bb_fab1(sch_1):\CC37\"
				( spacingCSetRef "@crescent_city_bb_fab1_lib.crescent_city_bb_fab1(sch_1):\DEFAULT\" )
				( netClassRef "@sapphirecity_baseboard_lib.sapphirecity_baseboard(sch_1):\POWER\" )
				( netClassRef "@sapphirecity_baseboard_lib.sapphirecity_baseboard(sch_1):\DDR4_CHN_E_DQ_DQS_BYTE1\" )
			)
			( classClass "@sapphirecity_baseboard_lib.sapphirecity_baseboard(sch_1):\CC500\"
				( spacingCSetRef "@sapphirecity_baseboard_lib.sapphirecity_baseboard(sch_1):\DDR4_2SPC_DQ/DQS\" )
				( netClassRef "@sapphirecity_baseboard_lib.sapphirecity_baseboard(sch_1):\DDR4_CHN_E_DQ_DQS_BYTE0\" )
				( netClassRef "@sapphirecity_baseboard_lib.sapphirecity_baseboard(sch_1):\DDR4_CHN_E_DQ_DQS_BYTE0\" )
			)
			( classClass "@crescent_city_bb_fab1_lib.crescent_city_bb_fab1(sch_1):\CC147\"
				( spacingCSetRef "@sapphirecity_baseboard_lib.sapphirecity_baseboard(sch_1):\DQ_TO_DQ\" )
				( netClassRef "@sapphirecity_baseboard_lib.sapphirecity_baseboard(sch_1):\DDR4_CHN_E_CLK\" )
				( netClassRef "@sapphirecity_baseboard_lib.sapphirecity_baseboard(sch_1):\DDR4_CHN_E_DQ_DQS_BYTE0\" )
			)
			( classClass "@crescent_city_bb_fab1_lib.crescent_city_bb_fab1(sch_1):\CC148\"
				( spacingCSetRef "@sapphirecity_baseboard_lib.sapphirecity_baseboard(sch_1):\DQ_TO_DQ\" )
				( netClassRef "@sapphirecity_baseboard_lib.sapphirecity_baseboard(sch_1):\DDR4_CHN_E_CMD_ADD\" )
				( netClassRef "@sapphirecity_baseboard_lib.sapphirecity_baseboard(sch_1):\DDR4_CHN_E_DQ_DQS_BYTE0\" )
			)
			( classClass "@crescent_city_bb_fab1_lib.crescent_city_bb_fab1(sch_1):\CC149\"
				( spacingCSetRef "@sapphirecity_baseboard_lib.sapphirecity_baseboard(sch_1):\DQ_TO_DQ\" )
				( netClassRef "@sapphirecity_baseboard_lib.sapphirecity_baseboard(sch_1):\DDR4_CHN_E_CTRL\" )
				( netClassRef "@sapphirecity_baseboard_lib.sapphirecity_baseboard(sch_1):\DDR4_CHN_E_DQ_DQS_BYTE0\" )
			)
			( classClass "@crescent_city_bb_fab1_lib.crescent_city_bb_fab1(sch_1):\CC158\"
				( spacingCSetRef "@crescent_city_bb_fab1_lib.crescent_city_bb_fab1(sch_1):\DEFAULT\" )
				( netClassRef "@sapphirecity_baseboard_lib.sapphirecity_baseboard(sch_1):\GND\" )
				( netClassRef "@sapphirecity_baseboard_lib.sapphirecity_baseboard(sch_1):\DDR4_CHN_E_DQ_DQS_BYTE0\" )
			)
			( classClass "@crescent_city_bb_fab1_lib.crescent_city_bb_fab1(sch_1):\CC36\"
				( spacingCSetRef "@crescent_city_bb_fab1_lib.crescent_city_bb_fab1(sch_1):\DEFAULT\" )
				( netClassRef "@sapphirecity_baseboard_lib.sapphirecity_baseboard(sch_1):\POWER\" )
				( netClassRef "@sapphirecity_baseboard_lib.sapphirecity_baseboard(sch_1):\DDR4_CHN_E_DQ_DQS_BYTE0\" )
			)
			( classClass "@sapphirecity_baseboard_lib.sapphirecity_baseboard(sch_1):\CC236\"
				( spacingCSetRef "@crescent_city_bb_fab1_lib.crescent_city_bb_fab1(sch_1):\DEFAULT\" )
				( netClassRef "@sapphirecity_baseboard_lib.sapphirecity_baseboard(sch_1):\GND\" )
				( netClassRef "@sapphirecity_baseboard_lib.sapphirecity_baseboard(sch_1):\DDR4_CHN_E_CTRL\" )
			)
			( classClass "@sapphirecity_baseboard_lib.sapphirecity_baseboard(sch_1):\CC494\"
				( spacingCSetRef "@sapphirecity_baseboard_lib.sapphirecity_baseboard(sch_1):\DDR4_2SPC_CAC\" )
				( netClassRef "@sapphirecity_baseboard_lib.sapphirecity_baseboard(sch_1):\DDR4_CHN_E_CLK\" )
				( netClassRef "@sapphirecity_baseboard_lib.sapphirecity_baseboard(sch_1):\DDR4_CHN_E_CTRL\" )
			)
			( classClass "@sapphirecity_baseboard_lib.sapphirecity_baseboard(sch_1):\CC497\"
				( spacingCSetRef "@sapphirecity_baseboard_lib.sapphirecity_baseboard(sch_1):\DDR4_2SPC_CAC\" )
				( netClassRef "@sapphirecity_baseboard_lib.sapphirecity_baseboard(sch_1):\DDR4_CHN_E_CMD_ADD\" )
				( netClassRef "@sapphirecity_baseboard_lib.sapphirecity_baseboard(sch_1):\DDR4_CHN_E_CTRL\" )
			)
			( classClass "@sapphirecity_baseboard_lib.sapphirecity_baseboard(sch_1):\CC499\"
				( spacingCSetRef "@sapphirecity_baseboard_lib.sapphirecity_baseboard(sch_1):\DDR4_2SPC_CAC\" )
				( netClassRef "@sapphirecity_baseboard_lib.sapphirecity_baseboard(sch_1):\DDR4_CHN_E_CTRL\" )
				( netClassRef "@sapphirecity_baseboard_lib.sapphirecity_baseboard(sch_1):\DDR4_CHN_E_CTRL\" )
			)
			( classClass "@crescent_city_bb_fab1_lib.crescent_city_bb_fab1(sch_1):\CC25\"
				( spacingCSetRef "@crescent_city_bb_fab1_lib.crescent_city_bb_fab1(sch_1):\DEFAULT\" )
				( netClassRef "@sapphirecity_baseboard_lib.sapphirecity_baseboard(sch_1):\POWER\" )
				( netClassRef "@sapphirecity_baseboard_lib.sapphirecity_baseboard(sch_1):\DDR4_CHN_E_CTRL\" )
			)
			( classClass "@sapphirecity_baseboard_lib.sapphirecity_baseboard(sch_1):\CC235\"
				( spacingCSetRef "@crescent_city_bb_fab1_lib.crescent_city_bb_fab1(sch_1):\DEFAULT\" )
				( netClassRef "@sapphirecity_baseboard_lib.sapphirecity_baseboard(sch_1):\GND\" )
				( netClassRef "@sapphirecity_baseboard_lib.sapphirecity_baseboard(sch_1):\DDR4_CHN_E_CMD_ADD\" )
			)
			( classClass "@sapphirecity_baseboard_lib.sapphirecity_baseboard(sch_1):\CC495\"
				( spacingCSetRef "@sapphirecity_baseboard_lib.sapphirecity_baseboard(sch_1):\DDR4_2SPC_CAC\" )
				( netClassRef "@sapphirecity_baseboard_lib.sapphirecity_baseboard(sch_1):\DDR4_CHN_E_CLK\" )
				( netClassRef "@sapphirecity_baseboard_lib.sapphirecity_baseboard(sch_1):\DDR4_CHN_E_CMD_ADD\" )
			)
			( classClass "@sapphirecity_baseboard_lib.sapphirecity_baseboard(sch_1):\CC498\"
				( spacingCSetRef "@sapphirecity_baseboard_lib.sapphirecity_baseboard(sch_1):\DDR4_2SPC_CAC\" )
				( netClassRef "@sapphirecity_baseboard_lib.sapphirecity_baseboard(sch_1):\DDR4_CHN_E_CMD_ADD\" )
				( netClassRef "@sapphirecity_baseboard_lib.sapphirecity_baseboard(sch_1):\DDR4_CHN_E_CMD_ADD\" )
			)
			( classClass "@crescent_city_bb_fab1_lib.crescent_city_bb_fab1(sch_1):\CC69\"
				( spacingCSetRef "@crescent_city_bb_fab1_lib.crescent_city_bb_fab1(sch_1):\DEFAULT\" )
				( netClassRef "@sapphirecity_baseboard_lib.sapphirecity_baseboard(sch_1):\POWER\" )
				( netClassRef "@sapphirecity_baseboard_lib.sapphirecity_baseboard(sch_1):\DDR4_CHN_E_CMD_ADD\" )
			)
			( classClass "@sapphirecity_baseboard_lib.sapphirecity_baseboard(sch_1):\CC234\"
				( spacingCSetRef "@crescent_city_bb_fab1_lib.crescent_city_bb_fab1(sch_1):\DEFAULT\" )
				( netClassRef "@sapphirecity_baseboard_lib.sapphirecity_baseboard(sch_1):\GND\" )
				( netClassRef "@sapphirecity_baseboard_lib.sapphirecity_baseboard(sch_1):\DDR4_CHN_E_CLK\" )
			)
			( classClass "@sapphirecity_baseboard_lib.sapphirecity_baseboard(sch_1):\CC496\"
				( spacingCSetRef "@sapphirecity_baseboard_lib.sapphirecity_baseboard(sch_1):\DDR4_2SPC_CAC\" )
				( netClassRef "@sapphirecity_baseboard_lib.sapphirecity_baseboard(sch_1):\DDR4_CHN_E_CLK\" )
				( netClassRef "@sapphirecity_baseboard_lib.sapphirecity_baseboard(sch_1):\DDR4_CHN_E_CLK\" )
			)
			( classClass "@crescent_city_bb_fab1_lib.crescent_city_bb_fab1(sch_1):\CC68\"
				( spacingCSetRef "@crescent_city_bb_fab1_lib.crescent_city_bb_fab1(sch_1):\DEFAULT\" )
				( netClassRef "@sapphirecity_baseboard_lib.sapphirecity_baseboard(sch_1):\POWER\" )
				( netClassRef "@sapphirecity_baseboard_lib.sapphirecity_baseboard(sch_1):\DDR4_CHN_E_CLK\" )
			)
			( classClass "@sapphirecity_baseboard_lib.sapphirecity_baseboard(sch_1):\CC493\"
				( spacingCSetRef "@sapphirecity_baseboard_lib.sapphirecity_baseboard(sch_1):\DDR4_2SPC_DQ/DQS\" )
				( netClassRef "@sapphirecity_baseboard_lib.sapphirecity_baseboard(sch_1):\DDR4_CHN_D_ECC\" )
				( netClassRef "@sapphirecity_baseboard_lib.sapphirecity_baseboard(sch_1):\DDR4_CHN_D_ECC\" )
			)
			( classClass "@crescent_city_bb_fab1_lib.crescent_city_bb_fab1(sch_1):\CC143\"
				( spacingCSetRef "@sapphirecity_baseboard_lib.sapphirecity_baseboard(sch_1):\DQ_TO_DQ\" )
				( netClassRef "@sapphirecity_baseboard_lib.sapphirecity_baseboard(sch_1):\DDR4_CHN_D_CLK\" )
				( netClassRef "@sapphirecity_baseboard_lib.sapphirecity_baseboard(sch_1):\DDR4_CHN_D_ECC\" )
			)
			( classClass "@crescent_city_bb_fab1_lib.crescent_city_bb_fab1(sch_1):\CC144\"
				( spacingCSetRef "@sapphirecity_baseboard_lib.sapphirecity_baseboard(sch_1):\DQ_TO_DQ\" )
				( netClassRef "@sapphirecity_baseboard_lib.sapphirecity_baseboard(sch_1):\DDR4_CHN_D_CMD_ADD\" )
				( netClassRef "@sapphirecity_baseboard_lib.sapphirecity_baseboard(sch_1):\DDR4_CHN_D_ECC\" )
			)
			( classClass "@crescent_city_bb_fab1_lib.crescent_city_bb_fab1(sch_1):\CC145\"
				( spacingCSetRef "@sapphirecity_baseboard_lib.sapphirecity_baseboard(sch_1):\10H_SL_12H_MS\" )
				( netClassRef "@sapphirecity_baseboard_lib.sapphirecity_baseboard(sch_1):\DDR4_CHN_D_CTRL\" )
				( netClassRef "@sapphirecity_baseboard_lib.sapphirecity_baseboard(sch_1):\DDR4_CHN_D_ECC\" )
			)
			( classClass "@crescent_city_bb_fab1_lib.crescent_city_bb_fab1(sch_1):\CC146\"
				( spacingCSetRef "@crescent_city_bb_fab1_lib.crescent_city_bb_fab1(sch_1):\DEFAULT\" )
				( netClassRef "@sapphirecity_baseboard_lib.sapphirecity_baseboard(sch_1):\GND\" )
				( netClassRef "@sapphirecity_baseboard_lib.sapphirecity_baseboard(sch_1):\DDR4_CHN_D_ECC\" )
			)
			( classClass "@crescent_city_bb_fab1_lib.crescent_city_bb_fab1(sch_1):\CC35\"
				( spacingCSetRef "@crescent_city_bb_fab1_lib.crescent_city_bb_fab1(sch_1):\DEFAULT\" )
				( netClassRef "@sapphirecity_baseboard_lib.sapphirecity_baseboard(sch_1):\POWER\" )
				( netClassRef "@sapphirecity_baseboard_lib.sapphirecity_baseboard(sch_1):\DDR4_CHN_D_ECC\" )
			)
			( classClass "@sapphirecity_baseboard_lib.sapphirecity_baseboard(sch_1):\CC233\"
				( spacingCSetRef "@crescent_city_bb_fab1_lib.crescent_city_bb_fab1(sch_1):\DEFAULT\" )
				( netClassRef "@sapphirecity_baseboard_lib.sapphirecity_baseboard(sch_1):\GND\" )
				( netClassRef "@sapphirecity_baseboard_lib.sapphirecity_baseboard(sch_1):\DDR4_CHN_D_CTRL\" )
			)
			( classClass "@sapphirecity_baseboard_lib.sapphirecity_baseboard(sch_1):\CC487\"
				( spacingCSetRef "@sapphirecity_baseboard_lib.sapphirecity_baseboard(sch_1):\DDR4_2SPC_CAC\" )
				( netClassRef "@sapphirecity_baseboard_lib.sapphirecity_baseboard(sch_1):\DDR4_CHN_D_CLK\" )
				( netClassRef "@sapphirecity_baseboard_lib.sapphirecity_baseboard(sch_1):\DDR4_CHN_D_CTRL\" )
			)
			( classClass "@sapphirecity_baseboard_lib.sapphirecity_baseboard(sch_1):\CC490\"
				( spacingCSetRef "@sapphirecity_baseboard_lib.sapphirecity_baseboard(sch_1):\DDR4_2SPC_CAC\" )
				( netClassRef "@sapphirecity_baseboard_lib.sapphirecity_baseboard(sch_1):\DDR4_CHN_D_CMD_ADD\" )
				( netClassRef "@sapphirecity_baseboard_lib.sapphirecity_baseboard(sch_1):\DDR4_CHN_D_CTRL\" )
			)
			( classClass "@sapphirecity_baseboard_lib.sapphirecity_baseboard(sch_1):\CC492\"
				( spacingCSetRef "@sapphirecity_baseboard_lib.sapphirecity_baseboard(sch_1):\DDR4_2SPC_CAC\" )
				( netClassRef "@sapphirecity_baseboard_lib.sapphirecity_baseboard(sch_1):\DDR4_CHN_D_CTRL\" )
				( netClassRef "@sapphirecity_baseboard_lib.sapphirecity_baseboard(sch_1):\DDR4_CHN_D_CTRL\" )
			)
			( classClass "@crescent_city_bb_fab1_lib.crescent_city_bb_fab1(sch_1):\CC67\"
				( spacingCSetRef "@crescent_city_bb_fab1_lib.crescent_city_bb_fab1(sch_1):\DEFAULT\" )
				( netClassRef "@sapphirecity_baseboard_lib.sapphirecity_baseboard(sch_1):\POWER\" )
				( netClassRef "@sapphirecity_baseboard_lib.sapphirecity_baseboard(sch_1):\DDR4_CHN_D_CTRL\" )
			)
			( classClass "@sapphirecity_baseboard_lib.sapphirecity_baseboard(sch_1):\CC232\"
				( spacingCSetRef "@crescent_city_bb_fab1_lib.crescent_city_bb_fab1(sch_1):\DEFAULT\" )
				( netClassRef "@sapphirecity_baseboard_lib.sapphirecity_baseboard(sch_1):\GND\" )
				( netClassRef "@sapphirecity_baseboard_lib.sapphirecity_baseboard(sch_1):\DDR4_CHN_D_CMD_ADD\" )
			)
			( classClass "@sapphirecity_baseboard_lib.sapphirecity_baseboard(sch_1):\CC488\"
				( spacingCSetRef "@sapphirecity_baseboard_lib.sapphirecity_baseboard(sch_1):\DDR4_2SPC_CAC\" )
				( netClassRef "@sapphirecity_baseboard_lib.sapphirecity_baseboard(sch_1):\DDR4_CHN_D_CLK\" )
				( netClassRef "@sapphirecity_baseboard_lib.sapphirecity_baseboard(sch_1):\DDR4_CHN_D_CMD_ADD\" )
			)
			( classClass "@sapphirecity_baseboard_lib.sapphirecity_baseboard(sch_1):\CC491\"
				( spacingCSetRef "@sapphirecity_baseboard_lib.sapphirecity_baseboard(sch_1):\DDR4_2SPC_CAC\" )
				( netClassRef "@sapphirecity_baseboard_lib.sapphirecity_baseboard(sch_1):\DDR4_CHN_D_CMD_ADD\" )
				( netClassRef "@sapphirecity_baseboard_lib.sapphirecity_baseboard(sch_1):\DDR4_CHN_D_CMD_ADD\" )
			)
			( classClass "@crescent_city_bb_fab1_lib.crescent_city_bb_fab1(sch_1):\CC66\"
				( spacingCSetRef "@crescent_city_bb_fab1_lib.crescent_city_bb_fab1(sch_1):\DEFAULT\" )
				( netClassRef "@sapphirecity_baseboard_lib.sapphirecity_baseboard(sch_1):\POWER\" )
				( netClassRef "@sapphirecity_baseboard_lib.sapphirecity_baseboard(sch_1):\DDR4_CHN_D_CMD_ADD\" )
			)
			( classClass "@sapphirecity_baseboard_lib.sapphirecity_baseboard(sch_1):\CC231\"
				( spacingCSetRef "@crescent_city_bb_fab1_lib.crescent_city_bb_fab1(sch_1):\DEFAULT\" )
				( netClassRef "@sapphirecity_baseboard_lib.sapphirecity_baseboard(sch_1):\GND\" )
				( netClassRef "@sapphirecity_baseboard_lib.sapphirecity_baseboard(sch_1):\DDR4_CHN_D_CLK\" )
			)
			( classClass "@sapphirecity_baseboard_lib.sapphirecity_baseboard(sch_1):\CC489\"
				( spacingCSetRef "@sapphirecity_baseboard_lib.sapphirecity_baseboard(sch_1):\DDR4_2SPC_CAC\" )
				( netClassRef "@sapphirecity_baseboard_lib.sapphirecity_baseboard(sch_1):\DDR4_CHN_D_CLK\" )
				( netClassRef "@sapphirecity_baseboard_lib.sapphirecity_baseboard(sch_1):\DDR4_CHN_D_CLK\" )
			)
			( classClass "@crescent_city_bb_fab1_lib.crescent_city_bb_fab1(sch_1):\CC65\"
				( spacingCSetRef "@crescent_city_bb_fab1_lib.crescent_city_bb_fab1(sch_1):\DEFAULT\" )
				( netClassRef "@sapphirecity_baseboard_lib.sapphirecity_baseboard(sch_1):\POWER\" )
				( netClassRef "@sapphirecity_baseboard_lib.sapphirecity_baseboard(sch_1):\DDR4_CHN_D_CLK\" )
			)
			( classClass "@sapphirecity_baseboard_lib.sapphirecity_baseboard(sch_1):\CC230\"
				( spacingCSetRef "@crescent_city_bb_fab1_lib.crescent_city_bb_fab1(sch_1):\DEFAULT\" )
				( netClassRef "@sapphirecity_baseboard_lib.sapphirecity_baseboard(sch_1):\GND\" )
				( netClassRef "@sapphirecity_baseboard_lib.sapphirecity_baseboard(sch_1):\DDR4_CHN_C_ECC\" )
			)
			( classClass "@sapphirecity_baseboard_lib.sapphirecity_baseboard(sch_1):\CC453\"
				( spacingCSetRef "@sapphirecity_baseboard_lib.sapphirecity_baseboard(sch_1):\DQ_TO_DQ\" )
				( netClassRef "@sapphirecity_baseboard_lib.sapphirecity_baseboard(sch_1):\DDR4_CHN_C_CLK\" )
				( netClassRef "@sapphirecity_baseboard_lib.sapphirecity_baseboard(sch_1):\DDR4_CHN_C_ECC\" )
			)
			( classClass "@sapphirecity_baseboard_lib.sapphirecity_baseboard(sch_1):\CC465\"
				( spacingCSetRef "@sapphirecity_baseboard_lib.sapphirecity_baseboard(sch_1):\DQ_TO_DQ\" )
				( netClassRef "@sapphirecity_baseboard_lib.sapphirecity_baseboard(sch_1):\DDR4_CHN_C_CMD_ADD\" )
				( netClassRef "@sapphirecity_baseboard_lib.sapphirecity_baseboard(sch_1):\DDR4_CHN_C_ECC\" )
			)
			( classClass "@sapphirecity_baseboard_lib.sapphirecity_baseboard(sch_1):\CC476\"
				( spacingCSetRef "@sapphirecity_baseboard_lib.sapphirecity_baseboard(sch_1):\DQ_TO_DQ\" )
				( netClassRef "@sapphirecity_baseboard_lib.sapphirecity_baseboard(sch_1):\DDR4_CHN_C_CTRL\" )
				( netClassRef "@sapphirecity_baseboard_lib.sapphirecity_baseboard(sch_1):\DDR4_CHN_C_ECC\" )
			)
			( classClass "@sapphirecity_baseboard_lib.sapphirecity_baseboard(sch_1):\CC486\"
				( spacingCSetRef "@sapphirecity_baseboard_lib.sapphirecity_baseboard(sch_1):\DDR4_2SPC_DQ/DQS\" )
				( netClassRef "@sapphirecity_baseboard_lib.sapphirecity_baseboard(sch_1):\DDR4_CHN_C_ECC\" )
				( netClassRef "@sapphirecity_baseboard_lib.sapphirecity_baseboard(sch_1):\DDR4_CHN_C_ECC\" )
			)
			( classClass "@crescent_city_bb_fab1_lib.crescent_city_bb_fab1(sch_1):\CC64\"
				( spacingCSetRef "@crescent_city_bb_fab1_lib.crescent_city_bb_fab1(sch_1):\DEFAULT\" )
				( netClassRef "@sapphirecity_baseboard_lib.sapphirecity_baseboard(sch_1):\POWER\" )
				( netClassRef "@sapphirecity_baseboard_lib.sapphirecity_baseboard(sch_1):\DDR4_CHN_C_ECC\" )
			)
			( classClass "@sapphirecity_baseboard_lib.sapphirecity_baseboard(sch_1):\CC229\"
				( spacingCSetRef "@crescent_city_bb_fab1_lib.crescent_city_bb_fab1(sch_1):\DEFAULT\" )
				( netClassRef "@sapphirecity_baseboard_lib.sapphirecity_baseboard(sch_1):\GND\" )
				( netClassRef "@sapphirecity_baseboard_lib.sapphirecity_baseboard(sch_1):\DDR4_CHN_C_CTRL\" )
			)
			( classClass "@sapphirecity_baseboard_lib.sapphirecity_baseboard(sch_1):\CC454\"
				( spacingCSetRef "@sapphirecity_baseboard_lib.sapphirecity_baseboard(sch_1):\DDR4_2SPC_CAC\" )
				( netClassRef "@sapphirecity_baseboard_lib.sapphirecity_baseboard(sch_1):\DDR4_CHN_C_CLK\" )
				( netClassRef "@sapphirecity_baseboard_lib.sapphirecity_baseboard(sch_1):\DDR4_CHN_C_CTRL\" )
			)
			( classClass "@sapphirecity_baseboard_lib.sapphirecity_baseboard(sch_1):\CC466\"
				( spacingCSetRef "@sapphirecity_baseboard_lib.sapphirecity_baseboard(sch_1):\DDR4_2SPC_CAC\" )
				( netClassRef "@sapphirecity_baseboard_lib.sapphirecity_baseboard(sch_1):\DDR4_CHN_C_CMD_ADD\" )
				( netClassRef "@sapphirecity_baseboard_lib.sapphirecity_baseboard(sch_1):\DDR4_CHN_C_CTRL\" )
			)
			( classClass "@sapphirecity_baseboard_lib.sapphirecity_baseboard(sch_1):\CC477\"
				( spacingCSetRef "@sapphirecity_baseboard_lib.sapphirecity_baseboard(sch_1):\DDR4_2SPC_CAC\" )
				( netClassRef "@sapphirecity_baseboard_lib.sapphirecity_baseboard(sch_1):\DDR4_CHN_C_CTRL\" )
				( netClassRef "@sapphirecity_baseboard_lib.sapphirecity_baseboard(sch_1):\DDR4_CHN_C_CTRL\" )
			)
			( classClass "@sapphirecity_baseboard_lib.sapphirecity_baseboard(sch_1):\CC228\"
				( spacingCSetRef "@crescent_city_bb_fab1_lib.crescent_city_bb_fab1(sch_1):\DEFAULT\" )
				( netClassRef "@sapphirecity_baseboard_lib.sapphirecity_baseboard(sch_1):\GND\" )
				( netClassRef "@sapphirecity_baseboard_lib.sapphirecity_baseboard(sch_1):\DDR4_CHN_C_CMD_ADD\" )
			)
			( classClass "@sapphirecity_baseboard_lib.sapphirecity_baseboard(sch_1):\CC455\"
				( spacingCSetRef "@sapphirecity_baseboard_lib.sapphirecity_baseboard(sch_1):\DDR4_2SPC_CAC\" )
				( netClassRef "@sapphirecity_baseboard_lib.sapphirecity_baseboard(sch_1):\DDR4_CHN_C_CLK\" )
				( netClassRef "@sapphirecity_baseboard_lib.sapphirecity_baseboard(sch_1):\DDR4_CHN_C_CMD_ADD\" )
			)
			( classClass "@sapphirecity_baseboard_lib.sapphirecity_baseboard(sch_1):\CC467\"
				( spacingCSetRef "@sapphirecity_baseboard_lib.sapphirecity_baseboard(sch_1):\DDR4_2SPC_CAC\" )
				( netClassRef "@sapphirecity_baseboard_lib.sapphirecity_baseboard(sch_1):\DDR4_CHN_C_CMD_ADD\" )
				( netClassRef "@sapphirecity_baseboard_lib.sapphirecity_baseboard(sch_1):\DDR4_CHN_C_CMD_ADD\" )
			)
			( classClass "@crescent_city_bb_fab1_lib.crescent_city_bb_fab1(sch_1):\CC63\"
				( spacingCSetRef "@crescent_city_bb_fab1_lib.crescent_city_bb_fab1(sch_1):\DEFAULT\" )
				( netClassRef "@sapphirecity_baseboard_lib.sapphirecity_baseboard(sch_1):\POWER\" )
				( netClassRef "@sapphirecity_baseboard_lib.sapphirecity_baseboard(sch_1):\DDR4_CHN_C_CMD_ADD\" )
			)
			( classClass "@sapphirecity_baseboard_lib.sapphirecity_baseboard(sch_1):\CC227\"
				( spacingCSetRef "@crescent_city_bb_fab1_lib.crescent_city_bb_fab1(sch_1):\DEFAULT\" )
				( netClassRef "@sapphirecity_baseboard_lib.sapphirecity_baseboard(sch_1):\GND\" )
				( netClassRef "@sapphirecity_baseboard_lib.sapphirecity_baseboard(sch_1):\DDR4_CHN_C_CLK\" )
			)
			( classClass "@sapphirecity_baseboard_lib.sapphirecity_baseboard(sch_1):\CC456\"
				( spacingCSetRef "@sapphirecity_baseboard_lib.sapphirecity_baseboard(sch_1):\DDR4_2SPC_CAC\" )
				( netClassRef "@sapphirecity_baseboard_lib.sapphirecity_baseboard(sch_1):\DDR4_CHN_C_CLK\" )
				( netClassRef "@sapphirecity_baseboard_lib.sapphirecity_baseboard(sch_1):\DDR4_CHN_C_CLK\" )
			)
			( classClass "@crescent_city_bb_fab1_lib.crescent_city_bb_fab1(sch_1):\CC62\"
				( spacingCSetRef "@crescent_city_bb_fab1_lib.crescent_city_bb_fab1(sch_1):\DEFAULT\" )
				( netClassRef "@sapphirecity_baseboard_lib.sapphirecity_baseboard(sch_1):\POWER\" )
				( netClassRef "@sapphirecity_baseboard_lib.sapphirecity_baseboard(sch_1):\DDR4_CHN_C_CLK\" )
			)
			( classClass "@sapphirecity_baseboard_lib.sapphirecity_baseboard(sch_1):\CC226\"
				( spacingCSetRef "@crescent_city_bb_fab1_lib.crescent_city_bb_fab1(sch_1):\DEFAULT\" )
				( netClassRef "@sapphirecity_baseboard_lib.sapphirecity_baseboard(sch_1):\GND\" )
				( netClassRef "@sapphirecity_baseboard_lib.sapphirecity_baseboard(sch_1):\DDR4_CHN_B_ECC\" )
			)
			( classClass "@sapphirecity_baseboard_lib.sapphirecity_baseboard(sch_1):\CC411\"
				( spacingCSetRef "@sapphirecity_baseboard_lib.sapphirecity_baseboard(sch_1):\DQ_TO_DQ\" )
				( netClassRef "@sapphirecity_baseboard_lib.sapphirecity_baseboard(sch_1):\DDR4_CHN_B_CLK\" )
				( netClassRef "@sapphirecity_baseboard_lib.sapphirecity_baseboard(sch_1):\DDR4_CHN_B_ECC\" )
			)
			( classClass "@sapphirecity_baseboard_lib.sapphirecity_baseboard(sch_1):\CC425\"
				( spacingCSetRef "@sapphirecity_baseboard_lib.sapphirecity_baseboard(sch_1):\DQ_TO_DQ\" )
				( netClassRef "@sapphirecity_baseboard_lib.sapphirecity_baseboard(sch_1):\DDR4_CHN_B_CMD_ADD\" )
				( netClassRef "@sapphirecity_baseboard_lib.sapphirecity_baseboard(sch_1):\DDR4_CHN_B_ECC\" )
			)
			( classClass "@sapphirecity_baseboard_lib.sapphirecity_baseboard(sch_1):\CC434\"
				( spacingCSetRef "@sapphirecity_baseboard_lib.sapphirecity_baseboard(sch_1):\DQ_TO_DQ\" )
				( netClassRef "@sapphirecity_baseboard_lib.sapphirecity_baseboard(sch_1):\DDR4_CHN_B_CTRL\" )
				( netClassRef "@sapphirecity_baseboard_lib.sapphirecity_baseboard(sch_1):\DDR4_CHN_B_ECC\" )
			)
			( classClass "@sapphirecity_baseboard_lib.sapphirecity_baseboard(sch_1):\CC444\"
				( spacingCSetRef "@sapphirecity_baseboard_lib.sapphirecity_baseboard(sch_1):\DDR4_2SPC_DQ/DQS\" )
				( netClassRef "@sapphirecity_baseboard_lib.sapphirecity_baseboard(sch_1):\DDR4_CHN_B_ECC\" )
				( netClassRef "@sapphirecity_baseboard_lib.sapphirecity_baseboard(sch_1):\DDR4_CHN_B_ECC\" )
			)
			( classClass "@crescent_city_bb_fab1_lib.crescent_city_bb_fab1(sch_1):\CC61\"
				( spacingCSetRef "@crescent_city_bb_fab1_lib.crescent_city_bb_fab1(sch_1):\DEFAULT\" )
				( netClassRef "@sapphirecity_baseboard_lib.sapphirecity_baseboard(sch_1):\POWER\" )
				( netClassRef "@sapphirecity_baseboard_lib.sapphirecity_baseboard(sch_1):\DDR4_CHN_B_ECC\" )
			)
			( classClass "@sapphirecity_baseboard_lib.sapphirecity_baseboard(sch_1):\CC225\"
				( spacingCSetRef "@crescent_city_bb_fab1_lib.crescent_city_bb_fab1(sch_1):\DEFAULT\" )
				( netClassRef "@sapphirecity_baseboard_lib.sapphirecity_baseboard(sch_1):\GND\" )
				( netClassRef "@sapphirecity_baseboard_lib.sapphirecity_baseboard(sch_1):\DDR4_CHN_B_CTRL\" )
			)
			( classClass "@sapphirecity_baseboard_lib.sapphirecity_baseboard(sch_1):\CC412\"
				( spacingCSetRef "@sapphirecity_baseboard_lib.sapphirecity_baseboard(sch_1):\DDR4_2SPC_CAC\" )
				( netClassRef "@sapphirecity_baseboard_lib.sapphirecity_baseboard(sch_1):\DDR4_CHN_B_CLK\" )
				( netClassRef "@sapphirecity_baseboard_lib.sapphirecity_baseboard(sch_1):\DDR4_CHN_B_CTRL\" )
			)
			( classClass "@sapphirecity_baseboard_lib.sapphirecity_baseboard(sch_1):\CC415\"
				( spacingCSetRef "@sapphirecity_baseboard_lib.sapphirecity_baseboard(sch_1):\DDR4_2SPC_CAC\" )
				( netClassRef "@sapphirecity_baseboard_lib.sapphirecity_baseboard(sch_1):\DDR4_CHN_B_CMD_ADD\" )
				( netClassRef "@sapphirecity_baseboard_lib.sapphirecity_baseboard(sch_1):\DDR4_CHN_B_CTRL\" )
			)
			( classClass "@sapphirecity_baseboard_lib.sapphirecity_baseboard(sch_1):\CC435\"
				( spacingCSetRef "@sapphirecity_baseboard_lib.sapphirecity_baseboard(sch_1):\DDR4_2SPC_CAC\" )
				( netClassRef "@sapphirecity_baseboard_lib.sapphirecity_baseboard(sch_1):\DDR4_CHN_B_CTRL\" )
				( netClassRef "@sapphirecity_baseboard_lib.sapphirecity_baseboard(sch_1):\DDR4_CHN_B_CTRL\" )
			)
			( classClass "@crescent_city_bb_fab1_lib.crescent_city_bb_fab1(sch_1):\CC60\"
				( spacingCSetRef "@crescent_city_bb_fab1_lib.crescent_city_bb_fab1(sch_1):\DEFAULT\" )
				( netClassRef "@sapphirecity_baseboard_lib.sapphirecity_baseboard(sch_1):\POWER\" )
				( netClassRef "@sapphirecity_baseboard_lib.sapphirecity_baseboard(sch_1):\DDR4_CHN_B_CTRL\" )
			)
			( classClass "@sapphirecity_baseboard_lib.sapphirecity_baseboard(sch_1):\CC224\"
				( spacingCSetRef "@crescent_city_bb_fab1_lib.crescent_city_bb_fab1(sch_1):\DEFAULT\" )
				( netClassRef "@sapphirecity_baseboard_lib.sapphirecity_baseboard(sch_1):\GND\" )
				( netClassRef "@sapphirecity_baseboard_lib.sapphirecity_baseboard(sch_1):\DDR4_CHN_B_CMD_ADD\" )
			)
			( classClass "@sapphirecity_baseboard_lib.sapphirecity_baseboard(sch_1):\CC414\"
				( spacingCSetRef "@sapphirecity_baseboard_lib.sapphirecity_baseboard(sch_1):\DDR4_2SPC_CAC\" )
				( netClassRef "@sapphirecity_baseboard_lib.sapphirecity_baseboard(sch_1):\DDR4_CHN_B_CLK\" )
				( netClassRef "@sapphirecity_baseboard_lib.sapphirecity_baseboard(sch_1):\DDR4_CHN_B_CMD_ADD\" )
			)
			( classClass "@sapphirecity_baseboard_lib.sapphirecity_baseboard(sch_1):\CC416\"
				( spacingCSetRef "@sapphirecity_baseboard_lib.sapphirecity_baseboard(sch_1):\DDR4_2SPC_CAC\" )
				( netClassRef "@sapphirecity_baseboard_lib.sapphirecity_baseboard(sch_1):\DDR4_CHN_B_CMD_ADD\" )
				( netClassRef "@sapphirecity_baseboard_lib.sapphirecity_baseboard(sch_1):\DDR4_CHN_B_CMD_ADD\" )
			)
			( classClass "@crescent_city_bb_fab1_lib.crescent_city_bb_fab1(sch_1):\CC59\"
				( spacingCSetRef "@crescent_city_bb_fab1_lib.crescent_city_bb_fab1(sch_1):\DEFAULT\" )
				( netClassRef "@sapphirecity_baseboard_lib.sapphirecity_baseboard(sch_1):\POWER\" )
				( netClassRef "@sapphirecity_baseboard_lib.sapphirecity_baseboard(sch_1):\DDR4_CHN_B_CMD_ADD\" )
			)
			( classClass "@sapphirecity_baseboard_lib.sapphirecity_baseboard(sch_1):\CC223\"
				( spacingCSetRef "@crescent_city_bb_fab1_lib.crescent_city_bb_fab1(sch_1):\DEFAULT\" )
				( netClassRef "@sapphirecity_baseboard_lib.sapphirecity_baseboard(sch_1):\GND\" )
				( netClassRef "@sapphirecity_baseboard_lib.sapphirecity_baseboard(sch_1):\DDR4_CHN_B_CLK\" )
			)
			( classClass "@sapphirecity_baseboard_lib.sapphirecity_baseboard(sch_1):\CC413\"
				( spacingCSetRef "@sapphirecity_baseboard_lib.sapphirecity_baseboard(sch_1):\DDR4_2SPC_CAC\" )
				( netClassRef "@sapphirecity_baseboard_lib.sapphirecity_baseboard(sch_1):\DDR4_CHN_B_CLK\" )
				( netClassRef "@sapphirecity_baseboard_lib.sapphirecity_baseboard(sch_1):\DDR4_CHN_B_CLK\" )
			)
			( classClass "@crescent_city_bb_fab1_lib.crescent_city_bb_fab1(sch_1):\CC57\"
				( spacingCSetRef "@crescent_city_bb_fab1_lib.crescent_city_bb_fab1(sch_1):\DEFAULT\" )
				( netClassRef "@sapphirecity_baseboard_lib.sapphirecity_baseboard(sch_1):\POWER\" )
				( netClassRef "@sapphirecity_baseboard_lib.sapphirecity_baseboard(sch_1):\DDR4_CHN_B_CLK\" )
			)
			( classClass "@sapphirecity_baseboard_lib.sapphirecity_baseboard(sch_1):\CC222\"
				( spacingCSetRef "@crescent_city_bb_fab1_lib.crescent_city_bb_fab1(sch_1):\DEFAULT\" )
				( netClassRef "@sapphirecity_baseboard_lib.sapphirecity_baseboard(sch_1):\GND\" )
				( netClassRef "@sapphirecity_baseboard_lib.sapphirecity_baseboard(sch_1):\DDR4_CHN_A_ECC\" )
			)
			( classClass "@sapphirecity_baseboard_lib.sapphirecity_baseboard(sch_1):\CC370\"
				( spacingCSetRef "@sapphirecity_baseboard_lib.sapphirecity_baseboard(sch_1):\DQ_TO_DQ\" )
				( netClassRef "@sapphirecity_baseboard_lib.sapphirecity_baseboard(sch_1):\DDR4_CHN_A_CLK\" )
				( netClassRef "@sapphirecity_baseboard_lib.sapphirecity_baseboard(sch_1):\DDR4_CHN_A_ECC\" )
			)
			( classClass "@sapphirecity_baseboard_lib.sapphirecity_baseboard(sch_1):\CC382\"
				( spacingCSetRef "@sapphirecity_baseboard_lib.sapphirecity_baseboard(sch_1):\DQ_TO_DQ\" )
				( netClassRef "@sapphirecity_baseboard_lib.sapphirecity_baseboard(sch_1):\DDR4_CHN_A_CMD_ADD\" )
				( netClassRef "@sapphirecity_baseboard_lib.sapphirecity_baseboard(sch_1):\DDR4_CHN_A_ECC\" )
			)
			( classClass "@sapphirecity_baseboard_lib.sapphirecity_baseboard(sch_1):\CC392\"
				( spacingCSetRef "@sapphirecity_baseboard_lib.sapphirecity_baseboard(sch_1):\DQ_TO_DQ\" )
				( netClassRef "@sapphirecity_baseboard_lib.sapphirecity_baseboard(sch_1):\DDR4_CHN_A_CTRL\" )
				( netClassRef "@sapphirecity_baseboard_lib.sapphirecity_baseboard(sch_1):\DDR4_CHN_A_ECC\" )
			)
			( classClass "@sapphirecity_baseboard_lib.sapphirecity_baseboard(sch_1):\CC402\"
				( spacingCSetRef "@sapphirecity_baseboard_lib.sapphirecity_baseboard(sch_1):\DDR4_2SPC_DQ/DQS\" )
				( netClassRef "@sapphirecity_baseboard_lib.sapphirecity_baseboard(sch_1):\DDR4_CHN_A_ECC\" )
				( netClassRef "@sapphirecity_baseboard_lib.sapphirecity_baseboard(sch_1):\DDR4_CHN_A_ECC\" )
			)
			( classClass "@crescent_city_bb_fab1_lib.crescent_city_bb_fab1(sch_1):\CC58\"
				( spacingCSetRef "@crescent_city_bb_fab1_lib.crescent_city_bb_fab1(sch_1):\DEFAULT\" )
				( netClassRef "@sapphirecity_baseboard_lib.sapphirecity_baseboard(sch_1):\POWER\" )
				( netClassRef "@sapphirecity_baseboard_lib.sapphirecity_baseboard(sch_1):\DDR4_CHN_A_ECC\" )
			)
			( classClass "@sapphirecity_baseboard_lib.sapphirecity_baseboard(sch_1):\CC221\"
				( spacingCSetRef "@crescent_city_bb_fab1_lib.crescent_city_bb_fab1(sch_1):\DEFAULT\" )
				( netClassRef "@sapphirecity_baseboard_lib.sapphirecity_baseboard(sch_1):\GND\" )
				( netClassRef "@sapphirecity_baseboard_lib.sapphirecity_baseboard(sch_1):\DDR4_CHN_A_CTRL\" )
			)
			( classClass "@sapphirecity_baseboard_lib.sapphirecity_baseboard(sch_1):\CC372\"
				( spacingCSetRef "@sapphirecity_baseboard_lib.sapphirecity_baseboard(sch_1):\DDR4_2SPC_CAC\" )
				( netClassRef "@sapphirecity_baseboard_lib.sapphirecity_baseboard(sch_1):\DDR4_CHN_A_CLK\" )
				( netClassRef "@sapphirecity_baseboard_lib.sapphirecity_baseboard(sch_1):\DDR4_CHN_A_CTRL\" )
			)
			( classClass "@sapphirecity_baseboard_lib.sapphirecity_baseboard(sch_1):\CC374\"
				( spacingCSetRef "@sapphirecity_baseboard_lib.sapphirecity_baseboard(sch_1):\DDR4_2SPC_CAC\" )
				( netClassRef "@sapphirecity_baseboard_lib.sapphirecity_baseboard(sch_1):\DDR4_CHN_A_CMD_ADD\" )
				( netClassRef "@sapphirecity_baseboard_lib.sapphirecity_baseboard(sch_1):\DDR4_CHN_A_CTRL\" )
			)
			( classClass "@sapphirecity_baseboard_lib.sapphirecity_baseboard(sch_1):\CC393\"
				( spacingCSetRef "@sapphirecity_baseboard_lib.sapphirecity_baseboard(sch_1):\DDR4_2SPC_CAC\" )
				( netClassRef "@sapphirecity_baseboard_lib.sapphirecity_baseboard(sch_1):\DDR4_CHN_A_CTRL\" )
				( netClassRef "@sapphirecity_baseboard_lib.sapphirecity_baseboard(sch_1):\DDR4_CHN_A_CTRL\" )
			)
			( classClass "@crescent_city_bb_fab1_lib.crescent_city_bb_fab1(sch_1):\CC56\"
				( spacingCSetRef "@crescent_city_bb_fab1_lib.crescent_city_bb_fab1(sch_1):\DEFAULT\" )
				( netClassRef "@sapphirecity_baseboard_lib.sapphirecity_baseboard(sch_1):\POWER\" )
				( netClassRef "@sapphirecity_baseboard_lib.sapphirecity_baseboard(sch_1):\DDR4_CHN_A_CTRL\" )
			)
			( classClass "@sapphirecity_baseboard_lib.sapphirecity_baseboard(sch_1):\CC220\"
				( spacingCSetRef "@crescent_city_bb_fab1_lib.crescent_city_bb_fab1(sch_1):\DEFAULT\" )
				( netClassRef "@sapphirecity_baseboard_lib.sapphirecity_baseboard(sch_1):\GND\" )
				( netClassRef "@sapphirecity_baseboard_lib.sapphirecity_baseboard(sch_1):\DDR4_CHN_A_CMD_ADD\" )
			)
			( classClass "@sapphirecity_baseboard_lib.sapphirecity_baseboard(sch_1):\CC371\"
				( spacingCSetRef "@sapphirecity_baseboard_lib.sapphirecity_baseboard(sch_1):\DDR4_2SPC_CAC\" )
				( netClassRef "@sapphirecity_baseboard_lib.sapphirecity_baseboard(sch_1):\DDR4_CHN_A_CLK\" )
				( netClassRef "@sapphirecity_baseboard_lib.sapphirecity_baseboard(sch_1):\DDR4_CHN_A_CMD_ADD\" )
			)
			( classClass "@sapphirecity_baseboard_lib.sapphirecity_baseboard(sch_1):\CC383\"
				( spacingCSetRef "@sapphirecity_baseboard_lib.sapphirecity_baseboard(sch_1):\DDR4_2SPC_CAC\" )
				( netClassRef "@sapphirecity_baseboard_lib.sapphirecity_baseboard(sch_1):\DDR4_CHN_A_CMD_ADD\" )
				( netClassRef "@sapphirecity_baseboard_lib.sapphirecity_baseboard(sch_1):\DDR4_CHN_A_CMD_ADD\" )
			)
			( classClass "@crescent_city_bb_fab1_lib.crescent_city_bb_fab1(sch_1):\CC55\"
				( spacingCSetRef "@crescent_city_bb_fab1_lib.crescent_city_bb_fab1(sch_1):\DEFAULT\" )
				( netClassRef "@sapphirecity_baseboard_lib.sapphirecity_baseboard(sch_1):\POWER\" )
				( netClassRef "@sapphirecity_baseboard_lib.sapphirecity_baseboard(sch_1):\DDR4_CHN_A_CMD_ADD\" )
			)
			( classClass "@sapphirecity_baseboard_lib.sapphirecity_baseboard(sch_1):\CC219\"
				( spacingCSetRef "@crescent_city_bb_fab1_lib.crescent_city_bb_fab1(sch_1):\DEFAULT\" )
				( netClassRef "@sapphirecity_baseboard_lib.sapphirecity_baseboard(sch_1):\GND\" )
				( netClassRef "@sapphirecity_baseboard_lib.sapphirecity_baseboard(sch_1):\DDR4_CHN_A_CLK\" )
			)
			( classClass "@sapphirecity_baseboard_lib.sapphirecity_baseboard(sch_1):\CC373\"
				( spacingCSetRef "@sapphirecity_baseboard_lib.sapphirecity_baseboard(sch_1):\DDR4_2SPC_CAC\" )
				( netClassRef "@sapphirecity_baseboard_lib.sapphirecity_baseboard(sch_1):\DDR4_CHN_A_CLK\" )
				( netClassRef "@sapphirecity_baseboard_lib.sapphirecity_baseboard(sch_1):\DDR4_CHN_A_CLK\" )
			)
			( classClass "@crescent_city_bb_fab1_lib.crescent_city_bb_fab1(sch_1):\CC54\"
				( spacingCSetRef "@crescent_city_bb_fab1_lib.crescent_city_bb_fab1(sch_1):\DEFAULT\" )
				( netClassRef "@sapphirecity_baseboard_lib.sapphirecity_baseboard(sch_1):\POWER\" )
				( netClassRef "@sapphirecity_baseboard_lib.sapphirecity_baseboard(sch_1):\DDR4_CHN_A_CLK\" )
			)
			( classClass "@sapphirecity_baseboard_lib.sapphirecity_baseboard(sch_1):\CC140\"
				( spacingCSetRef "@crescent_city_bb_fab1_lib.crescent_city_bb_fab1(sch_1):\DEFAULT\" )
				( netClassRef "@sapphirecity_baseboard_lib.sapphirecity_baseboard(sch_1):\DIGITAL_DEBUG\" )
				( netClassRef "@sapphirecity_baseboard_lib.sapphirecity_baseboard(sch_1):\GND\" )
			)
			( classClass "@sapphirecity_baseboard_lib.sapphirecity_baseboard(sch_1):\CC23\"
				( spacingCSetRef "@sapphirecity_baseboard_lib.sapphirecity_baseboard(sch_1):\20_MILS\" )
				( netClassRef "@sapphirecity_baseboard_lib.sapphirecity_baseboard(sch_1):\BMC_DDR3_ADR_CMD_CTRL\" )
				( netClassRef "@sapphirecity_baseboard_lib.sapphirecity_baseboard(sch_1):\BMC_DDR3_CLKDIFF\" )
			)
			( classClass "@sapphirecity_baseboard_lib.sapphirecity_baseboard(sch_1):\CC26\"
				( spacingCSetRef "@sapphirecity_baseboard_lib.sapphirecity_baseboard(sch_1):\20_MILS\" )
				( netClassRef "@sapphirecity_baseboard_lib.sapphirecity_baseboard(sch_1):\BMC_DDR3_ADR_CMD_CTRL\" )
				( netClassRef "@sapphirecity_baseboard_lib.sapphirecity_baseboard(sch_1):\BMC_DDR3_DQS\" )
			)
			( classClass "@sapphirecity_baseboard_lib.sapphirecity_baseboard(sch_1):\CC208\"
				( spacingCSetRef "@crescent_city_bb_fab1_lib.crescent_city_bb_fab1(sch_1):\DEFAULT\" )
				( netClassRef "@sapphirecity_baseboard_lib.sapphirecity_baseboard(sch_1):\GND\" )
				( netClassRef "@sapphirecity_baseboard_lib.sapphirecity_baseboard(sch_1):\BMC_DDR3_ADR_CMD_CTRL\" )
			)
			( classClass "@sapphirecity_baseboard_lib.sapphirecity_baseboard(sch_1):\CC350\"
				( spacingCSetRef "@sapphirecity_baseboard_lib.sapphirecity_baseboard(sch_1):\10MIL\" )
				( netClassRef "@sapphirecity_baseboard_lib.sapphirecity_baseboard(sch_1):\BMC_DDR3_ADR_CMD_CTRL\" )
				( netClassRef "@sapphirecity_baseboard_lib.sapphirecity_baseboard(sch_1):\BMC_DDR3_DATA_BYTE2\" )
			)
			( classClass "@sapphirecity_baseboard_lib.sapphirecity_baseboard(sch_1):\CC355\"
				( spacingCSetRef "@sapphirecity_baseboard_lib.sapphirecity_baseboard(sch_1):\10MIL\" )
				( netClassRef "@sapphirecity_baseboard_lib.sapphirecity_baseboard(sch_1):\BMC_DDR3_ADR_CMD_CTRL\" )
				( netClassRef "@sapphirecity_baseboard_lib.sapphirecity_baseboard(sch_1):\BMC_DDR3_DATA_BYTE1\" )
			)
			( classClass "@sapphirecity_baseboard_lib.sapphirecity_baseboard(sch_1):\CC358\"
				( spacingCSetRef "@sapphirecity_baseboard_lib.sapphirecity_baseboard(sch_1):\20_MILS\" )
				( netClassRef "@sapphirecity_baseboard_lib.sapphirecity_baseboard(sch_1):\BMC_DDR3_ADR_CMD_CTRL\" )
				( netClassRef "@sapphirecity_baseboard_lib.sapphirecity_baseboard(sch_1):\BMC_DDR3_COMP\" )
			)
			( classClass "@sapphirecity_baseboard_lib.sapphirecity_baseboard(sch_1):\CC360\"
				( spacingCSetRef "@sapphirecity_baseboard_lib.sapphirecity_baseboard(sch_1):\20_MILS\" )
				( netClassRef "@sapphirecity_baseboard_lib.sapphirecity_baseboard(sch_1):\BMC_DDR3_ADR_CMD_CTRL\" )
				( netClassRef "@sapphirecity_baseboard_lib.sapphirecity_baseboard(sch_1):\BMC_DDR3_RST\" )
			)
			( classClass "@sapphirecity_baseboard_lib.sapphirecity_baseboard(sch_1):\CC362\"
				( spacingCSetRef "@sapphirecity_baseboard_lib.sapphirecity_baseboard(sch_1):\10MIL\" )
				( netClassRef "@sapphirecity_baseboard_lib.sapphirecity_baseboard(sch_1):\BMC_DDR3_ADR_CMD_CTRL\" )
				( netClassRef "@sapphirecity_baseboard_lib.sapphirecity_baseboard(sch_1):\BMC_DDR3_ADR_CMD_CTRL\" )
			)
			( classClass "@crescent_city_bb_fab1_lib.crescent_city_bb_fab1(sch_1):\CC957\"
				( spacingCSetRef "@crescent_city_bb_fab1_lib.crescent_city_bb_fab1(sch_1):\DEFAULT\" )
				( netClassRef "@sapphirecity_baseboard_lib.sapphirecity_baseboard(sch_1):\POWER\" )
				( netClassRef "@sapphirecity_baseboard_lib.sapphirecity_baseboard(sch_1):\BMC_DDR3_ADR_CMD_CTRL\" )
			)
			( classClass "@sapphirecity_baseboard_lib.sapphirecity_baseboard(sch_1):\CC15\"
				( spacingCSetRef "@sapphirecity_baseboard_lib.sapphirecity_baseboard(sch_1):\20_MILS\" )
				( netClassRef "@sapphirecity_baseboard_lib.sapphirecity_baseboard(sch_1):\BMC_DDR3_CLKDIFF\" )
				( netClassRef "@sapphirecity_baseboard_lib.sapphirecity_baseboard(sch_1):\BMC_DDR3_RST\" )
			)
			( classClass "@sapphirecity_baseboard_lib.sapphirecity_baseboard(sch_1):\CC25\"
				( spacingCSetRef "@sapphirecity_baseboard_lib.sapphirecity_baseboard(sch_1):\20_MILS\" )
				( netClassRef "@sapphirecity_baseboard_lib.sapphirecity_baseboard(sch_1):\BMC_DDR3_DQS\" )
				( netClassRef "@sapphirecity_baseboard_lib.sapphirecity_baseboard(sch_1):\BMC_DDR3_RST\" )
			)
			( classClass "@sapphirecity_baseboard_lib.sapphirecity_baseboard(sch_1):\CC142\"
				( spacingCSetRef "@crescent_city_bb_fab1_lib.crescent_city_bb_fab1(sch_1):\DEFAULT\" )
				( netClassRef "@sapphirecity_baseboard_lib.sapphirecity_baseboard(sch_1):\GND\" )
				( netClassRef "@sapphirecity_baseboard_lib.sapphirecity_baseboard(sch_1):\BMC_DDR3_RST\" )
			)
			( classClass "@sapphirecity_baseboard_lib.sapphirecity_baseboard(sch_1):\CC348\"
				( spacingCSetRef "@sapphirecity_baseboard_lib.sapphirecity_baseboard(sch_1):\10MIL\" )
				( netClassRef "@sapphirecity_baseboard_lib.sapphirecity_baseboard(sch_1):\BMC_DDR3_DATA_BYTE2\" )
				( netClassRef "@sapphirecity_baseboard_lib.sapphirecity_baseboard(sch_1):\BMC_DDR3_RST\" )
			)
			( classClass "@sapphirecity_baseboard_lib.sapphirecity_baseboard(sch_1):\CC353\"
				( spacingCSetRef "@sapphirecity_baseboard_lib.sapphirecity_baseboard(sch_1):\10MIL\" )
				( netClassRef "@sapphirecity_baseboard_lib.sapphirecity_baseboard(sch_1):\BMC_DDR3_DATA_BYTE1\" )
				( netClassRef "@sapphirecity_baseboard_lib.sapphirecity_baseboard(sch_1):\BMC_DDR3_RST\" )
			)
			( classClass "@sapphirecity_baseboard_lib.sapphirecity_baseboard(sch_1):\CC357\"
				( spacingCSetRef "@sapphirecity_baseboard_lib.sapphirecity_baseboard(sch_1):\20_MILS\" )
				( netClassRef "@sapphirecity_baseboard_lib.sapphirecity_baseboard(sch_1):\BMC_DDR3_RST\" )
				( netClassRef "@sapphirecity_baseboard_lib.sapphirecity_baseboard(sch_1):\BMC_DDR3_COMP\" )
			)
			( classClass "@sapphirecity_baseboard_lib.sapphirecity_baseboard(sch_1):\CC361\"
				( spacingCSetRef "@sapphirecity_baseboard_lib.sapphirecity_baseboard(sch_1):\10MIL\" )
				( netClassRef "@sapphirecity_baseboard_lib.sapphirecity_baseboard(sch_1):\BMC_DDR3_RST\" )
				( netClassRef "@sapphirecity_baseboard_lib.sapphirecity_baseboard(sch_1):\BMC_DDR3_RST\" )
			)
			( classClass "@crescent_city_bb_fab1_lib.crescent_city_bb_fab1(sch_1):\CC951\"
				( spacingCSetRef "@crescent_city_bb_fab1_lib.crescent_city_bb_fab1(sch_1):\DEFAULT\" )
				( netClassRef "@sapphirecity_baseboard_lib.sapphirecity_baseboard(sch_1):\POWER\" )
				( netClassRef "@sapphirecity_baseboard_lib.sapphirecity_baseboard(sch_1):\BMC_DDR3_RST\" )
			)
			( classClass "@sapphirecity_baseboard_lib.sapphirecity_baseboard(sch_1):\CC14\"
				( spacingCSetRef "@sapphirecity_baseboard_lib.sapphirecity_baseboard(sch_1):\20_MILS\" )
				( netClassRef "@sapphirecity_baseboard_lib.sapphirecity_baseboard(sch_1):\BMC_DDR3_CLKDIFF\" )
				( netClassRef "@sapphirecity_baseboard_lib.sapphirecity_baseboard(sch_1):\BMC_DDR3_DQS\" )
			)
			( classClass "@sapphirecity_baseboard_lib.sapphirecity_baseboard(sch_1):\CC27\"
				( spacingCSetRef "@sapphirecity_baseboard_lib.sapphirecity_baseboard(sch_1):\20_MILS\" )
				( netClassRef "@sapphirecity_baseboard_lib.sapphirecity_baseboard(sch_1):\BMC_DDR3_DQS\" )
				( netClassRef "@sapphirecity_baseboard_lib.sapphirecity_baseboard(sch_1):\BMC_DDR3_COMP\" )
			)
			( classClass "@sapphirecity_baseboard_lib.sapphirecity_baseboard(sch_1):\CC28\"
				( spacingCSetRef "@sapphirecity_baseboard_lib.sapphirecity_baseboard(sch_1):\20_MILS\" )
				( netClassRef "@sapphirecity_baseboard_lib.sapphirecity_baseboard(sch_1):\BMC_DDR3_DATA_BYTE1\" )
				( netClassRef "@sapphirecity_baseboard_lib.sapphirecity_baseboard(sch_1):\BMC_DDR3_DQS\" )
			)
			( classClass "@sapphirecity_baseboard_lib.sapphirecity_baseboard(sch_1):\CC29\"
				( spacingCSetRef "@sapphirecity_baseboard_lib.sapphirecity_baseboard(sch_1):\20_MILS\" )
				( netClassRef "@sapphirecity_baseboard_lib.sapphirecity_baseboard(sch_1):\BMC_DDR3_DATA_BYTE2\" )
				( netClassRef "@sapphirecity_baseboard_lib.sapphirecity_baseboard(sch_1):\BMC_DDR3_DQS\" )
			)
			( classClass "@sapphirecity_baseboard_lib.sapphirecity_baseboard(sch_1):\CC30\"
				( spacingCSetRef "@sapphirecity_baseboard_lib.sapphirecity_baseboard(sch_1):\20_MILS\" )
				( netClassRef "@sapphirecity_baseboard_lib.sapphirecity_baseboard(sch_1):\BMC_DDR3_DQS\" )
				( netClassRef "@sapphirecity_baseboard_lib.sapphirecity_baseboard(sch_1):\BMC_DDR3_DQS\" )
			)
			( classClass "@sapphirecity_baseboard_lib.sapphirecity_baseboard(sch_1):\CC34\"
				( spacingCSetRef "@crescent_city_bb_fab1_lib.crescent_city_bb_fab1(sch_1):\DEFAULT\" )
				( netClassRef "@sapphirecity_baseboard_lib.sapphirecity_baseboard(sch_1):\GND\" )
				( netClassRef "@sapphirecity_baseboard_lib.sapphirecity_baseboard(sch_1):\BMC_DDR3_DQS\" )
			)
			( classClass "@crescent_city_bb_fab1_lib.crescent_city_bb_fab1(sch_1):\CC952\"
				( spacingCSetRef "@crescent_city_bb_fab1_lib.crescent_city_bb_fab1(sch_1):\DEFAULT\" )
				( netClassRef "@sapphirecity_baseboard_lib.sapphirecity_baseboard(sch_1):\POWER\" )
				( netClassRef "@sapphirecity_baseboard_lib.sapphirecity_baseboard(sch_1):\BMC_DDR3_DQS\" )
			)
			( classClass "@sapphirecity_baseboard_lib.sapphirecity_baseboard(sch_1):\CC16\"
				( spacingCSetRef "@crescent_city_bb_fab1_lib.crescent_city_bb_fab1(sch_1):\DEFAULT\" )
				( netClassRef "@sapphirecity_baseboard_lib.sapphirecity_baseboard(sch_1):\GND\" )
				( netClassRef "@sapphirecity_baseboard_lib.sapphirecity_baseboard(sch_1):\BMC_DDR3_CLKDIFF\" )
			)
			( classClass "@sapphirecity_baseboard_lib.sapphirecity_baseboard(sch_1):\CC20\"
				( spacingCSetRef "@sapphirecity_baseboard_lib.sapphirecity_baseboard(sch_1):\20_MILS\" )
				( netClassRef "@sapphirecity_baseboard_lib.sapphirecity_baseboard(sch_1):\BMC_DDR3_CLKDIFF\" )
				( netClassRef "@sapphirecity_baseboard_lib.sapphirecity_baseboard(sch_1):\BMC_DDR3_DATA_BYTE2\" )
			)
			( classClass "@sapphirecity_baseboard_lib.sapphirecity_baseboard(sch_1):\CC21\"
				( spacingCSetRef "@sapphirecity_baseboard_lib.sapphirecity_baseboard(sch_1):\20_MILS\" )
				( netClassRef "@sapphirecity_baseboard_lib.sapphirecity_baseboard(sch_1):\BMC_DDR3_CLKDIFF\" )
				( netClassRef "@sapphirecity_baseboard_lib.sapphirecity_baseboard(sch_1):\BMC_DDR3_DATA_BYTE1\" )
			)
			( classClass "@sapphirecity_baseboard_lib.sapphirecity_baseboard(sch_1):\CC22\"
				( spacingCSetRef "@sapphirecity_baseboard_lib.sapphirecity_baseboard(sch_1):\20_MILS\" )
				( netClassRef "@sapphirecity_baseboard_lib.sapphirecity_baseboard(sch_1):\BMC_DDR3_CLKDIFF\" )
				( netClassRef "@sapphirecity_baseboard_lib.sapphirecity_baseboard(sch_1):\BMC_DDR3_COMP\" )
			)
			( classClass "@sapphirecity_baseboard_lib.sapphirecity_baseboard(sch_1):\CC24\"
				( spacingCSetRef "@sapphirecity_baseboard_lib.sapphirecity_baseboard(sch_1):\20_MILS\" )
				( netClassRef "@sapphirecity_baseboard_lib.sapphirecity_baseboard(sch_1):\BMC_DDR3_CLKDIFF\" )
				( netClassRef "@sapphirecity_baseboard_lib.sapphirecity_baseboard(sch_1):\BMC_DDR3_CLKDIFF\" )
			)
			( classClass "@crescent_city_bb_fab1_lib.crescent_city_bb_fab1(sch_1):\CC955\"
				( spacingCSetRef "@crescent_city_bb_fab1_lib.crescent_city_bb_fab1(sch_1):\DEFAULT\" )
				( netClassRef "@sapphirecity_baseboard_lib.sapphirecity_baseboard(sch_1):\POWER\" )
				( netClassRef "@sapphirecity_baseboard_lib.sapphirecity_baseboard(sch_1):\BMC_DDR3_CLKDIFF\" )
			)
			( classClass "@sapphirecity_baseboard_lib.sapphirecity_baseboard(sch_1):\CC203\"
				( spacingCSetRef "@crescent_city_bb_fab1_lib.crescent_city_bb_fab1(sch_1):\DEFAULT\" )
				( netClassRef "@sapphirecity_baseboard_lib.sapphirecity_baseboard(sch_1):\GND\" )
				( netClassRef "@sapphirecity_baseboard_lib.sapphirecity_baseboard(sch_1):\BMC_DDR3_COMP\" )
			)
			( classClass "@sapphirecity_baseboard_lib.sapphirecity_baseboard(sch_1):\CC349\"
				( spacingCSetRef "@sapphirecity_baseboard_lib.sapphirecity_baseboard(sch_1):\20_MILS\" )
				( netClassRef "@sapphirecity_baseboard_lib.sapphirecity_baseboard(sch_1):\BMC_DDR3_DATA_BYTE2\" )
				( netClassRef "@sapphirecity_baseboard_lib.sapphirecity_baseboard(sch_1):\BMC_DDR3_COMP\" )
			)
			( classClass "@sapphirecity_baseboard_lib.sapphirecity_baseboard(sch_1):\CC354\"
				( spacingCSetRef "@sapphirecity_baseboard_lib.sapphirecity_baseboard(sch_1):\20_MILS\" )
				( netClassRef "@sapphirecity_baseboard_lib.sapphirecity_baseboard(sch_1):\BMC_DDR3_DATA_BYTE1\" )
				( netClassRef "@sapphirecity_baseboard_lib.sapphirecity_baseboard(sch_1):\BMC_DDR3_COMP\" )
			)
			( classClass "@sapphirecity_baseboard_lib.sapphirecity_baseboard(sch_1):\CC359\"
				( spacingCSetRef "@sapphirecity_baseboard_lib.sapphirecity_baseboard(sch_1):\20_MILS\" )
				( netClassRef "@sapphirecity_baseboard_lib.sapphirecity_baseboard(sch_1):\BMC_DDR3_COMP\" )
				( netClassRef "@sapphirecity_baseboard_lib.sapphirecity_baseboard(sch_1):\BMC_DDR3_COMP\" )
			)
			( classClass "@crescent_city_bb_fab1_lib.crescent_city_bb_fab1(sch_1):\CC950\"
				( spacingCSetRef "@crescent_city_bb_fab1_lib.crescent_city_bb_fab1(sch_1):\DEFAULT\" )
				( netClassRef "@sapphirecity_baseboard_lib.sapphirecity_baseboard(sch_1):\POWER\" )
				( netClassRef "@sapphirecity_baseboard_lib.sapphirecity_baseboard(sch_1):\BMC_DDR3_COMP\" )
			)
			( classClass "@sapphirecity_baseboard_lib.sapphirecity_baseboard(sch_1):\CC209\"
				( spacingCSetRef "@crescent_city_bb_fab1_lib.crescent_city_bb_fab1(sch_1):\DEFAULT\" )
				( netClassRef "@sapphirecity_baseboard_lib.sapphirecity_baseboard(sch_1):\GND\" )
				( netClassRef "@sapphirecity_baseboard_lib.sapphirecity_baseboard(sch_1):\BMC_DDR3_DATA_BYTE1\" )
			)
			( classClass "@sapphirecity_baseboard_lib.sapphirecity_baseboard(sch_1):\CC351\"
				( spacingCSetRef "@sapphirecity_baseboard_lib.sapphirecity_baseboard(sch_1):\10MIL\" )
				( netClassRef "@sapphirecity_baseboard_lib.sapphirecity_baseboard(sch_1):\BMC_DDR3_DATA_BYTE1\" )
				( netClassRef "@sapphirecity_baseboard_lib.sapphirecity_baseboard(sch_1):\BMC_DDR3_DATA_BYTE2\" )
			)
			( classClass "@sapphirecity_baseboard_lib.sapphirecity_baseboard(sch_1):\CC356\"
				( spacingCSetRef "@sapphirecity_baseboard_lib.sapphirecity_baseboard(sch_1):\10MIL\" )
				( netClassRef "@sapphirecity_baseboard_lib.sapphirecity_baseboard(sch_1):\BMC_DDR3_DATA_BYTE1\" )
				( netClassRef "@sapphirecity_baseboard_lib.sapphirecity_baseboard(sch_1):\BMC_DDR3_DATA_BYTE1\" )
			)
			( classClass "@crescent_city_bb_fab1_lib.crescent_city_bb_fab1(sch_1):\CC954\"
				( spacingCSetRef "@crescent_city_bb_fab1_lib.crescent_city_bb_fab1(sch_1):\DEFAULT\" )
				( netClassRef "@sapphirecity_baseboard_lib.sapphirecity_baseboard(sch_1):\POWER\" )
				( netClassRef "@sapphirecity_baseboard_lib.sapphirecity_baseboard(sch_1):\BMC_DDR3_DATA_BYTE1\" )
			)
			( classClass "@sapphirecity_baseboard_lib.sapphirecity_baseboard(sch_1):\CC210\"
				( spacingCSetRef "@crescent_city_bb_fab1_lib.crescent_city_bb_fab1(sch_1):\DEFAULT\" )
				( netClassRef "@sapphirecity_baseboard_lib.sapphirecity_baseboard(sch_1):\GND\" )
				( netClassRef "@sapphirecity_baseboard_lib.sapphirecity_baseboard(sch_1):\BMC_DDR3_DATA_BYTE2\" )
			)
			( classClass "@sapphirecity_baseboard_lib.sapphirecity_baseboard(sch_1):\CC352\"
				( spacingCSetRef "@sapphirecity_baseboard_lib.sapphirecity_baseboard(sch_1):\10MIL\" )
				( netClassRef "@sapphirecity_baseboard_lib.sapphirecity_baseboard(sch_1):\BMC_DDR3_DATA_BYTE2\" )
				( netClassRef "@sapphirecity_baseboard_lib.sapphirecity_baseboard(sch_1):\BMC_DDR3_DATA_BYTE2\" )
			)
			( classClass "@crescent_city_bb_fab1_lib.crescent_city_bb_fab1(sch_1):\CC953\"
				( spacingCSetRef "@crescent_city_bb_fab1_lib.crescent_city_bb_fab1(sch_1):\DEFAULT\" )
				( netClassRef "@sapphirecity_baseboard_lib.sapphirecity_baseboard(sch_1):\POWER\" )
				( netClassRef "@sapphirecity_baseboard_lib.sapphirecity_baseboard(sch_1):\BMC_DDR3_DATA_BYTE2\" )
			)
			( classClass "@sapphirecity_baseboard_lib.sapphirecity_baseboard(sch_1):\CC143\"
				( spacingCSetRef "@crescent_city_bb_fab1_lib.crescent_city_bb_fab1(sch_1):\DEFAULT\" )
				( netClassRef "@sapphirecity_baseboard_lib.sapphirecity_baseboard(sch_1):\GND\" )
				( netClassRef "@sapphirecity_baseboard_lib.sapphirecity_baseboard(sch_1):\XTAL_EXT\" )
			)
			( classClass "@sapphirecity_baseboard_lib.sapphirecity_baseboard(sch_1):\CC144\"
				( spacingCSetRef "@crescent_city_bb_fab1_lib.crescent_city_bb_fab1(sch_1):\DEFAULT\" )
				( netClassRef "@sapphirecity_baseboard_lib.sapphirecity_baseboard(sch_1):\GND\" )
				( netClassRef "@sapphirecity_baseboard_lib.sapphirecity_baseboard(sch_1):\WBG_PLLS\" )
			)
			( classClass "@sapphirecity_baseboard_lib.sapphirecity_baseboard(sch_1):\CC145\"
				( spacingCSetRef "@crescent_city_bb_fab1_lib.crescent_city_bb_fab1(sch_1):\DEFAULT\" )
				( netClassRef "@sapphirecity_baseboard_lib.sapphirecity_baseboard(sch_1):\GND\" )
				( netClassRef "@sapphirecity_baseboard_lib.sapphirecity_baseboard(sch_1):\VR_VSENSE\" )
			)
			( classClass "@sapphirecity_baseboard_lib.sapphirecity_baseboard(sch_1):\CC146\"
				( spacingCSetRef "@crescent_city_bb_fab1_lib.crescent_city_bb_fab1(sch_1):\DEFAULT\" )
				( netClassRef "@sapphirecity_baseboard_lib.sapphirecity_baseboard(sch_1):\GND\" )
				( netClassRef "@sapphirecity_baseboard_lib.sapphirecity_baseboard(sch_1):\VR_VCCIN_CPU0\" )
			)
			( classClass "@sapphirecity_baseboard_lib.sapphirecity_baseboard(sch_1):\CC151\"
				( spacingCSetRef "@crescent_city_bb_fab1_lib.crescent_city_bb_fab1(sch_1):\DEFAULT\" )
				( netClassRef "@sapphirecity_baseboard_lib.sapphirecity_baseboard(sch_1):\GND\" )
				( netClassRef "@sapphirecity_baseboard_lib.sapphirecity_baseboard(sch_1):\VR_P2V5_AUX\" )
			)
			( classClass "@sapphirecity_baseboard_lib.sapphirecity_baseboard(sch_1):\CC157\"
				( spacingCSetRef "@crescent_city_bb_fab1_lib.crescent_city_bb_fab1(sch_1):\DEFAULT\" )
				( netClassRef "@sapphirecity_baseboard_lib.sapphirecity_baseboard(sch_1):\GND\" )
				( netClassRef "@sapphirecity_baseboard_lib.sapphirecity_baseboard(sch_1):\VR_P1V2_AUX\" )
			)
			( classClass "@sapphirecity_baseboard_lib.sapphirecity_baseboard(sch_1):\CC159\"
				( spacingCSetRef "@crescent_city_bb_fab1_lib.crescent_city_bb_fab1(sch_1):\DEFAULT\" )
				( netClassRef "@sapphirecity_baseboard_lib.sapphirecity_baseboard(sch_1):\GND\" )
				( netClassRef "@sapphirecity_baseboard_lib.sapphirecity_baseboard(sch_1):\VR_P0V95\" )
			)
			( classClass "@sapphirecity_baseboard_lib.sapphirecity_baseboard(sch_1):\CC160\"
				( spacingCSetRef "@crescent_city_bb_fab1_lib.crescent_city_bb_fab1(sch_1):\DEFAULT\" )
				( netClassRef "@sapphirecity_baseboard_lib.sapphirecity_baseboard(sch_1):\GND\" )
				( netClassRef "@sapphirecity_baseboard_lib.sapphirecity_baseboard(sch_1):\VR_P0V75\" )
			)
			( classClass "@sapphirecity_baseboard_lib.sapphirecity_baseboard(sch_1):\CC161\"
				( spacingCSetRef "@crescent_city_bb_fab1_lib.crescent_city_bb_fab1(sch_1):\DEFAULT\" )
				( netClassRef "@sapphirecity_baseboard_lib.sapphirecity_baseboard(sch_1):\GND\" )
				( netClassRef "@sapphirecity_baseboard_lib.sapphirecity_baseboard(sch_1):\VR_P0V67\" )
			)
			( classClass "@sapphirecity_baseboard_lib.sapphirecity_baseboard(sch_1):\CC162\"
				( spacingCSetRef "@crescent_city_bb_fab1_lib.crescent_city_bb_fab1(sch_1):\DEFAULT\" )
				( netClassRef "@sapphirecity_baseboard_lib.sapphirecity_baseboard(sch_1):\GND\" )
				( netClassRef "@sapphirecity_baseboard_lib.sapphirecity_baseboard(sch_1):\VR_P0V8\" )
			)
			( classClass "@sapphirecity_baseboard_lib.sapphirecity_baseboard(sch_1):\CC167\"
				( spacingCSetRef "@crescent_city_bb_fab1_lib.crescent_city_bb_fab1(sch_1):\DEFAULT\" )
				( netClassRef "@sapphirecity_baseboard_lib.sapphirecity_baseboard(sch_1):\GND\" )
				( netClassRef "@sapphirecity_baseboard_lib.sapphirecity_baseboard(sch_1):\VR_PVPP_GH\" )
			)
			( classClass "@sapphirecity_baseboard_lib.sapphirecity_baseboard(sch_1):\CC168\"
				( spacingCSetRef "@crescent_city_bb_fab1_lib.crescent_city_bb_fab1(sch_1):\DEFAULT\" )
				( netClassRef "@sapphirecity_baseboard_lib.sapphirecity_baseboard(sch_1):\GND\" )
				( netClassRef "@sapphirecity_baseboard_lib.sapphirecity_baseboard(sch_1):\VR_PVPP_EF\" )
			)
			( classClass "@sapphirecity_baseboard_lib.sapphirecity_baseboard(sch_1):\CC169\"
				( spacingCSetRef "@crescent_city_bb_fab1_lib.crescent_city_bb_fab1(sch_1):\DEFAULT\" )
				( netClassRef "@sapphirecity_baseboard_lib.sapphirecity_baseboard(sch_1):\GND\" )
				( netClassRef "@sapphirecity_baseboard_lib.sapphirecity_baseboard(sch_1):\VR_PVPP_AB\" )
			)
			( classClass "@sapphirecity_baseboard_lib.sapphirecity_baseboard(sch_1):\CC170\"
				( spacingCSetRef "@crescent_city_bb_fab1_lib.crescent_city_bb_fab1(sch_1):\DEFAULT\" )
				( netClassRef "@sapphirecity_baseboard_lib.sapphirecity_baseboard(sch_1):\GND\" )
				( netClassRef "@sapphirecity_baseboard_lib.sapphirecity_baseboard(sch_1):\VR_PVPP\" )
			)
			( classClass "@sapphirecity_baseboard_lib.sapphirecity_baseboard(sch_1):\CC173\"
				( spacingCSetRef "@crescent_city_bb_fab1_lib.crescent_city_bb_fab1(sch_1):\DEFAULT\" )
				( netClassRef "@sapphirecity_baseboard_lib.sapphirecity_baseboard(sch_1):\GND\" )
				( netClassRef "@sapphirecity_baseboard_lib.sapphirecity_baseboard(sch_1):\VR_PVDDQ_CD\" )
			)
			( classClass "@sapphirecity_baseboard_lib.sapphirecity_baseboard(sch_1):\CC174\"
				( spacingCSetRef "@crescent_city_bb_fab1_lib.crescent_city_bb_fab1(sch_1):\DEFAULT\" )
				( netClassRef "@sapphirecity_baseboard_lib.sapphirecity_baseboard(sch_1):\GND\" )
				( netClassRef "@sapphirecity_baseboard_lib.sapphirecity_baseboard(sch_1):\VR_PVDDQ_AB\" )
			)
			( classClass "@sapphirecity_baseboard_lib.sapphirecity_baseboard(sch_1):\CC177\"
				( spacingCSetRef "@crescent_city_bb_fab1_lib.crescent_city_bb_fab1(sch_1):\DEFAULT\" )
				( netClassRef "@sapphirecity_baseboard_lib.sapphirecity_baseboard(sch_1):\GND\" )
				( netClassRef "@sapphirecity_baseboard_lib.sapphirecity_baseboard(sch_1):\VR_PCH\" )
			)
			( classClass "@sapphirecity_baseboard_lib.sapphirecity_baseboard(sch_1):\CC13\"
				( spacingCSetRef "@crescent_city_bb_fab1_lib.crescent_city_bb_fab1(sch_1):\DEFAULT\" )
				( netClassRef "@sapphirecity_baseboard_lib.sapphirecity_baseboard(sch_1):\GND\" )
				( netClassRef "@sapphirecity_baseboard_lib.sapphirecity_baseboard(sch_1):\VR_LAN\" )
			)
			( classClass "@sapphirecity_baseboard_lib.sapphirecity_baseboard(sch_1):\CC12\"
				( spacingCSetRef "@crescent_city_bb_fab1_lib.crescent_city_bb_fab1(sch_1):\DEFAULT\" )
				( netClassRef "@sapphirecity_baseboard_lib.sapphirecity_baseboard(sch_1):\GND\" )
				( netClassRef "@sapphirecity_baseboard_lib.sapphirecity_baseboard(sch_1):\VR_ISENSE\" )
			)
			( classClass "@sapphirecity_baseboard_lib.sapphirecity_baseboard(sch_1):\CC182\"
				( spacingCSetRef "@crescent_city_bb_fab1_lib.crescent_city_bb_fab1(sch_1):\DEFAULT\" )
				( netClassRef "@sapphirecity_baseboard_lib.sapphirecity_baseboard(sch_1):\GND\" )
				( netClassRef "@sapphirecity_baseboard_lib.sapphirecity_baseboard(sch_1):\SPA-B_12V\" )
			)
			( classClass "@sapphirecity_baseboard_lib.sapphirecity_baseboard(sch_1):\CC324\"
				( spacingCSetRef "@crescent_city_bb_fab1_lib.crescent_city_bb_fab1(sch_1):\DEFAULT\" )
				( netClassRef "@sapphirecity_baseboard_lib.sapphirecity_baseboard(sch_1):\SPA-B_12V\" )
				( netClassRef "@sapphirecity_baseboard_lib.sapphirecity_baseboard(sch_1):\SPA-B_12V\" )
			)
			( classClass "@sapphirecity_baseboard_lib.sapphirecity_baseboard(sch_1):\CC183\"
				( spacingCSetRef "@crescent_city_bb_fab1_lib.crescent_city_bb_fab1(sch_1):\DEFAULT\" )
				( netClassRef "@sapphirecity_baseboard_lib.sapphirecity_baseboard(sch_1):\GND\" )
				( netClassRef "@sapphirecity_baseboard_lib.sapphirecity_baseboard(sch_1):\SPA-B_3V\" )
			)
			( classClass "@sapphirecity_baseboard_lib.sapphirecity_baseboard(sch_1):\CC185\"
				( spacingCSetRef "@crescent_city_bb_fab1_lib.crescent_city_bb_fab1(sch_1):\DEFAULT\" )
				( netClassRef "@sapphirecity_baseboard_lib.sapphirecity_baseboard(sch_1):\GND\" )
				( netClassRef "@sapphirecity_baseboard_lib.sapphirecity_baseboard(sch_1):\SET2DIL\" )
			)
			( classClass "@sapphirecity_baseboard_lib.sapphirecity_baseboard(sch_1):\CC11\"
				( spacingCSetRef "@crescent_city_bb_fab1_lib.crescent_city_bb_fab1(sch_1):\DEFAULT\" )
				( netClassRef "@sapphirecity_baseboard_lib.sapphirecity_baseboard(sch_1):\GND\" )
				( netClassRef "@sapphirecity_baseboard_lib.sapphirecity_baseboard(sch_1):\POWER\" )
			)
			( classClass "@crescent_city_bb_fab1_lib.crescent_city_bb_fab1(sch_1):\CC370\"
				( spacingCSetRef "@crescent_city_bb_fab1_lib.crescent_city_bb_fab1(sch_1):\DEFAULT\" )
				( netClassRef "@sapphirecity_baseboard_lib.sapphirecity_baseboard(sch_1):\POWER\" )
				( netClassRef "@sapphirecity_baseboard_lib.sapphirecity_baseboard(sch_1):\DDR4_CHN_J_CLK\" )
			)
			( classClass "@crescent_city_bb_fab1_lib.crescent_city_bb_fab1(sch_1):\CC383\"
				( spacingCSetRef "@crescent_city_bb_fab1_lib.crescent_city_bb_fab1(sch_1):\DEFAULT\" )
				( netClassRef "@sapphirecity_baseboard_lib.sapphirecity_baseboard(sch_1):\POWER\" )
				( netClassRef "@sapphirecity_baseboard_lib.sapphirecity_baseboard(sch_1):\DDR4_CHN_J_CMD_ADD\" )
			)
			( classClass "@crescent_city_bb_fab1_lib.crescent_city_bb_fab1(sch_1):\CC395\"
				( spacingCSetRef "@crescent_city_bb_fab1_lib.crescent_city_bb_fab1(sch_1):\DEFAULT\" )
				( netClassRef "@sapphirecity_baseboard_lib.sapphirecity_baseboard(sch_1):\POWER\" )
				( netClassRef "@sapphirecity_baseboard_lib.sapphirecity_baseboard(sch_1):\DDR4_CHN_J_CTRL\" )
			)
			( classClass "@crescent_city_bb_fab1_lib.crescent_city_bb_fab1(sch_1):\CC409\"
				( spacingCSetRef "@crescent_city_bb_fab1_lib.crescent_city_bb_fab1(sch_1):\DEFAULT\" )
				( netClassRef "@sapphirecity_baseboard_lib.sapphirecity_baseboard(sch_1):\POWER\" )
				( netClassRef "@sapphirecity_baseboard_lib.sapphirecity_baseboard(sch_1):\DDR4_CHN_K_CLK\" )
			)
			( classClass "@crescent_city_bb_fab1_lib.crescent_city_bb_fab1(sch_1):\CC422\"
				( spacingCSetRef "@crescent_city_bb_fab1_lib.crescent_city_bb_fab1(sch_1):\DEFAULT\" )
				( netClassRef "@sapphirecity_baseboard_lib.sapphirecity_baseboard(sch_1):\POWER\" )
				( netClassRef "@sapphirecity_baseboard_lib.sapphirecity_baseboard(sch_1):\DDR4_CHN_K_CMD_ADD\" )
			)
			( classClass "@crescent_city_bb_fab1_lib.crescent_city_bb_fab1(sch_1):\CC434\"
				( spacingCSetRef "@crescent_city_bb_fab1_lib.crescent_city_bb_fab1(sch_1):\DEFAULT\" )
				( netClassRef "@sapphirecity_baseboard_lib.sapphirecity_baseboard(sch_1):\POWER\" )
				( netClassRef "@sapphirecity_baseboard_lib.sapphirecity_baseboard(sch_1):\DDR4_CHN_K_CTRL\" )
			)
			( classClass "@crescent_city_bb_fab1_lib.crescent_city_bb_fab1(sch_1):\CC448\"
				( spacingCSetRef "@crescent_city_bb_fab1_lib.crescent_city_bb_fab1(sch_1):\DEFAULT\" )
				( netClassRef "@sapphirecity_baseboard_lib.sapphirecity_baseboard(sch_1):\POWER\" )
				( netClassRef "@sapphirecity_baseboard_lib.sapphirecity_baseboard(sch_1):\DDR4_CHN_L_CLK\" )
			)
			( classClass "@crescent_city_bb_fab1_lib.crescent_city_bb_fab1(sch_1):\CC461\"
				( spacingCSetRef "@crescent_city_bb_fab1_lib.crescent_city_bb_fab1(sch_1):\DEFAULT\" )
				( netClassRef "@sapphirecity_baseboard_lib.sapphirecity_baseboard(sch_1):\POWER\" )
				( netClassRef "@sapphirecity_baseboard_lib.sapphirecity_baseboard(sch_1):\DDR4_CHN_L_CMD_ADD\" )
			)
			( classClass "@crescent_city_bb_fab1_lib.crescent_city_bb_fab1(sch_1):\CC473\"
				( spacingCSetRef "@crescent_city_bb_fab1_lib.crescent_city_bb_fab1(sch_1):\DEFAULT\" )
				( netClassRef "@sapphirecity_baseboard_lib.sapphirecity_baseboard(sch_1):\POWER\" )
				( netClassRef "@sapphirecity_baseboard_lib.sapphirecity_baseboard(sch_1):\DDR4_CHN_L_CTRL\" )
			)
			( classClass "@crescent_city_bb_fab1_lib.crescent_city_bb_fab1(sch_1):\CC487\"
				( spacingCSetRef "@crescent_city_bb_fab1_lib.crescent_city_bb_fab1(sch_1):\DEFAULT\" )
				( netClassRef "@sapphirecity_baseboard_lib.sapphirecity_baseboard(sch_1):\POWER\" )
				( netClassRef "@sapphirecity_baseboard_lib.sapphirecity_baseboard(sch_1):\DDR4_CHN_M_CLK\" )
			)
			( classClass "@crescent_city_bb_fab1_lib.crescent_city_bb_fab1(sch_1):\CC500\"
				( spacingCSetRef "@crescent_city_bb_fab1_lib.crescent_city_bb_fab1(sch_1):\DEFAULT\" )
				( netClassRef "@sapphirecity_baseboard_lib.sapphirecity_baseboard(sch_1):\POWER\" )
				( netClassRef "@sapphirecity_baseboard_lib.sapphirecity_baseboard(sch_1):\DDR4_CHN_M_CMD_ADD\" )
			)
			( classClass "@crescent_city_bb_fab1_lib.crescent_city_bb_fab1(sch_1):\CC512\"
				( spacingCSetRef "@crescent_city_bb_fab1_lib.crescent_city_bb_fab1(sch_1):\DEFAULT\" )
				( netClassRef "@sapphirecity_baseboard_lib.sapphirecity_baseboard(sch_1):\POWER\" )
				( netClassRef "@sapphirecity_baseboard_lib.sapphirecity_baseboard(sch_1):\DDR4_CHN_M_CTRL\" )
			)
			( classClass "@crescent_city_bb_fab1_lib.crescent_city_bb_fab1(sch_1):\CC668\"
				( spacingCSetRef "@crescent_city_bb_fab1_lib.crescent_city_bb_fab1(sch_1):\DEFAULT\" )
				( netClassRef "@sapphirecity_baseboard_lib.sapphirecity_baseboard(sch_1):\POWER\" )
				( netClassRef "@sapphirecity_baseboard_lib.sapphirecity_baseboard(sch_1):\DDR4_CHN_J_DQ_DQS_BYTE0\" )
			)
			( classClass "@crescent_city_bb_fab1_lib.crescent_city_bb_fab1(sch_1):\CC669\"
				( spacingCSetRef "@crescent_city_bb_fab1_lib.crescent_city_bb_fab1(sch_1):\DEFAULT\" )
				( netClassRef "@sapphirecity_baseboard_lib.sapphirecity_baseboard(sch_1):\POWER\" )
				( netClassRef "@sapphirecity_baseboard_lib.sapphirecity_baseboard(sch_1):\DDR4_CHN_J_DQ_DQS_BYTE1\" )
			)
			( classClass "@crescent_city_bb_fab1_lib.crescent_city_bb_fab1(sch_1):\CC670\"
				( spacingCSetRef "@crescent_city_bb_fab1_lib.crescent_city_bb_fab1(sch_1):\DEFAULT\" )
				( netClassRef "@sapphirecity_baseboard_lib.sapphirecity_baseboard(sch_1):\POWER\" )
				( netClassRef "@sapphirecity_baseboard_lib.sapphirecity_baseboard(sch_1):\DDR4_CHN_J_DQ_DQS_BYTE2\" )
			)
			( classClass "@crescent_city_bb_fab1_lib.crescent_city_bb_fab1(sch_1):\CC671\"
				( spacingCSetRef "@crescent_city_bb_fab1_lib.crescent_city_bb_fab1(sch_1):\DEFAULT\" )
				( netClassRef "@sapphirecity_baseboard_lib.sapphirecity_baseboard(sch_1):\POWER\" )
				( netClassRef "@sapphirecity_baseboard_lib.sapphirecity_baseboard(sch_1):\DDR4_CHN_J_DQ_DQS_BYTE3\" )
			)
			( classClass "@crescent_city_bb_fab1_lib.crescent_city_bb_fab1(sch_1):\CC672\"
				( spacingCSetRef "@crescent_city_bb_fab1_lib.crescent_city_bb_fab1(sch_1):\DEFAULT\" )
				( netClassRef "@sapphirecity_baseboard_lib.sapphirecity_baseboard(sch_1):\POWER\" )
				( netClassRef "@sapphirecity_baseboard_lib.sapphirecity_baseboard(sch_1):\DDR4_CHN_J_DQ_DQS_BYTE4\" )
			)
			( classClass "@crescent_city_bb_fab1_lib.crescent_city_bb_fab1(sch_1):\CC673\"
				( spacingCSetRef "@crescent_city_bb_fab1_lib.crescent_city_bb_fab1(sch_1):\DEFAULT\" )
				( netClassRef "@sapphirecity_baseboard_lib.sapphirecity_baseboard(sch_1):\POWER\" )
				( netClassRef "@sapphirecity_baseboard_lib.sapphirecity_baseboard(sch_1):\DDR4_CHN_J_DQ_DQS_BYTE5\" )
			)
			( classClass "@crescent_city_bb_fab1_lib.crescent_city_bb_fab1(sch_1):\CC674\"
				( spacingCSetRef "@crescent_city_bb_fab1_lib.crescent_city_bb_fab1(sch_1):\DEFAULT\" )
				( netClassRef "@sapphirecity_baseboard_lib.sapphirecity_baseboard(sch_1):\POWER\" )
				( netClassRef "@sapphirecity_baseboard_lib.sapphirecity_baseboard(sch_1):\DDR4_CHN_J_DQ_DQS_BYTE6\" )
			)
			( classClass "@crescent_city_bb_fab1_lib.crescent_city_bb_fab1(sch_1):\CC675\"
				( spacingCSetRef "@crescent_city_bb_fab1_lib.crescent_city_bb_fab1(sch_1):\DEFAULT\" )
				( netClassRef "@sapphirecity_baseboard_lib.sapphirecity_baseboard(sch_1):\POWER\" )
				( netClassRef "@sapphirecity_baseboard_lib.sapphirecity_baseboard(sch_1):\DDR4_CHN_J_DQ_DQS_BYTE7\" )
			)
			( classClass "@crescent_city_bb_fab1_lib.crescent_city_bb_fab1(sch_1):\CC676\"
				( spacingCSetRef "@crescent_city_bb_fab1_lib.crescent_city_bb_fab1(sch_1):\DEFAULT\" )
				( netClassRef "@sapphirecity_baseboard_lib.sapphirecity_baseboard(sch_1):\POWER\" )
				( netClassRef "@sapphirecity_baseboard_lib.sapphirecity_baseboard(sch_1):\DDR4_CHN_J_ECC\" )
			)
			( classClass "@crescent_city_bb_fab1_lib.crescent_city_bb_fab1(sch_1):\CC677\"
				( spacingCSetRef "@crescent_city_bb_fab1_lib.crescent_city_bb_fab1(sch_1):\DEFAULT\" )
				( netClassRef "@sapphirecity_baseboard_lib.sapphirecity_baseboard(sch_1):\POWER\" )
				( netClassRef "@sapphirecity_baseboard_lib.sapphirecity_baseboard(sch_1):\DDR4_CHN_K_DQ_DQS_BYTE0\" )
			)
			( classClass "@crescent_city_bb_fab1_lib.crescent_city_bb_fab1(sch_1):\CC678\"
				( spacingCSetRef "@crescent_city_bb_fab1_lib.crescent_city_bb_fab1(sch_1):\DEFAULT\" )
				( netClassRef "@sapphirecity_baseboard_lib.sapphirecity_baseboard(sch_1):\POWER\" )
				( netClassRef "@sapphirecity_baseboard_lib.sapphirecity_baseboard(sch_1):\DDR4_CHN_K_DQ_DQS_BYTE1\" )
			)
			( classClass "@crescent_city_bb_fab1_lib.crescent_city_bb_fab1(sch_1):\CC679\"
				( spacingCSetRef "@crescent_city_bb_fab1_lib.crescent_city_bb_fab1(sch_1):\DEFAULT\" )
				( netClassRef "@sapphirecity_baseboard_lib.sapphirecity_baseboard(sch_1):\POWER\" )
				( netClassRef "@sapphirecity_baseboard_lib.sapphirecity_baseboard(sch_1):\DDR4_CHN_K_DQ_DQS_BYTE2\" )
			)
			( classClass "@crescent_city_bb_fab1_lib.crescent_city_bb_fab1(sch_1):\CC680\"
				( spacingCSetRef "@crescent_city_bb_fab1_lib.crescent_city_bb_fab1(sch_1):\DEFAULT\" )
				( netClassRef "@sapphirecity_baseboard_lib.sapphirecity_baseboard(sch_1):\POWER\" )
				( netClassRef "@sapphirecity_baseboard_lib.sapphirecity_baseboard(sch_1):\DDR4_CHN_K_DQ_DQS_BYTE3\" )
			)
			( classClass "@crescent_city_bb_fab1_lib.crescent_city_bb_fab1(sch_1):\CC681\"
				( spacingCSetRef "@crescent_city_bb_fab1_lib.crescent_city_bb_fab1(sch_1):\DEFAULT\" )
				( netClassRef "@sapphirecity_baseboard_lib.sapphirecity_baseboard(sch_1):\POWER\" )
				( netClassRef "@sapphirecity_baseboard_lib.sapphirecity_baseboard(sch_1):\DDR4_CHN_K_DQ_DQS_BYTE4\" )
			)
			( classClass "@crescent_city_bb_fab1_lib.crescent_city_bb_fab1(sch_1):\CC682\"
				( spacingCSetRef "@crescent_city_bb_fab1_lib.crescent_city_bb_fab1(sch_1):\DEFAULT\" )
				( netClassRef "@sapphirecity_baseboard_lib.sapphirecity_baseboard(sch_1):\POWER\" )
				( netClassRef "@sapphirecity_baseboard_lib.sapphirecity_baseboard(sch_1):\DDR4_CHN_K_DQ_DQS_BYTE5\" )
			)
			( classClass "@crescent_city_bb_fab1_lib.crescent_city_bb_fab1(sch_1):\CC683\"
				( spacingCSetRef "@crescent_city_bb_fab1_lib.crescent_city_bb_fab1(sch_1):\DEFAULT\" )
				( netClassRef "@sapphirecity_baseboard_lib.sapphirecity_baseboard(sch_1):\POWER\" )
				( netClassRef "@sapphirecity_baseboard_lib.sapphirecity_baseboard(sch_1):\DDR4_CHN_K_DQ_DQS_BYTE6\" )
			)
			( classClass "@crescent_city_bb_fab1_lib.crescent_city_bb_fab1(sch_1):\CC684\"
				( spacingCSetRef "@crescent_city_bb_fab1_lib.crescent_city_bb_fab1(sch_1):\DEFAULT\" )
				( netClassRef "@sapphirecity_baseboard_lib.sapphirecity_baseboard(sch_1):\POWER\" )
				( netClassRef "@sapphirecity_baseboard_lib.sapphirecity_baseboard(sch_1):\DDR4_CHN_K_DQ_DQS_BYTE7\" )
			)
			( classClass "@crescent_city_bb_fab1_lib.crescent_city_bb_fab1(sch_1):\CC685\"
				( spacingCSetRef "@crescent_city_bb_fab1_lib.crescent_city_bb_fab1(sch_1):\DEFAULT\" )
				( netClassRef "@sapphirecity_baseboard_lib.sapphirecity_baseboard(sch_1):\POWER\" )
				( netClassRef "@sapphirecity_baseboard_lib.sapphirecity_baseboard(sch_1):\DDR4_CHN_K_ECC\" )
			)
			( classClass "@crescent_city_bb_fab1_lib.crescent_city_bb_fab1(sch_1):\CC686\"
				( spacingCSetRef "@crescent_city_bb_fab1_lib.crescent_city_bb_fab1(sch_1):\DEFAULT\" )
				( netClassRef "@sapphirecity_baseboard_lib.sapphirecity_baseboard(sch_1):\POWER\" )
				( netClassRef "@sapphirecity_baseboard_lib.sapphirecity_baseboard(sch_1):\DDR4_CHN_L_DQ_DQS_BYTE0\" )
			)
			( classClass "@crescent_city_bb_fab1_lib.crescent_city_bb_fab1(sch_1):\CC687\"
				( spacingCSetRef "@crescent_city_bb_fab1_lib.crescent_city_bb_fab1(sch_1):\DEFAULT\" )
				( netClassRef "@sapphirecity_baseboard_lib.sapphirecity_baseboard(sch_1):\POWER\" )
				( netClassRef "@sapphirecity_baseboard_lib.sapphirecity_baseboard(sch_1):\DDR4_CHN_L_DQ_DQS_BYTE1\" )
			)
			( classClass "@crescent_city_bb_fab1_lib.crescent_city_bb_fab1(sch_1):\CC688\"
				( spacingCSetRef "@crescent_city_bb_fab1_lib.crescent_city_bb_fab1(sch_1):\DEFAULT\" )
				( netClassRef "@sapphirecity_baseboard_lib.sapphirecity_baseboard(sch_1):\POWER\" )
				( netClassRef "@sapphirecity_baseboard_lib.sapphirecity_baseboard(sch_1):\DDR4_CHN_L_DQ_DQS_BYTE2\" )
			)
			( classClass "@crescent_city_bb_fab1_lib.crescent_city_bb_fab1(sch_1):\CC689\"
				( spacingCSetRef "@crescent_city_bb_fab1_lib.crescent_city_bb_fab1(sch_1):\DEFAULT\" )
				( netClassRef "@sapphirecity_baseboard_lib.sapphirecity_baseboard(sch_1):\POWER\" )
				( netClassRef "@sapphirecity_baseboard_lib.sapphirecity_baseboard(sch_1):\DDR4_CHN_L_DQ_DQS_BYTE3\" )
			)
			( classClass "@crescent_city_bb_fab1_lib.crescent_city_bb_fab1(sch_1):\CC690\"
				( spacingCSetRef "@crescent_city_bb_fab1_lib.crescent_city_bb_fab1(sch_1):\DEFAULT\" )
				( netClassRef "@sapphirecity_baseboard_lib.sapphirecity_baseboard(sch_1):\POWER\" )
				( netClassRef "@sapphirecity_baseboard_lib.sapphirecity_baseboard(sch_1):\DDR4_CHN_L_DQ_DQS_BYTE4\" )
			)
			( classClass "@crescent_city_bb_fab1_lib.crescent_city_bb_fab1(sch_1):\CC691\"
				( spacingCSetRef "@crescent_city_bb_fab1_lib.crescent_city_bb_fab1(sch_1):\DEFAULT\" )
				( netClassRef "@sapphirecity_baseboard_lib.sapphirecity_baseboard(sch_1):\POWER\" )
				( netClassRef "@sapphirecity_baseboard_lib.sapphirecity_baseboard(sch_1):\DDR4_CHN_L_DQ_DQS_BYTE5\" )
			)
			( classClass "@crescent_city_bb_fab1_lib.crescent_city_bb_fab1(sch_1):\CC692\"
				( spacingCSetRef "@crescent_city_bb_fab1_lib.crescent_city_bb_fab1(sch_1):\DEFAULT\" )
				( netClassRef "@sapphirecity_baseboard_lib.sapphirecity_baseboard(sch_1):\POWER\" )
				( netClassRef "@sapphirecity_baseboard_lib.sapphirecity_baseboard(sch_1):\DDR4_CHN_L_DQ_DQS_BYTE6\" )
			)
			( classClass "@crescent_city_bb_fab1_lib.crescent_city_bb_fab1(sch_1):\CC693\"
				( spacingCSetRef "@crescent_city_bb_fab1_lib.crescent_city_bb_fab1(sch_1):\DEFAULT\" )
				( netClassRef "@sapphirecity_baseboard_lib.sapphirecity_baseboard(sch_1):\POWER\" )
				( netClassRef "@sapphirecity_baseboard_lib.sapphirecity_baseboard(sch_1):\DDR4_CHN_L_DQ_DQS_BYTE7\" )
			)
			( classClass "@crescent_city_bb_fab1_lib.crescent_city_bb_fab1(sch_1):\CC694\"
				( spacingCSetRef "@crescent_city_bb_fab1_lib.crescent_city_bb_fab1(sch_1):\DEFAULT\" )
				( netClassRef "@sapphirecity_baseboard_lib.sapphirecity_baseboard(sch_1):\POWER\" )
				( netClassRef "@sapphirecity_baseboard_lib.sapphirecity_baseboard(sch_1):\DDR4_CHN_L_ECC\" )
			)
			( classClass "@crescent_city_bb_fab1_lib.crescent_city_bb_fab1(sch_1):\CC695\"
				( spacingCSetRef "@crescent_city_bb_fab1_lib.crescent_city_bb_fab1(sch_1):\DEFAULT\" )
				( netClassRef "@sapphirecity_baseboard_lib.sapphirecity_baseboard(sch_1):\POWER\" )
				( netClassRef "@sapphirecity_baseboard_lib.sapphirecity_baseboard(sch_1):\DDR4_CHN_M_DQ_DQS_BYTE0\" )
			)
			( classClass "@crescent_city_bb_fab1_lib.crescent_city_bb_fab1(sch_1):\CC696\"
				( spacingCSetRef "@crescent_city_bb_fab1_lib.crescent_city_bb_fab1(sch_1):\DEFAULT\" )
				( netClassRef "@sapphirecity_baseboard_lib.sapphirecity_baseboard(sch_1):\POWER\" )
				( netClassRef "@sapphirecity_baseboard_lib.sapphirecity_baseboard(sch_1):\DDR4_CHN_M_DQ_DQS_BYTE1\" )
			)
			( classClass "@crescent_city_bb_fab1_lib.crescent_city_bb_fab1(sch_1):\CC697\"
				( spacingCSetRef "@crescent_city_bb_fab1_lib.crescent_city_bb_fab1(sch_1):\DEFAULT\" )
				( netClassRef "@sapphirecity_baseboard_lib.sapphirecity_baseboard(sch_1):\POWER\" )
				( netClassRef "@sapphirecity_baseboard_lib.sapphirecity_baseboard(sch_1):\DDR4_CHN_M_DQ_DQS_BYTE2\" )
			)
			( classClass "@crescent_city_bb_fab1_lib.crescent_city_bb_fab1(sch_1):\CC698\"
				( spacingCSetRef "@crescent_city_bb_fab1_lib.crescent_city_bb_fab1(sch_1):\DEFAULT\" )
				( netClassRef "@sapphirecity_baseboard_lib.sapphirecity_baseboard(sch_1):\POWER\" )
				( netClassRef "@sapphirecity_baseboard_lib.sapphirecity_baseboard(sch_1):\DDR4_CHN_M_DQ_DQS_BYTE3\" )
			)
			( classClass "@crescent_city_bb_fab1_lib.crescent_city_bb_fab1(sch_1):\CC699\"
				( spacingCSetRef "@crescent_city_bb_fab1_lib.crescent_city_bb_fab1(sch_1):\DEFAULT\" )
				( netClassRef "@sapphirecity_baseboard_lib.sapphirecity_baseboard(sch_1):\POWER\" )
				( netClassRef "@sapphirecity_baseboard_lib.sapphirecity_baseboard(sch_1):\DDR4_CHN_M_DQ_DQS_BYTE4\" )
			)
			( classClass "@crescent_city_bb_fab1_lib.crescent_city_bb_fab1(sch_1):\CC700\"
				( spacingCSetRef "@crescent_city_bb_fab1_lib.crescent_city_bb_fab1(sch_1):\DEFAULT\" )
				( netClassRef "@sapphirecity_baseboard_lib.sapphirecity_baseboard(sch_1):\POWER\" )
				( netClassRef "@sapphirecity_baseboard_lib.sapphirecity_baseboard(sch_1):\DDR4_CHN_M_DQ_DQS_BYTE5\" )
			)
			( classClass "@crescent_city_bb_fab1_lib.crescent_city_bb_fab1(sch_1):\CC701\"
				( spacingCSetRef "@crescent_city_bb_fab1_lib.crescent_city_bb_fab1(sch_1):\DEFAULT\" )
				( netClassRef "@sapphirecity_baseboard_lib.sapphirecity_baseboard(sch_1):\POWER\" )
				( netClassRef "@sapphirecity_baseboard_lib.sapphirecity_baseboard(sch_1):\DDR4_CHN_M_DQ_DQS_BYTE6\" )
			)
			( classClass "@crescent_city_bb_fab1_lib.crescent_city_bb_fab1(sch_1):\CC702\"
				( spacingCSetRef "@crescent_city_bb_fab1_lib.crescent_city_bb_fab1(sch_1):\DEFAULT\" )
				( netClassRef "@sapphirecity_baseboard_lib.sapphirecity_baseboard(sch_1):\POWER\" )
				( netClassRef "@sapphirecity_baseboard_lib.sapphirecity_baseboard(sch_1):\DDR4_CHN_M_DQ_DQS_BYTE7\" )
			)
			( classClass "@crescent_city_bb_fab1_lib.crescent_city_bb_fab1(sch_1):\CC703\"
				( spacingCSetRef "@crescent_city_bb_fab1_lib.crescent_city_bb_fab1(sch_1):\DEFAULT\" )
				( netClassRef "@sapphirecity_baseboard_lib.sapphirecity_baseboard(sch_1):\POWER\" )
				( netClassRef "@sapphirecity_baseboard_lib.sapphirecity_baseboard(sch_1):\DDR4_CHN_M_ECC\" )
			)
			( classClass "@crescent_city_bb_fab1_lib.crescent_city_bb_fab1(sch_1):\CC933\"
				( spacingCSetRef "@crescent_city_bb_fab1_lib.crescent_city_bb_fab1(sch_1):\DEFAULT\" )
				( netClassRef "@sapphirecity_baseboard_lib.sapphirecity_baseboard(sch_1):\POWER\" )
				( netClassRef "@sapphirecity_baseboard_lib.sapphirecity_baseboard(sch_1):\KTI_CPU0_CPU1_P1P0\" )
			)
			( classClass "@crescent_city_bb_fab1_lib.crescent_city_bb_fab1(sch_1):\CC934\"
				( spacingCSetRef "@crescent_city_bb_fab1_lib.crescent_city_bb_fab1(sch_1):\DEFAULT\" )
				( netClassRef "@sapphirecity_baseboard_lib.sapphirecity_baseboard(sch_1):\POWER\" )
				( netClassRef "@sapphirecity_baseboard_lib.sapphirecity_baseboard(sch_1):\KTI_CPU0_CPU1_P0P1\" )
			)
			( classClass "@crescent_city_bb_fab1_lib.crescent_city_bb_fab1(sch_1):\CC936\"
				( spacingCSetRef "@crescent_city_bb_fab1_lib.crescent_city_bb_fab1(sch_1):\DEFAULT\" )
				( netClassRef "@sapphirecity_baseboard_lib.sapphirecity_baseboard(sch_1):\POWER\" )
				( netClassRef "@sapphirecity_baseboard_lib.sapphirecity_baseboard(sch_1):\KTI_CPU1_CPU0_P1P0\" )
			)
			( classClass "@crescent_city_bb_fab1_lib.crescent_city_bb_fab1(sch_1):\CC937\"
				( spacingCSetRef "@crescent_city_bb_fab1_lib.crescent_city_bb_fab1(sch_1):\DEFAULT\" )
				( netClassRef "@sapphirecity_baseboard_lib.sapphirecity_baseboard(sch_1):\POWER\" )
				( netClassRef "@sapphirecity_baseboard_lib.sapphirecity_baseboard(sch_1):\KTI_CPU1_CPU0_P0P1\" )
			)
			( classClass "@crescent_city_bb_fab1_lib.crescent_city_bb_fab1(sch_1):\CC938\"
				( spacingCSetRef "@crescent_city_bb_fab1_lib.crescent_city_bb_fab1(sch_1):\DEFAULT\" )
				( netClassRef "@sapphirecity_baseboard_lib.sapphirecity_baseboard(sch_1):\POWER\" )
				( netClassRef "@sapphirecity_baseboard_lib.sapphirecity_baseboard(sch_1):\DMI_CPU0_PCH_RX\" )
			)
			( classClass "@crescent_city_bb_fab1_lib.crescent_city_bb_fab1(sch_1):\CC939\"
				( spacingCSetRef "@crescent_city_bb_fab1_lib.crescent_city_bb_fab1(sch_1):\DEFAULT\" )
				( netClassRef "@sapphirecity_baseboard_lib.sapphirecity_baseboard(sch_1):\POWER\" )
				( netClassRef "@sapphirecity_baseboard_lib.sapphirecity_baseboard(sch_1):\DMI_CPU0_PCH_TX\" )
			)
			( classClass "@sapphirecity_baseboard_lib.sapphirecity_baseboard(sch_1):\CC194\"
				( spacingCSetRef "@crescent_city_bb_fab1_lib.crescent_city_bb_fab1(sch_1):\DEFAULT\" )
				( netClassRef "@sapphirecity_baseboard_lib.sapphirecity_baseboard(sch_1):\GND\" )
				( netClassRef "@sapphirecity_baseboard_lib.sapphirecity_baseboard(sch_1):\PE_PCH_BMC_TX\" )
			)
			( classClass "@sapphirecity_baseboard_lib.sapphirecity_baseboard(sch_1):\CC319\"
				( spacingCSetRef "@sapphirecity_baseboard_lib.sapphirecity_baseboard(sch_1):\3H_SL_9H_MS_VIA_3H+A\" )
				( netClassRef "@sapphirecity_baseboard_lib.sapphirecity_baseboard(sch_1):\PE_PCH_BMC_TX\" )
				( netClassRef "@sapphirecity_baseboard_lib.sapphirecity_baseboard(sch_1):\PE_PCH_BMC_TX\" )
			)
			( classClass "@sapphirecity_baseboard_lib.sapphirecity_baseboard(sch_1):\CC195\"
				( spacingCSetRef "@crescent_city_bb_fab1_lib.crescent_city_bb_fab1(sch_1):\DEFAULT\" )
				( netClassRef "@sapphirecity_baseboard_lib.sapphirecity_baseboard(sch_1):\GND\" )
				( netClassRef "@sapphirecity_baseboard_lib.sapphirecity_baseboard(sch_1):\PE_PCH_BMC_RX\" )
			)
			( classClass "@sapphirecity_baseboard_lib.sapphirecity_baseboard(sch_1):\CC318\"
				( spacingCSetRef "@sapphirecity_baseboard_lib.sapphirecity_baseboard(sch_1):\3H_SL_9H_MS_VIA_3H+A\" )
				( netClassRef "@sapphirecity_baseboard_lib.sapphirecity_baseboard(sch_1):\PE_PCH_BMC_RX\" )
				( netClassRef "@sapphirecity_baseboard_lib.sapphirecity_baseboard(sch_1):\PE_PCH_BMC_RX\" )
			)
			( classClass "@sapphirecity_baseboard_lib.sapphirecity_baseboard(sch_1):\CC197\"
				( spacingCSetRef "@crescent_city_bb_fab1_lib.crescent_city_bb_fab1(sch_1):\DEFAULT\" )
				( netClassRef "@sapphirecity_baseboard_lib.sapphirecity_baseboard(sch_1):\GND\" )
				( netClassRef "@sapphirecity_baseboard_lib.sapphirecity_baseboard(sch_1):\MISC_INTEL_STATIC\" )
			)
			( classClass "@sapphirecity_baseboard_lib.sapphirecity_baseboard(sch_1):\CC201\"
				( spacingCSetRef "@crescent_city_bb_fab1_lib.crescent_city_bb_fab1(sch_1):\DEFAULT\" )
				( netClassRef "@sapphirecity_baseboard_lib.sapphirecity_baseboard(sch_1):\GND\" )
				( netClassRef "@sapphirecity_baseboard_lib.sapphirecity_baseboard(sch_1):\HOT_PLUG\" )
			)
			( classClass "@sapphirecity_baseboard_lib.sapphirecity_baseboard(sch_1):\CC202\"
				( spacingCSetRef "@crescent_city_bb_fab1_lib.crescent_city_bb_fab1(sch_1):\DEFAULT\" )
				( netClassRef "@sapphirecity_baseboard_lib.sapphirecity_baseboard(sch_1):\GND\" )
				( netClassRef "@sapphirecity_baseboard_lib.sapphirecity_baseboard(sch_1):\GSX\" )
			)
			( classClass "@sapphirecity_baseboard_lib.sapphirecity_baseboard(sch_1):\CC8\"
				( spacingCSetRef "@crescent_city_bb_fab1_lib.crescent_city_bb_fab1(sch_1):\DEFAULT\" )
				( netClassRef "@sapphirecity_baseboard_lib.sapphirecity_baseboard(sch_1):\GND\" )
				( netClassRef "@sapphirecity_baseboard_lib.sapphirecity_baseboard(sch_1):\RCOMP_ALL\" )
			)
			( classClass "@sapphirecity_baseboard_lib.sapphirecity_baseboard(sch_1):\CC6\"
				( spacingCSetRef "@crescent_city_bb_fab1_lib.crescent_city_bb_fab1(sch_1):\DEFAULT\" )
				( netClassRef "@sapphirecity_baseboard_lib.sapphirecity_baseboard(sch_1):\ANALOG_SIG-DIFF\" )
				( netClassRef "@sapphirecity_baseboard_lib.sapphirecity_baseboard(sch_1):\GND\" )
			)
			( classClass "@sapphirecity_baseboard_lib.sapphirecity_baseboard(sch_1):\CC7\"
				( spacingCSetRef "@sapphirecity_baseboard_lib.sapphirecity_baseboard(sch_1):\2.5H_US_AND_2H_SL\" )
				( netClassRef "@sapphirecity_baseboard_lib.sapphirecity_baseboard(sch_1):\ANALOG_SIG-DIFF\" )
				( netClassRef "@sapphirecity_baseboard_lib.sapphirecity_baseboard(sch_1):\ANALOG_SIG-DIFF\" )
			)
			( classClass "@sapphirecity_baseboard_lib.sapphirecity_baseboard(sch_1):\CC204\"
				( spacingCSetRef "@crescent_city_bb_fab1_lib.crescent_city_bb_fab1(sch_1):\DEFAULT\" )
				( netClassRef "@sapphirecity_baseboard_lib.sapphirecity_baseboard(sch_1):\DDR_VREFDQRX\" )
				( netClassRef "@sapphirecity_baseboard_lib.sapphirecity_baseboard(sch_1):\GND\" )
			)
			( classClass "@sapphirecity_baseboard_lib.sapphirecity_baseboard(sch_1):\CC205\"
				( spacingCSetRef "@crescent_city_bb_fab1_lib.crescent_city_bb_fab1(sch_1):\DEFAULT\" )
				( netClassRef "@sapphirecity_baseboard_lib.sapphirecity_baseboard(sch_1):\ANALOG_SIG-SE\" )
				( netClassRef "@sapphirecity_baseboard_lib.sapphirecity_baseboard(sch_1):\GND\" )
			)
			( classClass "@sapphirecity_baseboard_lib.sapphirecity_baseboard(sch_1):\CC281\"
				( spacingCSetRef "@sapphirecity_baseboard_lib.sapphirecity_baseboard(sch_1):\2.5H_US_AND_2H_SL\" )
				( netClassRef "@sapphirecity_baseboard_lib.sapphirecity_baseboard(sch_1):\ANALOG_SIG-SE\" )
				( netClassRef "@sapphirecity_baseboard_lib.sapphirecity_baseboard(sch_1):\ANALOG_SIG-SE\" )
			)
			( classClass "@sapphirecity_baseboard_lib.sapphirecity_baseboard(sch_1):\CC4\"
				( spacingCSetRef "@crescent_city_bb_fab1_lib.crescent_city_bb_fab1(sch_1):\DEFAULT\" )
				( netClassRef "@sapphirecity_baseboard_lib.sapphirecity_baseboard(sch_1):\AGND\" )
				( netClassRef "@sapphirecity_baseboard_lib.sapphirecity_baseboard(sch_1):\GND\" )
			)
			( classClass "@sapphirecity_baseboard_lib.sapphirecity_baseboard(sch_1):\CC5\"
				( netClassRef "@sapphirecity_baseboard_lib.sapphirecity_baseboard(sch_1):\AGND\" )
				( netClassRef "@sapphirecity_baseboard_lib.sapphirecity_baseboard(sch_1):\AGND\" )
			)
			( classClass "@sapphirecity_baseboard_lib.sapphirecity_baseboard(sch_1):\CC206\"
				( spacingCSetRef "@crescent_city_bb_fab1_lib.crescent_city_bb_fab1(sch_1):\DEFAULT\" )
				( netClassRef "@sapphirecity_baseboard_lib.sapphirecity_baseboard(sch_1):\AUDIO_AZALIA\" )
				( netClassRef "@sapphirecity_baseboard_lib.sapphirecity_baseboard(sch_1):\GND\" )
			)
			( classClass "@sapphirecity_baseboard_lib.sapphirecity_baseboard(sch_1):\CC280\"
				( spacingCSetRef "@sapphirecity_baseboard_lib.sapphirecity_baseboard(sch_1):\2.5H_US_AND_2H_SL\" )
				( netClassRef "@sapphirecity_baseboard_lib.sapphirecity_baseboard(sch_1):\AUDIO_AZALIA\" )
				( netClassRef "@sapphirecity_baseboard_lib.sapphirecity_baseboard(sch_1):\AUDIO_AZALIA\" )
			)
			( classClass "@sapphirecity_baseboard_lib.sapphirecity_baseboard(sch_1):\CC207\"
				( spacingCSetRef "@crescent_city_bb_fab1_lib.crescent_city_bb_fab1(sch_1):\DEFAULT\" )
				( netClassRef "@sapphirecity_baseboard_lib.sapphirecity_baseboard(sch_1):\AVMC\" )
				( netClassRef "@sapphirecity_baseboard_lib.sapphirecity_baseboard(sch_1):\GND\" )
			)
			( classClass "@sapphirecity_baseboard_lib.sapphirecity_baseboard(sch_1):\CC279\"
				( spacingCSetRef "@sapphirecity_baseboard_lib.sapphirecity_baseboard(sch_1):\8_MILS\" )
				( netClassRef "@sapphirecity_baseboard_lib.sapphirecity_baseboard(sch_1):\AVMC\" )
				( netClassRef "@sapphirecity_baseboard_lib.sapphirecity_baseboard(sch_1):\AVMC\" )
			)
			( classClass "@sapphirecity_baseboard_lib.sapphirecity_baseboard(sch_1):\CC214\"
				( spacingCSetRef "@crescent_city_bb_fab1_lib.crescent_city_bb_fab1(sch_1):\DEFAULT\" )
				( netClassRef "@sapphirecity_baseboard_lib.sapphirecity_baseboard(sch_1):\GND\" )
				( netClassRef "@sapphirecity_baseboard_lib.sapphirecity_baseboard(sch_1):\CLK_DIFF_100M\" )
			)
			( classClass "@sapphirecity_baseboard_lib.sapphirecity_baseboard(sch_1):\CC218\"
				( spacingCSetRef "@crescent_city_bb_fab1_lib.crescent_city_bb_fab1(sch_1):\DEFAULT\" )
				( netClassRef "@sapphirecity_baseboard_lib.sapphirecity_baseboard(sch_1):\GND\" )
				( netClassRef "@sapphirecity_baseboard_lib.sapphirecity_baseboard(sch_1):\CLK_SE_48_50M\" )
			)
			( classClass "@sapphirecity_baseboard_lib.sapphirecity_baseboard(sch_1):\CC3\"
				( spacingCSetRef "@crescent_city_bb_fab1_lib.crescent_city_bb_fab1(sch_1):\DEFAULT\" )
				( netClassRef "@sapphirecity_baseboard_lib.sapphirecity_baseboard(sch_1):\DDR4_VIEWDIG\" )
				( netClassRef "@sapphirecity_baseboard_lib.sapphirecity_baseboard(sch_1):\GND\" )
			)
			( classClass "@sapphirecity_baseboard_lib.sapphirecity_baseboard(sch_1):\CC246\"
				( spacingCSetRef "@crescent_city_bb_fab1_lib.crescent_city_bb_fab1(sch_1):\DEFAULT\" )
				( netClassRef "@sapphirecity_baseboard_lib.sapphirecity_baseboard(sch_1):\GND\" )
				( netClassRef "@sapphirecity_baseboard_lib.sapphirecity_baseboard(sch_1):\DMI_CPU0_PCH_RX\" )
			)
			( classClass "@sapphirecity_baseboard_lib.sapphirecity_baseboard(sch_1):\CC278\"
				( spacingCSetRef "@sapphirecity_baseboard_lib.sapphirecity_baseboard(sch_1):\3H_SL_9H_MS_VIA_3H+A\" )
				( netClassRef "@sapphirecity_baseboard_lib.sapphirecity_baseboard(sch_1):\DMI_CPU0_PCH_RX\" )
				( netClassRef "@sapphirecity_baseboard_lib.sapphirecity_baseboard(sch_1):\DMI_CPU0_PCH_RX\" )
			)
			( classClass "@sapphirecity_baseboard_lib.sapphirecity_baseboard(sch_1):\CC247\"
				( spacingCSetRef "@crescent_city_bb_fab1_lib.crescent_city_bb_fab1(sch_1):\DEFAULT\" )
				( netClassRef "@sapphirecity_baseboard_lib.sapphirecity_baseboard(sch_1):\GND\" )
				( netClassRef "@sapphirecity_baseboard_lib.sapphirecity_baseboard(sch_1):\DMI_CPU0_PCH_TX\" )
			)
			( classClass "@sapphirecity_baseboard_lib.sapphirecity_baseboard(sch_1):\CC277\"
				( spacingCSetRef "@sapphirecity_baseboard_lib.sapphirecity_baseboard(sch_1):\3H_SL_9H_MS_VIA_3H+A\" )
				( netClassRef "@sapphirecity_baseboard_lib.sapphirecity_baseboard(sch_1):\DMI_CPU0_PCH_TX\" )
				( netClassRef "@sapphirecity_baseboard_lib.sapphirecity_baseboard(sch_1):\DMI_CPU0_PCH_TX\" )
			)
			( classClass "@sapphirecity_baseboard_lib.sapphirecity_baseboard(sch_1):\CC276\"
				( spacingCSetRef "@crescent_city_bb_fab1_lib.crescent_city_bb_fab1(sch_1):\DEFAULT\" )
				( netClassRef "@sapphirecity_baseboard_lib.sapphirecity_baseboard(sch_1):\GND\" )
				( netClassRef "@sapphirecity_baseboard_lib.sapphirecity_baseboard(sch_1):\SMBUS_ALL\" )
			)
			( classClass "@sapphirecity_baseboard_lib.sapphirecity_baseboard(sch_1):\CC2\"
				( spacingCSetRef "@crescent_city_bb_fab1_lib.crescent_city_bb_fab1(sch_1):\DEFAULT\" )
				( netClassRef "@sapphirecity_baseboard_lib.sapphirecity_baseboard(sch_1):\GND\" )
				( netClassRef "@sapphirecity_baseboard_lib.sapphirecity_baseboard(sch_1):\SMBUS_DDR\" )
			)
			( classClass "@sapphirecity_baseboard_lib.sapphirecity_baseboard(sch_1):\CC249\"
				( spacingCSetRef "@crescent_city_bb_fab1_lib.crescent_city_bb_fab1(sch_1):\DEFAULT\" )
				( netClassRef "@sapphirecity_baseboard_lib.sapphirecity_baseboard(sch_1):\GND\" )
				( netClassRef "@sapphirecity_baseboard_lib.sapphirecity_baseboard(sch_1):\GND\" )
			)
			( classClass "@crescent_city_bb_fab1_lib.crescent_city_bb_fab1(sch_1):\CC369\"
				( spacingCSetRef "@crescent_city_bb_fab1_lib.crescent_city_bb_fab1(sch_1):\DEFAULT\" )
				( netClassRef "@sapphirecity_baseboard_lib.sapphirecity_baseboard(sch_1):\GND\" )
				( netClassRef "@sapphirecity_baseboard_lib.sapphirecity_baseboard(sch_1):\DDR4_CHN_J_CLK\" )
			)
			( classClass "@crescent_city_bb_fab1_lib.crescent_city_bb_fab1(sch_1):\CC382\"
				( spacingCSetRef "@crescent_city_bb_fab1_lib.crescent_city_bb_fab1(sch_1):\DEFAULT\" )
				( netClassRef "@sapphirecity_baseboard_lib.sapphirecity_baseboard(sch_1):\GND\" )
				( netClassRef "@sapphirecity_baseboard_lib.sapphirecity_baseboard(sch_1):\DDR4_CHN_J_CMD_ADD\" )
			)
			( classClass "@crescent_city_bb_fab1_lib.crescent_city_bb_fab1(sch_1):\CC394\"
				( spacingCSetRef "@crescent_city_bb_fab1_lib.crescent_city_bb_fab1(sch_1):\DEFAULT\" )
				( netClassRef "@sapphirecity_baseboard_lib.sapphirecity_baseboard(sch_1):\GND\" )
				( netClassRef "@sapphirecity_baseboard_lib.sapphirecity_baseboard(sch_1):\DDR4_CHN_J_CTRL\" )
			)
			( classClass "@crescent_city_bb_fab1_lib.crescent_city_bb_fab1(sch_1):\CC408\"
				( spacingCSetRef "@crescent_city_bb_fab1_lib.crescent_city_bb_fab1(sch_1):\DEFAULT\" )
				( netClassRef "@sapphirecity_baseboard_lib.sapphirecity_baseboard(sch_1):\GND\" )
				( netClassRef "@sapphirecity_baseboard_lib.sapphirecity_baseboard(sch_1):\DDR4_CHN_K_CLK\" )
			)
			( classClass "@crescent_city_bb_fab1_lib.crescent_city_bb_fab1(sch_1):\CC421\"
				( spacingCSetRef "@crescent_city_bb_fab1_lib.crescent_city_bb_fab1(sch_1):\DEFAULT\" )
				( netClassRef "@sapphirecity_baseboard_lib.sapphirecity_baseboard(sch_1):\GND\" )
				( netClassRef "@sapphirecity_baseboard_lib.sapphirecity_baseboard(sch_1):\DDR4_CHN_K_CMD_ADD\" )
			)
			( classClass "@crescent_city_bb_fab1_lib.crescent_city_bb_fab1(sch_1):\CC433\"
				( spacingCSetRef "@crescent_city_bb_fab1_lib.crescent_city_bb_fab1(sch_1):\DEFAULT\" )
				( netClassRef "@sapphirecity_baseboard_lib.sapphirecity_baseboard(sch_1):\GND\" )
				( netClassRef "@sapphirecity_baseboard_lib.sapphirecity_baseboard(sch_1):\DDR4_CHN_K_CTRL\" )
			)
			( classClass "@crescent_city_bb_fab1_lib.crescent_city_bb_fab1(sch_1):\CC447\"
				( spacingCSetRef "@crescent_city_bb_fab1_lib.crescent_city_bb_fab1(sch_1):\DEFAULT\" )
				( netClassRef "@sapphirecity_baseboard_lib.sapphirecity_baseboard(sch_1):\GND\" )
				( netClassRef "@sapphirecity_baseboard_lib.sapphirecity_baseboard(sch_1):\DDR4_CHN_L_CLK\" )
			)
			( classClass "@crescent_city_bb_fab1_lib.crescent_city_bb_fab1(sch_1):\CC460\"
				( spacingCSetRef "@crescent_city_bb_fab1_lib.crescent_city_bb_fab1(sch_1):\DEFAULT\" )
				( netClassRef "@sapphirecity_baseboard_lib.sapphirecity_baseboard(sch_1):\GND\" )
				( netClassRef "@sapphirecity_baseboard_lib.sapphirecity_baseboard(sch_1):\DDR4_CHN_L_CMD_ADD\" )
			)
			( classClass "@crescent_city_bb_fab1_lib.crescent_city_bb_fab1(sch_1):\CC472\"
				( spacingCSetRef "@crescent_city_bb_fab1_lib.crescent_city_bb_fab1(sch_1):\DEFAULT\" )
				( netClassRef "@sapphirecity_baseboard_lib.sapphirecity_baseboard(sch_1):\GND\" )
				( netClassRef "@sapphirecity_baseboard_lib.sapphirecity_baseboard(sch_1):\DDR4_CHN_L_CTRL\" )
			)
			( classClass "@crescent_city_bb_fab1_lib.crescent_city_bb_fab1(sch_1):\CC486\"
				( spacingCSetRef "@crescent_city_bb_fab1_lib.crescent_city_bb_fab1(sch_1):\DEFAULT\" )
				( netClassRef "@sapphirecity_baseboard_lib.sapphirecity_baseboard(sch_1):\GND\" )
				( netClassRef "@sapphirecity_baseboard_lib.sapphirecity_baseboard(sch_1):\DDR4_CHN_M_CLK\" )
			)
			( classClass "@crescent_city_bb_fab1_lib.crescent_city_bb_fab1(sch_1):\CC499\"
				( spacingCSetRef "@crescent_city_bb_fab1_lib.crescent_city_bb_fab1(sch_1):\DEFAULT\" )
				( netClassRef "@sapphirecity_baseboard_lib.sapphirecity_baseboard(sch_1):\GND\" )
				( netClassRef "@sapphirecity_baseboard_lib.sapphirecity_baseboard(sch_1):\DDR4_CHN_M_CMD_ADD\" )
			)
			( classClass "@crescent_city_bb_fab1_lib.crescent_city_bb_fab1(sch_1):\CC511\"
				( spacingCSetRef "@crescent_city_bb_fab1_lib.crescent_city_bb_fab1(sch_1):\DEFAULT\" )
				( netClassRef "@sapphirecity_baseboard_lib.sapphirecity_baseboard(sch_1):\GND\" )
				( netClassRef "@sapphirecity_baseboard_lib.sapphirecity_baseboard(sch_1):\DDR4_CHN_M_CTRL\" )
			)
			( classClass "@crescent_city_bb_fab1_lib.crescent_city_bb_fab1(sch_1):\CC614\"
				( spacingCSetRef "@crescent_city_bb_fab1_lib.crescent_city_bb_fab1(sch_1):\DEFAULT\" )
				( netClassRef "@sapphirecity_baseboard_lib.sapphirecity_baseboard(sch_1):\GND\" )
				( netClassRef "@sapphirecity_baseboard_lib.sapphirecity_baseboard(sch_1):\DDR4_CHN_J_DQ_DQS_BYTE0\" )
			)
			( classClass "@crescent_city_bb_fab1_lib.crescent_city_bb_fab1(sch_1):\CC615\"
				( spacingCSetRef "@crescent_city_bb_fab1_lib.crescent_city_bb_fab1(sch_1):\DEFAULT\" )
				( netClassRef "@sapphirecity_baseboard_lib.sapphirecity_baseboard(sch_1):\GND\" )
				( netClassRef "@sapphirecity_baseboard_lib.sapphirecity_baseboard(sch_1):\DDR4_CHN_J_DQ_DQS_BYTE1\" )
			)
			( classClass "@crescent_city_bb_fab1_lib.crescent_city_bb_fab1(sch_1):\CC616\"
				( spacingCSetRef "@crescent_city_bb_fab1_lib.crescent_city_bb_fab1(sch_1):\DEFAULT\" )
				( netClassRef "@sapphirecity_baseboard_lib.sapphirecity_baseboard(sch_1):\GND\" )
				( netClassRef "@sapphirecity_baseboard_lib.sapphirecity_baseboard(sch_1):\DDR4_CHN_J_DQ_DQS_BYTE2\" )
			)
			( classClass "@crescent_city_bb_fab1_lib.crescent_city_bb_fab1(sch_1):\CC617\"
				( spacingCSetRef "@crescent_city_bb_fab1_lib.crescent_city_bb_fab1(sch_1):\DEFAULT\" )
				( netClassRef "@sapphirecity_baseboard_lib.sapphirecity_baseboard(sch_1):\GND\" )
				( netClassRef "@sapphirecity_baseboard_lib.sapphirecity_baseboard(sch_1):\DDR4_CHN_J_DQ_DQS_BYTE3\" )
			)
			( classClass "@crescent_city_bb_fab1_lib.crescent_city_bb_fab1(sch_1):\CC618\"
				( spacingCSetRef "@crescent_city_bb_fab1_lib.crescent_city_bb_fab1(sch_1):\DEFAULT\" )
				( netClassRef "@sapphirecity_baseboard_lib.sapphirecity_baseboard(sch_1):\GND\" )
				( netClassRef "@sapphirecity_baseboard_lib.sapphirecity_baseboard(sch_1):\DDR4_CHN_J_DQ_DQS_BYTE4\" )
			)
			( classClass "@crescent_city_bb_fab1_lib.crescent_city_bb_fab1(sch_1):\CC619\"
				( spacingCSetRef "@crescent_city_bb_fab1_lib.crescent_city_bb_fab1(sch_1):\DEFAULT\" )
				( netClassRef "@sapphirecity_baseboard_lib.sapphirecity_baseboard(sch_1):\GND\" )
				( netClassRef "@sapphirecity_baseboard_lib.sapphirecity_baseboard(sch_1):\DDR4_CHN_J_DQ_DQS_BYTE5\" )
			)
			( classClass "@crescent_city_bb_fab1_lib.crescent_city_bb_fab1(sch_1):\CC620\"
				( spacingCSetRef "@crescent_city_bb_fab1_lib.crescent_city_bb_fab1(sch_1):\DEFAULT\" )
				( netClassRef "@sapphirecity_baseboard_lib.sapphirecity_baseboard(sch_1):\GND\" )
				( netClassRef "@sapphirecity_baseboard_lib.sapphirecity_baseboard(sch_1):\DDR4_CHN_J_DQ_DQS_BYTE6\" )
			)
			( classClass "@crescent_city_bb_fab1_lib.crescent_city_bb_fab1(sch_1):\CC621\"
				( spacingCSetRef "@crescent_city_bb_fab1_lib.crescent_city_bb_fab1(sch_1):\DEFAULT\" )
				( netClassRef "@sapphirecity_baseboard_lib.sapphirecity_baseboard(sch_1):\GND\" )
				( netClassRef "@sapphirecity_baseboard_lib.sapphirecity_baseboard(sch_1):\DDR4_CHN_J_DQ_DQS_BYTE7\" )
			)
			( classClass "@crescent_city_bb_fab1_lib.crescent_city_bb_fab1(sch_1):\CC622\"
				( spacingCSetRef "@crescent_city_bb_fab1_lib.crescent_city_bb_fab1(sch_1):\DEFAULT\" )
				( netClassRef "@sapphirecity_baseboard_lib.sapphirecity_baseboard(sch_1):\GND\" )
				( netClassRef "@sapphirecity_baseboard_lib.sapphirecity_baseboard(sch_1):\DDR4_CHN_J_ECC\" )
			)
			( classClass "@crescent_city_bb_fab1_lib.crescent_city_bb_fab1(sch_1):\CC623\"
				( spacingCSetRef "@crescent_city_bb_fab1_lib.crescent_city_bb_fab1(sch_1):\DEFAULT\" )
				( netClassRef "@sapphirecity_baseboard_lib.sapphirecity_baseboard(sch_1):\GND\" )
				( netClassRef "@sapphirecity_baseboard_lib.sapphirecity_baseboard(sch_1):\DDR4_CHN_K_DQ_DQS_BYTE0\" )
			)
			( classClass "@crescent_city_bb_fab1_lib.crescent_city_bb_fab1(sch_1):\CC624\"
				( spacingCSetRef "@crescent_city_bb_fab1_lib.crescent_city_bb_fab1(sch_1):\DEFAULT\" )
				( netClassRef "@sapphirecity_baseboard_lib.sapphirecity_baseboard(sch_1):\GND\" )
				( netClassRef "@sapphirecity_baseboard_lib.sapphirecity_baseboard(sch_1):\DDR4_CHN_K_DQ_DQS_BYTE1\" )
			)
			( classClass "@crescent_city_bb_fab1_lib.crescent_city_bb_fab1(sch_1):\CC625\"
				( spacingCSetRef "@crescent_city_bb_fab1_lib.crescent_city_bb_fab1(sch_1):\DEFAULT\" )
				( netClassRef "@sapphirecity_baseboard_lib.sapphirecity_baseboard(sch_1):\GND\" )
				( netClassRef "@sapphirecity_baseboard_lib.sapphirecity_baseboard(sch_1):\DDR4_CHN_K_DQ_DQS_BYTE2\" )
			)
			( classClass "@crescent_city_bb_fab1_lib.crescent_city_bb_fab1(sch_1):\CC626\"
				( spacingCSetRef "@crescent_city_bb_fab1_lib.crescent_city_bb_fab1(sch_1):\DEFAULT\" )
				( netClassRef "@sapphirecity_baseboard_lib.sapphirecity_baseboard(sch_1):\GND\" )
				( netClassRef "@sapphirecity_baseboard_lib.sapphirecity_baseboard(sch_1):\DDR4_CHN_K_DQ_DQS_BYTE3\" )
			)
			( classClass "@crescent_city_bb_fab1_lib.crescent_city_bb_fab1(sch_1):\CC627\"
				( spacingCSetRef "@crescent_city_bb_fab1_lib.crescent_city_bb_fab1(sch_1):\DEFAULT\" )
				( netClassRef "@sapphirecity_baseboard_lib.sapphirecity_baseboard(sch_1):\GND\" )
				( netClassRef "@sapphirecity_baseboard_lib.sapphirecity_baseboard(sch_1):\DDR4_CHN_K_DQ_DQS_BYTE4\" )
			)
			( classClass "@crescent_city_bb_fab1_lib.crescent_city_bb_fab1(sch_1):\CC628\"
				( spacingCSetRef "@crescent_city_bb_fab1_lib.crescent_city_bb_fab1(sch_1):\DEFAULT\" )
				( netClassRef "@sapphirecity_baseboard_lib.sapphirecity_baseboard(sch_1):\GND\" )
				( netClassRef "@sapphirecity_baseboard_lib.sapphirecity_baseboard(sch_1):\DDR4_CHN_K_DQ_DQS_BYTE5\" )
			)
			( classClass "@crescent_city_bb_fab1_lib.crescent_city_bb_fab1(sch_1):\CC629\"
				( spacingCSetRef "@crescent_city_bb_fab1_lib.crescent_city_bb_fab1(sch_1):\DEFAULT\" )
				( netClassRef "@sapphirecity_baseboard_lib.sapphirecity_baseboard(sch_1):\GND\" )
				( netClassRef "@sapphirecity_baseboard_lib.sapphirecity_baseboard(sch_1):\DDR4_CHN_K_DQ_DQS_BYTE6\" )
			)
			( classClass "@crescent_city_bb_fab1_lib.crescent_city_bb_fab1(sch_1):\CC630\"
				( spacingCSetRef "@crescent_city_bb_fab1_lib.crescent_city_bb_fab1(sch_1):\DEFAULT\" )
				( netClassRef "@sapphirecity_baseboard_lib.sapphirecity_baseboard(sch_1):\GND\" )
				( netClassRef "@sapphirecity_baseboard_lib.sapphirecity_baseboard(sch_1):\DDR4_CHN_K_DQ_DQS_BYTE7\" )
			)
			( classClass "@crescent_city_bb_fab1_lib.crescent_city_bb_fab1(sch_1):\CC631\"
				( spacingCSetRef "@crescent_city_bb_fab1_lib.crescent_city_bb_fab1(sch_1):\DEFAULT\" )
				( netClassRef "@sapphirecity_baseboard_lib.sapphirecity_baseboard(sch_1):\GND\" )
				( netClassRef "@sapphirecity_baseboard_lib.sapphirecity_baseboard(sch_1):\DDR4_CHN_K_ECC\" )
			)
			( classClass "@crescent_city_bb_fab1_lib.crescent_city_bb_fab1(sch_1):\CC632\"
				( spacingCSetRef "@crescent_city_bb_fab1_lib.crescent_city_bb_fab1(sch_1):\DEFAULT\" )
				( netClassRef "@sapphirecity_baseboard_lib.sapphirecity_baseboard(sch_1):\GND\" )
				( netClassRef "@sapphirecity_baseboard_lib.sapphirecity_baseboard(sch_1):\DDR4_CHN_L_DQ_DQS_BYTE0\" )
			)
			( classClass "@crescent_city_bb_fab1_lib.crescent_city_bb_fab1(sch_1):\CC633\"
				( spacingCSetRef "@crescent_city_bb_fab1_lib.crescent_city_bb_fab1(sch_1):\DEFAULT\" )
				( netClassRef "@sapphirecity_baseboard_lib.sapphirecity_baseboard(sch_1):\GND\" )
				( netClassRef "@sapphirecity_baseboard_lib.sapphirecity_baseboard(sch_1):\DDR4_CHN_L_DQ_DQS_BYTE1\" )
			)
			( classClass "@crescent_city_bb_fab1_lib.crescent_city_bb_fab1(sch_1):\CC634\"
				( spacingCSetRef "@crescent_city_bb_fab1_lib.crescent_city_bb_fab1(sch_1):\DEFAULT\" )
				( netClassRef "@sapphirecity_baseboard_lib.sapphirecity_baseboard(sch_1):\GND\" )
				( netClassRef "@sapphirecity_baseboard_lib.sapphirecity_baseboard(sch_1):\DDR4_CHN_L_DQ_DQS_BYTE2\" )
			)
			( classClass "@crescent_city_bb_fab1_lib.crescent_city_bb_fab1(sch_1):\CC635\"
				( spacingCSetRef "@crescent_city_bb_fab1_lib.crescent_city_bb_fab1(sch_1):\DEFAULT\" )
				( netClassRef "@sapphirecity_baseboard_lib.sapphirecity_baseboard(sch_1):\GND\" )
				( netClassRef "@sapphirecity_baseboard_lib.sapphirecity_baseboard(sch_1):\DDR4_CHN_L_DQ_DQS_BYTE3\" )
			)
			( classClass "@crescent_city_bb_fab1_lib.crescent_city_bb_fab1(sch_1):\CC636\"
				( spacingCSetRef "@crescent_city_bb_fab1_lib.crescent_city_bb_fab1(sch_1):\DEFAULT\" )
				( netClassRef "@sapphirecity_baseboard_lib.sapphirecity_baseboard(sch_1):\GND\" )
				( netClassRef "@sapphirecity_baseboard_lib.sapphirecity_baseboard(sch_1):\DDR4_CHN_L_DQ_DQS_BYTE4\" )
			)
			( classClass "@crescent_city_bb_fab1_lib.crescent_city_bb_fab1(sch_1):\CC637\"
				( spacingCSetRef "@crescent_city_bb_fab1_lib.crescent_city_bb_fab1(sch_1):\DEFAULT\" )
				( netClassRef "@sapphirecity_baseboard_lib.sapphirecity_baseboard(sch_1):\GND\" )
				( netClassRef "@sapphirecity_baseboard_lib.sapphirecity_baseboard(sch_1):\DDR4_CHN_L_DQ_DQS_BYTE5\" )
			)
			( classClass "@crescent_city_bb_fab1_lib.crescent_city_bb_fab1(sch_1):\CC638\"
				( spacingCSetRef "@crescent_city_bb_fab1_lib.crescent_city_bb_fab1(sch_1):\DEFAULT\" )
				( netClassRef "@sapphirecity_baseboard_lib.sapphirecity_baseboard(sch_1):\GND\" )
				( netClassRef "@sapphirecity_baseboard_lib.sapphirecity_baseboard(sch_1):\DDR4_CHN_L_DQ_DQS_BYTE6\" )
			)
			( classClass "@crescent_city_bb_fab1_lib.crescent_city_bb_fab1(sch_1):\CC639\"
				( spacingCSetRef "@crescent_city_bb_fab1_lib.crescent_city_bb_fab1(sch_1):\DEFAULT\" )
				( netClassRef "@sapphirecity_baseboard_lib.sapphirecity_baseboard(sch_1):\GND\" )
				( netClassRef "@sapphirecity_baseboard_lib.sapphirecity_baseboard(sch_1):\DDR4_CHN_L_DQ_DQS_BYTE7\" )
			)
			( classClass "@crescent_city_bb_fab1_lib.crescent_city_bb_fab1(sch_1):\CC640\"
				( spacingCSetRef "@crescent_city_bb_fab1_lib.crescent_city_bb_fab1(sch_1):\DEFAULT\" )
				( netClassRef "@sapphirecity_baseboard_lib.sapphirecity_baseboard(sch_1):\GND\" )
				( netClassRef "@sapphirecity_baseboard_lib.sapphirecity_baseboard(sch_1):\DDR4_CHN_L_ECC\" )
			)
			( classClass "@crescent_city_bb_fab1_lib.crescent_city_bb_fab1(sch_1):\CC641\"
				( spacingCSetRef "@crescent_city_bb_fab1_lib.crescent_city_bb_fab1(sch_1):\DEFAULT\" )
				( netClassRef "@sapphirecity_baseboard_lib.sapphirecity_baseboard(sch_1):\GND\" )
				( netClassRef "@sapphirecity_baseboard_lib.sapphirecity_baseboard(sch_1):\DDR4_CHN_M_DQ_DQS_BYTE0\" )
			)
			( classClass "@crescent_city_bb_fab1_lib.crescent_city_bb_fab1(sch_1):\CC642\"
				( spacingCSetRef "@crescent_city_bb_fab1_lib.crescent_city_bb_fab1(sch_1):\DEFAULT\" )
				( netClassRef "@sapphirecity_baseboard_lib.sapphirecity_baseboard(sch_1):\GND\" )
				( netClassRef "@sapphirecity_baseboard_lib.sapphirecity_baseboard(sch_1):\DDR4_CHN_M_DQ_DQS_BYTE1\" )
			)
			( classClass "@crescent_city_bb_fab1_lib.crescent_city_bb_fab1(sch_1):\CC643\"
				( spacingCSetRef "@crescent_city_bb_fab1_lib.crescent_city_bb_fab1(sch_1):\DEFAULT\" )
				( netClassRef "@sapphirecity_baseboard_lib.sapphirecity_baseboard(sch_1):\GND\" )
				( netClassRef "@sapphirecity_baseboard_lib.sapphirecity_baseboard(sch_1):\DDR4_CHN_M_DQ_DQS_BYTE2\" )
			)
			( classClass "@crescent_city_bb_fab1_lib.crescent_city_bb_fab1(sch_1):\CC644\"
				( spacingCSetRef "@crescent_city_bb_fab1_lib.crescent_city_bb_fab1(sch_1):\DEFAULT\" )
				( netClassRef "@sapphirecity_baseboard_lib.sapphirecity_baseboard(sch_1):\GND\" )
				( netClassRef "@sapphirecity_baseboard_lib.sapphirecity_baseboard(sch_1):\DDR4_CHN_M_DQ_DQS_BYTE3\" )
			)
			( classClass "@crescent_city_bb_fab1_lib.crescent_city_bb_fab1(sch_1):\CC645\"
				( spacingCSetRef "@crescent_city_bb_fab1_lib.crescent_city_bb_fab1(sch_1):\DEFAULT\" )
				( netClassRef "@sapphirecity_baseboard_lib.sapphirecity_baseboard(sch_1):\GND\" )
				( netClassRef "@sapphirecity_baseboard_lib.sapphirecity_baseboard(sch_1):\DDR4_CHN_M_DQ_DQS_BYTE4\" )
			)
			( classClass "@crescent_city_bb_fab1_lib.crescent_city_bb_fab1(sch_1):\CC646\"
				( spacingCSetRef "@crescent_city_bb_fab1_lib.crescent_city_bb_fab1(sch_1):\DEFAULT\" )
				( netClassRef "@sapphirecity_baseboard_lib.sapphirecity_baseboard(sch_1):\GND\" )
				( netClassRef "@sapphirecity_baseboard_lib.sapphirecity_baseboard(sch_1):\DDR4_CHN_M_DQ_DQS_BYTE5\" )
			)
			( classClass "@crescent_city_bb_fab1_lib.crescent_city_bb_fab1(sch_1):\CC647\"
				( spacingCSetRef "@crescent_city_bb_fab1_lib.crescent_city_bb_fab1(sch_1):\DEFAULT\" )
				( netClassRef "@sapphirecity_baseboard_lib.sapphirecity_baseboard(sch_1):\GND\" )
				( netClassRef "@sapphirecity_baseboard_lib.sapphirecity_baseboard(sch_1):\DDR4_CHN_M_DQ_DQS_BYTE6\" )
			)
			( classClass "@crescent_city_bb_fab1_lib.crescent_city_bb_fab1(sch_1):\CC648\"
				( spacingCSetRef "@crescent_city_bb_fab1_lib.crescent_city_bb_fab1(sch_1):\DEFAULT\" )
				( netClassRef "@sapphirecity_baseboard_lib.sapphirecity_baseboard(sch_1):\GND\" )
				( netClassRef "@sapphirecity_baseboard_lib.sapphirecity_baseboard(sch_1):\DDR4_CHN_M_DQ_DQS_BYTE7\" )
			)
			( classClass "@crescent_city_bb_fab1_lib.crescent_city_bb_fab1(sch_1):\CC649\"
				( spacingCSetRef "@crescent_city_bb_fab1_lib.crescent_city_bb_fab1(sch_1):\DEFAULT\" )
				( netClassRef "@sapphirecity_baseboard_lib.sapphirecity_baseboard(sch_1):\GND\" )
				( netClassRef "@sapphirecity_baseboard_lib.sapphirecity_baseboard(sch_1):\DDR4_CHN_M_ECC\" )
			)
			( classClass "@crescent_city_bb_fab1_lib.crescent_city_bb_fab1(sch_1):\CC929\"
				( spacingCSetRef "@crescent_city_bb_fab1_lib.crescent_city_bb_fab1(sch_1):\DEFAULT\" )
				( netClassRef "@sapphirecity_baseboard_lib.sapphirecity_baseboard(sch_1):\GND\" )
				( netClassRef "@sapphirecity_baseboard_lib.sapphirecity_baseboard(sch_1):\KTI_CPU0_CPU1_P1P0\" )
			)
			( classClass "@crescent_city_bb_fab1_lib.crescent_city_bb_fab1(sch_1):\CC930\"
				( spacingCSetRef "@crescent_city_bb_fab1_lib.crescent_city_bb_fab1(sch_1):\DEFAULT\" )
				( netClassRef "@sapphirecity_baseboard_lib.sapphirecity_baseboard(sch_1):\GND\" )
				( netClassRef "@sapphirecity_baseboard_lib.sapphirecity_baseboard(sch_1):\KTI_CPU0_CPU1_P0P1\" )
			)
			( classClass "@crescent_city_bb_fab1_lib.crescent_city_bb_fab1(sch_1):\CC931\"
				( spacingCSetRef "@crescent_city_bb_fab1_lib.crescent_city_bb_fab1(sch_1):\DEFAULT\" )
				( netClassRef "@sapphirecity_baseboard_lib.sapphirecity_baseboard(sch_1):\GND\" )
				( netClassRef "@sapphirecity_baseboard_lib.sapphirecity_baseboard(sch_1):\KTI_CPU1_CPU0_P1P0\" )
			)
			( classClass "@crescent_city_bb_fab1_lib.crescent_city_bb_fab1(sch_1):\CC932\"
				( spacingCSetRef "@crescent_city_bb_fab1_lib.crescent_city_bb_fab1(sch_1):\DEFAULT\" )
				( netClassRef "@sapphirecity_baseboard_lib.sapphirecity_baseboard(sch_1):\GND\" )
				( netClassRef "@sapphirecity_baseboard_lib.sapphirecity_baseboard(sch_1):\KTI_CPU1_CPU0_P0P1\" )
			)
			( classClass "@sapphirecity_baseboard_lib.sapphirecity_baseboard(sch_1):\CC1039\"
				( spacingCSetRef "@sapphirecity_baseboard_lib.sapphirecity_baseboard(sch_1):\DDR4_2SPC_DQ/DQS\" )
				( netClassRef "@sapphirecity_baseboard_lib.sapphirecity_baseboard(sch_1):\DDR4_CHN_J_ECC\" )
				( netClassRef "@sapphirecity_baseboard_lib.sapphirecity_baseboard(sch_1):\DDR4_CHN_J_ECC\" )
			)
			( classClass "@crescent_city_bb_fab1_lib.crescent_city_bb_fab1(sch_1):\CC368\"
				( spacingCSetRef "@sapphirecity_baseboard_lib.sapphirecity_baseboard(sch_1):\DQ_TO_DQ\" )
				( netClassRef "@sapphirecity_baseboard_lib.sapphirecity_baseboard(sch_1):\DDR4_CHN_J_CLK\" )
				( netClassRef "@sapphirecity_baseboard_lib.sapphirecity_baseboard(sch_1):\DDR4_CHN_J_ECC\" )
			)
			( classClass "@crescent_city_bb_fab1_lib.crescent_city_bb_fab1(sch_1):\CC381\"
				( spacingCSetRef "@sapphirecity_baseboard_lib.sapphirecity_baseboard(sch_1):\DQ_TO_DQ\" )
				( netClassRef "@sapphirecity_baseboard_lib.sapphirecity_baseboard(sch_1):\DDR4_CHN_J_CMD_ADD\" )
				( netClassRef "@sapphirecity_baseboard_lib.sapphirecity_baseboard(sch_1):\DDR4_CHN_J_ECC\" )
			)
			( classClass "@crescent_city_bb_fab1_lib.crescent_city_bb_fab1(sch_1):\CC393\"
				( spacingCSetRef "@sapphirecity_baseboard_lib.sapphirecity_baseboard(sch_1):\DQ_TO_DQ\" )
				( netClassRef "@sapphirecity_baseboard_lib.sapphirecity_baseboard(sch_1):\DDR4_CHN_J_CTRL\" )
				( netClassRef "@sapphirecity_baseboard_lib.sapphirecity_baseboard(sch_1):\DDR4_CHN_J_ECC\" )
			)
			( classClass "@crescent_city_bb_fab1_lib.crescent_city_bb_fab1(sch_1):\CC783\"
				( spacingCSetRef "@sapphirecity_baseboard_lib.sapphirecity_baseboard(sch_1):\DQ_TO_DQ\" )
				( netClassRef "@sapphirecity_baseboard_lib.sapphirecity_baseboard(sch_1):\DDR4_CHN_J_DQ_DQS_BYTE0\" )
				( netClassRef "@sapphirecity_baseboard_lib.sapphirecity_baseboard(sch_1):\DDR4_CHN_J_ECC\" )
			)
			( classClass "@crescent_city_bb_fab1_lib.crescent_city_bb_fab1(sch_1):\CC790\"
				( spacingCSetRef "@sapphirecity_baseboard_lib.sapphirecity_baseboard(sch_1):\DQ_TO_DQ\" )
				( netClassRef "@sapphirecity_baseboard_lib.sapphirecity_baseboard(sch_1):\DDR4_CHN_J_DQ_DQS_BYTE1\" )
				( netClassRef "@sapphirecity_baseboard_lib.sapphirecity_baseboard(sch_1):\DDR4_CHN_J_ECC\" )
			)
			( classClass "@crescent_city_bb_fab1_lib.crescent_city_bb_fab1(sch_1):\CC796\"
				( spacingCSetRef "@sapphirecity_baseboard_lib.sapphirecity_baseboard(sch_1):\DQ_TO_DQ\" )
				( netClassRef "@sapphirecity_baseboard_lib.sapphirecity_baseboard(sch_1):\DDR4_CHN_J_DQ_DQS_BYTE2\" )
				( netClassRef "@sapphirecity_baseboard_lib.sapphirecity_baseboard(sch_1):\DDR4_CHN_J_ECC\" )
			)
			( classClass "@crescent_city_bb_fab1_lib.crescent_city_bb_fab1(sch_1):\CC801\"
				( spacingCSetRef "@sapphirecity_baseboard_lib.sapphirecity_baseboard(sch_1):\DQ_TO_DQ\" )
				( netClassRef "@sapphirecity_baseboard_lib.sapphirecity_baseboard(sch_1):\DDR4_CHN_J_DQ_DQS_BYTE3\" )
				( netClassRef "@sapphirecity_baseboard_lib.sapphirecity_baseboard(sch_1):\DDR4_CHN_J_ECC\" )
			)
			( classClass "@crescent_city_bb_fab1_lib.crescent_city_bb_fab1(sch_1):\CC805\"
				( spacingCSetRef "@sapphirecity_baseboard_lib.sapphirecity_baseboard(sch_1):\DQ_TO_DQ\" )
				( netClassRef "@sapphirecity_baseboard_lib.sapphirecity_baseboard(sch_1):\DDR4_CHN_J_DQ_DQS_BYTE4\" )
				( netClassRef "@sapphirecity_baseboard_lib.sapphirecity_baseboard(sch_1):\DDR4_CHN_J_ECC\" )
			)
			( classClass "@crescent_city_bb_fab1_lib.crescent_city_bb_fab1(sch_1):\CC808\"
				( spacingCSetRef "@sapphirecity_baseboard_lib.sapphirecity_baseboard(sch_1):\DQ_TO_DQ\" )
				( netClassRef "@sapphirecity_baseboard_lib.sapphirecity_baseboard(sch_1):\DDR4_CHN_J_DQ_DQS_BYTE5\" )
				( netClassRef "@sapphirecity_baseboard_lib.sapphirecity_baseboard(sch_1):\DDR4_CHN_J_ECC\" )
			)
			( classClass "@crescent_city_bb_fab1_lib.crescent_city_bb_fab1(sch_1):\CC810\"
				( spacingCSetRef "@sapphirecity_baseboard_lib.sapphirecity_baseboard(sch_1):\DQ_TO_DQ\" )
				( netClassRef "@sapphirecity_baseboard_lib.sapphirecity_baseboard(sch_1):\DDR4_CHN_J_DQ_DQS_BYTE6\" )
				( netClassRef "@sapphirecity_baseboard_lib.sapphirecity_baseboard(sch_1):\DDR4_CHN_J_ECC\" )
			)
			( classClass "@crescent_city_bb_fab1_lib.crescent_city_bb_fab1(sch_1):\CC811\"
				( spacingCSetRef "@sapphirecity_baseboard_lib.sapphirecity_baseboard(sch_1):\DQ_TO_DQ\" )
				( netClassRef "@sapphirecity_baseboard_lib.sapphirecity_baseboard(sch_1):\DDR4_CHN_J_DQ_DQS_BYTE7\" )
				( netClassRef "@sapphirecity_baseboard_lib.sapphirecity_baseboard(sch_1):\DDR4_CHN_J_ECC\" )
			)
			( classClass "@sapphirecity_baseboard_lib.sapphirecity_baseboard(sch_1):\CC1030\"
				( spacingCSetRef "@sapphirecity_baseboard_lib.sapphirecity_baseboard(sch_1):\DDR4_2SPC_DQ/DQS\" )
				( netClassRef "@sapphirecity_baseboard_lib.sapphirecity_baseboard(sch_1):\DDR4_CHN_K_ECC\" )
				( netClassRef "@sapphirecity_baseboard_lib.sapphirecity_baseboard(sch_1):\DDR4_CHN_K_ECC\" )
			)
			( classClass "@crescent_city_bb_fab1_lib.crescent_city_bb_fab1(sch_1):\CC407\"
				( spacingCSetRef "@sapphirecity_baseboard_lib.sapphirecity_baseboard(sch_1):\DQ_TO_DQ\" )
				( netClassRef "@sapphirecity_baseboard_lib.sapphirecity_baseboard(sch_1):\DDR4_CHN_K_CLK\" )
				( netClassRef "@sapphirecity_baseboard_lib.sapphirecity_baseboard(sch_1):\DDR4_CHN_K_ECC\" )
			)
			( classClass "@crescent_city_bb_fab1_lib.crescent_city_bb_fab1(sch_1):\CC420\"
				( spacingCSetRef "@sapphirecity_baseboard_lib.sapphirecity_baseboard(sch_1):\DQ_TO_DQ\" )
				( netClassRef "@sapphirecity_baseboard_lib.sapphirecity_baseboard(sch_1):\DDR4_CHN_K_CMD_ADD\" )
				( netClassRef "@sapphirecity_baseboard_lib.sapphirecity_baseboard(sch_1):\DDR4_CHN_K_ECC\" )
			)
			( classClass "@crescent_city_bb_fab1_lib.crescent_city_bb_fab1(sch_1):\CC432\"
				( spacingCSetRef "@sapphirecity_baseboard_lib.sapphirecity_baseboard(sch_1):\DQ_TO_DQ\" )
				( netClassRef "@sapphirecity_baseboard_lib.sapphirecity_baseboard(sch_1):\DDR4_CHN_K_CTRL\" )
				( netClassRef "@sapphirecity_baseboard_lib.sapphirecity_baseboard(sch_1):\DDR4_CHN_K_ECC\" )
			)
			( classClass "@crescent_city_bb_fab1_lib.crescent_city_bb_fab1(sch_1):\CC819\"
				( spacingCSetRef "@sapphirecity_baseboard_lib.sapphirecity_baseboard(sch_1):\DQ_TO_DQ\" )
				( netClassRef "@sapphirecity_baseboard_lib.sapphirecity_baseboard(sch_1):\DDR4_CHN_K_DQ_DQS_BYTE0\" )
				( netClassRef "@sapphirecity_baseboard_lib.sapphirecity_baseboard(sch_1):\DDR4_CHN_K_ECC\" )
			)
			( classClass "@crescent_city_bb_fab1_lib.crescent_city_bb_fab1(sch_1):\CC826\"
				( spacingCSetRef "@sapphirecity_baseboard_lib.sapphirecity_baseboard(sch_1):\DQ_TO_DQ\" )
				( netClassRef "@sapphirecity_baseboard_lib.sapphirecity_baseboard(sch_1):\DDR4_CHN_K_DQ_DQS_BYTE1\" )
				( netClassRef "@sapphirecity_baseboard_lib.sapphirecity_baseboard(sch_1):\DDR4_CHN_K_ECC\" )
			)
			( classClass "@crescent_city_bb_fab1_lib.crescent_city_bb_fab1(sch_1):\CC832\"
				( spacingCSetRef "@sapphirecity_baseboard_lib.sapphirecity_baseboard(sch_1):\DQ_TO_DQ\" )
				( netClassRef "@sapphirecity_baseboard_lib.sapphirecity_baseboard(sch_1):\DDR4_CHN_K_DQ_DQS_BYTE2\" )
				( netClassRef "@sapphirecity_baseboard_lib.sapphirecity_baseboard(sch_1):\DDR4_CHN_K_ECC\" )
			)
			( classClass "@crescent_city_bb_fab1_lib.crescent_city_bb_fab1(sch_1):\CC837\"
				( spacingCSetRef "@sapphirecity_baseboard_lib.sapphirecity_baseboard(sch_1):\DQ_TO_DQ\" )
				( netClassRef "@sapphirecity_baseboard_lib.sapphirecity_baseboard(sch_1):\DDR4_CHN_K_DQ_DQS_BYTE3\" )
				( netClassRef "@sapphirecity_baseboard_lib.sapphirecity_baseboard(sch_1):\DDR4_CHN_K_ECC\" )
			)
			( classClass "@crescent_city_bb_fab1_lib.crescent_city_bb_fab1(sch_1):\CC841\"
				( spacingCSetRef "@sapphirecity_baseboard_lib.sapphirecity_baseboard(sch_1):\DQ_TO_DQ\" )
				( netClassRef "@sapphirecity_baseboard_lib.sapphirecity_baseboard(sch_1):\DDR4_CHN_K_DQ_DQS_BYTE4\" )
				( netClassRef "@sapphirecity_baseboard_lib.sapphirecity_baseboard(sch_1):\DDR4_CHN_K_ECC\" )
			)
			( classClass "@crescent_city_bb_fab1_lib.crescent_city_bb_fab1(sch_1):\CC844\"
				( spacingCSetRef "@sapphirecity_baseboard_lib.sapphirecity_baseboard(sch_1):\DQ_TO_DQ\" )
				( netClassRef "@sapphirecity_baseboard_lib.sapphirecity_baseboard(sch_1):\DDR4_CHN_K_DQ_DQS_BYTE5\" )
				( netClassRef "@sapphirecity_baseboard_lib.sapphirecity_baseboard(sch_1):\DDR4_CHN_K_ECC\" )
			)
			( classClass "@crescent_city_bb_fab1_lib.crescent_city_bb_fab1(sch_1):\CC846\"
				( spacingCSetRef "@sapphirecity_baseboard_lib.sapphirecity_baseboard(sch_1):\DQ_TO_DQ\" )
				( netClassRef "@sapphirecity_baseboard_lib.sapphirecity_baseboard(sch_1):\DDR4_CHN_K_DQ_DQS_BYTE6\" )
				( netClassRef "@sapphirecity_baseboard_lib.sapphirecity_baseboard(sch_1):\DDR4_CHN_K_ECC\" )
			)
			( classClass "@crescent_city_bb_fab1_lib.crescent_city_bb_fab1(sch_1):\CC847\"
				( spacingCSetRef "@sapphirecity_baseboard_lib.sapphirecity_baseboard(sch_1):\DQ_TO_DQ\" )
				( netClassRef "@sapphirecity_baseboard_lib.sapphirecity_baseboard(sch_1):\DDR4_CHN_K_DQ_DQS_BYTE7\" )
				( netClassRef "@sapphirecity_baseboard_lib.sapphirecity_baseboard(sch_1):\DDR4_CHN_K_ECC\" )
			)
			( classClass "@sapphirecity_baseboard_lib.sapphirecity_baseboard(sch_1):\CC1021\"
				( spacingCSetRef "@sapphirecity_baseboard_lib.sapphirecity_baseboard(sch_1):\DDR4_2SPC_DQ/DQS\" )
				( netClassRef "@sapphirecity_baseboard_lib.sapphirecity_baseboard(sch_1):\DDR4_CHN_L_ECC\" )
				( netClassRef "@sapphirecity_baseboard_lib.sapphirecity_baseboard(sch_1):\DDR4_CHN_L_ECC\" )
			)
			( classClass "@crescent_city_bb_fab1_lib.crescent_city_bb_fab1(sch_1):\CC446\"
				( spacingCSetRef "@sapphirecity_baseboard_lib.sapphirecity_baseboard(sch_1):\DQ_TO_DQ\" )
				( netClassRef "@sapphirecity_baseboard_lib.sapphirecity_baseboard(sch_1):\DDR4_CHN_L_CLK\" )
				( netClassRef "@sapphirecity_baseboard_lib.sapphirecity_baseboard(sch_1):\DDR4_CHN_L_ECC\" )
			)
			( classClass "@crescent_city_bb_fab1_lib.crescent_city_bb_fab1(sch_1):\CC459\"
				( spacingCSetRef "@sapphirecity_baseboard_lib.sapphirecity_baseboard(sch_1):\DQ_TO_DQ\" )
				( netClassRef "@sapphirecity_baseboard_lib.sapphirecity_baseboard(sch_1):\DDR4_CHN_L_CMD_ADD\" )
				( netClassRef "@sapphirecity_baseboard_lib.sapphirecity_baseboard(sch_1):\DDR4_CHN_L_ECC\" )
			)
			( classClass "@crescent_city_bb_fab1_lib.crescent_city_bb_fab1(sch_1):\CC471\"
				( spacingCSetRef "@sapphirecity_baseboard_lib.sapphirecity_baseboard(sch_1):\DQ_TO_DQ\" )
				( netClassRef "@sapphirecity_baseboard_lib.sapphirecity_baseboard(sch_1):\DDR4_CHN_L_CTRL\" )
				( netClassRef "@sapphirecity_baseboard_lib.sapphirecity_baseboard(sch_1):\DDR4_CHN_L_ECC\" )
			)
			( classClass "@crescent_city_bb_fab1_lib.crescent_city_bb_fab1(sch_1):\CC855\"
				( spacingCSetRef "@sapphirecity_baseboard_lib.sapphirecity_baseboard(sch_1):\DQ_TO_DQ\" )
				( netClassRef "@sapphirecity_baseboard_lib.sapphirecity_baseboard(sch_1):\DDR4_CHN_L_DQ_DQS_BYTE0\" )
				( netClassRef "@sapphirecity_baseboard_lib.sapphirecity_baseboard(sch_1):\DDR4_CHN_L_ECC\" )
			)
			( classClass "@crescent_city_bb_fab1_lib.crescent_city_bb_fab1(sch_1):\CC862\"
				( spacingCSetRef "@sapphirecity_baseboard_lib.sapphirecity_baseboard(sch_1):\DQ_TO_DQ\" )
				( netClassRef "@sapphirecity_baseboard_lib.sapphirecity_baseboard(sch_1):\DDR4_CHN_L_DQ_DQS_BYTE1\" )
				( netClassRef "@sapphirecity_baseboard_lib.sapphirecity_baseboard(sch_1):\DDR4_CHN_L_ECC\" )
			)
			( classClass "@crescent_city_bb_fab1_lib.crescent_city_bb_fab1(sch_1):\CC868\"
				( spacingCSetRef "@sapphirecity_baseboard_lib.sapphirecity_baseboard(sch_1):\DQ_TO_DQ\" )
				( netClassRef "@sapphirecity_baseboard_lib.sapphirecity_baseboard(sch_1):\DDR4_CHN_L_DQ_DQS_BYTE2\" )
				( netClassRef "@sapphirecity_baseboard_lib.sapphirecity_baseboard(sch_1):\DDR4_CHN_L_ECC\" )
			)
			( classClass "@crescent_city_bb_fab1_lib.crescent_city_bb_fab1(sch_1):\CC873\"
				( spacingCSetRef "@sapphirecity_baseboard_lib.sapphirecity_baseboard(sch_1):\DQ_TO_DQ\" )
				( netClassRef "@sapphirecity_baseboard_lib.sapphirecity_baseboard(sch_1):\DDR4_CHN_L_DQ_DQS_BYTE3\" )
				( netClassRef "@sapphirecity_baseboard_lib.sapphirecity_baseboard(sch_1):\DDR4_CHN_L_ECC\" )
			)
			( classClass "@crescent_city_bb_fab1_lib.crescent_city_bb_fab1(sch_1):\CC877\"
				( spacingCSetRef "@sapphirecity_baseboard_lib.sapphirecity_baseboard(sch_1):\DQ_TO_DQ\" )
				( netClassRef "@sapphirecity_baseboard_lib.sapphirecity_baseboard(sch_1):\DDR4_CHN_L_DQ_DQS_BYTE4\" )
				( netClassRef "@sapphirecity_baseboard_lib.sapphirecity_baseboard(sch_1):\DDR4_CHN_L_ECC\" )
			)
			( classClass "@crescent_city_bb_fab1_lib.crescent_city_bb_fab1(sch_1):\CC880\"
				( spacingCSetRef "@sapphirecity_baseboard_lib.sapphirecity_baseboard(sch_1):\DQ_TO_DQ\" )
				( netClassRef "@sapphirecity_baseboard_lib.sapphirecity_baseboard(sch_1):\DDR4_CHN_L_DQ_DQS_BYTE5\" )
				( netClassRef "@sapphirecity_baseboard_lib.sapphirecity_baseboard(sch_1):\DDR4_CHN_L_ECC\" )
			)
			( classClass "@crescent_city_bb_fab1_lib.crescent_city_bb_fab1(sch_1):\CC882\"
				( spacingCSetRef "@sapphirecity_baseboard_lib.sapphirecity_baseboard(sch_1):\DQ_TO_DQ\" )
				( netClassRef "@sapphirecity_baseboard_lib.sapphirecity_baseboard(sch_1):\DDR4_CHN_L_DQ_DQS_BYTE6\" )
				( netClassRef "@sapphirecity_baseboard_lib.sapphirecity_baseboard(sch_1):\DDR4_CHN_L_ECC\" )
			)
			( classClass "@crescent_city_bb_fab1_lib.crescent_city_bb_fab1(sch_1):\CC883\"
				( spacingCSetRef "@sapphirecity_baseboard_lib.sapphirecity_baseboard(sch_1):\DQ_TO_DQ\" )
				( netClassRef "@sapphirecity_baseboard_lib.sapphirecity_baseboard(sch_1):\DDR4_CHN_L_DQ_DQS_BYTE7\" )
				( netClassRef "@sapphirecity_baseboard_lib.sapphirecity_baseboard(sch_1):\DDR4_CHN_L_ECC\" )
			)
			( classClass "@sapphirecity_baseboard_lib.sapphirecity_baseboard(sch_1):\CC1012\"
				( spacingCSetRef "@sapphirecity_baseboard_lib.sapphirecity_baseboard(sch_1):\DDR4_2SPC_DQ/DQS\" )
				( netClassRef "@sapphirecity_baseboard_lib.sapphirecity_baseboard(sch_1):\DDR4_CHN_M_ECC\" )
				( netClassRef "@sapphirecity_baseboard_lib.sapphirecity_baseboard(sch_1):\DDR4_CHN_M_ECC\" )
			)
			( classClass "@crescent_city_bb_fab1_lib.crescent_city_bb_fab1(sch_1):\CC485\"
				( spacingCSetRef "@sapphirecity_baseboard_lib.sapphirecity_baseboard(sch_1):\DQ_TO_DQ\" )
				( netClassRef "@sapphirecity_baseboard_lib.sapphirecity_baseboard(sch_1):\DDR4_CHN_M_CLK\" )
				( netClassRef "@sapphirecity_baseboard_lib.sapphirecity_baseboard(sch_1):\DDR4_CHN_M_ECC\" )
			)
			( classClass "@crescent_city_bb_fab1_lib.crescent_city_bb_fab1(sch_1):\CC498\"
				( spacingCSetRef "@sapphirecity_baseboard_lib.sapphirecity_baseboard(sch_1):\DQ_TO_DQ\" )
				( netClassRef "@sapphirecity_baseboard_lib.sapphirecity_baseboard(sch_1):\DDR4_CHN_M_CMD_ADD\" )
				( netClassRef "@sapphirecity_baseboard_lib.sapphirecity_baseboard(sch_1):\DDR4_CHN_M_ECC\" )
			)
			( classClass "@crescent_city_bb_fab1_lib.crescent_city_bb_fab1(sch_1):\CC510\"
				( spacingCSetRef "@sapphirecity_baseboard_lib.sapphirecity_baseboard(sch_1):\DQ_TO_DQ\" )
				( netClassRef "@sapphirecity_baseboard_lib.sapphirecity_baseboard(sch_1):\DDR4_CHN_M_CTRL\" )
				( netClassRef "@sapphirecity_baseboard_lib.sapphirecity_baseboard(sch_1):\DDR4_CHN_M_ECC\" )
			)
			( classClass "@crescent_city_bb_fab1_lib.crescent_city_bb_fab1(sch_1):\CC891\"
				( spacingCSetRef "@sapphirecity_baseboard_lib.sapphirecity_baseboard(sch_1):\DQ_TO_DQ\" )
				( netClassRef "@sapphirecity_baseboard_lib.sapphirecity_baseboard(sch_1):\DDR4_CHN_M_DQ_DQS_BYTE0\" )
				( netClassRef "@sapphirecity_baseboard_lib.sapphirecity_baseboard(sch_1):\DDR4_CHN_M_ECC\" )
			)
			( classClass "@crescent_city_bb_fab1_lib.crescent_city_bb_fab1(sch_1):\CC898\"
				( spacingCSetRef "@sapphirecity_baseboard_lib.sapphirecity_baseboard(sch_1):\DQ_TO_DQ\" )
				( netClassRef "@sapphirecity_baseboard_lib.sapphirecity_baseboard(sch_1):\DDR4_CHN_M_DQ_DQS_BYTE1\" )
				( netClassRef "@sapphirecity_baseboard_lib.sapphirecity_baseboard(sch_1):\DDR4_CHN_M_ECC\" )
			)
			( classClass "@crescent_city_bb_fab1_lib.crescent_city_bb_fab1(sch_1):\CC904\"
				( spacingCSetRef "@sapphirecity_baseboard_lib.sapphirecity_baseboard(sch_1):\DQ_TO_DQ\" )
				( netClassRef "@sapphirecity_baseboard_lib.sapphirecity_baseboard(sch_1):\DDR4_CHN_M_DQ_DQS_BYTE2\" )
				( netClassRef "@sapphirecity_baseboard_lib.sapphirecity_baseboard(sch_1):\DDR4_CHN_M_ECC\" )
			)
			( classClass "@crescent_city_bb_fab1_lib.crescent_city_bb_fab1(sch_1):\CC909\"
				( spacingCSetRef "@sapphirecity_baseboard_lib.sapphirecity_baseboard(sch_1):\DQ_TO_DQ\" )
				( netClassRef "@sapphirecity_baseboard_lib.sapphirecity_baseboard(sch_1):\DDR4_CHN_M_DQ_DQS_BYTE3\" )
				( netClassRef "@sapphirecity_baseboard_lib.sapphirecity_baseboard(sch_1):\DDR4_CHN_M_ECC\" )
			)
			( classClass "@crescent_city_bb_fab1_lib.crescent_city_bb_fab1(sch_1):\CC913\"
				( spacingCSetRef "@sapphirecity_baseboard_lib.sapphirecity_baseboard(sch_1):\DQ_TO_DQ\" )
				( netClassRef "@sapphirecity_baseboard_lib.sapphirecity_baseboard(sch_1):\DDR4_CHN_M_DQ_DQS_BYTE4\" )
				( netClassRef "@sapphirecity_baseboard_lib.sapphirecity_baseboard(sch_1):\DDR4_CHN_M_ECC\" )
			)
			( classClass "@crescent_city_bb_fab1_lib.crescent_city_bb_fab1(sch_1):\CC916\"
				( spacingCSetRef "@sapphirecity_baseboard_lib.sapphirecity_baseboard(sch_1):\DQ_TO_DQ\" )
				( netClassRef "@sapphirecity_baseboard_lib.sapphirecity_baseboard(sch_1):\DDR4_CHN_M_DQ_DQS_BYTE5\" )
				( netClassRef "@sapphirecity_baseboard_lib.sapphirecity_baseboard(sch_1):\DDR4_CHN_M_ECC\" )
			)
			( classClass "@crescent_city_bb_fab1_lib.crescent_city_bb_fab1(sch_1):\CC918\"
				( spacingCSetRef "@sapphirecity_baseboard_lib.sapphirecity_baseboard(sch_1):\DQ_TO_DQ\" )
				( netClassRef "@sapphirecity_baseboard_lib.sapphirecity_baseboard(sch_1):\DDR4_CHN_M_DQ_DQS_BYTE6\" )
				( netClassRef "@sapphirecity_baseboard_lib.sapphirecity_baseboard(sch_1):\DDR4_CHN_M_ECC\" )
			)
			( classClass "@crescent_city_bb_fab1_lib.crescent_city_bb_fab1(sch_1):\CC919\"
				( spacingCSetRef "@sapphirecity_baseboard_lib.sapphirecity_baseboard(sch_1):\DQ_TO_DQ\" )
				( netClassRef "@sapphirecity_baseboard_lib.sapphirecity_baseboard(sch_1):\DDR4_CHN_M_DQ_DQS_BYTE7\" )
				( netClassRef "@sapphirecity_baseboard_lib.sapphirecity_baseboard(sch_1):\DDR4_CHN_M_ECC\" )
			)
			( classClass "@sapphirecity_baseboard_lib.sapphirecity_baseboard(sch_1):\CC1011\"
				( spacingCSetRef "@sapphirecity_baseboard_lib.sapphirecity_baseboard(sch_1):\DDR4_2SPC_DQ/DQS\" )
				( netClassRef "@sapphirecity_baseboard_lib.sapphirecity_baseboard(sch_1):\DDR4_CHN_M_DQ_DQS_BYTE7\" )
				( netClassRef "@sapphirecity_baseboard_lib.sapphirecity_baseboard(sch_1):\DDR4_CHN_M_DQ_DQS_BYTE7\" )
			)
			( classClass "@crescent_city_bb_fab1_lib.crescent_city_bb_fab1(sch_1):\CC484\"
				( spacingCSetRef "@sapphirecity_baseboard_lib.sapphirecity_baseboard(sch_1):\DQ_TO_DQ\" )
				( netClassRef "@sapphirecity_baseboard_lib.sapphirecity_baseboard(sch_1):\DDR4_CHN_M_CLK\" )
				( netClassRef "@sapphirecity_baseboard_lib.sapphirecity_baseboard(sch_1):\DDR4_CHN_M_DQ_DQS_BYTE7\" )
			)
			( classClass "@crescent_city_bb_fab1_lib.crescent_city_bb_fab1(sch_1):\CC497\"
				( spacingCSetRef "@sapphirecity_baseboard_lib.sapphirecity_baseboard(sch_1):\DQ_TO_DQ\" )
				( netClassRef "@sapphirecity_baseboard_lib.sapphirecity_baseboard(sch_1):\DDR4_CHN_M_CMD_ADD\" )
				( netClassRef "@sapphirecity_baseboard_lib.sapphirecity_baseboard(sch_1):\DDR4_CHN_M_DQ_DQS_BYTE7\" )
			)
			( classClass "@crescent_city_bb_fab1_lib.crescent_city_bb_fab1(sch_1):\CC509\"
				( spacingCSetRef "@sapphirecity_baseboard_lib.sapphirecity_baseboard(sch_1):\DQ_TO_DQ\" )
				( netClassRef "@sapphirecity_baseboard_lib.sapphirecity_baseboard(sch_1):\DDR4_CHN_M_CTRL\" )
				( netClassRef "@sapphirecity_baseboard_lib.sapphirecity_baseboard(sch_1):\DDR4_CHN_M_DQ_DQS_BYTE7\" )
			)
			( classClass "@crescent_city_bb_fab1_lib.crescent_city_bb_fab1(sch_1):\CC890\"
				( spacingCSetRef "@sapphirecity_baseboard_lib.sapphirecity_baseboard(sch_1):\DQ_TO_DQ\" )
				( netClassRef "@sapphirecity_baseboard_lib.sapphirecity_baseboard(sch_1):\DDR4_CHN_M_DQ_DQS_BYTE0\" )
				( netClassRef "@sapphirecity_baseboard_lib.sapphirecity_baseboard(sch_1):\DDR4_CHN_M_DQ_DQS_BYTE7\" )
			)
			( classClass "@crescent_city_bb_fab1_lib.crescent_city_bb_fab1(sch_1):\CC897\"
				( spacingCSetRef "@sapphirecity_baseboard_lib.sapphirecity_baseboard(sch_1):\DQ_TO_DQ\" )
				( netClassRef "@sapphirecity_baseboard_lib.sapphirecity_baseboard(sch_1):\DDR4_CHN_M_DQ_DQS_BYTE1\" )
				( netClassRef "@sapphirecity_baseboard_lib.sapphirecity_baseboard(sch_1):\DDR4_CHN_M_DQ_DQS_BYTE7\" )
			)
			( classClass "@crescent_city_bb_fab1_lib.crescent_city_bb_fab1(sch_1):\CC903\"
				( spacingCSetRef "@sapphirecity_baseboard_lib.sapphirecity_baseboard(sch_1):\DQ_TO_DQ\" )
				( netClassRef "@sapphirecity_baseboard_lib.sapphirecity_baseboard(sch_1):\DDR4_CHN_M_DQ_DQS_BYTE2\" )
				( netClassRef "@sapphirecity_baseboard_lib.sapphirecity_baseboard(sch_1):\DDR4_CHN_M_DQ_DQS_BYTE7\" )
			)
			( classClass "@crescent_city_bb_fab1_lib.crescent_city_bb_fab1(sch_1):\CC908\"
				( spacingCSetRef "@sapphirecity_baseboard_lib.sapphirecity_baseboard(sch_1):\DQ_TO_DQ\" )
				( netClassRef "@sapphirecity_baseboard_lib.sapphirecity_baseboard(sch_1):\DDR4_CHN_M_DQ_DQS_BYTE3\" )
				( netClassRef "@sapphirecity_baseboard_lib.sapphirecity_baseboard(sch_1):\DDR4_CHN_M_DQ_DQS_BYTE7\" )
			)
			( classClass "@crescent_city_bb_fab1_lib.crescent_city_bb_fab1(sch_1):\CC912\"
				( spacingCSetRef "@sapphirecity_baseboard_lib.sapphirecity_baseboard(sch_1):\DQ_TO_DQ\" )
				( netClassRef "@sapphirecity_baseboard_lib.sapphirecity_baseboard(sch_1):\DDR4_CHN_M_DQ_DQS_BYTE4\" )
				( netClassRef "@sapphirecity_baseboard_lib.sapphirecity_baseboard(sch_1):\DDR4_CHN_M_DQ_DQS_BYTE7\" )
			)
			( classClass "@crescent_city_bb_fab1_lib.crescent_city_bb_fab1(sch_1):\CC915\"
				( spacingCSetRef "@sapphirecity_baseboard_lib.sapphirecity_baseboard(sch_1):\DQ_TO_DQ\" )
				( netClassRef "@sapphirecity_baseboard_lib.sapphirecity_baseboard(sch_1):\DDR4_CHN_M_DQ_DQS_BYTE5\" )
				( netClassRef "@sapphirecity_baseboard_lib.sapphirecity_baseboard(sch_1):\DDR4_CHN_M_DQ_DQS_BYTE7\" )
			)
			( classClass "@crescent_city_bb_fab1_lib.crescent_city_bb_fab1(sch_1):\CC917\"
				( spacingCSetRef "@sapphirecity_baseboard_lib.sapphirecity_baseboard(sch_1):\DQ_TO_DQ\" )
				( netClassRef "@sapphirecity_baseboard_lib.sapphirecity_baseboard(sch_1):\DDR4_CHN_M_DQ_DQS_BYTE6\" )
				( netClassRef "@sapphirecity_baseboard_lib.sapphirecity_baseboard(sch_1):\DDR4_CHN_M_DQ_DQS_BYTE7\" )
			)
			( classClass "@sapphirecity_baseboard_lib.sapphirecity_baseboard(sch_1):\CC1010\"
				( spacingCSetRef "@sapphirecity_baseboard_lib.sapphirecity_baseboard(sch_1):\DDR4_2SPC_DQ/DQS\" )
				( netClassRef "@sapphirecity_baseboard_lib.sapphirecity_baseboard(sch_1):\DDR4_CHN_M_DQ_DQS_BYTE6\" )
				( netClassRef "@sapphirecity_baseboard_lib.sapphirecity_baseboard(sch_1):\DDR4_CHN_M_DQ_DQS_BYTE6\" )
			)
			( classClass "@crescent_city_bb_fab1_lib.crescent_city_bb_fab1(sch_1):\CC483\"
				( spacingCSetRef "@sapphirecity_baseboard_lib.sapphirecity_baseboard(sch_1):\DQ_TO_DQ\" )
				( netClassRef "@sapphirecity_baseboard_lib.sapphirecity_baseboard(sch_1):\DDR4_CHN_M_CLK\" )
				( netClassRef "@sapphirecity_baseboard_lib.sapphirecity_baseboard(sch_1):\DDR4_CHN_M_DQ_DQS_BYTE6\" )
			)
			( classClass "@crescent_city_bb_fab1_lib.crescent_city_bb_fab1(sch_1):\CC496\"
				( spacingCSetRef "@sapphirecity_baseboard_lib.sapphirecity_baseboard(sch_1):\DQ_TO_DQ\" )
				( netClassRef "@sapphirecity_baseboard_lib.sapphirecity_baseboard(sch_1):\DDR4_CHN_M_CMD_ADD\" )
				( netClassRef "@sapphirecity_baseboard_lib.sapphirecity_baseboard(sch_1):\DDR4_CHN_M_DQ_DQS_BYTE6\" )
			)
			( classClass "@crescent_city_bb_fab1_lib.crescent_city_bb_fab1(sch_1):\CC508\"
				( spacingCSetRef "@sapphirecity_baseboard_lib.sapphirecity_baseboard(sch_1):\DQ_TO_DQ\" )
				( netClassRef "@sapphirecity_baseboard_lib.sapphirecity_baseboard(sch_1):\DDR4_CHN_M_CTRL\" )
				( netClassRef "@sapphirecity_baseboard_lib.sapphirecity_baseboard(sch_1):\DDR4_CHN_M_DQ_DQS_BYTE6\" )
			)
			( classClass "@crescent_city_bb_fab1_lib.crescent_city_bb_fab1(sch_1):\CC889\"
				( spacingCSetRef "@sapphirecity_baseboard_lib.sapphirecity_baseboard(sch_1):\DQ_TO_DQ\" )
				( netClassRef "@sapphirecity_baseboard_lib.sapphirecity_baseboard(sch_1):\DDR4_CHN_M_DQ_DQS_BYTE0\" )
				( netClassRef "@sapphirecity_baseboard_lib.sapphirecity_baseboard(sch_1):\DDR4_CHN_M_DQ_DQS_BYTE6\" )
			)
			( classClass "@crescent_city_bb_fab1_lib.crescent_city_bb_fab1(sch_1):\CC896\"
				( spacingCSetRef "@sapphirecity_baseboard_lib.sapphirecity_baseboard(sch_1):\DQ_TO_DQ\" )
				( netClassRef "@sapphirecity_baseboard_lib.sapphirecity_baseboard(sch_1):\DDR4_CHN_M_DQ_DQS_BYTE1\" )
				( netClassRef "@sapphirecity_baseboard_lib.sapphirecity_baseboard(sch_1):\DDR4_CHN_M_DQ_DQS_BYTE6\" )
			)
			( classClass "@crescent_city_bb_fab1_lib.crescent_city_bb_fab1(sch_1):\CC902\"
				( spacingCSetRef "@sapphirecity_baseboard_lib.sapphirecity_baseboard(sch_1):\DQ_TO_DQ\" )
				( netClassRef "@sapphirecity_baseboard_lib.sapphirecity_baseboard(sch_1):\DDR4_CHN_M_DQ_DQS_BYTE2\" )
				( netClassRef "@sapphirecity_baseboard_lib.sapphirecity_baseboard(sch_1):\DDR4_CHN_M_DQ_DQS_BYTE6\" )
			)
			( classClass "@crescent_city_bb_fab1_lib.crescent_city_bb_fab1(sch_1):\CC907\"
				( spacingCSetRef "@sapphirecity_baseboard_lib.sapphirecity_baseboard(sch_1):\DQ_TO_DQ\" )
				( netClassRef "@sapphirecity_baseboard_lib.sapphirecity_baseboard(sch_1):\DDR4_CHN_M_DQ_DQS_BYTE3\" )
				( netClassRef "@sapphirecity_baseboard_lib.sapphirecity_baseboard(sch_1):\DDR4_CHN_M_DQ_DQS_BYTE6\" )
			)
			( classClass "@crescent_city_bb_fab1_lib.crescent_city_bb_fab1(sch_1):\CC911\"
				( spacingCSetRef "@sapphirecity_baseboard_lib.sapphirecity_baseboard(sch_1):\DQ_TO_DQ\" )
				( netClassRef "@sapphirecity_baseboard_lib.sapphirecity_baseboard(sch_1):\DDR4_CHN_M_DQ_DQS_BYTE4\" )
				( netClassRef "@sapphirecity_baseboard_lib.sapphirecity_baseboard(sch_1):\DDR4_CHN_M_DQ_DQS_BYTE6\" )
			)
			( classClass "@crescent_city_bb_fab1_lib.crescent_city_bb_fab1(sch_1):\CC914\"
				( spacingCSetRef "@sapphirecity_baseboard_lib.sapphirecity_baseboard(sch_1):\DQ_TO_DQ\" )
				( netClassRef "@sapphirecity_baseboard_lib.sapphirecity_baseboard(sch_1):\DDR4_CHN_M_DQ_DQS_BYTE5\" )
				( netClassRef "@sapphirecity_baseboard_lib.sapphirecity_baseboard(sch_1):\DDR4_CHN_M_DQ_DQS_BYTE6\" )
			)
			( classClass "@sapphirecity_baseboard_lib.sapphirecity_baseboard(sch_1):\CC1009\"
				( spacingCSetRef "@sapphirecity_baseboard_lib.sapphirecity_baseboard(sch_1):\DDR4_2SPC_DQ/DQS\" )
				( netClassRef "@sapphirecity_baseboard_lib.sapphirecity_baseboard(sch_1):\DDR4_CHN_M_DQ_DQS_BYTE5\" )
				( netClassRef "@sapphirecity_baseboard_lib.sapphirecity_baseboard(sch_1):\DDR4_CHN_M_DQ_DQS_BYTE5\" )
			)
			( classClass "@crescent_city_bb_fab1_lib.crescent_city_bb_fab1(sch_1):\CC482\"
				( spacingCSetRef "@sapphirecity_baseboard_lib.sapphirecity_baseboard(sch_1):\DQ_TO_DQ\" )
				( netClassRef "@sapphirecity_baseboard_lib.sapphirecity_baseboard(sch_1):\DDR4_CHN_M_CLK\" )
				( netClassRef "@sapphirecity_baseboard_lib.sapphirecity_baseboard(sch_1):\DDR4_CHN_M_DQ_DQS_BYTE5\" )
			)
			( classClass "@crescent_city_bb_fab1_lib.crescent_city_bb_fab1(sch_1):\CC495\"
				( spacingCSetRef "@sapphirecity_baseboard_lib.sapphirecity_baseboard(sch_1):\DQ_TO_DQ\" )
				( netClassRef "@sapphirecity_baseboard_lib.sapphirecity_baseboard(sch_1):\DDR4_CHN_M_CMD_ADD\" )
				( netClassRef "@sapphirecity_baseboard_lib.sapphirecity_baseboard(sch_1):\DDR4_CHN_M_DQ_DQS_BYTE5\" )
			)
			( classClass "@crescent_city_bb_fab1_lib.crescent_city_bb_fab1(sch_1):\CC507\"
				( spacingCSetRef "@sapphirecity_baseboard_lib.sapphirecity_baseboard(sch_1):\DQ_TO_DQ\" )
				( netClassRef "@sapphirecity_baseboard_lib.sapphirecity_baseboard(sch_1):\DDR4_CHN_M_CTRL\" )
				( netClassRef "@sapphirecity_baseboard_lib.sapphirecity_baseboard(sch_1):\DDR4_CHN_M_DQ_DQS_BYTE5\" )
			)
			( classClass "@crescent_city_bb_fab1_lib.crescent_city_bb_fab1(sch_1):\CC888\"
				( spacingCSetRef "@sapphirecity_baseboard_lib.sapphirecity_baseboard(sch_1):\DQ_TO_DQ\" )
				( netClassRef "@sapphirecity_baseboard_lib.sapphirecity_baseboard(sch_1):\DDR4_CHN_M_DQ_DQS_BYTE0\" )
				( netClassRef "@sapphirecity_baseboard_lib.sapphirecity_baseboard(sch_1):\DDR4_CHN_M_DQ_DQS_BYTE5\" )
			)
			( classClass "@crescent_city_bb_fab1_lib.crescent_city_bb_fab1(sch_1):\CC895\"
				( spacingCSetRef "@sapphirecity_baseboard_lib.sapphirecity_baseboard(sch_1):\DQ_TO_DQ\" )
				( netClassRef "@sapphirecity_baseboard_lib.sapphirecity_baseboard(sch_1):\DDR4_CHN_M_DQ_DQS_BYTE1\" )
				( netClassRef "@sapphirecity_baseboard_lib.sapphirecity_baseboard(sch_1):\DDR4_CHN_M_DQ_DQS_BYTE5\" )
			)
			( classClass "@crescent_city_bb_fab1_lib.crescent_city_bb_fab1(sch_1):\CC901\"
				( spacingCSetRef "@sapphirecity_baseboard_lib.sapphirecity_baseboard(sch_1):\DQ_TO_DQ\" )
				( netClassRef "@sapphirecity_baseboard_lib.sapphirecity_baseboard(sch_1):\DDR4_CHN_M_DQ_DQS_BYTE2\" )
				( netClassRef "@sapphirecity_baseboard_lib.sapphirecity_baseboard(sch_1):\DDR4_CHN_M_DQ_DQS_BYTE5\" )
			)
			( classClass "@crescent_city_bb_fab1_lib.crescent_city_bb_fab1(sch_1):\CC906\"
				( spacingCSetRef "@sapphirecity_baseboard_lib.sapphirecity_baseboard(sch_1):\DQ_TO_DQ\" )
				( netClassRef "@sapphirecity_baseboard_lib.sapphirecity_baseboard(sch_1):\DDR4_CHN_M_DQ_DQS_BYTE3\" )
				( netClassRef "@sapphirecity_baseboard_lib.sapphirecity_baseboard(sch_1):\DDR4_CHN_M_DQ_DQS_BYTE5\" )
			)
			( classClass "@crescent_city_bb_fab1_lib.crescent_city_bb_fab1(sch_1):\CC910\"
				( spacingCSetRef "@sapphirecity_baseboard_lib.sapphirecity_baseboard(sch_1):\DQ_TO_DQ\" )
				( netClassRef "@sapphirecity_baseboard_lib.sapphirecity_baseboard(sch_1):\DDR4_CHN_M_DQ_DQS_BYTE4\" )
				( netClassRef "@sapphirecity_baseboard_lib.sapphirecity_baseboard(sch_1):\DDR4_CHN_M_DQ_DQS_BYTE5\" )
			)
			( classClass "@sapphirecity_baseboard_lib.sapphirecity_baseboard(sch_1):\CC1008\"
				( spacingCSetRef "@sapphirecity_baseboard_lib.sapphirecity_baseboard(sch_1):\DDR4_2SPC_DQ/DQS\" )
				( netClassRef "@sapphirecity_baseboard_lib.sapphirecity_baseboard(sch_1):\DDR4_CHN_M_DQ_DQS_BYTE4\" )
				( netClassRef "@sapphirecity_baseboard_lib.sapphirecity_baseboard(sch_1):\DDR4_CHN_M_DQ_DQS_BYTE4\" )
			)
			( classClass "@crescent_city_bb_fab1_lib.crescent_city_bb_fab1(sch_1):\CC481\"
				( spacingCSetRef "@sapphirecity_baseboard_lib.sapphirecity_baseboard(sch_1):\DQ_TO_DQ\" )
				( netClassRef "@sapphirecity_baseboard_lib.sapphirecity_baseboard(sch_1):\DDR4_CHN_M_CLK\" )
				( netClassRef "@sapphirecity_baseboard_lib.sapphirecity_baseboard(sch_1):\DDR4_CHN_M_DQ_DQS_BYTE4\" )
			)
			( classClass "@crescent_city_bb_fab1_lib.crescent_city_bb_fab1(sch_1):\CC494\"
				( spacingCSetRef "@sapphirecity_baseboard_lib.sapphirecity_baseboard(sch_1):\DQ_TO_DQ\" )
				( netClassRef "@sapphirecity_baseboard_lib.sapphirecity_baseboard(sch_1):\DDR4_CHN_M_CMD_ADD\" )
				( netClassRef "@sapphirecity_baseboard_lib.sapphirecity_baseboard(sch_1):\DDR4_CHN_M_DQ_DQS_BYTE4\" )
			)
			( classClass "@crescent_city_bb_fab1_lib.crescent_city_bb_fab1(sch_1):\CC506\"
				( spacingCSetRef "@sapphirecity_baseboard_lib.sapphirecity_baseboard(sch_1):\DQ_TO_DQ\" )
				( netClassRef "@sapphirecity_baseboard_lib.sapphirecity_baseboard(sch_1):\DDR4_CHN_M_CTRL\" )
				( netClassRef "@sapphirecity_baseboard_lib.sapphirecity_baseboard(sch_1):\DDR4_CHN_M_DQ_DQS_BYTE4\" )
			)
			( classClass "@crescent_city_bb_fab1_lib.crescent_city_bb_fab1(sch_1):\CC887\"
				( spacingCSetRef "@sapphirecity_baseboard_lib.sapphirecity_baseboard(sch_1):\DQ_TO_DQ\" )
				( netClassRef "@sapphirecity_baseboard_lib.sapphirecity_baseboard(sch_1):\DDR4_CHN_M_DQ_DQS_BYTE0\" )
				( netClassRef "@sapphirecity_baseboard_lib.sapphirecity_baseboard(sch_1):\DDR4_CHN_M_DQ_DQS_BYTE4\" )
			)
			( classClass "@crescent_city_bb_fab1_lib.crescent_city_bb_fab1(sch_1):\CC894\"
				( spacingCSetRef "@sapphirecity_baseboard_lib.sapphirecity_baseboard(sch_1):\DQ_TO_DQ\" )
				( netClassRef "@sapphirecity_baseboard_lib.sapphirecity_baseboard(sch_1):\DDR4_CHN_M_DQ_DQS_BYTE1\" )
				( netClassRef "@sapphirecity_baseboard_lib.sapphirecity_baseboard(sch_1):\DDR4_CHN_M_DQ_DQS_BYTE4\" )
			)
			( classClass "@crescent_city_bb_fab1_lib.crescent_city_bb_fab1(sch_1):\CC900\"
				( spacingCSetRef "@sapphirecity_baseboard_lib.sapphirecity_baseboard(sch_1):\DQ_TO_DQ\" )
				( netClassRef "@sapphirecity_baseboard_lib.sapphirecity_baseboard(sch_1):\DDR4_CHN_M_DQ_DQS_BYTE2\" )
				( netClassRef "@sapphirecity_baseboard_lib.sapphirecity_baseboard(sch_1):\DDR4_CHN_M_DQ_DQS_BYTE4\" )
			)
			( classClass "@crescent_city_bb_fab1_lib.crescent_city_bb_fab1(sch_1):\CC905\"
				( spacingCSetRef "@sapphirecity_baseboard_lib.sapphirecity_baseboard(sch_1):\DQ_TO_DQ\" )
				( netClassRef "@sapphirecity_baseboard_lib.sapphirecity_baseboard(sch_1):\DDR4_CHN_M_DQ_DQS_BYTE3\" )
				( netClassRef "@sapphirecity_baseboard_lib.sapphirecity_baseboard(sch_1):\DDR4_CHN_M_DQ_DQS_BYTE4\" )
			)
			( classClass "@sapphirecity_baseboard_lib.sapphirecity_baseboard(sch_1):\CC1007\"
				( spacingCSetRef "@sapphirecity_baseboard_lib.sapphirecity_baseboard(sch_1):\DDR4_2SPC_DQ/DQS\" )
				( netClassRef "@sapphirecity_baseboard_lib.sapphirecity_baseboard(sch_1):\DDR4_CHN_M_DQ_DQS_BYTE3\" )
				( netClassRef "@sapphirecity_baseboard_lib.sapphirecity_baseboard(sch_1):\DDR4_CHN_M_DQ_DQS_BYTE3\" )
			)
			( classClass "@crescent_city_bb_fab1_lib.crescent_city_bb_fab1(sch_1):\CC480\"
				( spacingCSetRef "@sapphirecity_baseboard_lib.sapphirecity_baseboard(sch_1):\DQ_TO_DQ\" )
				( netClassRef "@sapphirecity_baseboard_lib.sapphirecity_baseboard(sch_1):\DDR4_CHN_M_CLK\" )
				( netClassRef "@sapphirecity_baseboard_lib.sapphirecity_baseboard(sch_1):\DDR4_CHN_M_DQ_DQS_BYTE3\" )
			)
			( classClass "@crescent_city_bb_fab1_lib.crescent_city_bb_fab1(sch_1):\CC493\"
				( spacingCSetRef "@sapphirecity_baseboard_lib.sapphirecity_baseboard(sch_1):\DQ_TO_DQ\" )
				( netClassRef "@sapphirecity_baseboard_lib.sapphirecity_baseboard(sch_1):\DDR4_CHN_M_CMD_ADD\" )
				( netClassRef "@sapphirecity_baseboard_lib.sapphirecity_baseboard(sch_1):\DDR4_CHN_M_DQ_DQS_BYTE3\" )
			)
			( classClass "@crescent_city_bb_fab1_lib.crescent_city_bb_fab1(sch_1):\CC505\"
				( spacingCSetRef "@sapphirecity_baseboard_lib.sapphirecity_baseboard(sch_1):\DQ_TO_DQ\" )
				( netClassRef "@sapphirecity_baseboard_lib.sapphirecity_baseboard(sch_1):\DDR4_CHN_M_CTRL\" )
				( netClassRef "@sapphirecity_baseboard_lib.sapphirecity_baseboard(sch_1):\DDR4_CHN_M_DQ_DQS_BYTE3\" )
			)
			( classClass "@crescent_city_bb_fab1_lib.crescent_city_bb_fab1(sch_1):\CC886\"
				( spacingCSetRef "@sapphirecity_baseboard_lib.sapphirecity_baseboard(sch_1):\DQ_TO_DQ\" )
				( netClassRef "@sapphirecity_baseboard_lib.sapphirecity_baseboard(sch_1):\DDR4_CHN_M_DQ_DQS_BYTE0\" )
				( netClassRef "@sapphirecity_baseboard_lib.sapphirecity_baseboard(sch_1):\DDR4_CHN_M_DQ_DQS_BYTE3\" )
			)
			( classClass "@crescent_city_bb_fab1_lib.crescent_city_bb_fab1(sch_1):\CC893\"
				( spacingCSetRef "@sapphirecity_baseboard_lib.sapphirecity_baseboard(sch_1):\DQ_TO_DQ\" )
				( netClassRef "@sapphirecity_baseboard_lib.sapphirecity_baseboard(sch_1):\DDR4_CHN_M_DQ_DQS_BYTE1\" )
				( netClassRef "@sapphirecity_baseboard_lib.sapphirecity_baseboard(sch_1):\DDR4_CHN_M_DQ_DQS_BYTE3\" )
			)
			( classClass "@crescent_city_bb_fab1_lib.crescent_city_bb_fab1(sch_1):\CC899\"
				( spacingCSetRef "@sapphirecity_baseboard_lib.sapphirecity_baseboard(sch_1):\DQ_TO_DQ\" )
				( netClassRef "@sapphirecity_baseboard_lib.sapphirecity_baseboard(sch_1):\DDR4_CHN_M_DQ_DQS_BYTE2\" )
				( netClassRef "@sapphirecity_baseboard_lib.sapphirecity_baseboard(sch_1):\DDR4_CHN_M_DQ_DQS_BYTE3\" )
			)
			( classClass "@sapphirecity_baseboard_lib.sapphirecity_baseboard(sch_1):\CC1006\"
				( spacingCSetRef "@sapphirecity_baseboard_lib.sapphirecity_baseboard(sch_1):\DDR4_2SPC_DQ/DQS\" )
				( netClassRef "@sapphirecity_baseboard_lib.sapphirecity_baseboard(sch_1):\DDR4_CHN_M_DQ_DQS_BYTE2\" )
				( netClassRef "@sapphirecity_baseboard_lib.sapphirecity_baseboard(sch_1):\DDR4_CHN_M_DQ_DQS_BYTE2\" )
			)
			( classClass "@crescent_city_bb_fab1_lib.crescent_city_bb_fab1(sch_1):\CC479\"
				( spacingCSetRef "@sapphirecity_baseboard_lib.sapphirecity_baseboard(sch_1):\DQ_TO_DQ\" )
				( netClassRef "@sapphirecity_baseboard_lib.sapphirecity_baseboard(sch_1):\DDR4_CHN_M_CLK\" )
				( netClassRef "@sapphirecity_baseboard_lib.sapphirecity_baseboard(sch_1):\DDR4_CHN_M_DQ_DQS_BYTE2\" )
			)
			( classClass "@crescent_city_bb_fab1_lib.crescent_city_bb_fab1(sch_1):\CC492\"
				( spacingCSetRef "@sapphirecity_baseboard_lib.sapphirecity_baseboard(sch_1):\DQ_TO_DQ\" )
				( netClassRef "@sapphirecity_baseboard_lib.sapphirecity_baseboard(sch_1):\DDR4_CHN_M_CMD_ADD\" )
				( netClassRef "@sapphirecity_baseboard_lib.sapphirecity_baseboard(sch_1):\DDR4_CHN_M_DQ_DQS_BYTE2\" )
			)
			( classClass "@crescent_city_bb_fab1_lib.crescent_city_bb_fab1(sch_1):\CC504\"
				( spacingCSetRef "@sapphirecity_baseboard_lib.sapphirecity_baseboard(sch_1):\DQ_TO_DQ\" )
				( netClassRef "@sapphirecity_baseboard_lib.sapphirecity_baseboard(sch_1):\DDR4_CHN_M_CTRL\" )
				( netClassRef "@sapphirecity_baseboard_lib.sapphirecity_baseboard(sch_1):\DDR4_CHN_M_DQ_DQS_BYTE2\" )
			)
			( classClass "@crescent_city_bb_fab1_lib.crescent_city_bb_fab1(sch_1):\CC885\"
				( spacingCSetRef "@sapphirecity_baseboard_lib.sapphirecity_baseboard(sch_1):\DQ_TO_DQ\" )
				( netClassRef "@sapphirecity_baseboard_lib.sapphirecity_baseboard(sch_1):\DDR4_CHN_M_DQ_DQS_BYTE0\" )
				( netClassRef "@sapphirecity_baseboard_lib.sapphirecity_baseboard(sch_1):\DDR4_CHN_M_DQ_DQS_BYTE2\" )
			)
			( classClass "@crescent_city_bb_fab1_lib.crescent_city_bb_fab1(sch_1):\CC892\"
				( spacingCSetRef "@sapphirecity_baseboard_lib.sapphirecity_baseboard(sch_1):\DQ_TO_DQ\" )
				( netClassRef "@sapphirecity_baseboard_lib.sapphirecity_baseboard(sch_1):\DDR4_CHN_M_DQ_DQS_BYTE1\" )
				( netClassRef "@sapphirecity_baseboard_lib.sapphirecity_baseboard(sch_1):\DDR4_CHN_M_DQ_DQS_BYTE2\" )
			)
			( classClass "@sapphirecity_baseboard_lib.sapphirecity_baseboard(sch_1):\CC1005\"
				( spacingCSetRef "@sapphirecity_baseboard_lib.sapphirecity_baseboard(sch_1):\DDR4_2SPC_DQ/DQS\" )
				( netClassRef "@sapphirecity_baseboard_lib.sapphirecity_baseboard(sch_1):\DDR4_CHN_M_DQ_DQS_BYTE1\" )
				( netClassRef "@sapphirecity_baseboard_lib.sapphirecity_baseboard(sch_1):\DDR4_CHN_M_DQ_DQS_BYTE1\" )
			)
			( classClass "@crescent_city_bb_fab1_lib.crescent_city_bb_fab1(sch_1):\CC478\"
				( spacingCSetRef "@sapphirecity_baseboard_lib.sapphirecity_baseboard(sch_1):\DQ_TO_DQ\" )
				( netClassRef "@sapphirecity_baseboard_lib.sapphirecity_baseboard(sch_1):\DDR4_CHN_M_CLK\" )
				( netClassRef "@sapphirecity_baseboard_lib.sapphirecity_baseboard(sch_1):\DDR4_CHN_M_DQ_DQS_BYTE1\" )
			)
			( classClass "@crescent_city_bb_fab1_lib.crescent_city_bb_fab1(sch_1):\CC491\"
				( spacingCSetRef "@sapphirecity_baseboard_lib.sapphirecity_baseboard(sch_1):\DQ_TO_DQ\" )
				( netClassRef "@sapphirecity_baseboard_lib.sapphirecity_baseboard(sch_1):\DDR4_CHN_M_CMD_ADD\" )
				( netClassRef "@sapphirecity_baseboard_lib.sapphirecity_baseboard(sch_1):\DDR4_CHN_M_DQ_DQS_BYTE1\" )
			)
			( classClass "@crescent_city_bb_fab1_lib.crescent_city_bb_fab1(sch_1):\CC503\"
				( spacingCSetRef "@sapphirecity_baseboard_lib.sapphirecity_baseboard(sch_1):\DQ_TO_DQ\" )
				( netClassRef "@sapphirecity_baseboard_lib.sapphirecity_baseboard(sch_1):\DDR4_CHN_M_CTRL\" )
				( netClassRef "@sapphirecity_baseboard_lib.sapphirecity_baseboard(sch_1):\DDR4_CHN_M_DQ_DQS_BYTE1\" )
			)
			( classClass "@crescent_city_bb_fab1_lib.crescent_city_bb_fab1(sch_1):\CC884\"
				( spacingCSetRef "@sapphirecity_baseboard_lib.sapphirecity_baseboard(sch_1):\DQ_TO_DQ\" )
				( netClassRef "@sapphirecity_baseboard_lib.sapphirecity_baseboard(sch_1):\DDR4_CHN_M_DQ_DQS_BYTE0\" )
				( netClassRef "@sapphirecity_baseboard_lib.sapphirecity_baseboard(sch_1):\DDR4_CHN_M_DQ_DQS_BYTE1\" )
			)
			( classClass "@sapphirecity_baseboard_lib.sapphirecity_baseboard(sch_1):\CC1004\"
				( spacingCSetRef "@sapphirecity_baseboard_lib.sapphirecity_baseboard(sch_1):\DDR4_2SPC_DQ/DQS\" )
				( netClassRef "@sapphirecity_baseboard_lib.sapphirecity_baseboard(sch_1):\DDR4_CHN_M_DQ_DQS_BYTE0\" )
				( netClassRef "@sapphirecity_baseboard_lib.sapphirecity_baseboard(sch_1):\DDR4_CHN_M_DQ_DQS_BYTE0\" )
			)
			( classClass "@crescent_city_bb_fab1_lib.crescent_city_bb_fab1(sch_1):\CC477\"
				( spacingCSetRef "@sapphirecity_baseboard_lib.sapphirecity_baseboard(sch_1):\DQ_TO_DQ\" )
				( netClassRef "@sapphirecity_baseboard_lib.sapphirecity_baseboard(sch_1):\DDR4_CHN_M_CLK\" )
				( netClassRef "@sapphirecity_baseboard_lib.sapphirecity_baseboard(sch_1):\DDR4_CHN_M_DQ_DQS_BYTE0\" )
			)
			( classClass "@crescent_city_bb_fab1_lib.crescent_city_bb_fab1(sch_1):\CC490\"
				( spacingCSetRef "@sapphirecity_baseboard_lib.sapphirecity_baseboard(sch_1):\DQ_TO_DQ\" )
				( netClassRef "@sapphirecity_baseboard_lib.sapphirecity_baseboard(sch_1):\DDR4_CHN_M_CMD_ADD\" )
				( netClassRef "@sapphirecity_baseboard_lib.sapphirecity_baseboard(sch_1):\DDR4_CHN_M_DQ_DQS_BYTE0\" )
			)
			( classClass "@crescent_city_bb_fab1_lib.crescent_city_bb_fab1(sch_1):\CC502\"
				( spacingCSetRef "@sapphirecity_baseboard_lib.sapphirecity_baseboard(sch_1):\DQ_TO_DQ\" )
				( netClassRef "@sapphirecity_baseboard_lib.sapphirecity_baseboard(sch_1):\DDR4_CHN_M_CTRL\" )
				( netClassRef "@sapphirecity_baseboard_lib.sapphirecity_baseboard(sch_1):\DDR4_CHN_M_DQ_DQS_BYTE0\" )
			)
			( classClass "@sapphirecity_baseboard_lib.sapphirecity_baseboard(sch_1):\CC1020\"
				( spacingCSetRef "@sapphirecity_baseboard_lib.sapphirecity_baseboard(sch_1):\DDR4_2SPC_DQ/DQS\" )
				( netClassRef "@sapphirecity_baseboard_lib.sapphirecity_baseboard(sch_1):\DDR4_CHN_L_DQ_DQS_BYTE7\" )
				( netClassRef "@sapphirecity_baseboard_lib.sapphirecity_baseboard(sch_1):\DDR4_CHN_L_DQ_DQS_BYTE7\" )
			)
			( classClass "@crescent_city_bb_fab1_lib.crescent_city_bb_fab1(sch_1):\CC445\"
				( spacingCSetRef "@sapphirecity_baseboard_lib.sapphirecity_baseboard(sch_1):\DQ_TO_DQ\" )
				( netClassRef "@sapphirecity_baseboard_lib.sapphirecity_baseboard(sch_1):\DDR4_CHN_L_CLK\" )
				( netClassRef "@sapphirecity_baseboard_lib.sapphirecity_baseboard(sch_1):\DDR4_CHN_L_DQ_DQS_BYTE7\" )
			)
			( classClass "@crescent_city_bb_fab1_lib.crescent_city_bb_fab1(sch_1):\CC458\"
				( spacingCSetRef "@sapphirecity_baseboard_lib.sapphirecity_baseboard(sch_1):\DQ_TO_DQ\" )
				( netClassRef "@sapphirecity_baseboard_lib.sapphirecity_baseboard(sch_1):\DDR4_CHN_L_CMD_ADD\" )
				( netClassRef "@sapphirecity_baseboard_lib.sapphirecity_baseboard(sch_1):\DDR4_CHN_L_DQ_DQS_BYTE7\" )
			)
			( classClass "@crescent_city_bb_fab1_lib.crescent_city_bb_fab1(sch_1):\CC470\"
				( spacingCSetRef "@sapphirecity_baseboard_lib.sapphirecity_baseboard(sch_1):\DQ_TO_DQ\" )
				( netClassRef "@sapphirecity_baseboard_lib.sapphirecity_baseboard(sch_1):\DDR4_CHN_L_CTRL\" )
				( netClassRef "@sapphirecity_baseboard_lib.sapphirecity_baseboard(sch_1):\DDR4_CHN_L_DQ_DQS_BYTE7\" )
			)
			( classClass "@crescent_city_bb_fab1_lib.crescent_city_bb_fab1(sch_1):\CC854\"
				( spacingCSetRef "@sapphirecity_baseboard_lib.sapphirecity_baseboard(sch_1):\DQ_TO_DQ\" )
				( netClassRef "@sapphirecity_baseboard_lib.sapphirecity_baseboard(sch_1):\DDR4_CHN_L_DQ_DQS_BYTE0\" )
				( netClassRef "@sapphirecity_baseboard_lib.sapphirecity_baseboard(sch_1):\DDR4_CHN_L_DQ_DQS_BYTE7\" )
			)
			( classClass "@crescent_city_bb_fab1_lib.crescent_city_bb_fab1(sch_1):\CC861\"
				( spacingCSetRef "@sapphirecity_baseboard_lib.sapphirecity_baseboard(sch_1):\DQ_TO_DQ\" )
				( netClassRef "@sapphirecity_baseboard_lib.sapphirecity_baseboard(sch_1):\DDR4_CHN_L_DQ_DQS_BYTE1\" )
				( netClassRef "@sapphirecity_baseboard_lib.sapphirecity_baseboard(sch_1):\DDR4_CHN_L_DQ_DQS_BYTE7\" )
			)
			( classClass "@crescent_city_bb_fab1_lib.crescent_city_bb_fab1(sch_1):\CC867\"
				( spacingCSetRef "@sapphirecity_baseboard_lib.sapphirecity_baseboard(sch_1):\DQ_TO_DQ\" )
				( netClassRef "@sapphirecity_baseboard_lib.sapphirecity_baseboard(sch_1):\DDR4_CHN_L_DQ_DQS_BYTE2\" )
				( netClassRef "@sapphirecity_baseboard_lib.sapphirecity_baseboard(sch_1):\DDR4_CHN_L_DQ_DQS_BYTE7\" )
			)
			( classClass "@crescent_city_bb_fab1_lib.crescent_city_bb_fab1(sch_1):\CC872\"
				( spacingCSetRef "@sapphirecity_baseboard_lib.sapphirecity_baseboard(sch_1):\DQ_TO_DQ\" )
				( netClassRef "@sapphirecity_baseboard_lib.sapphirecity_baseboard(sch_1):\DDR4_CHN_L_DQ_DQS_BYTE3\" )
				( netClassRef "@sapphirecity_baseboard_lib.sapphirecity_baseboard(sch_1):\DDR4_CHN_L_DQ_DQS_BYTE7\" )
			)
			( classClass "@crescent_city_bb_fab1_lib.crescent_city_bb_fab1(sch_1):\CC876\"
				( spacingCSetRef "@sapphirecity_baseboard_lib.sapphirecity_baseboard(sch_1):\DQ_TO_DQ\" )
				( netClassRef "@sapphirecity_baseboard_lib.sapphirecity_baseboard(sch_1):\DDR4_CHN_L_DQ_DQS_BYTE4\" )
				( netClassRef "@sapphirecity_baseboard_lib.sapphirecity_baseboard(sch_1):\DDR4_CHN_L_DQ_DQS_BYTE7\" )
			)
			( classClass "@crescent_city_bb_fab1_lib.crescent_city_bb_fab1(sch_1):\CC879\"
				( spacingCSetRef "@sapphirecity_baseboard_lib.sapphirecity_baseboard(sch_1):\DQ_TO_DQ\" )
				( netClassRef "@sapphirecity_baseboard_lib.sapphirecity_baseboard(sch_1):\DDR4_CHN_L_DQ_DQS_BYTE5\" )
				( netClassRef "@sapphirecity_baseboard_lib.sapphirecity_baseboard(sch_1):\DDR4_CHN_L_DQ_DQS_BYTE7\" )
			)
			( classClass "@crescent_city_bb_fab1_lib.crescent_city_bb_fab1(sch_1):\CC881\"
				( spacingCSetRef "@sapphirecity_baseboard_lib.sapphirecity_baseboard(sch_1):\DQ_TO_DQ\" )
				( netClassRef "@sapphirecity_baseboard_lib.sapphirecity_baseboard(sch_1):\DDR4_CHN_L_DQ_DQS_BYTE6\" )
				( netClassRef "@sapphirecity_baseboard_lib.sapphirecity_baseboard(sch_1):\DDR4_CHN_L_DQ_DQS_BYTE7\" )
			)
			( classClass "@sapphirecity_baseboard_lib.sapphirecity_baseboard(sch_1):\CC1019\"
				( spacingCSetRef "@sapphirecity_baseboard_lib.sapphirecity_baseboard(sch_1):\DDR4_2SPC_DQ/DQS\" )
				( netClassRef "@sapphirecity_baseboard_lib.sapphirecity_baseboard(sch_1):\DDR4_CHN_L_DQ_DQS_BYTE6\" )
				( netClassRef "@sapphirecity_baseboard_lib.sapphirecity_baseboard(sch_1):\DDR4_CHN_L_DQ_DQS_BYTE6\" )
			)
			( classClass "@crescent_city_bb_fab1_lib.crescent_city_bb_fab1(sch_1):\CC444\"
				( spacingCSetRef "@sapphirecity_baseboard_lib.sapphirecity_baseboard(sch_1):\DQ_TO_DQ\" )
				( netClassRef "@sapphirecity_baseboard_lib.sapphirecity_baseboard(sch_1):\DDR4_CHN_L_CLK\" )
				( netClassRef "@sapphirecity_baseboard_lib.sapphirecity_baseboard(sch_1):\DDR4_CHN_L_DQ_DQS_BYTE6\" )
			)
			( classClass "@crescent_city_bb_fab1_lib.crescent_city_bb_fab1(sch_1):\CC457\"
				( spacingCSetRef "@sapphirecity_baseboard_lib.sapphirecity_baseboard(sch_1):\DQ_TO_DQ\" )
				( netClassRef "@sapphirecity_baseboard_lib.sapphirecity_baseboard(sch_1):\DDR4_CHN_L_CMD_ADD\" )
				( netClassRef "@sapphirecity_baseboard_lib.sapphirecity_baseboard(sch_1):\DDR4_CHN_L_DQ_DQS_BYTE6\" )
			)
			( classClass "@crescent_city_bb_fab1_lib.crescent_city_bb_fab1(sch_1):\CC469\"
				( spacingCSetRef "@sapphirecity_baseboard_lib.sapphirecity_baseboard(sch_1):\DQ_TO_DQ\" )
				( netClassRef "@sapphirecity_baseboard_lib.sapphirecity_baseboard(sch_1):\DDR4_CHN_L_CTRL\" )
				( netClassRef "@sapphirecity_baseboard_lib.sapphirecity_baseboard(sch_1):\DDR4_CHN_L_DQ_DQS_BYTE6\" )
			)
			( classClass "@crescent_city_bb_fab1_lib.crescent_city_bb_fab1(sch_1):\CC853\"
				( spacingCSetRef "@sapphirecity_baseboard_lib.sapphirecity_baseboard(sch_1):\DQ_TO_DQ\" )
				( netClassRef "@sapphirecity_baseboard_lib.sapphirecity_baseboard(sch_1):\DDR4_CHN_L_DQ_DQS_BYTE0\" )
				( netClassRef "@sapphirecity_baseboard_lib.sapphirecity_baseboard(sch_1):\DDR4_CHN_L_DQ_DQS_BYTE6\" )
			)
			( classClass "@crescent_city_bb_fab1_lib.crescent_city_bb_fab1(sch_1):\CC860\"
				( spacingCSetRef "@sapphirecity_baseboard_lib.sapphirecity_baseboard(sch_1):\DQ_TO_DQ\" )
				( netClassRef "@sapphirecity_baseboard_lib.sapphirecity_baseboard(sch_1):\DDR4_CHN_L_DQ_DQS_BYTE1\" )
				( netClassRef "@sapphirecity_baseboard_lib.sapphirecity_baseboard(sch_1):\DDR4_CHN_L_DQ_DQS_BYTE6\" )
			)
			( classClass "@crescent_city_bb_fab1_lib.crescent_city_bb_fab1(sch_1):\CC866\"
				( spacingCSetRef "@sapphirecity_baseboard_lib.sapphirecity_baseboard(sch_1):\DQ_TO_DQ\" )
				( netClassRef "@sapphirecity_baseboard_lib.sapphirecity_baseboard(sch_1):\DDR4_CHN_L_DQ_DQS_BYTE2\" )
				( netClassRef "@sapphirecity_baseboard_lib.sapphirecity_baseboard(sch_1):\DDR4_CHN_L_DQ_DQS_BYTE6\" )
			)
			( classClass "@crescent_city_bb_fab1_lib.crescent_city_bb_fab1(sch_1):\CC871\"
				( spacingCSetRef "@sapphirecity_baseboard_lib.sapphirecity_baseboard(sch_1):\DQ_TO_DQ\" )
				( netClassRef "@sapphirecity_baseboard_lib.sapphirecity_baseboard(sch_1):\DDR4_CHN_L_DQ_DQS_BYTE3\" )
				( netClassRef "@sapphirecity_baseboard_lib.sapphirecity_baseboard(sch_1):\DDR4_CHN_L_DQ_DQS_BYTE6\" )
			)
			( classClass "@crescent_city_bb_fab1_lib.crescent_city_bb_fab1(sch_1):\CC875\"
				( spacingCSetRef "@sapphirecity_baseboard_lib.sapphirecity_baseboard(sch_1):\DQ_TO_DQ\" )
				( netClassRef "@sapphirecity_baseboard_lib.sapphirecity_baseboard(sch_1):\DDR4_CHN_L_DQ_DQS_BYTE4\" )
				( netClassRef "@sapphirecity_baseboard_lib.sapphirecity_baseboard(sch_1):\DDR4_CHN_L_DQ_DQS_BYTE6\" )
			)
			( classClass "@crescent_city_bb_fab1_lib.crescent_city_bb_fab1(sch_1):\CC878\"
				( spacingCSetRef "@sapphirecity_baseboard_lib.sapphirecity_baseboard(sch_1):\DQ_TO_DQ\" )
				( netClassRef "@sapphirecity_baseboard_lib.sapphirecity_baseboard(sch_1):\DDR4_CHN_L_DQ_DQS_BYTE5\" )
				( netClassRef "@sapphirecity_baseboard_lib.sapphirecity_baseboard(sch_1):\DDR4_CHN_L_DQ_DQS_BYTE6\" )
			)
			( classClass "@sapphirecity_baseboard_lib.sapphirecity_baseboard(sch_1):\CC1018\"
				( spacingCSetRef "@sapphirecity_baseboard_lib.sapphirecity_baseboard(sch_1):\DDR4_2SPC_DQ/DQS\" )
				( netClassRef "@sapphirecity_baseboard_lib.sapphirecity_baseboard(sch_1):\DDR4_CHN_L_DQ_DQS_BYTE5\" )
				( netClassRef "@sapphirecity_baseboard_lib.sapphirecity_baseboard(sch_1):\DDR4_CHN_L_DQ_DQS_BYTE5\" )
			)
			( classClass "@crescent_city_bb_fab1_lib.crescent_city_bb_fab1(sch_1):\CC443\"
				( spacingCSetRef "@sapphirecity_baseboard_lib.sapphirecity_baseboard(sch_1):\DQ_TO_DQ\" )
				( netClassRef "@sapphirecity_baseboard_lib.sapphirecity_baseboard(sch_1):\DDR4_CHN_L_CLK\" )
				( netClassRef "@sapphirecity_baseboard_lib.sapphirecity_baseboard(sch_1):\DDR4_CHN_L_DQ_DQS_BYTE5\" )
			)
			( classClass "@crescent_city_bb_fab1_lib.crescent_city_bb_fab1(sch_1):\CC456\"
				( spacingCSetRef "@sapphirecity_baseboard_lib.sapphirecity_baseboard(sch_1):\DQ_TO_DQ\" )
				( netClassRef "@sapphirecity_baseboard_lib.sapphirecity_baseboard(sch_1):\DDR4_CHN_L_CMD_ADD\" )
				( netClassRef "@sapphirecity_baseboard_lib.sapphirecity_baseboard(sch_1):\DDR4_CHN_L_DQ_DQS_BYTE5\" )
			)
			( classClass "@crescent_city_bb_fab1_lib.crescent_city_bb_fab1(sch_1):\CC468\"
				( spacingCSetRef "@sapphirecity_baseboard_lib.sapphirecity_baseboard(sch_1):\DQ_TO_DQ\" )
				( netClassRef "@sapphirecity_baseboard_lib.sapphirecity_baseboard(sch_1):\DDR4_CHN_L_CTRL\" )
				( netClassRef "@sapphirecity_baseboard_lib.sapphirecity_baseboard(sch_1):\DDR4_CHN_L_DQ_DQS_BYTE5\" )
			)
			( classClass "@crescent_city_bb_fab1_lib.crescent_city_bb_fab1(sch_1):\CC852\"
				( spacingCSetRef "@sapphirecity_baseboard_lib.sapphirecity_baseboard(sch_1):\DQ_TO_DQ\" )
				( netClassRef "@sapphirecity_baseboard_lib.sapphirecity_baseboard(sch_1):\DDR4_CHN_L_DQ_DQS_BYTE0\" )
				( netClassRef "@sapphirecity_baseboard_lib.sapphirecity_baseboard(sch_1):\DDR4_CHN_L_DQ_DQS_BYTE5\" )
			)
			( classClass "@crescent_city_bb_fab1_lib.crescent_city_bb_fab1(sch_1):\CC859\"
				( spacingCSetRef "@sapphirecity_baseboard_lib.sapphirecity_baseboard(sch_1):\DQ_TO_DQ\" )
				( netClassRef "@sapphirecity_baseboard_lib.sapphirecity_baseboard(sch_1):\DDR4_CHN_L_DQ_DQS_BYTE1\" )
				( netClassRef "@sapphirecity_baseboard_lib.sapphirecity_baseboard(sch_1):\DDR4_CHN_L_DQ_DQS_BYTE5\" )
			)
			( classClass "@crescent_city_bb_fab1_lib.crescent_city_bb_fab1(sch_1):\CC865\"
				( spacingCSetRef "@sapphirecity_baseboard_lib.sapphirecity_baseboard(sch_1):\DQ_TO_DQ\" )
				( netClassRef "@sapphirecity_baseboard_lib.sapphirecity_baseboard(sch_1):\DDR4_CHN_L_DQ_DQS_BYTE2\" )
				( netClassRef "@sapphirecity_baseboard_lib.sapphirecity_baseboard(sch_1):\DDR4_CHN_L_DQ_DQS_BYTE5\" )
			)
			( classClass "@crescent_city_bb_fab1_lib.crescent_city_bb_fab1(sch_1):\CC870\"
				( spacingCSetRef "@sapphirecity_baseboard_lib.sapphirecity_baseboard(sch_1):\DQ_TO_DQ\" )
				( netClassRef "@sapphirecity_baseboard_lib.sapphirecity_baseboard(sch_1):\DDR4_CHN_L_DQ_DQS_BYTE3\" )
				( netClassRef "@sapphirecity_baseboard_lib.sapphirecity_baseboard(sch_1):\DDR4_CHN_L_DQ_DQS_BYTE5\" )
			)
			( classClass "@crescent_city_bb_fab1_lib.crescent_city_bb_fab1(sch_1):\CC874\"
				( spacingCSetRef "@sapphirecity_baseboard_lib.sapphirecity_baseboard(sch_1):\DQ_TO_DQ\" )
				( netClassRef "@sapphirecity_baseboard_lib.sapphirecity_baseboard(sch_1):\DDR4_CHN_L_DQ_DQS_BYTE4\" )
				( netClassRef "@sapphirecity_baseboard_lib.sapphirecity_baseboard(sch_1):\DDR4_CHN_L_DQ_DQS_BYTE5\" )
			)
			( classClass "@sapphirecity_baseboard_lib.sapphirecity_baseboard(sch_1):\CC1017\"
				( spacingCSetRef "@sapphirecity_baseboard_lib.sapphirecity_baseboard(sch_1):\DDR4_2SPC_DQ/DQS\" )
				( netClassRef "@sapphirecity_baseboard_lib.sapphirecity_baseboard(sch_1):\DDR4_CHN_L_DQ_DQS_BYTE4\" )
				( netClassRef "@sapphirecity_baseboard_lib.sapphirecity_baseboard(sch_1):\DDR4_CHN_L_DQ_DQS_BYTE4\" )
			)
			( classClass "@crescent_city_bb_fab1_lib.crescent_city_bb_fab1(sch_1):\CC442\"
				( spacingCSetRef "@sapphirecity_baseboard_lib.sapphirecity_baseboard(sch_1):\DQ_TO_DQ\" )
				( netClassRef "@sapphirecity_baseboard_lib.sapphirecity_baseboard(sch_1):\DDR4_CHN_L_CLK\" )
				( netClassRef "@sapphirecity_baseboard_lib.sapphirecity_baseboard(sch_1):\DDR4_CHN_L_DQ_DQS_BYTE4\" )
			)
			( classClass "@crescent_city_bb_fab1_lib.crescent_city_bb_fab1(sch_1):\CC455\"
				( spacingCSetRef "@sapphirecity_baseboard_lib.sapphirecity_baseboard(sch_1):\DQ_TO_DQ\" )
				( netClassRef "@sapphirecity_baseboard_lib.sapphirecity_baseboard(sch_1):\DDR4_CHN_L_CMD_ADD\" )
				( netClassRef "@sapphirecity_baseboard_lib.sapphirecity_baseboard(sch_1):\DDR4_CHN_L_DQ_DQS_BYTE4\" )
			)
			( classClass "@crescent_city_bb_fab1_lib.crescent_city_bb_fab1(sch_1):\CC467\"
				( spacingCSetRef "@sapphirecity_baseboard_lib.sapphirecity_baseboard(sch_1):\DQ_TO_DQ\" )
				( netClassRef "@sapphirecity_baseboard_lib.sapphirecity_baseboard(sch_1):\DDR4_CHN_L_CTRL\" )
				( netClassRef "@sapphirecity_baseboard_lib.sapphirecity_baseboard(sch_1):\DDR4_CHN_L_DQ_DQS_BYTE4\" )
			)
			( classClass "@crescent_city_bb_fab1_lib.crescent_city_bb_fab1(sch_1):\CC851\"
				( spacingCSetRef "@sapphirecity_baseboard_lib.sapphirecity_baseboard(sch_1):\DQ_TO_DQ\" )
				( netClassRef "@sapphirecity_baseboard_lib.sapphirecity_baseboard(sch_1):\DDR4_CHN_L_DQ_DQS_BYTE0\" )
				( netClassRef "@sapphirecity_baseboard_lib.sapphirecity_baseboard(sch_1):\DDR4_CHN_L_DQ_DQS_BYTE4\" )
			)
			( classClass "@crescent_city_bb_fab1_lib.crescent_city_bb_fab1(sch_1):\CC858\"
				( spacingCSetRef "@sapphirecity_baseboard_lib.sapphirecity_baseboard(sch_1):\DQ_TO_DQ\" )
				( netClassRef "@sapphirecity_baseboard_lib.sapphirecity_baseboard(sch_1):\DDR4_CHN_L_DQ_DQS_BYTE1\" )
				( netClassRef "@sapphirecity_baseboard_lib.sapphirecity_baseboard(sch_1):\DDR4_CHN_L_DQ_DQS_BYTE4\" )
			)
			( classClass "@crescent_city_bb_fab1_lib.crescent_city_bb_fab1(sch_1):\CC864\"
				( spacingCSetRef "@sapphirecity_baseboard_lib.sapphirecity_baseboard(sch_1):\DQ_TO_DQ\" )
				( netClassRef "@sapphirecity_baseboard_lib.sapphirecity_baseboard(sch_1):\DDR4_CHN_L_DQ_DQS_BYTE2\" )
				( netClassRef "@sapphirecity_baseboard_lib.sapphirecity_baseboard(sch_1):\DDR4_CHN_L_DQ_DQS_BYTE4\" )
			)
			( classClass "@crescent_city_bb_fab1_lib.crescent_city_bb_fab1(sch_1):\CC869\"
				( spacingCSetRef "@sapphirecity_baseboard_lib.sapphirecity_baseboard(sch_1):\DQ_TO_DQ\" )
				( netClassRef "@sapphirecity_baseboard_lib.sapphirecity_baseboard(sch_1):\DDR4_CHN_L_DQ_DQS_BYTE3\" )
				( netClassRef "@sapphirecity_baseboard_lib.sapphirecity_baseboard(sch_1):\DDR4_CHN_L_DQ_DQS_BYTE4\" )
			)
			( classClass "@sapphirecity_baseboard_lib.sapphirecity_baseboard(sch_1):\CC1016\"
				( spacingCSetRef "@sapphirecity_baseboard_lib.sapphirecity_baseboard(sch_1):\DDR4_2SPC_DQ/DQS\" )
				( netClassRef "@sapphirecity_baseboard_lib.sapphirecity_baseboard(sch_1):\DDR4_CHN_L_DQ_DQS_BYTE3\" )
				( netClassRef "@sapphirecity_baseboard_lib.sapphirecity_baseboard(sch_1):\DDR4_CHN_L_DQ_DQS_BYTE3\" )
			)
			( classClass "@crescent_city_bb_fab1_lib.crescent_city_bb_fab1(sch_1):\CC441\"
				( spacingCSetRef "@sapphirecity_baseboard_lib.sapphirecity_baseboard(sch_1):\DQ_TO_DQ\" )
				( netClassRef "@sapphirecity_baseboard_lib.sapphirecity_baseboard(sch_1):\DDR4_CHN_L_CLK\" )
				( netClassRef "@sapphirecity_baseboard_lib.sapphirecity_baseboard(sch_1):\DDR4_CHN_L_DQ_DQS_BYTE3\" )
			)
			( classClass "@crescent_city_bb_fab1_lib.crescent_city_bb_fab1(sch_1):\CC454\"
				( spacingCSetRef "@sapphirecity_baseboard_lib.sapphirecity_baseboard(sch_1):\DQ_TO_DQ\" )
				( netClassRef "@sapphirecity_baseboard_lib.sapphirecity_baseboard(sch_1):\DDR4_CHN_L_CMD_ADD\" )
				( netClassRef "@sapphirecity_baseboard_lib.sapphirecity_baseboard(sch_1):\DDR4_CHN_L_DQ_DQS_BYTE3\" )
			)
			( classClass "@crescent_city_bb_fab1_lib.crescent_city_bb_fab1(sch_1):\CC466\"
				( spacingCSetRef "@sapphirecity_baseboard_lib.sapphirecity_baseboard(sch_1):\DQ_TO_DQ\" )
				( netClassRef "@sapphirecity_baseboard_lib.sapphirecity_baseboard(sch_1):\DDR4_CHN_L_CTRL\" )
				( netClassRef "@sapphirecity_baseboard_lib.sapphirecity_baseboard(sch_1):\DDR4_CHN_L_DQ_DQS_BYTE3\" )
			)
			( classClass "@crescent_city_bb_fab1_lib.crescent_city_bb_fab1(sch_1):\CC850\"
				( spacingCSetRef "@sapphirecity_baseboard_lib.sapphirecity_baseboard(sch_1):\DQ_TO_DQ\" )
				( netClassRef "@sapphirecity_baseboard_lib.sapphirecity_baseboard(sch_1):\DDR4_CHN_L_DQ_DQS_BYTE0\" )
				( netClassRef "@sapphirecity_baseboard_lib.sapphirecity_baseboard(sch_1):\DDR4_CHN_L_DQ_DQS_BYTE3\" )
			)
			( classClass "@crescent_city_bb_fab1_lib.crescent_city_bb_fab1(sch_1):\CC857\"
				( spacingCSetRef "@sapphirecity_baseboard_lib.sapphirecity_baseboard(sch_1):\DQ_TO_DQ\" )
				( netClassRef "@sapphirecity_baseboard_lib.sapphirecity_baseboard(sch_1):\DDR4_CHN_L_DQ_DQS_BYTE1\" )
				( netClassRef "@sapphirecity_baseboard_lib.sapphirecity_baseboard(sch_1):\DDR4_CHN_L_DQ_DQS_BYTE3\" )
			)
			( classClass "@crescent_city_bb_fab1_lib.crescent_city_bb_fab1(sch_1):\CC863\"
				( spacingCSetRef "@sapphirecity_baseboard_lib.sapphirecity_baseboard(sch_1):\DQ_TO_DQ\" )
				( netClassRef "@sapphirecity_baseboard_lib.sapphirecity_baseboard(sch_1):\DDR4_CHN_L_DQ_DQS_BYTE2\" )
				( netClassRef "@sapphirecity_baseboard_lib.sapphirecity_baseboard(sch_1):\DDR4_CHN_L_DQ_DQS_BYTE3\" )
			)
			( classClass "@sapphirecity_baseboard_lib.sapphirecity_baseboard(sch_1):\CC1015\"
				( spacingCSetRef "@sapphirecity_baseboard_lib.sapphirecity_baseboard(sch_1):\DDR4_2SPC_DQ/DQS\" )
				( netClassRef "@sapphirecity_baseboard_lib.sapphirecity_baseboard(sch_1):\DDR4_CHN_L_DQ_DQS_BYTE2\" )
				( netClassRef "@sapphirecity_baseboard_lib.sapphirecity_baseboard(sch_1):\DDR4_CHN_L_DQ_DQS_BYTE2\" )
			)
			( classClass "@crescent_city_bb_fab1_lib.crescent_city_bb_fab1(sch_1):\CC440\"
				( spacingCSetRef "@sapphirecity_baseboard_lib.sapphirecity_baseboard(sch_1):\DQ_TO_DQ\" )
				( netClassRef "@sapphirecity_baseboard_lib.sapphirecity_baseboard(sch_1):\DDR4_CHN_L_CLK\" )
				( netClassRef "@sapphirecity_baseboard_lib.sapphirecity_baseboard(sch_1):\DDR4_CHN_L_DQ_DQS_BYTE2\" )
			)
			( classClass "@crescent_city_bb_fab1_lib.crescent_city_bb_fab1(sch_1):\CC453\"
				( spacingCSetRef "@sapphirecity_baseboard_lib.sapphirecity_baseboard(sch_1):\DQ_TO_DQ\" )
				( netClassRef "@sapphirecity_baseboard_lib.sapphirecity_baseboard(sch_1):\DDR4_CHN_L_CMD_ADD\" )
				( netClassRef "@sapphirecity_baseboard_lib.sapphirecity_baseboard(sch_1):\DDR4_CHN_L_DQ_DQS_BYTE2\" )
			)
			( classClass "@crescent_city_bb_fab1_lib.crescent_city_bb_fab1(sch_1):\CC465\"
				( spacingCSetRef "@sapphirecity_baseboard_lib.sapphirecity_baseboard(sch_1):\DQ_TO_DQ\" )
				( netClassRef "@sapphirecity_baseboard_lib.sapphirecity_baseboard(sch_1):\DDR4_CHN_L_CTRL\" )
				( netClassRef "@sapphirecity_baseboard_lib.sapphirecity_baseboard(sch_1):\DDR4_CHN_L_DQ_DQS_BYTE2\" )
			)
			( classClass "@crescent_city_bb_fab1_lib.crescent_city_bb_fab1(sch_1):\CC849\"
				( spacingCSetRef "@sapphirecity_baseboard_lib.sapphirecity_baseboard(sch_1):\DQ_TO_DQ\" )
				( netClassRef "@sapphirecity_baseboard_lib.sapphirecity_baseboard(sch_1):\DDR4_CHN_L_DQ_DQS_BYTE0\" )
				( netClassRef "@sapphirecity_baseboard_lib.sapphirecity_baseboard(sch_1):\DDR4_CHN_L_DQ_DQS_BYTE2\" )
			)
			( classClass "@crescent_city_bb_fab1_lib.crescent_city_bb_fab1(sch_1):\CC856\"
				( spacingCSetRef "@sapphirecity_baseboard_lib.sapphirecity_baseboard(sch_1):\DQ_TO_DQ\" )
				( netClassRef "@sapphirecity_baseboard_lib.sapphirecity_baseboard(sch_1):\DDR4_CHN_L_DQ_DQS_BYTE1\" )
				( netClassRef "@sapphirecity_baseboard_lib.sapphirecity_baseboard(sch_1):\DDR4_CHN_L_DQ_DQS_BYTE2\" )
			)
			( classClass "@sapphirecity_baseboard_lib.sapphirecity_baseboard(sch_1):\CC1014\"
				( spacingCSetRef "@sapphirecity_baseboard_lib.sapphirecity_baseboard(sch_1):\DDR4_2SPC_DQ/DQS\" )
				( netClassRef "@sapphirecity_baseboard_lib.sapphirecity_baseboard(sch_1):\DDR4_CHN_L_DQ_DQS_BYTE1\" )
				( netClassRef "@sapphirecity_baseboard_lib.sapphirecity_baseboard(sch_1):\DDR4_CHN_L_DQ_DQS_BYTE1\" )
			)
			( classClass "@crescent_city_bb_fab1_lib.crescent_city_bb_fab1(sch_1):\CC439\"
				( spacingCSetRef "@sapphirecity_baseboard_lib.sapphirecity_baseboard(sch_1):\DQ_TO_DQ\" )
				( netClassRef "@sapphirecity_baseboard_lib.sapphirecity_baseboard(sch_1):\DDR4_CHN_L_CLK\" )
				( netClassRef "@sapphirecity_baseboard_lib.sapphirecity_baseboard(sch_1):\DDR4_CHN_L_DQ_DQS_BYTE1\" )
			)
			( classClass "@crescent_city_bb_fab1_lib.crescent_city_bb_fab1(sch_1):\CC452\"
				( spacingCSetRef "@sapphirecity_baseboard_lib.sapphirecity_baseboard(sch_1):\DQ_TO_DQ\" )
				( netClassRef "@sapphirecity_baseboard_lib.sapphirecity_baseboard(sch_1):\DDR4_CHN_L_CMD_ADD\" )
				( netClassRef "@sapphirecity_baseboard_lib.sapphirecity_baseboard(sch_1):\DDR4_CHN_L_DQ_DQS_BYTE1\" )
			)
			( classClass "@crescent_city_bb_fab1_lib.crescent_city_bb_fab1(sch_1):\CC464\"
				( spacingCSetRef "@sapphirecity_baseboard_lib.sapphirecity_baseboard(sch_1):\DQ_TO_DQ\" )
				( netClassRef "@sapphirecity_baseboard_lib.sapphirecity_baseboard(sch_1):\DDR4_CHN_L_CTRL\" )
				( netClassRef "@sapphirecity_baseboard_lib.sapphirecity_baseboard(sch_1):\DDR4_CHN_L_DQ_DQS_BYTE1\" )
			)
			( classClass "@crescent_city_bb_fab1_lib.crescent_city_bb_fab1(sch_1):\CC848\"
				( spacingCSetRef "@sapphirecity_baseboard_lib.sapphirecity_baseboard(sch_1):\DQ_TO_DQ\" )
				( netClassRef "@sapphirecity_baseboard_lib.sapphirecity_baseboard(sch_1):\DDR4_CHN_L_DQ_DQS_BYTE0\" )
				( netClassRef "@sapphirecity_baseboard_lib.sapphirecity_baseboard(sch_1):\DDR4_CHN_L_DQ_DQS_BYTE1\" )
			)
			( classClass "@sapphirecity_baseboard_lib.sapphirecity_baseboard(sch_1):\CC1013\"
				( spacingCSetRef "@sapphirecity_baseboard_lib.sapphirecity_baseboard(sch_1):\DDR4_2SPC_DQ/DQS\" )
				( netClassRef "@sapphirecity_baseboard_lib.sapphirecity_baseboard(sch_1):\DDR4_CHN_L_DQ_DQS_BYTE0\" )
				( netClassRef "@sapphirecity_baseboard_lib.sapphirecity_baseboard(sch_1):\DDR4_CHN_L_DQ_DQS_BYTE0\" )
			)
			( classClass "@crescent_city_bb_fab1_lib.crescent_city_bb_fab1(sch_1):\CC438\"
				( spacingCSetRef "@sapphirecity_baseboard_lib.sapphirecity_baseboard(sch_1):\DQ_TO_DQ\" )
				( netClassRef "@sapphirecity_baseboard_lib.sapphirecity_baseboard(sch_1):\DDR4_CHN_L_CLK\" )
				( netClassRef "@sapphirecity_baseboard_lib.sapphirecity_baseboard(sch_1):\DDR4_CHN_L_DQ_DQS_BYTE0\" )
			)
			( classClass "@crescent_city_bb_fab1_lib.crescent_city_bb_fab1(sch_1):\CC451\"
				( spacingCSetRef "@sapphirecity_baseboard_lib.sapphirecity_baseboard(sch_1):\DQ_TO_DQ\" )
				( netClassRef "@sapphirecity_baseboard_lib.sapphirecity_baseboard(sch_1):\DDR4_CHN_L_CMD_ADD\" )
				( netClassRef "@sapphirecity_baseboard_lib.sapphirecity_baseboard(sch_1):\DDR4_CHN_L_DQ_DQS_BYTE0\" )
			)
			( classClass "@crescent_city_bb_fab1_lib.crescent_city_bb_fab1(sch_1):\CC463\"
				( spacingCSetRef "@sapphirecity_baseboard_lib.sapphirecity_baseboard(sch_1):\DQ_TO_DQ\" )
				( netClassRef "@sapphirecity_baseboard_lib.sapphirecity_baseboard(sch_1):\DDR4_CHN_L_CTRL\" )
				( netClassRef "@sapphirecity_baseboard_lib.sapphirecity_baseboard(sch_1):\DDR4_CHN_L_DQ_DQS_BYTE0\" )
			)
			( classClass "@sapphirecity_baseboard_lib.sapphirecity_baseboard(sch_1):\CC1029\"
				( spacingCSetRef "@sapphirecity_baseboard_lib.sapphirecity_baseboard(sch_1):\DDR4_2SPC_DQ/DQS\" )
				( netClassRef "@sapphirecity_baseboard_lib.sapphirecity_baseboard(sch_1):\DDR4_CHN_K_DQ_DQS_BYTE7\" )
				( netClassRef "@sapphirecity_baseboard_lib.sapphirecity_baseboard(sch_1):\DDR4_CHN_K_DQ_DQS_BYTE7\" )
			)
			( classClass "@crescent_city_bb_fab1_lib.crescent_city_bb_fab1(sch_1):\CC406\"
				( spacingCSetRef "@sapphirecity_baseboard_lib.sapphirecity_baseboard(sch_1):\DQ_TO_DQ\" )
				( netClassRef "@sapphirecity_baseboard_lib.sapphirecity_baseboard(sch_1):\DDR4_CHN_K_CLK\" )
				( netClassRef "@sapphirecity_baseboard_lib.sapphirecity_baseboard(sch_1):\DDR4_CHN_K_DQ_DQS_BYTE7\" )
			)
			( classClass "@crescent_city_bb_fab1_lib.crescent_city_bb_fab1(sch_1):\CC419\"
				( spacingCSetRef "@sapphirecity_baseboard_lib.sapphirecity_baseboard(sch_1):\DQ_TO_DQ\" )
				( netClassRef "@sapphirecity_baseboard_lib.sapphirecity_baseboard(sch_1):\DDR4_CHN_K_CMD_ADD\" )
				( netClassRef "@sapphirecity_baseboard_lib.sapphirecity_baseboard(sch_1):\DDR4_CHN_K_DQ_DQS_BYTE7\" )
			)
			( classClass "@crescent_city_bb_fab1_lib.crescent_city_bb_fab1(sch_1):\CC431\"
				( spacingCSetRef "@sapphirecity_baseboard_lib.sapphirecity_baseboard(sch_1):\DQ_TO_DQ\" )
				( netClassRef "@sapphirecity_baseboard_lib.sapphirecity_baseboard(sch_1):\DDR4_CHN_K_CTRL\" )
				( netClassRef "@sapphirecity_baseboard_lib.sapphirecity_baseboard(sch_1):\DDR4_CHN_K_DQ_DQS_BYTE7\" )
			)
			( classClass "@crescent_city_bb_fab1_lib.crescent_city_bb_fab1(sch_1):\CC818\"
				( spacingCSetRef "@sapphirecity_baseboard_lib.sapphirecity_baseboard(sch_1):\DQ_TO_DQ\" )
				( netClassRef "@sapphirecity_baseboard_lib.sapphirecity_baseboard(sch_1):\DDR4_CHN_K_DQ_DQS_BYTE0\" )
				( netClassRef "@sapphirecity_baseboard_lib.sapphirecity_baseboard(sch_1):\DDR4_CHN_K_DQ_DQS_BYTE7\" )
			)
			( classClass "@crescent_city_bb_fab1_lib.crescent_city_bb_fab1(sch_1):\CC825\"
				( spacingCSetRef "@sapphirecity_baseboard_lib.sapphirecity_baseboard(sch_1):\DQ_TO_DQ\" )
				( netClassRef "@sapphirecity_baseboard_lib.sapphirecity_baseboard(sch_1):\DDR4_CHN_K_DQ_DQS_BYTE1\" )
				( netClassRef "@sapphirecity_baseboard_lib.sapphirecity_baseboard(sch_1):\DDR4_CHN_K_DQ_DQS_BYTE7\" )
			)
			( classClass "@crescent_city_bb_fab1_lib.crescent_city_bb_fab1(sch_1):\CC831\"
				( spacingCSetRef "@sapphirecity_baseboard_lib.sapphirecity_baseboard(sch_1):\DQ_TO_DQ\" )
				( netClassRef "@sapphirecity_baseboard_lib.sapphirecity_baseboard(sch_1):\DDR4_CHN_K_DQ_DQS_BYTE2\" )
				( netClassRef "@sapphirecity_baseboard_lib.sapphirecity_baseboard(sch_1):\DDR4_CHN_K_DQ_DQS_BYTE7\" )
			)
			( classClass "@crescent_city_bb_fab1_lib.crescent_city_bb_fab1(sch_1):\CC836\"
				( spacingCSetRef "@sapphirecity_baseboard_lib.sapphirecity_baseboard(sch_1):\DQ_TO_DQ\" )
				( netClassRef "@sapphirecity_baseboard_lib.sapphirecity_baseboard(sch_1):\DDR4_CHN_K_DQ_DQS_BYTE3\" )
				( netClassRef "@sapphirecity_baseboard_lib.sapphirecity_baseboard(sch_1):\DDR4_CHN_K_DQ_DQS_BYTE7\" )
			)
			( classClass "@crescent_city_bb_fab1_lib.crescent_city_bb_fab1(sch_1):\CC840\"
				( spacingCSetRef "@sapphirecity_baseboard_lib.sapphirecity_baseboard(sch_1):\DQ_TO_DQ\" )
				( netClassRef "@sapphirecity_baseboard_lib.sapphirecity_baseboard(sch_1):\DDR4_CHN_K_DQ_DQS_BYTE4\" )
				( netClassRef "@sapphirecity_baseboard_lib.sapphirecity_baseboard(sch_1):\DDR4_CHN_K_DQ_DQS_BYTE7\" )
			)
			( classClass "@crescent_city_bb_fab1_lib.crescent_city_bb_fab1(sch_1):\CC843\"
				( spacingCSetRef "@sapphirecity_baseboard_lib.sapphirecity_baseboard(sch_1):\DQ_TO_DQ\" )
				( netClassRef "@sapphirecity_baseboard_lib.sapphirecity_baseboard(sch_1):\DDR4_CHN_K_DQ_DQS_BYTE5\" )
				( netClassRef "@sapphirecity_baseboard_lib.sapphirecity_baseboard(sch_1):\DDR4_CHN_K_DQ_DQS_BYTE7\" )
			)
			( classClass "@crescent_city_bb_fab1_lib.crescent_city_bb_fab1(sch_1):\CC845\"
				( spacingCSetRef "@sapphirecity_baseboard_lib.sapphirecity_baseboard(sch_1):\DQ_TO_DQ\" )
				( netClassRef "@sapphirecity_baseboard_lib.sapphirecity_baseboard(sch_1):\DDR4_CHN_K_DQ_DQS_BYTE6\" )
				( netClassRef "@sapphirecity_baseboard_lib.sapphirecity_baseboard(sch_1):\DDR4_CHN_K_DQ_DQS_BYTE7\" )
			)
			( classClass "@sapphirecity_baseboard_lib.sapphirecity_baseboard(sch_1):\CC1028\"
				( spacingCSetRef "@sapphirecity_baseboard_lib.sapphirecity_baseboard(sch_1):\DDR4_2SPC_DQ/DQS\" )
				( netClassRef "@sapphirecity_baseboard_lib.sapphirecity_baseboard(sch_1):\DDR4_CHN_K_DQ_DQS_BYTE6\" )
				( netClassRef "@sapphirecity_baseboard_lib.sapphirecity_baseboard(sch_1):\DDR4_CHN_K_DQ_DQS_BYTE6\" )
			)
			( classClass "@crescent_city_bb_fab1_lib.crescent_city_bb_fab1(sch_1):\CC405\"
				( spacingCSetRef "@sapphirecity_baseboard_lib.sapphirecity_baseboard(sch_1):\DQ_TO_DQ\" )
				( netClassRef "@sapphirecity_baseboard_lib.sapphirecity_baseboard(sch_1):\DDR4_CHN_K_CLK\" )
				( netClassRef "@sapphirecity_baseboard_lib.sapphirecity_baseboard(sch_1):\DDR4_CHN_K_DQ_DQS_BYTE6\" )
			)
			( classClass "@crescent_city_bb_fab1_lib.crescent_city_bb_fab1(sch_1):\CC418\"
				( spacingCSetRef "@sapphirecity_baseboard_lib.sapphirecity_baseboard(sch_1):\DQ_TO_DQ\" )
				( netClassRef "@sapphirecity_baseboard_lib.sapphirecity_baseboard(sch_1):\DDR4_CHN_K_CMD_ADD\" )
				( netClassRef "@sapphirecity_baseboard_lib.sapphirecity_baseboard(sch_1):\DDR4_CHN_K_DQ_DQS_BYTE6\" )
			)
			( classClass "@crescent_city_bb_fab1_lib.crescent_city_bb_fab1(sch_1):\CC430\"
				( spacingCSetRef "@sapphirecity_baseboard_lib.sapphirecity_baseboard(sch_1):\DQ_TO_DQ\" )
				( netClassRef "@sapphirecity_baseboard_lib.sapphirecity_baseboard(sch_1):\DDR4_CHN_K_CTRL\" )
				( netClassRef "@sapphirecity_baseboard_lib.sapphirecity_baseboard(sch_1):\DDR4_CHN_K_DQ_DQS_BYTE6\" )
			)
			( classClass "@crescent_city_bb_fab1_lib.crescent_city_bb_fab1(sch_1):\CC817\"
				( spacingCSetRef "@sapphirecity_baseboard_lib.sapphirecity_baseboard(sch_1):\DQ_TO_DQ\" )
				( netClassRef "@sapphirecity_baseboard_lib.sapphirecity_baseboard(sch_1):\DDR4_CHN_K_DQ_DQS_BYTE0\" )
				( netClassRef "@sapphirecity_baseboard_lib.sapphirecity_baseboard(sch_1):\DDR4_CHN_K_DQ_DQS_BYTE6\" )
			)
			( classClass "@crescent_city_bb_fab1_lib.crescent_city_bb_fab1(sch_1):\CC824\"
				( spacingCSetRef "@sapphirecity_baseboard_lib.sapphirecity_baseboard(sch_1):\DQ_TO_DQ\" )
				( netClassRef "@sapphirecity_baseboard_lib.sapphirecity_baseboard(sch_1):\DDR4_CHN_K_DQ_DQS_BYTE1\" )
				( netClassRef "@sapphirecity_baseboard_lib.sapphirecity_baseboard(sch_1):\DDR4_CHN_K_DQ_DQS_BYTE6\" )
			)
			( classClass "@crescent_city_bb_fab1_lib.crescent_city_bb_fab1(sch_1):\CC830\"
				( spacingCSetRef "@sapphirecity_baseboard_lib.sapphirecity_baseboard(sch_1):\DQ_TO_DQ\" )
				( netClassRef "@sapphirecity_baseboard_lib.sapphirecity_baseboard(sch_1):\DDR4_CHN_K_DQ_DQS_BYTE2\" )
				( netClassRef "@sapphirecity_baseboard_lib.sapphirecity_baseboard(sch_1):\DDR4_CHN_K_DQ_DQS_BYTE6\" )
			)
			( classClass "@crescent_city_bb_fab1_lib.crescent_city_bb_fab1(sch_1):\CC835\"
				( spacingCSetRef "@sapphirecity_baseboard_lib.sapphirecity_baseboard(sch_1):\DQ_TO_DQ\" )
				( netClassRef "@sapphirecity_baseboard_lib.sapphirecity_baseboard(sch_1):\DDR4_CHN_K_DQ_DQS_BYTE3\" )
				( netClassRef "@sapphirecity_baseboard_lib.sapphirecity_baseboard(sch_1):\DDR4_CHN_K_DQ_DQS_BYTE6\" )
			)
			( classClass "@crescent_city_bb_fab1_lib.crescent_city_bb_fab1(sch_1):\CC839\"
				( spacingCSetRef "@sapphirecity_baseboard_lib.sapphirecity_baseboard(sch_1):\DQ_TO_DQ\" )
				( netClassRef "@sapphirecity_baseboard_lib.sapphirecity_baseboard(sch_1):\DDR4_CHN_K_DQ_DQS_BYTE4\" )
				( netClassRef "@sapphirecity_baseboard_lib.sapphirecity_baseboard(sch_1):\DDR4_CHN_K_DQ_DQS_BYTE6\" )
			)
			( classClass "@crescent_city_bb_fab1_lib.crescent_city_bb_fab1(sch_1):\CC842\"
				( spacingCSetRef "@sapphirecity_baseboard_lib.sapphirecity_baseboard(sch_1):\DQ_TO_DQ\" )
				( netClassRef "@sapphirecity_baseboard_lib.sapphirecity_baseboard(sch_1):\DDR4_CHN_K_DQ_DQS_BYTE5\" )
				( netClassRef "@sapphirecity_baseboard_lib.sapphirecity_baseboard(sch_1):\DDR4_CHN_K_DQ_DQS_BYTE6\" )
			)
			( classClass "@sapphirecity_baseboard_lib.sapphirecity_baseboard(sch_1):\CC1027\"
				( spacingCSetRef "@sapphirecity_baseboard_lib.sapphirecity_baseboard(sch_1):\DDR4_2SPC_DQ/DQS\" )
				( netClassRef "@sapphirecity_baseboard_lib.sapphirecity_baseboard(sch_1):\DDR4_CHN_K_DQ_DQS_BYTE5\" )
				( netClassRef "@sapphirecity_baseboard_lib.sapphirecity_baseboard(sch_1):\DDR4_CHN_K_DQ_DQS_BYTE5\" )
			)
			( classClass "@crescent_city_bb_fab1_lib.crescent_city_bb_fab1(sch_1):\CC404\"
				( spacingCSetRef "@sapphirecity_baseboard_lib.sapphirecity_baseboard(sch_1):\DQ_TO_DQ\" )
				( netClassRef "@sapphirecity_baseboard_lib.sapphirecity_baseboard(sch_1):\DDR4_CHN_K_CLK\" )
				( netClassRef "@sapphirecity_baseboard_lib.sapphirecity_baseboard(sch_1):\DDR4_CHN_K_DQ_DQS_BYTE5\" )
			)
			( classClass "@crescent_city_bb_fab1_lib.crescent_city_bb_fab1(sch_1):\CC417\"
				( spacingCSetRef "@sapphirecity_baseboard_lib.sapphirecity_baseboard(sch_1):\DQ_TO_DQ\" )
				( netClassRef "@sapphirecity_baseboard_lib.sapphirecity_baseboard(sch_1):\DDR4_CHN_K_CMD_ADD\" )
				( netClassRef "@sapphirecity_baseboard_lib.sapphirecity_baseboard(sch_1):\DDR4_CHN_K_DQ_DQS_BYTE5\" )
			)
			( classClass "@crescent_city_bb_fab1_lib.crescent_city_bb_fab1(sch_1):\CC429\"
				( spacingCSetRef "@sapphirecity_baseboard_lib.sapphirecity_baseboard(sch_1):\DQ_TO_DQ\" )
				( netClassRef "@sapphirecity_baseboard_lib.sapphirecity_baseboard(sch_1):\DDR4_CHN_K_CTRL\" )
				( netClassRef "@sapphirecity_baseboard_lib.sapphirecity_baseboard(sch_1):\DDR4_CHN_K_DQ_DQS_BYTE5\" )
			)
			( classClass "@crescent_city_bb_fab1_lib.crescent_city_bb_fab1(sch_1):\CC816\"
				( spacingCSetRef "@sapphirecity_baseboard_lib.sapphirecity_baseboard(sch_1):\DQ_TO_DQ\" )
				( netClassRef "@sapphirecity_baseboard_lib.sapphirecity_baseboard(sch_1):\DDR4_CHN_K_DQ_DQS_BYTE0\" )
				( netClassRef "@sapphirecity_baseboard_lib.sapphirecity_baseboard(sch_1):\DDR4_CHN_K_DQ_DQS_BYTE5\" )
			)
			( classClass "@crescent_city_bb_fab1_lib.crescent_city_bb_fab1(sch_1):\CC823\"
				( spacingCSetRef "@sapphirecity_baseboard_lib.sapphirecity_baseboard(sch_1):\DQ_TO_DQ\" )
				( netClassRef "@sapphirecity_baseboard_lib.sapphirecity_baseboard(sch_1):\DDR4_CHN_K_DQ_DQS_BYTE1\" )
				( netClassRef "@sapphirecity_baseboard_lib.sapphirecity_baseboard(sch_1):\DDR4_CHN_K_DQ_DQS_BYTE5\" )
			)
			( classClass "@crescent_city_bb_fab1_lib.crescent_city_bb_fab1(sch_1):\CC829\"
				( spacingCSetRef "@sapphirecity_baseboard_lib.sapphirecity_baseboard(sch_1):\DQ_TO_DQ\" )
				( netClassRef "@sapphirecity_baseboard_lib.sapphirecity_baseboard(sch_1):\DDR4_CHN_K_DQ_DQS_BYTE2\" )
				( netClassRef "@sapphirecity_baseboard_lib.sapphirecity_baseboard(sch_1):\DDR4_CHN_K_DQ_DQS_BYTE5\" )
			)
			( classClass "@crescent_city_bb_fab1_lib.crescent_city_bb_fab1(sch_1):\CC834\"
				( spacingCSetRef "@sapphirecity_baseboard_lib.sapphirecity_baseboard(sch_1):\DQ_TO_DQ\" )
				( netClassRef "@sapphirecity_baseboard_lib.sapphirecity_baseboard(sch_1):\DDR4_CHN_K_DQ_DQS_BYTE3\" )
				( netClassRef "@sapphirecity_baseboard_lib.sapphirecity_baseboard(sch_1):\DDR4_CHN_K_DQ_DQS_BYTE5\" )
			)
			( classClass "@crescent_city_bb_fab1_lib.crescent_city_bb_fab1(sch_1):\CC838\"
				( spacingCSetRef "@sapphirecity_baseboard_lib.sapphirecity_baseboard(sch_1):\DQ_TO_DQ\" )
				( netClassRef "@sapphirecity_baseboard_lib.sapphirecity_baseboard(sch_1):\DDR4_CHN_K_DQ_DQS_BYTE4\" )
				( netClassRef "@sapphirecity_baseboard_lib.sapphirecity_baseboard(sch_1):\DDR4_CHN_K_DQ_DQS_BYTE5\" )
			)
			( classClass "@sapphirecity_baseboard_lib.sapphirecity_baseboard(sch_1):\CC1026\"
				( spacingCSetRef "@sapphirecity_baseboard_lib.sapphirecity_baseboard(sch_1):\DDR4_2SPC_DQ/DQS\" )
				( netClassRef "@sapphirecity_baseboard_lib.sapphirecity_baseboard(sch_1):\DDR4_CHN_K_DQ_DQS_BYTE4\" )
				( netClassRef "@sapphirecity_baseboard_lib.sapphirecity_baseboard(sch_1):\DDR4_CHN_K_DQ_DQS_BYTE4\" )
			)
			( classClass "@crescent_city_bb_fab1_lib.crescent_city_bb_fab1(sch_1):\CC403\"
				( spacingCSetRef "@sapphirecity_baseboard_lib.sapphirecity_baseboard(sch_1):\DQ_TO_DQ\" )
				( netClassRef "@sapphirecity_baseboard_lib.sapphirecity_baseboard(sch_1):\DDR4_CHN_K_CLK\" )
				( netClassRef "@sapphirecity_baseboard_lib.sapphirecity_baseboard(sch_1):\DDR4_CHN_K_DQ_DQS_BYTE4\" )
			)
			( classClass "@crescent_city_bb_fab1_lib.crescent_city_bb_fab1(sch_1):\CC416\"
				( spacingCSetRef "@sapphirecity_baseboard_lib.sapphirecity_baseboard(sch_1):\DQ_TO_DQ\" )
				( netClassRef "@sapphirecity_baseboard_lib.sapphirecity_baseboard(sch_1):\DDR4_CHN_K_CMD_ADD\" )
				( netClassRef "@sapphirecity_baseboard_lib.sapphirecity_baseboard(sch_1):\DDR4_CHN_K_DQ_DQS_BYTE4\" )
			)
			( classClass "@crescent_city_bb_fab1_lib.crescent_city_bb_fab1(sch_1):\CC428\"
				( spacingCSetRef "@sapphirecity_baseboard_lib.sapphirecity_baseboard(sch_1):\DQ_TO_DQ\" )
				( netClassRef "@sapphirecity_baseboard_lib.sapphirecity_baseboard(sch_1):\DDR4_CHN_K_CTRL\" )
				( netClassRef "@sapphirecity_baseboard_lib.sapphirecity_baseboard(sch_1):\DDR4_CHN_K_DQ_DQS_BYTE4\" )
			)
			( classClass "@crescent_city_bb_fab1_lib.crescent_city_bb_fab1(sch_1):\CC815\"
				( spacingCSetRef "@sapphirecity_baseboard_lib.sapphirecity_baseboard(sch_1):\DQ_TO_DQ\" )
				( netClassRef "@sapphirecity_baseboard_lib.sapphirecity_baseboard(sch_1):\DDR4_CHN_K_DQ_DQS_BYTE0\" )
				( netClassRef "@sapphirecity_baseboard_lib.sapphirecity_baseboard(sch_1):\DDR4_CHN_K_DQ_DQS_BYTE4\" )
			)
			( classClass "@crescent_city_bb_fab1_lib.crescent_city_bb_fab1(sch_1):\CC822\"
				( spacingCSetRef "@sapphirecity_baseboard_lib.sapphirecity_baseboard(sch_1):\DQ_TO_DQ\" )
				( netClassRef "@sapphirecity_baseboard_lib.sapphirecity_baseboard(sch_1):\DDR4_CHN_K_DQ_DQS_BYTE1\" )
				( netClassRef "@sapphirecity_baseboard_lib.sapphirecity_baseboard(sch_1):\DDR4_CHN_K_DQ_DQS_BYTE4\" )
			)
			( classClass "@crescent_city_bb_fab1_lib.crescent_city_bb_fab1(sch_1):\CC828\"
				( spacingCSetRef "@sapphirecity_baseboard_lib.sapphirecity_baseboard(sch_1):\DQ_TO_DQ\" )
				( netClassRef "@sapphirecity_baseboard_lib.sapphirecity_baseboard(sch_1):\DDR4_CHN_K_DQ_DQS_BYTE2\" )
				( netClassRef "@sapphirecity_baseboard_lib.sapphirecity_baseboard(sch_1):\DDR4_CHN_K_DQ_DQS_BYTE4\" )
			)
			( classClass "@crescent_city_bb_fab1_lib.crescent_city_bb_fab1(sch_1):\CC833\"
				( spacingCSetRef "@sapphirecity_baseboard_lib.sapphirecity_baseboard(sch_1):\DQ_TO_DQ\" )
				( netClassRef "@sapphirecity_baseboard_lib.sapphirecity_baseboard(sch_1):\DDR4_CHN_K_DQ_DQS_BYTE3\" )
				( netClassRef "@sapphirecity_baseboard_lib.sapphirecity_baseboard(sch_1):\DDR4_CHN_K_DQ_DQS_BYTE4\" )
			)
			( classClass "@sapphirecity_baseboard_lib.sapphirecity_baseboard(sch_1):\CC1025\"
				( spacingCSetRef "@sapphirecity_baseboard_lib.sapphirecity_baseboard(sch_1):\DDR4_2SPC_DQ/DQS\" )
				( netClassRef "@sapphirecity_baseboard_lib.sapphirecity_baseboard(sch_1):\DDR4_CHN_K_DQ_DQS_BYTE3\" )
				( netClassRef "@sapphirecity_baseboard_lib.sapphirecity_baseboard(sch_1):\DDR4_CHN_K_DQ_DQS_BYTE3\" )
			)
			( classClass "@crescent_city_bb_fab1_lib.crescent_city_bb_fab1(sch_1):\CC402\"
				( spacingCSetRef "@sapphirecity_baseboard_lib.sapphirecity_baseboard(sch_1):\DQ_TO_DQ\" )
				( netClassRef "@sapphirecity_baseboard_lib.sapphirecity_baseboard(sch_1):\DDR4_CHN_K_CLK\" )
				( netClassRef "@sapphirecity_baseboard_lib.sapphirecity_baseboard(sch_1):\DDR4_CHN_K_DQ_DQS_BYTE3\" )
			)
			( classClass "@crescent_city_bb_fab1_lib.crescent_city_bb_fab1(sch_1):\CC415\"
				( spacingCSetRef "@sapphirecity_baseboard_lib.sapphirecity_baseboard(sch_1):\DQ_TO_DQ\" )
				( netClassRef "@sapphirecity_baseboard_lib.sapphirecity_baseboard(sch_1):\DDR4_CHN_K_CMD_ADD\" )
				( netClassRef "@sapphirecity_baseboard_lib.sapphirecity_baseboard(sch_1):\DDR4_CHN_K_DQ_DQS_BYTE3\" )
			)
			( classClass "@crescent_city_bb_fab1_lib.crescent_city_bb_fab1(sch_1):\CC427\"
				( spacingCSetRef "@sapphirecity_baseboard_lib.sapphirecity_baseboard(sch_1):\DQ_TO_DQ\" )
				( netClassRef "@sapphirecity_baseboard_lib.sapphirecity_baseboard(sch_1):\DDR4_CHN_K_CTRL\" )
				( netClassRef "@sapphirecity_baseboard_lib.sapphirecity_baseboard(sch_1):\DDR4_CHN_K_DQ_DQS_BYTE3\" )
			)
			( classClass "@crescent_city_bb_fab1_lib.crescent_city_bb_fab1(sch_1):\CC814\"
				( spacingCSetRef "@sapphirecity_baseboard_lib.sapphirecity_baseboard(sch_1):\DQ_TO_DQ\" )
				( netClassRef "@sapphirecity_baseboard_lib.sapphirecity_baseboard(sch_1):\DDR4_CHN_K_DQ_DQS_BYTE0\" )
				( netClassRef "@sapphirecity_baseboard_lib.sapphirecity_baseboard(sch_1):\DDR4_CHN_K_DQ_DQS_BYTE3\" )
			)
			( classClass "@crescent_city_bb_fab1_lib.crescent_city_bb_fab1(sch_1):\CC821\"
				( spacingCSetRef "@sapphirecity_baseboard_lib.sapphirecity_baseboard(sch_1):\DQ_TO_DQ\" )
				( netClassRef "@sapphirecity_baseboard_lib.sapphirecity_baseboard(sch_1):\DDR4_CHN_K_DQ_DQS_BYTE1\" )
				( netClassRef "@sapphirecity_baseboard_lib.sapphirecity_baseboard(sch_1):\DDR4_CHN_K_DQ_DQS_BYTE3\" )
			)
			( classClass "@crescent_city_bb_fab1_lib.crescent_city_bb_fab1(sch_1):\CC827\"
				( spacingCSetRef "@sapphirecity_baseboard_lib.sapphirecity_baseboard(sch_1):\DQ_TO_DQ\" )
				( netClassRef "@sapphirecity_baseboard_lib.sapphirecity_baseboard(sch_1):\DDR4_CHN_K_DQ_DQS_BYTE2\" )
				( netClassRef "@sapphirecity_baseboard_lib.sapphirecity_baseboard(sch_1):\DDR4_CHN_K_DQ_DQS_BYTE3\" )
			)
			( classClass "@sapphirecity_baseboard_lib.sapphirecity_baseboard(sch_1):\CC1024\"
				( spacingCSetRef "@sapphirecity_baseboard_lib.sapphirecity_baseboard(sch_1):\DDR4_2SPC_DQ/DQS\" )
				( netClassRef "@sapphirecity_baseboard_lib.sapphirecity_baseboard(sch_1):\DDR4_CHN_K_DQ_DQS_BYTE2\" )
				( netClassRef "@sapphirecity_baseboard_lib.sapphirecity_baseboard(sch_1):\DDR4_CHN_K_DQ_DQS_BYTE2\" )
			)
			( classClass "@crescent_city_bb_fab1_lib.crescent_city_bb_fab1(sch_1):\CC401\"
				( spacingCSetRef "@sapphirecity_baseboard_lib.sapphirecity_baseboard(sch_1):\DQ_TO_DQ\" )
				( netClassRef "@sapphirecity_baseboard_lib.sapphirecity_baseboard(sch_1):\DDR4_CHN_K_CLK\" )
				( netClassRef "@sapphirecity_baseboard_lib.sapphirecity_baseboard(sch_1):\DDR4_CHN_K_DQ_DQS_BYTE2\" )
			)
			( classClass "@crescent_city_bb_fab1_lib.crescent_city_bb_fab1(sch_1):\CC414\"
				( spacingCSetRef "@sapphirecity_baseboard_lib.sapphirecity_baseboard(sch_1):\DQ_TO_DQ\" )
				( netClassRef "@sapphirecity_baseboard_lib.sapphirecity_baseboard(sch_1):\DDR4_CHN_K_CMD_ADD\" )
				( netClassRef "@sapphirecity_baseboard_lib.sapphirecity_baseboard(sch_1):\DDR4_CHN_K_DQ_DQS_BYTE2\" )
			)
			( classClass "@crescent_city_bb_fab1_lib.crescent_city_bb_fab1(sch_1):\CC426\"
				( spacingCSetRef "@sapphirecity_baseboard_lib.sapphirecity_baseboard(sch_1):\DQ_TO_DQ\" )
				( netClassRef "@sapphirecity_baseboard_lib.sapphirecity_baseboard(sch_1):\DDR4_CHN_K_CTRL\" )
				( netClassRef "@sapphirecity_baseboard_lib.sapphirecity_baseboard(sch_1):\DDR4_CHN_K_DQ_DQS_BYTE2\" )
			)
			( classClass "@crescent_city_bb_fab1_lib.crescent_city_bb_fab1(sch_1):\CC813\"
				( spacingCSetRef "@sapphirecity_baseboard_lib.sapphirecity_baseboard(sch_1):\DQ_TO_DQ\" )
				( netClassRef "@sapphirecity_baseboard_lib.sapphirecity_baseboard(sch_1):\DDR4_CHN_K_DQ_DQS_BYTE0\" )
				( netClassRef "@sapphirecity_baseboard_lib.sapphirecity_baseboard(sch_1):\DDR4_CHN_K_DQ_DQS_BYTE2\" )
			)
			( classClass "@crescent_city_bb_fab1_lib.crescent_city_bb_fab1(sch_1):\CC820\"
				( spacingCSetRef "@sapphirecity_baseboard_lib.sapphirecity_baseboard(sch_1):\DQ_TO_DQ\" )
				( netClassRef "@sapphirecity_baseboard_lib.sapphirecity_baseboard(sch_1):\DDR4_CHN_K_DQ_DQS_BYTE1\" )
				( netClassRef "@sapphirecity_baseboard_lib.sapphirecity_baseboard(sch_1):\DDR4_CHN_K_DQ_DQS_BYTE2\" )
			)
			( classClass "@sapphirecity_baseboard_lib.sapphirecity_baseboard(sch_1):\CC1023\"
				( spacingCSetRef "@sapphirecity_baseboard_lib.sapphirecity_baseboard(sch_1):\DDR4_2SPC_DQ/DQS\" )
				( netClassRef "@sapphirecity_baseboard_lib.sapphirecity_baseboard(sch_1):\DDR4_CHN_K_DQ_DQS_BYTE1\" )
				( netClassRef "@sapphirecity_baseboard_lib.sapphirecity_baseboard(sch_1):\DDR4_CHN_K_DQ_DQS_BYTE1\" )
			)
			( classClass "@crescent_city_bb_fab1_lib.crescent_city_bb_fab1(sch_1):\CC400\"
				( spacingCSetRef "@sapphirecity_baseboard_lib.sapphirecity_baseboard(sch_1):\DQ_TO_DQ\" )
				( netClassRef "@sapphirecity_baseboard_lib.sapphirecity_baseboard(sch_1):\DDR4_CHN_K_CLK\" )
				( netClassRef "@sapphirecity_baseboard_lib.sapphirecity_baseboard(sch_1):\DDR4_CHN_K_DQ_DQS_BYTE1\" )
			)
			( classClass "@crescent_city_bb_fab1_lib.crescent_city_bb_fab1(sch_1):\CC413\"
				( spacingCSetRef "@sapphirecity_baseboard_lib.sapphirecity_baseboard(sch_1):\DQ_TO_DQ\" )
				( netClassRef "@sapphirecity_baseboard_lib.sapphirecity_baseboard(sch_1):\DDR4_CHN_K_CMD_ADD\" )
				( netClassRef "@sapphirecity_baseboard_lib.sapphirecity_baseboard(sch_1):\DDR4_CHN_K_DQ_DQS_BYTE1\" )
			)
			( classClass "@crescent_city_bb_fab1_lib.crescent_city_bb_fab1(sch_1):\CC425\"
				( spacingCSetRef "@sapphirecity_baseboard_lib.sapphirecity_baseboard(sch_1):\DQ_TO_DQ\" )
				( netClassRef "@sapphirecity_baseboard_lib.sapphirecity_baseboard(sch_1):\DDR4_CHN_K_CTRL\" )
				( netClassRef "@sapphirecity_baseboard_lib.sapphirecity_baseboard(sch_1):\DDR4_CHN_K_DQ_DQS_BYTE1\" )
			)
			( classClass "@crescent_city_bb_fab1_lib.crescent_city_bb_fab1(sch_1):\CC812\"
				( spacingCSetRef "@sapphirecity_baseboard_lib.sapphirecity_baseboard(sch_1):\DQ_TO_DQ\" )
				( netClassRef "@sapphirecity_baseboard_lib.sapphirecity_baseboard(sch_1):\DDR4_CHN_K_DQ_DQS_BYTE0\" )
				( netClassRef "@sapphirecity_baseboard_lib.sapphirecity_baseboard(sch_1):\DDR4_CHN_K_DQ_DQS_BYTE1\" )
			)
			( classClass "@sapphirecity_baseboard_lib.sapphirecity_baseboard(sch_1):\CC1022\"
				( spacingCSetRef "@sapphirecity_baseboard_lib.sapphirecity_baseboard(sch_1):\DDR4_2SPC_DQ/DQS\" )
				( netClassRef "@sapphirecity_baseboard_lib.sapphirecity_baseboard(sch_1):\DDR4_CHN_K_DQ_DQS_BYTE0\" )
				( netClassRef "@sapphirecity_baseboard_lib.sapphirecity_baseboard(sch_1):\DDR4_CHN_K_DQ_DQS_BYTE0\" )
			)
			( classClass "@crescent_city_bb_fab1_lib.crescent_city_bb_fab1(sch_1):\CC399\"
				( spacingCSetRef "@sapphirecity_baseboard_lib.sapphirecity_baseboard(sch_1):\DQ_TO_DQ\" )
				( netClassRef "@sapphirecity_baseboard_lib.sapphirecity_baseboard(sch_1):\DDR4_CHN_K_CLK\" )
				( netClassRef "@sapphirecity_baseboard_lib.sapphirecity_baseboard(sch_1):\DDR4_CHN_K_DQ_DQS_BYTE0\" )
			)
			( classClass "@crescent_city_bb_fab1_lib.crescent_city_bb_fab1(sch_1):\CC412\"
				( spacingCSetRef "@sapphirecity_baseboard_lib.sapphirecity_baseboard(sch_1):\DQ_TO_DQ\" )
				( netClassRef "@sapphirecity_baseboard_lib.sapphirecity_baseboard(sch_1):\DDR4_CHN_K_CMD_ADD\" )
				( netClassRef "@sapphirecity_baseboard_lib.sapphirecity_baseboard(sch_1):\DDR4_CHN_K_DQ_DQS_BYTE0\" )
			)
			( classClass "@crescent_city_bb_fab1_lib.crescent_city_bb_fab1(sch_1):\CC424\"
				( spacingCSetRef "@sapphirecity_baseboard_lib.sapphirecity_baseboard(sch_1):\DQ_TO_DQ\" )
				( netClassRef "@sapphirecity_baseboard_lib.sapphirecity_baseboard(sch_1):\DDR4_CHN_K_CTRL\" )
				( netClassRef "@sapphirecity_baseboard_lib.sapphirecity_baseboard(sch_1):\DDR4_CHN_K_DQ_DQS_BYTE0\" )
			)
			( classClass "@sapphirecity_baseboard_lib.sapphirecity_baseboard(sch_1):\CC1038\"
				( spacingCSetRef "@sapphirecity_baseboard_lib.sapphirecity_baseboard(sch_1):\DDR4_2SPC_DQ/DQS\" )
				( netClassRef "@sapphirecity_baseboard_lib.sapphirecity_baseboard(sch_1):\DDR4_CHN_J_DQ_DQS_BYTE7\" )
				( netClassRef "@sapphirecity_baseboard_lib.sapphirecity_baseboard(sch_1):\DDR4_CHN_J_DQ_DQS_BYTE7\" )
			)
			( classClass "@crescent_city_bb_fab1_lib.crescent_city_bb_fab1(sch_1):\CC367\"
				( spacingCSetRef "@sapphirecity_baseboard_lib.sapphirecity_baseboard(sch_1):\DQ_TO_DQ\" )
				( netClassRef "@sapphirecity_baseboard_lib.sapphirecity_baseboard(sch_1):\DDR4_CHN_J_CLK\" )
				( netClassRef "@sapphirecity_baseboard_lib.sapphirecity_baseboard(sch_1):\DDR4_CHN_J_DQ_DQS_BYTE7\" )
			)
			( classClass "@crescent_city_bb_fab1_lib.crescent_city_bb_fab1(sch_1):\CC380\"
				( spacingCSetRef "@sapphirecity_baseboard_lib.sapphirecity_baseboard(sch_1):\DQ_TO_DQ\" )
				( netClassRef "@sapphirecity_baseboard_lib.sapphirecity_baseboard(sch_1):\DDR4_CHN_J_CMD_ADD\" )
				( netClassRef "@sapphirecity_baseboard_lib.sapphirecity_baseboard(sch_1):\DDR4_CHN_J_DQ_DQS_BYTE7\" )
			)
			( classClass "@crescent_city_bb_fab1_lib.crescent_city_bb_fab1(sch_1):\CC392\"
				( spacingCSetRef "@sapphirecity_baseboard_lib.sapphirecity_baseboard(sch_1):\DQ_TO_DQ\" )
				( netClassRef "@sapphirecity_baseboard_lib.sapphirecity_baseboard(sch_1):\DDR4_CHN_J_CTRL\" )
				( netClassRef "@sapphirecity_baseboard_lib.sapphirecity_baseboard(sch_1):\DDR4_CHN_J_DQ_DQS_BYTE7\" )
			)
			( classClass "@crescent_city_bb_fab1_lib.crescent_city_bb_fab1(sch_1):\CC782\"
				( spacingCSetRef "@sapphirecity_baseboard_lib.sapphirecity_baseboard(sch_1):\DQ_TO_DQ\" )
				( netClassRef "@sapphirecity_baseboard_lib.sapphirecity_baseboard(sch_1):\DDR4_CHN_J_DQ_DQS_BYTE0\" )
				( netClassRef "@sapphirecity_baseboard_lib.sapphirecity_baseboard(sch_1):\DDR4_CHN_J_DQ_DQS_BYTE7\" )
			)
			( classClass "@crescent_city_bb_fab1_lib.crescent_city_bb_fab1(sch_1):\CC789\"
				( spacingCSetRef "@sapphirecity_baseboard_lib.sapphirecity_baseboard(sch_1):\DQ_TO_DQ\" )
				( netClassRef "@sapphirecity_baseboard_lib.sapphirecity_baseboard(sch_1):\DDR4_CHN_J_DQ_DQS_BYTE1\" )
				( netClassRef "@sapphirecity_baseboard_lib.sapphirecity_baseboard(sch_1):\DDR4_CHN_J_DQ_DQS_BYTE7\" )
			)
			( classClass "@crescent_city_bb_fab1_lib.crescent_city_bb_fab1(sch_1):\CC795\"
				( spacingCSetRef "@sapphirecity_baseboard_lib.sapphirecity_baseboard(sch_1):\DQ_TO_DQ\" )
				( netClassRef "@sapphirecity_baseboard_lib.sapphirecity_baseboard(sch_1):\DDR4_CHN_J_DQ_DQS_BYTE2\" )
				( netClassRef "@sapphirecity_baseboard_lib.sapphirecity_baseboard(sch_1):\DDR4_CHN_J_DQ_DQS_BYTE7\" )
			)
			( classClass "@crescent_city_bb_fab1_lib.crescent_city_bb_fab1(sch_1):\CC800\"
				( spacingCSetRef "@sapphirecity_baseboard_lib.sapphirecity_baseboard(sch_1):\DQ_TO_DQ\" )
				( netClassRef "@sapphirecity_baseboard_lib.sapphirecity_baseboard(sch_1):\DDR4_CHN_J_DQ_DQS_BYTE3\" )
				( netClassRef "@sapphirecity_baseboard_lib.sapphirecity_baseboard(sch_1):\DDR4_CHN_J_DQ_DQS_BYTE7\" )
			)
			( classClass "@crescent_city_bb_fab1_lib.crescent_city_bb_fab1(sch_1):\CC804\"
				( spacingCSetRef "@sapphirecity_baseboard_lib.sapphirecity_baseboard(sch_1):\DQ_TO_DQ\" )
				( netClassRef "@sapphirecity_baseboard_lib.sapphirecity_baseboard(sch_1):\DDR4_CHN_J_DQ_DQS_BYTE4\" )
				( netClassRef "@sapphirecity_baseboard_lib.sapphirecity_baseboard(sch_1):\DDR4_CHN_J_DQ_DQS_BYTE7\" )
			)
			( classClass "@crescent_city_bb_fab1_lib.crescent_city_bb_fab1(sch_1):\CC807\"
				( spacingCSetRef "@sapphirecity_baseboard_lib.sapphirecity_baseboard(sch_1):\DQ_TO_DQ\" )
				( netClassRef "@sapphirecity_baseboard_lib.sapphirecity_baseboard(sch_1):\DDR4_CHN_J_DQ_DQS_BYTE5\" )
				( netClassRef "@sapphirecity_baseboard_lib.sapphirecity_baseboard(sch_1):\DDR4_CHN_J_DQ_DQS_BYTE7\" )
			)
			( classClass "@crescent_city_bb_fab1_lib.crescent_city_bb_fab1(sch_1):\CC809\"
				( spacingCSetRef "@sapphirecity_baseboard_lib.sapphirecity_baseboard(sch_1):\DQ_TO_DQ\" )
				( netClassRef "@sapphirecity_baseboard_lib.sapphirecity_baseboard(sch_1):\DDR4_CHN_J_DQ_DQS_BYTE6\" )
				( netClassRef "@sapphirecity_baseboard_lib.sapphirecity_baseboard(sch_1):\DDR4_CHN_J_DQ_DQS_BYTE7\" )
			)
			( classClass "@sapphirecity_baseboard_lib.sapphirecity_baseboard(sch_1):\CC1037\"
				( spacingCSetRef "@sapphirecity_baseboard_lib.sapphirecity_baseboard(sch_1):\DDR4_2SPC_DQ/DQS\" )
				( netClassRef "@sapphirecity_baseboard_lib.sapphirecity_baseboard(sch_1):\DDR4_CHN_J_DQ_DQS_BYTE6\" )
				( netClassRef "@sapphirecity_baseboard_lib.sapphirecity_baseboard(sch_1):\DDR4_CHN_J_DQ_DQS_BYTE6\" )
			)
			( classClass "@crescent_city_bb_fab1_lib.crescent_city_bb_fab1(sch_1):\CC366\"
				( spacingCSetRef "@sapphirecity_baseboard_lib.sapphirecity_baseboard(sch_1):\DQ_TO_DQ\" )
				( netClassRef "@sapphirecity_baseboard_lib.sapphirecity_baseboard(sch_1):\DDR4_CHN_J_CLK\" )
				( netClassRef "@sapphirecity_baseboard_lib.sapphirecity_baseboard(sch_1):\DDR4_CHN_J_DQ_DQS_BYTE6\" )
			)
			( classClass "@crescent_city_bb_fab1_lib.crescent_city_bb_fab1(sch_1):\CC379\"
				( spacingCSetRef "@sapphirecity_baseboard_lib.sapphirecity_baseboard(sch_1):\DQ_TO_DQ\" )
				( netClassRef "@sapphirecity_baseboard_lib.sapphirecity_baseboard(sch_1):\DDR4_CHN_J_CMD_ADD\" )
				( netClassRef "@sapphirecity_baseboard_lib.sapphirecity_baseboard(sch_1):\DDR4_CHN_J_DQ_DQS_BYTE6\" )
			)
			( classClass "@crescent_city_bb_fab1_lib.crescent_city_bb_fab1(sch_1):\CC391\"
				( spacingCSetRef "@sapphirecity_baseboard_lib.sapphirecity_baseboard(sch_1):\DQ_TO_DQ\" )
				( netClassRef "@sapphirecity_baseboard_lib.sapphirecity_baseboard(sch_1):\DDR4_CHN_J_CTRL\" )
				( netClassRef "@sapphirecity_baseboard_lib.sapphirecity_baseboard(sch_1):\DDR4_CHN_J_DQ_DQS_BYTE6\" )
			)
			( classClass "@crescent_city_bb_fab1_lib.crescent_city_bb_fab1(sch_1):\CC781\"
				( spacingCSetRef "@sapphirecity_baseboard_lib.sapphirecity_baseboard(sch_1):\DQ_TO_DQ\" )
				( netClassRef "@sapphirecity_baseboard_lib.sapphirecity_baseboard(sch_1):\DDR4_CHN_J_DQ_DQS_BYTE0\" )
				( netClassRef "@sapphirecity_baseboard_lib.sapphirecity_baseboard(sch_1):\DDR4_CHN_J_DQ_DQS_BYTE6\" )
			)
			( classClass "@crescent_city_bb_fab1_lib.crescent_city_bb_fab1(sch_1):\CC788\"
				( spacingCSetRef "@sapphirecity_baseboard_lib.sapphirecity_baseboard(sch_1):\DQ_TO_DQ\" )
				( netClassRef "@sapphirecity_baseboard_lib.sapphirecity_baseboard(sch_1):\DDR4_CHN_J_DQ_DQS_BYTE1\" )
				( netClassRef "@sapphirecity_baseboard_lib.sapphirecity_baseboard(sch_1):\DDR4_CHN_J_DQ_DQS_BYTE6\" )
			)
			( classClass "@crescent_city_bb_fab1_lib.crescent_city_bb_fab1(sch_1):\CC794\"
				( spacingCSetRef "@sapphirecity_baseboard_lib.sapphirecity_baseboard(sch_1):\DQ_TO_DQ\" )
				( netClassRef "@sapphirecity_baseboard_lib.sapphirecity_baseboard(sch_1):\DDR4_CHN_J_DQ_DQS_BYTE2\" )
				( netClassRef "@sapphirecity_baseboard_lib.sapphirecity_baseboard(sch_1):\DDR4_CHN_J_DQ_DQS_BYTE6\" )
			)
			( classClass "@crescent_city_bb_fab1_lib.crescent_city_bb_fab1(sch_1):\CC799\"
				( spacingCSetRef "@sapphirecity_baseboard_lib.sapphirecity_baseboard(sch_1):\DQ_TO_DQ\" )
				( netClassRef "@sapphirecity_baseboard_lib.sapphirecity_baseboard(sch_1):\DDR4_CHN_J_DQ_DQS_BYTE3\" )
				( netClassRef "@sapphirecity_baseboard_lib.sapphirecity_baseboard(sch_1):\DDR4_CHN_J_DQ_DQS_BYTE6\" )
			)
			( classClass "@crescent_city_bb_fab1_lib.crescent_city_bb_fab1(sch_1):\CC803\"
				( spacingCSetRef "@sapphirecity_baseboard_lib.sapphirecity_baseboard(sch_1):\DQ_TO_DQ\" )
				( netClassRef "@sapphirecity_baseboard_lib.sapphirecity_baseboard(sch_1):\DDR4_CHN_J_DQ_DQS_BYTE4\" )
				( netClassRef "@sapphirecity_baseboard_lib.sapphirecity_baseboard(sch_1):\DDR4_CHN_J_DQ_DQS_BYTE6\" )
			)
			( classClass "@crescent_city_bb_fab1_lib.crescent_city_bb_fab1(sch_1):\CC806\"
				( spacingCSetRef "@sapphirecity_baseboard_lib.sapphirecity_baseboard(sch_1):\DQ_TO_DQ\" )
				( netClassRef "@sapphirecity_baseboard_lib.sapphirecity_baseboard(sch_1):\DDR4_CHN_J_DQ_DQS_BYTE5\" )
				( netClassRef "@sapphirecity_baseboard_lib.sapphirecity_baseboard(sch_1):\DDR4_CHN_J_DQ_DQS_BYTE6\" )
			)
			( classClass "@sapphirecity_baseboard_lib.sapphirecity_baseboard(sch_1):\CC1036\"
				( spacingCSetRef "@sapphirecity_baseboard_lib.sapphirecity_baseboard(sch_1):\DDR4_2SPC_DQ/DQS\" )
				( netClassRef "@sapphirecity_baseboard_lib.sapphirecity_baseboard(sch_1):\DDR4_CHN_J_DQ_DQS_BYTE5\" )
				( netClassRef "@sapphirecity_baseboard_lib.sapphirecity_baseboard(sch_1):\DDR4_CHN_J_DQ_DQS_BYTE5\" )
			)
			( classClass "@crescent_city_bb_fab1_lib.crescent_city_bb_fab1(sch_1):\CC365\"
				( spacingCSetRef "@sapphirecity_baseboard_lib.sapphirecity_baseboard(sch_1):\DQ_TO_DQ\" )
				( netClassRef "@sapphirecity_baseboard_lib.sapphirecity_baseboard(sch_1):\DDR4_CHN_J_CLK\" )
				( netClassRef "@sapphirecity_baseboard_lib.sapphirecity_baseboard(sch_1):\DDR4_CHN_J_DQ_DQS_BYTE5\" )
			)
			( classClass "@crescent_city_bb_fab1_lib.crescent_city_bb_fab1(sch_1):\CC378\"
				( spacingCSetRef "@sapphirecity_baseboard_lib.sapphirecity_baseboard(sch_1):\DQ_TO_DQ\" )
				( netClassRef "@sapphirecity_baseboard_lib.sapphirecity_baseboard(sch_1):\DDR4_CHN_J_CMD_ADD\" )
				( netClassRef "@sapphirecity_baseboard_lib.sapphirecity_baseboard(sch_1):\DDR4_CHN_J_DQ_DQS_BYTE5\" )
			)
			( classClass "@crescent_city_bb_fab1_lib.crescent_city_bb_fab1(sch_1):\CC390\"
				( spacingCSetRef "@sapphirecity_baseboard_lib.sapphirecity_baseboard(sch_1):\DQ_TO_DQ\" )
				( netClassRef "@sapphirecity_baseboard_lib.sapphirecity_baseboard(sch_1):\DDR4_CHN_J_CTRL\" )
				( netClassRef "@sapphirecity_baseboard_lib.sapphirecity_baseboard(sch_1):\DDR4_CHN_J_DQ_DQS_BYTE5\" )
			)
			( classClass "@crescent_city_bb_fab1_lib.crescent_city_bb_fab1(sch_1):\CC780\"
				( spacingCSetRef "@sapphirecity_baseboard_lib.sapphirecity_baseboard(sch_1):\DQ_TO_DQ\" )
				( netClassRef "@sapphirecity_baseboard_lib.sapphirecity_baseboard(sch_1):\DDR4_CHN_J_DQ_DQS_BYTE0\" )
				( netClassRef "@sapphirecity_baseboard_lib.sapphirecity_baseboard(sch_1):\DDR4_CHN_J_DQ_DQS_BYTE5\" )
			)
			( classClass "@crescent_city_bb_fab1_lib.crescent_city_bb_fab1(sch_1):\CC787\"
				( spacingCSetRef "@sapphirecity_baseboard_lib.sapphirecity_baseboard(sch_1):\DQ_TO_DQ\" )
				( netClassRef "@sapphirecity_baseboard_lib.sapphirecity_baseboard(sch_1):\DDR4_CHN_J_DQ_DQS_BYTE1\" )
				( netClassRef "@sapphirecity_baseboard_lib.sapphirecity_baseboard(sch_1):\DDR4_CHN_J_DQ_DQS_BYTE5\" )
			)
			( classClass "@crescent_city_bb_fab1_lib.crescent_city_bb_fab1(sch_1):\CC793\"
				( spacingCSetRef "@sapphirecity_baseboard_lib.sapphirecity_baseboard(sch_1):\DQ_TO_DQ\" )
				( netClassRef "@sapphirecity_baseboard_lib.sapphirecity_baseboard(sch_1):\DDR4_CHN_J_DQ_DQS_BYTE2\" )
				( netClassRef "@sapphirecity_baseboard_lib.sapphirecity_baseboard(sch_1):\DDR4_CHN_J_DQ_DQS_BYTE5\" )
			)
			( classClass "@crescent_city_bb_fab1_lib.crescent_city_bb_fab1(sch_1):\CC798\"
				( spacingCSetRef "@sapphirecity_baseboard_lib.sapphirecity_baseboard(sch_1):\DQ_TO_DQ\" )
				( netClassRef "@sapphirecity_baseboard_lib.sapphirecity_baseboard(sch_1):\DDR4_CHN_J_DQ_DQS_BYTE3\" )
				( netClassRef "@sapphirecity_baseboard_lib.sapphirecity_baseboard(sch_1):\DDR4_CHN_J_DQ_DQS_BYTE5\" )
			)
			( classClass "@crescent_city_bb_fab1_lib.crescent_city_bb_fab1(sch_1):\CC802\"
				( spacingCSetRef "@sapphirecity_baseboard_lib.sapphirecity_baseboard(sch_1):\DQ_TO_DQ\" )
				( netClassRef "@sapphirecity_baseboard_lib.sapphirecity_baseboard(sch_1):\DDR4_CHN_J_DQ_DQS_BYTE4\" )
				( netClassRef "@sapphirecity_baseboard_lib.sapphirecity_baseboard(sch_1):\DDR4_CHN_J_DQ_DQS_BYTE5\" )
			)
			( classClass "@sapphirecity_baseboard_lib.sapphirecity_baseboard(sch_1):\CC1035\"
				( spacingCSetRef "@sapphirecity_baseboard_lib.sapphirecity_baseboard(sch_1):\DDR4_2SPC_DQ/DQS\" )
				( netClassRef "@sapphirecity_baseboard_lib.sapphirecity_baseboard(sch_1):\DDR4_CHN_J_DQ_DQS_BYTE4\" )
				( netClassRef "@sapphirecity_baseboard_lib.sapphirecity_baseboard(sch_1):\DDR4_CHN_J_DQ_DQS_BYTE4\" )
			)
			( classClass "@crescent_city_bb_fab1_lib.crescent_city_bb_fab1(sch_1):\CC364\"
				( spacingCSetRef "@sapphirecity_baseboard_lib.sapphirecity_baseboard(sch_1):\DQ_TO_DQ\" )
				( netClassRef "@sapphirecity_baseboard_lib.sapphirecity_baseboard(sch_1):\DDR4_CHN_J_CLK\" )
				( netClassRef "@sapphirecity_baseboard_lib.sapphirecity_baseboard(sch_1):\DDR4_CHN_J_DQ_DQS_BYTE4\" )
			)
			( classClass "@crescent_city_bb_fab1_lib.crescent_city_bb_fab1(sch_1):\CC377\"
				( spacingCSetRef "@sapphirecity_baseboard_lib.sapphirecity_baseboard(sch_1):\DQ_TO_DQ\" )
				( netClassRef "@sapphirecity_baseboard_lib.sapphirecity_baseboard(sch_1):\DDR4_CHN_J_CMD_ADD\" )
				( netClassRef "@sapphirecity_baseboard_lib.sapphirecity_baseboard(sch_1):\DDR4_CHN_J_DQ_DQS_BYTE4\" )
			)
			( classClass "@crescent_city_bb_fab1_lib.crescent_city_bb_fab1(sch_1):\CC389\"
				( spacingCSetRef "@sapphirecity_baseboard_lib.sapphirecity_baseboard(sch_1):\DQ_TO_DQ\" )
				( netClassRef "@sapphirecity_baseboard_lib.sapphirecity_baseboard(sch_1):\DDR4_CHN_J_CTRL\" )
				( netClassRef "@sapphirecity_baseboard_lib.sapphirecity_baseboard(sch_1):\DDR4_CHN_J_DQ_DQS_BYTE4\" )
			)
			( classClass "@crescent_city_bb_fab1_lib.crescent_city_bb_fab1(sch_1):\CC779\"
				( spacingCSetRef "@sapphirecity_baseboard_lib.sapphirecity_baseboard(sch_1):\DQ_TO_DQ\" )
				( netClassRef "@sapphirecity_baseboard_lib.sapphirecity_baseboard(sch_1):\DDR4_CHN_J_DQ_DQS_BYTE0\" )
				( netClassRef "@sapphirecity_baseboard_lib.sapphirecity_baseboard(sch_1):\DDR4_CHN_J_DQ_DQS_BYTE4\" )
			)
			( classClass "@crescent_city_bb_fab1_lib.crescent_city_bb_fab1(sch_1):\CC786\"
				( spacingCSetRef "@sapphirecity_baseboard_lib.sapphirecity_baseboard(sch_1):\DQ_TO_DQ\" )
				( netClassRef "@sapphirecity_baseboard_lib.sapphirecity_baseboard(sch_1):\DDR4_CHN_J_DQ_DQS_BYTE1\" )
				( netClassRef "@sapphirecity_baseboard_lib.sapphirecity_baseboard(sch_1):\DDR4_CHN_J_DQ_DQS_BYTE4\" )
			)
			( classClass "@crescent_city_bb_fab1_lib.crescent_city_bb_fab1(sch_1):\CC792\"
				( spacingCSetRef "@sapphirecity_baseboard_lib.sapphirecity_baseboard(sch_1):\DQ_TO_DQ\" )
				( netClassRef "@sapphirecity_baseboard_lib.sapphirecity_baseboard(sch_1):\DDR4_CHN_J_DQ_DQS_BYTE2\" )
				( netClassRef "@sapphirecity_baseboard_lib.sapphirecity_baseboard(sch_1):\DDR4_CHN_J_DQ_DQS_BYTE4\" )
			)
			( classClass "@crescent_city_bb_fab1_lib.crescent_city_bb_fab1(sch_1):\CC797\"
				( spacingCSetRef "@sapphirecity_baseboard_lib.sapphirecity_baseboard(sch_1):\DQ_TO_DQ\" )
				( netClassRef "@sapphirecity_baseboard_lib.sapphirecity_baseboard(sch_1):\DDR4_CHN_J_DQ_DQS_BYTE3\" )
				( netClassRef "@sapphirecity_baseboard_lib.sapphirecity_baseboard(sch_1):\DDR4_CHN_J_DQ_DQS_BYTE4\" )
			)
			( classClass "@sapphirecity_baseboard_lib.sapphirecity_baseboard(sch_1):\CC1034\"
				( spacingCSetRef "@sapphirecity_baseboard_lib.sapphirecity_baseboard(sch_1):\DDR4_2SPC_DQ/DQS\" )
				( netClassRef "@sapphirecity_baseboard_lib.sapphirecity_baseboard(sch_1):\DDR4_CHN_J_DQ_DQS_BYTE3\" )
				( netClassRef "@sapphirecity_baseboard_lib.sapphirecity_baseboard(sch_1):\DDR4_CHN_J_DQ_DQS_BYTE3\" )
			)
			( classClass "@crescent_city_bb_fab1_lib.crescent_city_bb_fab1(sch_1):\CC363\"
				( spacingCSetRef "@sapphirecity_baseboard_lib.sapphirecity_baseboard(sch_1):\DQ_TO_DQ\" )
				( netClassRef "@sapphirecity_baseboard_lib.sapphirecity_baseboard(sch_1):\DDR4_CHN_J_CLK\" )
				( netClassRef "@sapphirecity_baseboard_lib.sapphirecity_baseboard(sch_1):\DDR4_CHN_J_DQ_DQS_BYTE3\" )
			)
			( classClass "@crescent_city_bb_fab1_lib.crescent_city_bb_fab1(sch_1):\CC376\"
				( spacingCSetRef "@sapphirecity_baseboard_lib.sapphirecity_baseboard(sch_1):\DQ_TO_DQ\" )
				( netClassRef "@sapphirecity_baseboard_lib.sapphirecity_baseboard(sch_1):\DDR4_CHN_J_CMD_ADD\" )
				( netClassRef "@sapphirecity_baseboard_lib.sapphirecity_baseboard(sch_1):\DDR4_CHN_J_DQ_DQS_BYTE3\" )
			)
			( classClass "@crescent_city_bb_fab1_lib.crescent_city_bb_fab1(sch_1):\CC388\"
				( spacingCSetRef "@sapphirecity_baseboard_lib.sapphirecity_baseboard(sch_1):\DQ_TO_DQ\" )
				( netClassRef "@sapphirecity_baseboard_lib.sapphirecity_baseboard(sch_1):\DDR4_CHN_J_CTRL\" )
				( netClassRef "@sapphirecity_baseboard_lib.sapphirecity_baseboard(sch_1):\DDR4_CHN_J_DQ_DQS_BYTE3\" )
			)
			( classClass "@crescent_city_bb_fab1_lib.crescent_city_bb_fab1(sch_1):\CC778\"
				( spacingCSetRef "@sapphirecity_baseboard_lib.sapphirecity_baseboard(sch_1):\DQ_TO_DQ\" )
				( netClassRef "@sapphirecity_baseboard_lib.sapphirecity_baseboard(sch_1):\DDR4_CHN_J_DQ_DQS_BYTE0\" )
				( netClassRef "@sapphirecity_baseboard_lib.sapphirecity_baseboard(sch_1):\DDR4_CHN_J_DQ_DQS_BYTE3\" )
			)
			( classClass "@crescent_city_bb_fab1_lib.crescent_city_bb_fab1(sch_1):\CC785\"
				( spacingCSetRef "@sapphirecity_baseboard_lib.sapphirecity_baseboard(sch_1):\DQ_TO_DQ\" )
				( netClassRef "@sapphirecity_baseboard_lib.sapphirecity_baseboard(sch_1):\DDR4_CHN_J_DQ_DQS_BYTE1\" )
				( netClassRef "@sapphirecity_baseboard_lib.sapphirecity_baseboard(sch_1):\DDR4_CHN_J_DQ_DQS_BYTE3\" )
			)
			( classClass "@crescent_city_bb_fab1_lib.crescent_city_bb_fab1(sch_1):\CC791\"
				( spacingCSetRef "@sapphirecity_baseboard_lib.sapphirecity_baseboard(sch_1):\DQ_TO_DQ\" )
				( netClassRef "@sapphirecity_baseboard_lib.sapphirecity_baseboard(sch_1):\DDR4_CHN_J_DQ_DQS_BYTE2\" )
				( netClassRef "@sapphirecity_baseboard_lib.sapphirecity_baseboard(sch_1):\DDR4_CHN_J_DQ_DQS_BYTE3\" )
			)
			( classClass "@sapphirecity_baseboard_lib.sapphirecity_baseboard(sch_1):\CC1033\"
				( spacingCSetRef "@sapphirecity_baseboard_lib.sapphirecity_baseboard(sch_1):\DDR4_2SPC_DQ/DQS\" )
				( netClassRef "@sapphirecity_baseboard_lib.sapphirecity_baseboard(sch_1):\DDR4_CHN_J_DQ_DQS_BYTE2\" )
				( netClassRef "@sapphirecity_baseboard_lib.sapphirecity_baseboard(sch_1):\DDR4_CHN_J_DQ_DQS_BYTE2\" )
			)
			( classClass "@crescent_city_bb_fab1_lib.crescent_city_bb_fab1(sch_1):\CC362\"
				( spacingCSetRef "@sapphirecity_baseboard_lib.sapphirecity_baseboard(sch_1):\DQ_TO_DQ\" )
				( netClassRef "@sapphirecity_baseboard_lib.sapphirecity_baseboard(sch_1):\DDR4_CHN_J_CLK\" )
				( netClassRef "@sapphirecity_baseboard_lib.sapphirecity_baseboard(sch_1):\DDR4_CHN_J_DQ_DQS_BYTE2\" )
			)
			( classClass "@crescent_city_bb_fab1_lib.crescent_city_bb_fab1(sch_1):\CC375\"
				( spacingCSetRef "@sapphirecity_baseboard_lib.sapphirecity_baseboard(sch_1):\DQ_TO_DQ\" )
				( netClassRef "@sapphirecity_baseboard_lib.sapphirecity_baseboard(sch_1):\DDR4_CHN_J_CMD_ADD\" )
				( netClassRef "@sapphirecity_baseboard_lib.sapphirecity_baseboard(sch_1):\DDR4_CHN_J_DQ_DQS_BYTE2\" )
			)
			( classClass "@crescent_city_bb_fab1_lib.crescent_city_bb_fab1(sch_1):\CC387\"
				( spacingCSetRef "@sapphirecity_baseboard_lib.sapphirecity_baseboard(sch_1):\DQ_TO_DQ\" )
				( netClassRef "@sapphirecity_baseboard_lib.sapphirecity_baseboard(sch_1):\DDR4_CHN_J_CTRL\" )
				( netClassRef "@sapphirecity_baseboard_lib.sapphirecity_baseboard(sch_1):\DDR4_CHN_J_DQ_DQS_BYTE2\" )
			)
			( classClass "@crescent_city_bb_fab1_lib.crescent_city_bb_fab1(sch_1):\CC777\"
				( spacingCSetRef "@sapphirecity_baseboard_lib.sapphirecity_baseboard(sch_1):\DQ_TO_DQ\" )
				( netClassRef "@sapphirecity_baseboard_lib.sapphirecity_baseboard(sch_1):\DDR4_CHN_J_DQ_DQS_BYTE0\" )
				( netClassRef "@sapphirecity_baseboard_lib.sapphirecity_baseboard(sch_1):\DDR4_CHN_J_DQ_DQS_BYTE2\" )
			)
			( classClass "@crescent_city_bb_fab1_lib.crescent_city_bb_fab1(sch_1):\CC784\"
				( spacingCSetRef "@sapphirecity_baseboard_lib.sapphirecity_baseboard(sch_1):\DQ_TO_DQ\" )
				( netClassRef "@sapphirecity_baseboard_lib.sapphirecity_baseboard(sch_1):\DDR4_CHN_J_DQ_DQS_BYTE1\" )
				( netClassRef "@sapphirecity_baseboard_lib.sapphirecity_baseboard(sch_1):\DDR4_CHN_J_DQ_DQS_BYTE2\" )
			)
			( classClass "@sapphirecity_baseboard_lib.sapphirecity_baseboard(sch_1):\CC1032\"
				( spacingCSetRef "@sapphirecity_baseboard_lib.sapphirecity_baseboard(sch_1):\DDR4_2SPC_DQ/DQS\" )
				( netClassRef "@sapphirecity_baseboard_lib.sapphirecity_baseboard(sch_1):\DDR4_CHN_J_DQ_DQS_BYTE1\" )
				( netClassRef "@sapphirecity_baseboard_lib.sapphirecity_baseboard(sch_1):\DDR4_CHN_J_DQ_DQS_BYTE1\" )
			)
			( classClass "@crescent_city_bb_fab1_lib.crescent_city_bb_fab1(sch_1):\CC361\"
				( spacingCSetRef "@sapphirecity_baseboard_lib.sapphirecity_baseboard(sch_1):\DQ_TO_DQ\" )
				( netClassRef "@sapphirecity_baseboard_lib.sapphirecity_baseboard(sch_1):\DDR4_CHN_J_CLK\" )
				( netClassRef "@sapphirecity_baseboard_lib.sapphirecity_baseboard(sch_1):\DDR4_CHN_J_DQ_DQS_BYTE1\" )
			)
			( classClass "@crescent_city_bb_fab1_lib.crescent_city_bb_fab1(sch_1):\CC374\"
				( spacingCSetRef "@sapphirecity_baseboard_lib.sapphirecity_baseboard(sch_1):\DQ_TO_DQ\" )
				( netClassRef "@sapphirecity_baseboard_lib.sapphirecity_baseboard(sch_1):\DDR4_CHN_J_CMD_ADD\" )
				( netClassRef "@sapphirecity_baseboard_lib.sapphirecity_baseboard(sch_1):\DDR4_CHN_J_DQ_DQS_BYTE1\" )
			)
			( classClass "@crescent_city_bb_fab1_lib.crescent_city_bb_fab1(sch_1):\CC386\"
				( spacingCSetRef "@sapphirecity_baseboard_lib.sapphirecity_baseboard(sch_1):\DQ_TO_DQ\" )
				( netClassRef "@sapphirecity_baseboard_lib.sapphirecity_baseboard(sch_1):\DDR4_CHN_J_CTRL\" )
				( netClassRef "@sapphirecity_baseboard_lib.sapphirecity_baseboard(sch_1):\DDR4_CHN_J_DQ_DQS_BYTE1\" )
			)
			( classClass "@crescent_city_bb_fab1_lib.crescent_city_bb_fab1(sch_1):\CC776\"
				( spacingCSetRef "@sapphirecity_baseboard_lib.sapphirecity_baseboard(sch_1):\DQ_TO_DQ\" )
				( netClassRef "@sapphirecity_baseboard_lib.sapphirecity_baseboard(sch_1):\DDR4_CHN_J_DQ_DQS_BYTE0\" )
				( netClassRef "@sapphirecity_baseboard_lib.sapphirecity_baseboard(sch_1):\DDR4_CHN_J_DQ_DQS_BYTE1\" )
			)
			( classClass "@sapphirecity_baseboard_lib.sapphirecity_baseboard(sch_1):\CC1031\"
				( spacingCSetRef "@sapphirecity_baseboard_lib.sapphirecity_baseboard(sch_1):\DDR4_2SPC_DQ/DQS\" )
				( netClassRef "@sapphirecity_baseboard_lib.sapphirecity_baseboard(sch_1):\DDR4_CHN_J_DQ_DQS_BYTE0\" )
				( netClassRef "@sapphirecity_baseboard_lib.sapphirecity_baseboard(sch_1):\DDR4_CHN_J_DQ_DQS_BYTE0\" )
			)
			( classClass "@crescent_city_bb_fab1_lib.crescent_city_bb_fab1(sch_1):\CC360\"
				( spacingCSetRef "@sapphirecity_baseboard_lib.sapphirecity_baseboard(sch_1):\DQ_TO_DQ\" )
				( netClassRef "@sapphirecity_baseboard_lib.sapphirecity_baseboard(sch_1):\DDR4_CHN_J_CLK\" )
				( netClassRef "@sapphirecity_baseboard_lib.sapphirecity_baseboard(sch_1):\DDR4_CHN_J_DQ_DQS_BYTE0\" )
			)
			( classClass "@crescent_city_bb_fab1_lib.crescent_city_bb_fab1(sch_1):\CC373\"
				( spacingCSetRef "@sapphirecity_baseboard_lib.sapphirecity_baseboard(sch_1):\DQ_TO_DQ\" )
				( netClassRef "@sapphirecity_baseboard_lib.sapphirecity_baseboard(sch_1):\DDR4_CHN_J_CMD_ADD\" )
				( netClassRef "@sapphirecity_baseboard_lib.sapphirecity_baseboard(sch_1):\DDR4_CHN_J_DQ_DQS_BYTE0\" )
			)
			( classClass "@crescent_city_bb_fab1_lib.crescent_city_bb_fab1(sch_1):\CC385\"
				( spacingCSetRef "@sapphirecity_baseboard_lib.sapphirecity_baseboard(sch_1):\DQ_TO_DQ\" )
				( netClassRef "@sapphirecity_baseboard_lib.sapphirecity_baseboard(sch_1):\DDR4_CHN_J_CTRL\" )
				( netClassRef "@sapphirecity_baseboard_lib.sapphirecity_baseboard(sch_1):\DDR4_CHN_J_DQ_DQS_BYTE0\" )
			)
			( classClass "@crescent_city_bb_fab1_lib.crescent_city_bb_fab1(sch_1):\CC357\"
				( spacingCSetRef "@sapphirecity_baseboard_lib.sapphirecity_baseboard(sch_1):\DDR4_2SPC_CAC\" )
				( netClassRef "@sapphirecity_baseboard_lib.sapphirecity_baseboard(sch_1):\DDR4_CHN_J_CLK\" )
				( netClassRef "@sapphirecity_baseboard_lib.sapphirecity_baseboard(sch_1):\DDR4_CHN_J_CLK\" )
			)
			( classClass "@crescent_city_bb_fab1_lib.crescent_city_bb_fab1(sch_1):\CC358\"
				( spacingCSetRef "@sapphirecity_baseboard_lib.sapphirecity_baseboard(sch_1):\DDR4_2SPC_CAC\" )
				( netClassRef "@sapphirecity_baseboard_lib.sapphirecity_baseboard(sch_1):\DDR4_CHN_J_CLK\" )
				( netClassRef "@sapphirecity_baseboard_lib.sapphirecity_baseboard(sch_1):\DDR4_CHN_J_CMD_ADD\" )
			)
			( classClass "@crescent_city_bb_fab1_lib.crescent_city_bb_fab1(sch_1):\CC359\"
				( spacingCSetRef "@sapphirecity_baseboard_lib.sapphirecity_baseboard(sch_1):\DDR4_2SPC_CAC\" )
				( netClassRef "@sapphirecity_baseboard_lib.sapphirecity_baseboard(sch_1):\DDR4_CHN_J_CLK\" )
				( netClassRef "@sapphirecity_baseboard_lib.sapphirecity_baseboard(sch_1):\DDR4_CHN_J_CTRL\" )
			)
			( classClass "@crescent_city_bb_fab1_lib.crescent_city_bb_fab1(sch_1):\CC396\"
				( spacingCSetRef "@sapphirecity_baseboard_lib.sapphirecity_baseboard(sch_1):\DDR4_2SPC_CAC\" )
				( netClassRef "@sapphirecity_baseboard_lib.sapphirecity_baseboard(sch_1):\DDR4_CHN_K_CLK\" )
				( netClassRef "@sapphirecity_baseboard_lib.sapphirecity_baseboard(sch_1):\DDR4_CHN_K_CLK\" )
			)
			( classClass "@crescent_city_bb_fab1_lib.crescent_city_bb_fab1(sch_1):\CC397\"
				( spacingCSetRef "@sapphirecity_baseboard_lib.sapphirecity_baseboard(sch_1):\DDR4_2SPC_CAC\" )
				( netClassRef "@sapphirecity_baseboard_lib.sapphirecity_baseboard(sch_1):\DDR4_CHN_K_CLK\" )
				( netClassRef "@sapphirecity_baseboard_lib.sapphirecity_baseboard(sch_1):\DDR4_CHN_K_CMD_ADD\" )
			)
			( classClass "@crescent_city_bb_fab1_lib.crescent_city_bb_fab1(sch_1):\CC398\"
				( spacingCSetRef "@sapphirecity_baseboard_lib.sapphirecity_baseboard(sch_1):\DDR4_2SPC_CAC\" )
				( netClassRef "@sapphirecity_baseboard_lib.sapphirecity_baseboard(sch_1):\DDR4_CHN_K_CLK\" )
				( netClassRef "@sapphirecity_baseboard_lib.sapphirecity_baseboard(sch_1):\DDR4_CHN_K_CTRL\" )
			)
			( classClass "@crescent_city_bb_fab1_lib.crescent_city_bb_fab1(sch_1):\CC435\"
				( spacingCSetRef "@sapphirecity_baseboard_lib.sapphirecity_baseboard(sch_1):\DDR4_2SPC_CAC\" )
				( netClassRef "@sapphirecity_baseboard_lib.sapphirecity_baseboard(sch_1):\DDR4_CHN_L_CLK\" )
				( netClassRef "@sapphirecity_baseboard_lib.sapphirecity_baseboard(sch_1):\DDR4_CHN_L_CLK\" )
			)
			( classClass "@crescent_city_bb_fab1_lib.crescent_city_bb_fab1(sch_1):\CC436\"
				( spacingCSetRef "@sapphirecity_baseboard_lib.sapphirecity_baseboard(sch_1):\DDR4_2SPC_CAC\" )
				( netClassRef "@sapphirecity_baseboard_lib.sapphirecity_baseboard(sch_1):\DDR4_CHN_L_CLK\" )
				( netClassRef "@sapphirecity_baseboard_lib.sapphirecity_baseboard(sch_1):\DDR4_CHN_L_CMD_ADD\" )
			)
			( classClass "@crescent_city_bb_fab1_lib.crescent_city_bb_fab1(sch_1):\CC437\"
				( spacingCSetRef "@sapphirecity_baseboard_lib.sapphirecity_baseboard(sch_1):\DDR4_2SPC_CAC\" )
				( netClassRef "@sapphirecity_baseboard_lib.sapphirecity_baseboard(sch_1):\DDR4_CHN_L_CLK\" )
				( netClassRef "@sapphirecity_baseboard_lib.sapphirecity_baseboard(sch_1):\DDR4_CHN_L_CTRL\" )
			)
			( classClass "@crescent_city_bb_fab1_lib.crescent_city_bb_fab1(sch_1):\CC474\"
				( spacingCSetRef "@sapphirecity_baseboard_lib.sapphirecity_baseboard(sch_1):\DDR4_2SPC_CAC\" )
				( netClassRef "@sapphirecity_baseboard_lib.sapphirecity_baseboard(sch_1):\DDR4_CHN_M_CLK\" )
				( netClassRef "@sapphirecity_baseboard_lib.sapphirecity_baseboard(sch_1):\DDR4_CHN_M_CLK\" )
			)
			( classClass "@crescent_city_bb_fab1_lib.crescent_city_bb_fab1(sch_1):\CC475\"
				( spacingCSetRef "@sapphirecity_baseboard_lib.sapphirecity_baseboard(sch_1):\DDR4_2SPC_CAC\" )
				( netClassRef "@sapphirecity_baseboard_lib.sapphirecity_baseboard(sch_1):\DDR4_CHN_M_CLK\" )
				( netClassRef "@sapphirecity_baseboard_lib.sapphirecity_baseboard(sch_1):\DDR4_CHN_M_CMD_ADD\" )
			)
			( classClass "@crescent_city_bb_fab1_lib.crescent_city_bb_fab1(sch_1):\CC476\"
				( spacingCSetRef "@sapphirecity_baseboard_lib.sapphirecity_baseboard(sch_1):\DDR4_2SPC_CAC\" )
				( netClassRef "@sapphirecity_baseboard_lib.sapphirecity_baseboard(sch_1):\DDR4_CHN_M_CLK\" )
				( netClassRef "@sapphirecity_baseboard_lib.sapphirecity_baseboard(sch_1):\DDR4_CHN_M_CTRL\" )
			)
			( classClass "@crescent_city_bb_fab1_lib.crescent_city_bb_fab1(sch_1):\CC371\"
				( spacingCSetRef "@sapphirecity_baseboard_lib.sapphirecity_baseboard(sch_1):\DDR4_2SPC_CAC\" )
				( netClassRef "@sapphirecity_baseboard_lib.sapphirecity_baseboard(sch_1):\DDR4_CHN_J_CMD_ADD\" )
				( netClassRef "@sapphirecity_baseboard_lib.sapphirecity_baseboard(sch_1):\DDR4_CHN_J_CMD_ADD\" )
			)
			( classClass "@crescent_city_bb_fab1_lib.crescent_city_bb_fab1(sch_1):\CC372\"
				( spacingCSetRef "@sapphirecity_baseboard_lib.sapphirecity_baseboard(sch_1):\DDR4_2SPC_CAC\" )
				( netClassRef "@sapphirecity_baseboard_lib.sapphirecity_baseboard(sch_1):\DDR4_CHN_J_CMD_ADD\" )
				( netClassRef "@sapphirecity_baseboard_lib.sapphirecity_baseboard(sch_1):\DDR4_CHN_J_CTRL\" )
			)
			( classClass "@crescent_city_bb_fab1_lib.crescent_city_bb_fab1(sch_1):\CC410\"
				( spacingCSetRef "@sapphirecity_baseboard_lib.sapphirecity_baseboard(sch_1):\DDR4_2SPC_CAC\" )
				( netClassRef "@sapphirecity_baseboard_lib.sapphirecity_baseboard(sch_1):\DDR4_CHN_K_CMD_ADD\" )
				( netClassRef "@sapphirecity_baseboard_lib.sapphirecity_baseboard(sch_1):\DDR4_CHN_K_CMD_ADD\" )
			)
			( classClass "@crescent_city_bb_fab1_lib.crescent_city_bb_fab1(sch_1):\CC411\"
				( spacingCSetRef "@sapphirecity_baseboard_lib.sapphirecity_baseboard(sch_1):\DDR4_2SPC_CAC\" )
				( netClassRef "@sapphirecity_baseboard_lib.sapphirecity_baseboard(sch_1):\DDR4_CHN_K_CMD_ADD\" )
				( netClassRef "@sapphirecity_baseboard_lib.sapphirecity_baseboard(sch_1):\DDR4_CHN_K_CTRL\" )
			)
			( classClass "@crescent_city_bb_fab1_lib.crescent_city_bb_fab1(sch_1):\CC449\"
				( spacingCSetRef "@sapphirecity_baseboard_lib.sapphirecity_baseboard(sch_1):\DDR4_2SPC_CAC\" )
				( netClassRef "@sapphirecity_baseboard_lib.sapphirecity_baseboard(sch_1):\DDR4_CHN_L_CMD_ADD\" )
				( netClassRef "@sapphirecity_baseboard_lib.sapphirecity_baseboard(sch_1):\DDR4_CHN_L_CMD_ADD\" )
			)
			( classClass "@crescent_city_bb_fab1_lib.crescent_city_bb_fab1(sch_1):\CC450\"
				( spacingCSetRef "@sapphirecity_baseboard_lib.sapphirecity_baseboard(sch_1):\DDR4_2SPC_CAC\" )
				( netClassRef "@sapphirecity_baseboard_lib.sapphirecity_baseboard(sch_1):\DDR4_CHN_L_CMD_ADD\" )
				( netClassRef "@sapphirecity_baseboard_lib.sapphirecity_baseboard(sch_1):\DDR4_CHN_L_CTRL\" )
			)
			( classClass "@crescent_city_bb_fab1_lib.crescent_city_bb_fab1(sch_1):\CC488\"
				( spacingCSetRef "@sapphirecity_baseboard_lib.sapphirecity_baseboard(sch_1):\DDR4_2SPC_CAC\" )
				( netClassRef "@sapphirecity_baseboard_lib.sapphirecity_baseboard(sch_1):\DDR4_CHN_M_CMD_ADD\" )
				( netClassRef "@sapphirecity_baseboard_lib.sapphirecity_baseboard(sch_1):\DDR4_CHN_M_CMD_ADD\" )
			)
			( classClass "@crescent_city_bb_fab1_lib.crescent_city_bb_fab1(sch_1):\CC489\"
				( spacingCSetRef "@sapphirecity_baseboard_lib.sapphirecity_baseboard(sch_1):\DDR4_2SPC_CAC\" )
				( netClassRef "@sapphirecity_baseboard_lib.sapphirecity_baseboard(sch_1):\DDR4_CHN_M_CMD_ADD\" )
				( netClassRef "@sapphirecity_baseboard_lib.sapphirecity_baseboard(sch_1):\DDR4_CHN_M_CTRL\" )
			)
			( classClass "@crescent_city_bb_fab1_lib.crescent_city_bb_fab1(sch_1):\CC384\"
				( spacingCSetRef "@sapphirecity_baseboard_lib.sapphirecity_baseboard(sch_1):\DDR4_2SPC_CAC\" )
				( netClassRef "@sapphirecity_baseboard_lib.sapphirecity_baseboard(sch_1):\DDR4_CHN_J_CTRL\" )
				( netClassRef "@sapphirecity_baseboard_lib.sapphirecity_baseboard(sch_1):\DDR4_CHN_J_CTRL\" )
			)
			( classClass "@crescent_city_bb_fab1_lib.crescent_city_bb_fab1(sch_1):\CC423\"
				( spacingCSetRef "@sapphirecity_baseboard_lib.sapphirecity_baseboard(sch_1):\DDR4_2SPC_CAC\" )
				( netClassRef "@sapphirecity_baseboard_lib.sapphirecity_baseboard(sch_1):\DDR4_CHN_K_CTRL\" )
				( netClassRef "@sapphirecity_baseboard_lib.sapphirecity_baseboard(sch_1):\DDR4_CHN_K_CTRL\" )
			)
			( classClass "@crescent_city_bb_fab1_lib.crescent_city_bb_fab1(sch_1):\CC462\"
				( spacingCSetRef "@sapphirecity_baseboard_lib.sapphirecity_baseboard(sch_1):\DDR4_2SPC_CAC\" )
				( netClassRef "@sapphirecity_baseboard_lib.sapphirecity_baseboard(sch_1):\DDR4_CHN_L_CTRL\" )
				( netClassRef "@sapphirecity_baseboard_lib.sapphirecity_baseboard(sch_1):\DDR4_CHN_L_CTRL\" )
			)
			( classClass "@crescent_city_bb_fab1_lib.crescent_city_bb_fab1(sch_1):\CC501\"
				( spacingCSetRef "@sapphirecity_baseboard_lib.sapphirecity_baseboard(sch_1):\DDR4_2SPC_CAC\" )
				( netClassRef "@sapphirecity_baseboard_lib.sapphirecity_baseboard(sch_1):\DDR4_CHN_M_CTRL\" )
				( netClassRef "@sapphirecity_baseboard_lib.sapphirecity_baseboard(sch_1):\DDR4_CHN_M_CTRL\" )
			)
			( classClass "@sapphirecity_baseboard_lib.sapphirecity_baseboard(sch_1):\CC52\"
				( spacingCSetRef "@crescent_city_bb_fab1_lib.crescent_city_bb_fab1(sch_1):\11H_US_&_2H_SL_VIA_3H+A\" )
				( netClassRef "@sapphirecity_baseboard_lib.sapphirecity_baseboard(sch_1):\KTI_CPU0_CPU1_P0P1\" )
				( netClassRef "@sapphirecity_baseboard_lib.sapphirecity_baseboard(sch_1):\KTI_CPU0_CPU1_P0P1\" )
			)
			( classClass "@sapphirecity_baseboard_lib.sapphirecity_baseboard(sch_1):\CC51\"
				( spacingCSetRef "@crescent_city_bb_fab1_lib.crescent_city_bb_fab1(sch_1):\11H_US_&_2H_SL_VIA_3H+A\" )
				( netClassRef "@sapphirecity_baseboard_lib.sapphirecity_baseboard(sch_1):\KTI_CPU0_CPU1_P1P0\" )
				( netClassRef "@sapphirecity_baseboard_lib.sapphirecity_baseboard(sch_1):\KTI_CPU0_CPU1_P1P0\" )
			)
			( classClass "@sapphirecity_baseboard_lib.sapphirecity_baseboard(sch_1):\CC50\"
				( spacingCSetRef "@crescent_city_bb_fab1_lib.crescent_city_bb_fab1(sch_1):\11H_US_&_2H_SL_VIA_3H+A\" )
				( netClassRef "@sapphirecity_baseboard_lib.sapphirecity_baseboard(sch_1):\KTI_CPU1_CPU0_P0P1\" )
				( netClassRef "@sapphirecity_baseboard_lib.sapphirecity_baseboard(sch_1):\KTI_CPU1_CPU0_P0P1\" )
			)
			( classClass "@sapphirecity_baseboard_lib.sapphirecity_baseboard(sch_1):\CC1\"
				( spacingCSetRef "@crescent_city_bb_fab1_lib.crescent_city_bb_fab1(sch_1):\11H_US_&_2H_SL_VIA_3H+A\" )
				( netClassRef "@sapphirecity_baseboard_lib.sapphirecity_baseboard(sch_1):\KTI_CPU1_CPU0_P1P0\" )
				( netClassRef "@sapphirecity_baseboard_lib.sapphirecity_baseboard(sch_1):\KTI_CPU1_CPU0_P1P0\" )
			)
			( region "@crescent_city_bb_fab1_lib.crescent_city_bb_fab1(sch_1):\CPU_4MIL_PAD_2_LINE_TOP\"
				( attribute "LINE_TO_SMDPIN_SPACING" "4.00"
					( Origin gBackEnd )
				)
				( objectStatus "CPU_4MIL_PAD_2_LINE_TOP" )
			)
			( region "@crescent_city_bb_fab1_lib.crescent_city_bb_fab1(sch_1):\STUFFING_OPTION\"
				( objectStatus "STUFFING_OPTION" )
			)
			( region "@crescent_city_bb_fab1_lib.crescent_city_bb_fab1(sch_1):\SNAIL_PF1\"
				( spacingCSetRef "@crescent_city_bb_fab1_lib.crescent_city_bb_fab1(sch_1):\PCS_SNAIL_PF1\" )
				( attribute "SN_SHAPE_TO_THRUVIA_SPACING" "4.00"
					( Origin gBackEnd )
				)
				( objectStatus "SNAIL_PF1" )
			)
			( region "@crescent_city_bb_fab1_lib.crescent_city_bb_fab1(sch_1):\SNAIL\"
				( spacingCSetRef "@crescent_city_bb_fab1_lib.crescent_city_bb_fab1(sch_1):\PCS_SNAIL\" )
				( attribute "SN_SHAPE_TO_THRUVIA_SPACING" "4.00"
					( Origin gBackEnd )
				)
				( attribute "SN_LINE_TO_LINE_SPACING" "5.00"
					( Origin gBackEnd )
				)
				( objectStatus "SNAIL_PF2" )
			)
			( region "@crescent_city_bb_fab1_lib.crescent_city_bb_fab1(sch_1):\VIA_ON_PAD\"
				( attribute "SAME_NET" "FALSE"
					( Origin gBackEnd )
				)
				( objectStatus "VIA_ON_PAD" )
			)
			( region "@crescent_city_bb_fab1_lib.crescent_city_bb_fab1(sch_1):\UPI_2H\"
				( attribute "THRUPIN_TO_THRUVIA_SPACING" "6.00"
					( Origin gBackEnd )
				)
				( attribute "TESTVIA_TO_THRUPIN_SPACING" "6.00"
					( Origin gBackEnd )
				)
				( attribute "BBV_TO_THRUPIN_SPACING" "6.00"
					( Origin gBackEnd )
				)
				( attribute "SMDPIN_TO_THRUVIA_SPACING" "6.00"
					( Origin gBackEnd )
				)
				( attribute "SMDPIN_TO_TESTVIA_SPACING" "6.00"
					( Origin gBackEnd )
				)
				( attribute "BBV_TO_SMDPIN_SPACING" "6.00"
					( Origin gBackEnd )
				)
				( attribute "TESTPIN_TO_THRUVIA_SPACING" "6.00"
					( Origin gBackEnd )
				)
				( attribute "TESTPIN_TO_TESTVIA_SPACING" "6.00"
					( Origin gBackEnd )
				)
				( attribute "BBV_TO_TESTPIN_SPACING" "6.00"
					( Origin gBackEnd )
				)
				( attribute "THRUVIA_TO_THRUVIA_SPACING" "6.00"
					( Origin gBackEnd )
				)
				( attribute "TESTVIA_TO_THRUVIA_SPACING" "6.00"
					( Origin gBackEnd )
				)
				( attribute "BBV_TO_THRUVIA_SPACING" "6.00"
					( Origin gBackEnd )
				)
				( attribute "BONDPAD_TO_THRUVIA_SPACING" "6.00"
					( Origin gBackEnd )
				)
				( attribute "LINE_TO_THRUVIA_SPACING" "6.00"
					( Origin gBackEnd )
				)
				( attribute "SHAPE_TO_THRUVIA_SPACING" "6.00"
					( Origin gBackEnd )
				)
				( attribute "TESTVIA_TO_TESTVIA_SPACING" "6.00"
					( Origin gBackEnd )
				)
				( attribute "BBV_TO_TESTVIA_SPACING" "6.00"
					( Origin gBackEnd )
				)
				( attribute "BONDPAD_TO_TESTVIA_SPACING" "6.00"
					( Origin gBackEnd )
				)
				( attribute "LINE_TO_TESTVIA_SPACING" "6.00"
					( Origin gBackEnd )
				)
				( attribute "SHAPE_TO_TESTVIA_SPACING" "6.00"
					( Origin gBackEnd )
				)
				( attribute "BBV_TO_BBV_SPACING" "6.00"
					( Origin gBackEnd )
				)
				( attribute "BONDPAD_TO_BBV_SPACING" "6.00"
					( Origin gBackEnd )
				)
				( attribute "BBV_TO_LINE_SPACING" "6.00"
					( Origin gBackEnd )
				)
				( attribute "BBV_TO_SHAPE_SPACING" "6.00"
					( Origin gBackEnd )
				)
				( attribute "LINE_TO_LINE_SPACING" "6.00"
					( Origin gBackEnd )
				)
				( attribute "HOLE_TO_VIA_SPACING" "6.00"
					( Origin gBackEnd )
				)
				( objectStatus "UPI_2H" )
			)
			( region "@crescent_city_bb_fab1_lib.crescent_city_bb_fab1(sch_1):\BGA_AREA\"
				( objectStatus "BGA_AREA" )
			)
			( region "@crescent_city_bb_fab1_lib.crescent_city_bb_fab1(sch_1):\CPU_OVAL_PADS\"
				( attribute "SN_SMDPIN_TO_THRUVIA_SPACING" "1.00"
					( Origin gBackEnd )
				)
				( attribute "SN_SMDPIN_TO_TESTVIA_SPACING" "1.00"
					( Origin gBackEnd )
				)
				( attribute "SN_LINE_TO_SMDPIN_SPACING" "2.30"
					( Origin gBackEnd )
				)
				( objectStatus "CPU_OVAL_PADS" )
			)
			( region "@crescent_city_bb_fab1_lib.crescent_city_bb_fab1(sch_1):\UPI_9H\"
				( spacingCSetRef "@sapphirecity_baseboard_lib.sapphirecity_baseboard(sch_1):\3H_SL_9H_MS_VIA_3H+A\" )
				( objectStatus "UPI_9H" )
			)
			( region "@crescent_city_bb_fab1_lib.crescent_city_bb_fab1(sch_1):\UPI_6H\"
				( spacingCSetRef "@crescent_city_bb_fab1_lib.crescent_city_bb_fab1(sch_1):\6H_US_&_3H_SL_VIA_3H+A\" )
				( objectStatus "UPI_6H" )
			)
			( region "@crescent_city_bb_fab1_lib.crescent_city_bb_fab1(sch_1):\DDR_ESCAPE\"
				( spacingCSetRef "@sapphirecity_baseboard_lib.sapphirecity_baseboard(sch_1):\12_MIL\" )
				( sameNetSpacingCSetRef "@crescent_city_bb_fab1_lib.crescent_city_bb_fab1(sch_1):\BGA\" )
				( attribute "MIN_NECK_WIDTH" "3.50"
					( Origin gBackEnd )
				)
				( attribute "MAXIMUM_NECK_LENGTH" "1100.00"
					( Origin gBackEnd )
				)
				( attribute "VIA_LIST" "V_C20P10AP28,V_C20P10AP28_TP,V_C20P10C26AP28_TP"
					( Origin gBackEnd )
				)
				( attribute "SAME_NET" "TRUE"
					( Origin gBackEnd )
				)
				( objectStatus "DDR_ESCAPE" )
			)
			( region "@sapphirecity_baseboard_lib.sapphirecity_baseboard(sch_1):\SMT_PIN_TH_PIN\"
				( spacingCSetRef "@sapphirecity_baseboard_lib.sapphirecity_baseboard(sch_1):\TH_PIN_SMT_PIN\" )
				( objectStatus "SMT_PIN_TH_PIN" )
			)
			( region "@sapphirecity_baseboard_lib.sapphirecity_baseboard(sch_1):\VR_PWR_VIAS_5H\"
				( spacingCSetRef "@sapphirecity_baseboard_lib.sapphirecity_baseboard(sch_1):\VIA_5H\" )
				( objectStatus "VR_PWR_VIAS_5H" )
			)
			( region "@sapphirecity_baseboard_lib.sapphirecity_baseboard(sch_1):\VR_PWR_VIAS_10H\"
				( spacingCSetRef "@sapphirecity_baseboard_lib.sapphirecity_baseboard(sch_1):\VIA_10H\" )
				( objectStatus "VR_PWR_VIAS_10H" )
			)
			( region "@sapphirecity_baseboard_lib.sapphirecity_baseboard(sch_1):\BGA_3.5MILS\"
				( physicalCSetRef "@crescent_city_bb_fab1_lib.crescent_city_bb_fab1(sch_1):\BGA_3.5MILS\" )
				( spacingCSetRef "@sapphirecity_baseboard_lib.sapphirecity_baseboard(sch_1):\BGA\" )
				( objectStatus "BGA_3.5MILS" )
			)
			( region "@sapphirecity_baseboard_lib.sapphirecity_baseboard(sch_1):\BMC_MEM\"
				( spacingCSetRef "@sapphirecity_baseboard_lib.sapphirecity_baseboard(sch_1):\BMC_MEM\" )
				( sameNetSpacingCSetRef "@crescent_city_bb_fab1_lib.crescent_city_bb_fab1(sch_1):\BMC_MEM\" )
				( objectStatus "BMC_MEM" )
			)
			( region "@sapphirecity_baseboard_lib.sapphirecity_baseboard(sch_1):\BGA_WBG\"
				( spacingCSetRef "@sapphirecity_baseboard_lib.sapphirecity_baseboard(sch_1):\BGA\" )
				( sameNetSpacingCSetRef "@crescent_city_bb_fab1_lib.crescent_city_bb_fab1(sch_1):\BGA_WBG\" )
				( attribute "MIN_NECK_WIDTH" "3.50"
					( Origin gBackEnd )
				)
				( attribute "SMDPIN_TO_THRUVIA_SPACING" "4.37"
					( Origin gBackEnd )
				)
				( attribute "SMDPIN_TO_TESTVIA_SPACING" "4.37"
					( Origin gBackEnd )
				)
				( attribute "SHAPE_TO_SMDPIN_SPACING" "4.50"
					( Origin gBackEnd )
				)
				( attribute "SHAPE_TO_THRUVIA_SPACING" "4.00"
					( Origin gBackEnd )
				)
				( attribute "SHAPE_TO_TESTVIA_SPACING" "4.50"
					( Origin gBackEnd )
				)
				( attribute "LINE_TO_LINE_SPACING" "4.00"
					( Origin gBackEnd )
				)
				( attribute "SN_SMDPIN_TO_THRUVIA_SPACING" "2.50"
					( Origin gBackEnd )
				)
				( attribute "SN_SMDPIN_TO_TESTVIA_SPACING" "2.50"
					( Origin gBackEnd )
				)
				( objectStatus "BGA_P8MM_PITCH" )
			)
			( region "@sapphirecity_baseboard_lib.sapphirecity_baseboard(sch_1):\VR_CONT\"
				( physicalCSetRef "@crescent_city_bb_fab1_lib.crescent_city_bb_fab1(sch_1):\DEFAULT\" )
				( spacingCSetRef "@sapphirecity_baseboard_lib.sapphirecity_baseboard(sch_1):\BGA\" )
				( objectStatus "VR_CONT" )
			)
			( region "@sapphirecity_baseboard_lib.sapphirecity_baseboard(sch_1):\BMC\"
				( physicalCSetRef "@crescent_city_bb_fab1_lib.crescent_city_bb_fab1(sch_1):\DEFAULT\" )
				( spacingCSetRef "@sapphirecity_baseboard_lib.sapphirecity_baseboard(sch_1):\BGA\" )
				( attribute "MIN_LINE_WIDTH" "3.50"
					( Origin gBackEnd )
				)
				( attribute "LINE_TO_TESTVIA_SPACING" "4.00"
					( Origin gBackEnd )
				)
				( objectStatus "BMC" )
			)
			( region "@sapphirecity_baseboard_lib.sapphirecity_baseboard(sch_1):\CPU_BO\"
				( spacingCSetRef "@sapphirecity_baseboard_lib.sapphirecity_baseboard(sch_1):\2H_SL_5H_MS\" )
				( objectStatus "CPU_BO" )
			)
			( region "@sapphirecity_baseboard_lib.sapphirecity_baseboard(sch_1):\DDR4_DIMM\"
				( objectStatus "DDR4_DIMM" )
			)
			( region "@sapphirecity_baseboard_lib.sapphirecity_baseboard(sch_1):\QPI_BO_SPACING\"
				( spacingCSetRef "@sapphirecity_baseboard_lib.sapphirecity_baseboard(sch_1):\12_MIL\" )
				( objectStatus "QPI_BO_SPACING" )
			)
			( region "@sapphirecity_baseboard_lib.sapphirecity_baseboard(sch_1):\BGA\"
				( spacingCSetRef "@sapphirecity_baseboard_lib.sapphirecity_baseboard(sch_1):\BGA\" )
				( attribute "MIN_NECK_WIDTH" "3.50"
					( Origin gBackEnd )
				)
				( attribute "MAXIMUM_NECK_LENGTH" "9999.00"
					( Origin gBackEnd )
				)
				( attribute "VIA_LIST" "V_C20P10AP28,V_C20P10AP28_TP,V_C20P10C26AP28_TP"
					( Origin gBackEnd )
				)
				( attribute "LINE_TO_THRUVIA_SPACING" "3.94"
					( Origin gBackEnd )
				)
				( attribute "SAME_NET" "TRUE"
					( Origin gBackEnd )
				)
				( attribute "SN_SMDPIN_TO_THRUVIA_SPACING" "4.00"
					( Origin gBackEnd )
				)
				( attribute "SN_SMDPIN_TO_TESTVIA_SPACING" "4.00"
					( Origin gBackEnd )
				)
				( attribute "SN_LINE_TO_SMDPIN_SPACING" "4.50"
					( Origin gBackEnd )
				)
				( attribute "SN_SHAPE_TO_SMDPIN_SPACING" "4.00"
					( Origin gBackEnd )
				)
				( attribute "SN_LINE_TO_THRUVIA_SPACING" "3.99"
					( Origin gBackEnd )
				)
				( attribute "SN_LINE_TO_TESTVIA_SPACING" "3.99"
					( Origin gBackEnd )
				)
				( attribute "SN_LINE_TO_LINE_SPACING" "4.00"
					( Origin gBackEnd )
				)
				( objectStatus "BGA" )
			)
			( region "@sapphirecity_baseboard_lib.sapphirecity_baseboard(sch_1):\BMC_3.5_MILS\"
				( spacingCSetRef "@sapphirecity_baseboard_lib.sapphirecity_baseboard(sch_1):\BMC_MEM\" )
				( attribute "MIN_LINE_WIDTH" "3.50"
					( Origin gBackEnd )
				)
				( attribute "MAX_LINE_WIDTH" "3.50"
					( Origin gBackEnd )
				)
				( objectStatus "BMC_3.5_MILS" )
			)
			( region "@sapphirecity_baseboard_lib.sapphirecity_baseboard(sch_1):\USB2\"
				( attribute "DIFFP_PRIMARY_GAP" "6.50"
					( Origin gBackEnd )
				)
				( attribute "DIFFP_COUPLED_PLUS" "0.10"
					( Origin gBackEnd )
				)
				( attribute "DIFFP_COUPLED_MINUS" "0.10"
					( Origin gBackEnd )
				)
				( attribute "DIFFP_MIN_SPACE" "4.00"
					( Origin gBackEnd )
				)
				( attribute "MIN_LINE_WIDTH" "5.00"
					( Origin gBackEnd )
				)
				( attribute "MAX_LINE_WIDTH" "500.00"
					( Origin gBackEnd )
				)
				( attribute "DIFFP_NECK_GAP" "4.10"
					( Origin gBackEnd )
				)
				( attribute "MIN_NECK_WIDTH" "3.90"
					( Origin gBackEnd )
				)
				( attribute "MAXIMUM_NECK_LENGTH" "500.00"
					( Origin gBackEnd )
				)
				( attribute "LINE_TO_THRUPIN_SPACING" "4.00"
					( Origin gBackEnd )
				)
				( attribute "LINE_TO_TESTVIA_SPACING" "4.00"
					( Origin gBackEnd )
				)
				( attribute "BBV_TO_LINE_SPACING" "4.00"
					( Origin gBackEnd )
				)
				( attribute "LINE_TO_LINE_SPACING" "8.00"
					( Origin gBackEnd )
				)
				( objectStatus "USB2" )
			)
			( region "@sapphirecity_baseboard_lib.sapphirecity_baseboard(sch_1):\STUBBY_OPEN\"
				( spacingCSetRef "@sapphirecity_baseboard_lib.sapphirecity_baseboard(sch_1):\DDR4_STUBBY_TIGHT_EXT\" )
				( objectStatus "TABBED_BO_TOP" )
			)
			( region "@sapphirecity_baseboard_lib.sapphirecity_baseboard(sch_1):\CPU_BRKT\"
				( attribute "MIN_LINE_WIDTH" "3.90"
					( Origin gBackEnd )
				)
				( objectStatus "CPU_BRKT" )
			)
			( region "@sapphirecity_baseboard_lib.sapphirecity_baseboard(sch_1):\DDR4_STUBBY\"
				( spacingCSetRef "@sapphirecity_baseboard_lib.sapphirecity_baseboard(sch_1):\DDR4_STUBBY_EXTERNAL\" )
				( sameNetSpacingCSetRef "@crescent_city_bb_fab1_lib.crescent_city_bb_fab1(sch_1):\BGA\" )
				( attribute "SAME_NET" "TRUE"
					( Origin gBackEnd )
				)
				( objectStatus "TABBED_OF_TOP" )
			)
			( regionClass "@crescent_city_bb_fab1_lib.crescent_city_bb_fab1(sch_1):\RC54\"
				( spacingCSetRef "@sapphirecity_baseboard_lib.sapphirecity_baseboard(sch_1):\DDR4_DIMM\" )
				( attribute "LINE_TO_LINE_SPACING" "10.00"
					( Origin gBackEnd )
				)
				( regionRef "@sapphirecity_baseboard_lib.sapphirecity_baseboard(sch_1):\DDR4_DIMM\" )
				( netClassRef "@sapphirecity_baseboard_lib.sapphirecity_baseboard(sch_1):\DDR4_CHN_A_CLK\" )
			)
			( regionClass "@crescent_city_bb_fab1_lib.crescent_city_bb_fab1(sch_1):\RC55\"
				( spacingCSetRef "@sapphirecity_baseboard_lib.sapphirecity_baseboard(sch_1):\DDR4_DIMM\" )
				( attribute "LINE_TO_LINE_SPACING" "10.00"
					( Origin gBackEnd )
				)
				( regionRef "@sapphirecity_baseboard_lib.sapphirecity_baseboard(sch_1):\DDR4_DIMM\" )
				( netClassRef "@sapphirecity_baseboard_lib.sapphirecity_baseboard(sch_1):\DDR4_CHN_A_CMD_ADD\" )
			)
			( regionClass "@crescent_city_bb_fab1_lib.crescent_city_bb_fab1(sch_1):\RC56\"
				( spacingCSetRef "@sapphirecity_baseboard_lib.sapphirecity_baseboard(sch_1):\DDR4_DIMM\" )
				( attribute "LINE_TO_LINE_SPACING" "10.00"
					( Origin gBackEnd )
				)
				( regionRef "@sapphirecity_baseboard_lib.sapphirecity_baseboard(sch_1):\DDR4_DIMM\" )
				( netClassRef "@sapphirecity_baseboard_lib.sapphirecity_baseboard(sch_1):\DDR4_CHN_A_CTRL\" )
			)
			( regionClass "@crescent_city_bb_fab1_lib.crescent_city_bb_fab1(sch_1):\RC1\"
				( spacingCSetRef "@sapphirecity_baseboard_lib.sapphirecity_baseboard(sch_1):\DDR4_DIMM\" )
				( attribute "LINE_TO_LINE_SPACING" "10.00"
					( Origin gBackEnd )
				)
				( regionRef "@sapphirecity_baseboard_lib.sapphirecity_baseboard(sch_1):\DDR4_DIMM\" )
				( netClassRef "@sapphirecity_baseboard_lib.sapphirecity_baseboard(sch_1):\DDR4_CHN_A_DQ_DQS_BYTE0\" )
			)
			( regionClass "@crescent_city_bb_fab1_lib.crescent_city_bb_fab1(sch_1):\RC2\"
				( spacingCSetRef "@sapphirecity_baseboard_lib.sapphirecity_baseboard(sch_1):\DDR4_DIMM\" )
				( attribute "LINE_TO_LINE_SPACING" "10.00"
					( Origin gBackEnd )
				)
				( regionRef "@sapphirecity_baseboard_lib.sapphirecity_baseboard(sch_1):\DDR4_DIMM\" )
				( netClassRef "@sapphirecity_baseboard_lib.sapphirecity_baseboard(sch_1):\DDR4_CHN_A_DQ_DQS_BYTE1\" )
			)
			( regionClass "@crescent_city_bb_fab1_lib.crescent_city_bb_fab1(sch_1):\RC3\"
				( spacingCSetRef "@sapphirecity_baseboard_lib.sapphirecity_baseboard(sch_1):\DDR4_DIMM\" )
				( attribute "LINE_TO_LINE_SPACING" "10.00"
					( Origin gBackEnd )
				)
				( regionRef "@sapphirecity_baseboard_lib.sapphirecity_baseboard(sch_1):\DDR4_DIMM\" )
				( netClassRef "@sapphirecity_baseboard_lib.sapphirecity_baseboard(sch_1):\DDR4_CHN_A_DQ_DQS_BYTE2\" )
			)
			( regionClass "@crescent_city_bb_fab1_lib.crescent_city_bb_fab1(sch_1):\RC4\"
				( spacingCSetRef "@sapphirecity_baseboard_lib.sapphirecity_baseboard(sch_1):\DDR4_DIMM\" )
				( attribute "LINE_TO_LINE_SPACING" "10.00"
					( Origin gBackEnd )
				)
				( regionRef "@sapphirecity_baseboard_lib.sapphirecity_baseboard(sch_1):\DDR4_DIMM\" )
				( netClassRef "@sapphirecity_baseboard_lib.sapphirecity_baseboard(sch_1):\DDR4_CHN_A_DQ_DQS_BYTE3\" )
			)
			( regionClass "@crescent_city_bb_fab1_lib.crescent_city_bb_fab1(sch_1):\RC5\"
				( spacingCSetRef "@sapphirecity_baseboard_lib.sapphirecity_baseboard(sch_1):\DDR4_DIMM\" )
				( attribute "LINE_TO_LINE_SPACING" "10.00"
					( Origin gBackEnd )
				)
				( regionRef "@sapphirecity_baseboard_lib.sapphirecity_baseboard(sch_1):\DDR4_DIMM\" )
				( netClassRef "@sapphirecity_baseboard_lib.sapphirecity_baseboard(sch_1):\DDR4_CHN_A_DQ_DQS_BYTE4\" )
			)
			( regionClass "@crescent_city_bb_fab1_lib.crescent_city_bb_fab1(sch_1):\RC6\"
				( spacingCSetRef "@sapphirecity_baseboard_lib.sapphirecity_baseboard(sch_1):\DDR4_DIMM\" )
				( attribute "LINE_TO_LINE_SPACING" "10.00"
					( Origin gBackEnd )
				)
				( regionRef "@sapphirecity_baseboard_lib.sapphirecity_baseboard(sch_1):\DDR4_DIMM\" )
				( netClassRef "@sapphirecity_baseboard_lib.sapphirecity_baseboard(sch_1):\DDR4_CHN_A_DQ_DQS_BYTE5\" )
			)
			( regionClass "@crescent_city_bb_fab1_lib.crescent_city_bb_fab1(sch_1):\RC7\"
				( spacingCSetRef "@sapphirecity_baseboard_lib.sapphirecity_baseboard(sch_1):\DDR4_DIMM\" )
				( attribute "LINE_TO_LINE_SPACING" "10.00"
					( Origin gBackEnd )
				)
				( regionRef "@sapphirecity_baseboard_lib.sapphirecity_baseboard(sch_1):\DDR4_DIMM\" )
				( netClassRef "@sapphirecity_baseboard_lib.sapphirecity_baseboard(sch_1):\DDR4_CHN_A_DQ_DQS_BYTE6\" )
			)
			( regionClass "@crescent_city_bb_fab1_lib.crescent_city_bb_fab1(sch_1):\RC8\"
				( spacingCSetRef "@sapphirecity_baseboard_lib.sapphirecity_baseboard(sch_1):\DDR4_DIMM\" )
				( attribute "LINE_TO_LINE_SPACING" "10.00"
					( Origin gBackEnd )
				)
				( regionRef "@sapphirecity_baseboard_lib.sapphirecity_baseboard(sch_1):\DDR4_DIMM\" )
				( netClassRef "@sapphirecity_baseboard_lib.sapphirecity_baseboard(sch_1):\DDR4_CHN_A_DQ_DQS_BYTE7\" )
			)
			( regionClass "@crescent_city_bb_fab1_lib.crescent_city_bb_fab1(sch_1):\RC58\"
				( spacingCSetRef "@sapphirecity_baseboard_lib.sapphirecity_baseboard(sch_1):\DDR4_DIMM\" )
				( attribute "LINE_TO_LINE_SPACING" "10.00"
					( Origin gBackEnd )
				)
				( regionRef "@sapphirecity_baseboard_lib.sapphirecity_baseboard(sch_1):\DDR4_DIMM\" )
				( netClassRef "@sapphirecity_baseboard_lib.sapphirecity_baseboard(sch_1):\DDR4_CHN_A_ECC\" )
			)
			( regionClass "@crescent_city_bb_fab1_lib.crescent_city_bb_fab1(sch_1):\RC57\"
				( spacingCSetRef "@sapphirecity_baseboard_lib.sapphirecity_baseboard(sch_1):\DDR4_DIMM\" )
				( attribute "LINE_TO_LINE_SPACING" "10.00"
					( Origin gBackEnd )
				)
				( regionRef "@sapphirecity_baseboard_lib.sapphirecity_baseboard(sch_1):\DDR4_DIMM\" )
				( netClassRef "@sapphirecity_baseboard_lib.sapphirecity_baseboard(sch_1):\DDR4_CHN_B_CLK\" )
			)
			( regionClass "@crescent_city_bb_fab1_lib.crescent_city_bb_fab1(sch_1):\RC59\"
				( spacingCSetRef "@sapphirecity_baseboard_lib.sapphirecity_baseboard(sch_1):\DDR4_DIMM\" )
				( attribute "LINE_TO_LINE_SPACING" "10.00"
					( Origin gBackEnd )
				)
				( regionRef "@sapphirecity_baseboard_lib.sapphirecity_baseboard(sch_1):\DDR4_DIMM\" )
				( netClassRef "@sapphirecity_baseboard_lib.sapphirecity_baseboard(sch_1):\DDR4_CHN_B_CMD_ADD\" )
			)
			( regionClass "@crescent_city_bb_fab1_lib.crescent_city_bb_fab1(sch_1):\RC60\"
				( spacingCSetRef "@sapphirecity_baseboard_lib.sapphirecity_baseboard(sch_1):\DDR4_DIMM\" )
				( attribute "LINE_TO_LINE_SPACING" "10.00"
					( Origin gBackEnd )
				)
				( regionRef "@sapphirecity_baseboard_lib.sapphirecity_baseboard(sch_1):\DDR4_DIMM\" )
				( netClassRef "@sapphirecity_baseboard_lib.sapphirecity_baseboard(sch_1):\DDR4_CHN_B_CTRL\" )
			)
			( regionClass "@crescent_city_bb_fab1_lib.crescent_city_bb_fab1(sch_1):\RC9\"
				( spacingCSetRef "@sapphirecity_baseboard_lib.sapphirecity_baseboard(sch_1):\DDR4_DIMM\" )
				( attribute "LINE_TO_LINE_SPACING" "10.00"
					( Origin gBackEnd )
				)
				( regionRef "@sapphirecity_baseboard_lib.sapphirecity_baseboard(sch_1):\DDR4_DIMM\" )
				( netClassRef "@sapphirecity_baseboard_lib.sapphirecity_baseboard(sch_1):\DDR4_CHN_B_DQ_DQS_BYTE0\" )
			)
			( regionClass "@crescent_city_bb_fab1_lib.crescent_city_bb_fab1(sch_1):\RC10\"
				( spacingCSetRef "@sapphirecity_baseboard_lib.sapphirecity_baseboard(sch_1):\DDR4_DIMM\" )
				( attribute "LINE_TO_LINE_SPACING" "10.00"
					( Origin gBackEnd )
				)
				( regionRef "@sapphirecity_baseboard_lib.sapphirecity_baseboard(sch_1):\DDR4_DIMM\" )
				( netClassRef "@sapphirecity_baseboard_lib.sapphirecity_baseboard(sch_1):\DDR4_CHN_B_DQ_DQS_BYTE1\" )
			)
			( regionClass "@crescent_city_bb_fab1_lib.crescent_city_bb_fab1(sch_1):\RC11\"
				( spacingCSetRef "@sapphirecity_baseboard_lib.sapphirecity_baseboard(sch_1):\DDR4_DIMM\" )
				( attribute "LINE_TO_LINE_SPACING" "10.00"
					( Origin gBackEnd )
				)
				( regionRef "@sapphirecity_baseboard_lib.sapphirecity_baseboard(sch_1):\DDR4_DIMM\" )
				( netClassRef "@sapphirecity_baseboard_lib.sapphirecity_baseboard(sch_1):\DDR4_CHN_B_DQ_DQS_BYTE2\" )
			)
			( regionClass "@crescent_city_bb_fab1_lib.crescent_city_bb_fab1(sch_1):\RC12\"
				( spacingCSetRef "@sapphirecity_baseboard_lib.sapphirecity_baseboard(sch_1):\DDR4_DIMM\" )
				( attribute "LINE_TO_LINE_SPACING" "10.00"
					( Origin gBackEnd )
				)
				( regionRef "@sapphirecity_baseboard_lib.sapphirecity_baseboard(sch_1):\DDR4_DIMM\" )
				( netClassRef "@sapphirecity_baseboard_lib.sapphirecity_baseboard(sch_1):\DDR4_CHN_B_DQ_DQS_BYTE3\" )
			)
			( regionClass "@crescent_city_bb_fab1_lib.crescent_city_bb_fab1(sch_1):\RC13\"
				( spacingCSetRef "@sapphirecity_baseboard_lib.sapphirecity_baseboard(sch_1):\DDR4_DIMM\" )
				( attribute "LINE_TO_LINE_SPACING" "10.00"
					( Origin gBackEnd )
				)
				( regionRef "@sapphirecity_baseboard_lib.sapphirecity_baseboard(sch_1):\DDR4_DIMM\" )
				( netClassRef "@sapphirecity_baseboard_lib.sapphirecity_baseboard(sch_1):\DDR4_CHN_B_DQ_DQS_BYTE4\" )
			)
			( regionClass "@crescent_city_bb_fab1_lib.crescent_city_bb_fab1(sch_1):\RC14\"
				( spacingCSetRef "@sapphirecity_baseboard_lib.sapphirecity_baseboard(sch_1):\DDR4_DIMM\" )
				( attribute "LINE_TO_LINE_SPACING" "10.00"
					( Origin gBackEnd )
				)
				( regionRef "@sapphirecity_baseboard_lib.sapphirecity_baseboard(sch_1):\DDR4_DIMM\" )
				( netClassRef "@sapphirecity_baseboard_lib.sapphirecity_baseboard(sch_1):\DDR4_CHN_B_DQ_DQS_BYTE5\" )
			)
			( regionClass "@crescent_city_bb_fab1_lib.crescent_city_bb_fab1(sch_1):\RC15\"
				( spacingCSetRef "@sapphirecity_baseboard_lib.sapphirecity_baseboard(sch_1):\DDR4_DIMM\" )
				( attribute "LINE_TO_LINE_SPACING" "10.00"
					( Origin gBackEnd )
				)
				( regionRef "@sapphirecity_baseboard_lib.sapphirecity_baseboard(sch_1):\DDR4_DIMM\" )
				( netClassRef "@sapphirecity_baseboard_lib.sapphirecity_baseboard(sch_1):\DDR4_CHN_B_DQ_DQS_BYTE6\" )
			)
			( regionClass "@crescent_city_bb_fab1_lib.crescent_city_bb_fab1(sch_1):\RC16\"
				( spacingCSetRef "@sapphirecity_baseboard_lib.sapphirecity_baseboard(sch_1):\DDR4_DIMM\" )
				( attribute "LINE_TO_LINE_SPACING" "10.00"
					( Origin gBackEnd )
				)
				( regionRef "@sapphirecity_baseboard_lib.sapphirecity_baseboard(sch_1):\DDR4_DIMM\" )
				( netClassRef "@sapphirecity_baseboard_lib.sapphirecity_baseboard(sch_1):\DDR4_CHN_B_DQ_DQS_BYTE7\" )
			)
			( regionClass "@crescent_city_bb_fab1_lib.crescent_city_bb_fab1(sch_1):\RC61\"
				( spacingCSetRef "@sapphirecity_baseboard_lib.sapphirecity_baseboard(sch_1):\DDR4_DIMM\" )
				( attribute "LINE_TO_LINE_SPACING" "10.00"
					( Origin gBackEnd )
				)
				( regionRef "@sapphirecity_baseboard_lib.sapphirecity_baseboard(sch_1):\DDR4_DIMM\" )
				( netClassRef "@sapphirecity_baseboard_lib.sapphirecity_baseboard(sch_1):\DDR4_CHN_B_ECC\" )
			)
			( regionClass "@crescent_city_bb_fab1_lib.crescent_city_bb_fab1(sch_1):\RC62\"
				( spacingCSetRef "@sapphirecity_baseboard_lib.sapphirecity_baseboard(sch_1):\DDR4_DIMM\" )
				( attribute "LINE_TO_LINE_SPACING" "10.00"
					( Origin gBackEnd )
				)
				( regionRef "@sapphirecity_baseboard_lib.sapphirecity_baseboard(sch_1):\DDR4_DIMM\" )
				( netClassRef "@sapphirecity_baseboard_lib.sapphirecity_baseboard(sch_1):\DDR4_CHN_C_CLK\" )
			)
			( regionClass "@crescent_city_bb_fab1_lib.crescent_city_bb_fab1(sch_1):\RC63\"
				( spacingCSetRef "@sapphirecity_baseboard_lib.sapphirecity_baseboard(sch_1):\DDR4_DIMM\" )
				( attribute "LINE_TO_LINE_SPACING" "10.00"
					( Origin gBackEnd )
				)
				( regionRef "@sapphirecity_baseboard_lib.sapphirecity_baseboard(sch_1):\DDR4_DIMM\" )
				( netClassRef "@sapphirecity_baseboard_lib.sapphirecity_baseboard(sch_1):\DDR4_CHN_C_CMD_ADD\" )
			)
			( regionClass "@crescent_city_bb_fab1_lib.crescent_city_bb_fab1(sch_1):\RC144\"
				( spacingCSetRef "@sapphirecity_baseboard_lib.sapphirecity_baseboard(sch_1):\DDR4_DIMM\" )
				( attribute "LINE_TO_LINE_SPACING" "10.00"
					( Origin gBackEnd )
				)
				( regionRef "@sapphirecity_baseboard_lib.sapphirecity_baseboard(sch_1):\DDR4_DIMM\" )
				( netClassRef "@sapphirecity_baseboard_lib.sapphirecity_baseboard(sch_1):\DDR4_CHN_C_CTRL\" )
			)
			( regionClass "@crescent_city_bb_fab1_lib.crescent_city_bb_fab1(sch_1):\RC17\"
				( spacingCSetRef "@sapphirecity_baseboard_lib.sapphirecity_baseboard(sch_1):\DDR4_DIMM\" )
				( attribute "LINE_TO_LINE_SPACING" "10.00"
					( Origin gBackEnd )
				)
				( regionRef "@sapphirecity_baseboard_lib.sapphirecity_baseboard(sch_1):\DDR4_DIMM\" )
				( netClassRef "@sapphirecity_baseboard_lib.sapphirecity_baseboard(sch_1):\DDR4_CHN_C_DQ_DQS_BYTE0\" )
			)
			( regionClass "@crescent_city_bb_fab1_lib.crescent_city_bb_fab1(sch_1):\RC18\"
				( spacingCSetRef "@sapphirecity_baseboard_lib.sapphirecity_baseboard(sch_1):\DDR4_DIMM\" )
				( attribute "LINE_TO_LINE_SPACING" "10.00"
					( Origin gBackEnd )
				)
				( regionRef "@sapphirecity_baseboard_lib.sapphirecity_baseboard(sch_1):\DDR4_DIMM\" )
				( netClassRef "@sapphirecity_baseboard_lib.sapphirecity_baseboard(sch_1):\DDR4_CHN_C_DQ_DQS_BYTE1\" )
			)
			( regionClass "@crescent_city_bb_fab1_lib.crescent_city_bb_fab1(sch_1):\RC19\"
				( spacingCSetRef "@sapphirecity_baseboard_lib.sapphirecity_baseboard(sch_1):\DDR4_DIMM\" )
				( attribute "LINE_TO_LINE_SPACING" "10.00"
					( Origin gBackEnd )
				)
				( regionRef "@sapphirecity_baseboard_lib.sapphirecity_baseboard(sch_1):\DDR4_DIMM\" )
				( netClassRef "@sapphirecity_baseboard_lib.sapphirecity_baseboard(sch_1):\DDR4_CHN_C_DQ_DQS_BYTE2\" )
			)
			( regionClass "@crescent_city_bb_fab1_lib.crescent_city_bb_fab1(sch_1):\RC20\"
				( spacingCSetRef "@sapphirecity_baseboard_lib.sapphirecity_baseboard(sch_1):\DDR4_DIMM\" )
				( attribute "LINE_TO_LINE_SPACING" "10.00"
					( Origin gBackEnd )
				)
				( regionRef "@sapphirecity_baseboard_lib.sapphirecity_baseboard(sch_1):\DDR4_DIMM\" )
				( netClassRef "@sapphirecity_baseboard_lib.sapphirecity_baseboard(sch_1):\DDR4_CHN_C_DQ_DQS_BYTE3\" )
			)
			( regionClass "@crescent_city_bb_fab1_lib.crescent_city_bb_fab1(sch_1):\RC21\"
				( spacingCSetRef "@sapphirecity_baseboard_lib.sapphirecity_baseboard(sch_1):\DDR4_DIMM\" )
				( attribute "LINE_TO_LINE_SPACING" "10.00"
					( Origin gBackEnd )
				)
				( regionRef "@sapphirecity_baseboard_lib.sapphirecity_baseboard(sch_1):\DDR4_DIMM\" )
				( netClassRef "@sapphirecity_baseboard_lib.sapphirecity_baseboard(sch_1):\DDR4_CHN_C_DQ_DQS_BYTE4\" )
			)
			( regionClass "@crescent_city_bb_fab1_lib.crescent_city_bb_fab1(sch_1):\RC22\"
				( spacingCSetRef "@sapphirecity_baseboard_lib.sapphirecity_baseboard(sch_1):\DDR4_DIMM\" )
				( attribute "LINE_TO_LINE_SPACING" "10.00"
					( Origin gBackEnd )
				)
				( regionRef "@sapphirecity_baseboard_lib.sapphirecity_baseboard(sch_1):\DDR4_DIMM\" )
				( netClassRef "@sapphirecity_baseboard_lib.sapphirecity_baseboard(sch_1):\DDR4_CHN_C_DQ_DQS_BYTE5\" )
			)
			( regionClass "@crescent_city_bb_fab1_lib.crescent_city_bb_fab1(sch_1):\RC23\"
				( spacingCSetRef "@sapphirecity_baseboard_lib.sapphirecity_baseboard(sch_1):\DDR4_DIMM\" )
				( attribute "LINE_TO_LINE_SPACING" "10.00"
					( Origin gBackEnd )
				)
				( regionRef "@sapphirecity_baseboard_lib.sapphirecity_baseboard(sch_1):\DDR4_DIMM\" )
				( netClassRef "@sapphirecity_baseboard_lib.sapphirecity_baseboard(sch_1):\DDR4_CHN_C_DQ_DQS_BYTE6\" )
			)
			( regionClass "@crescent_city_bb_fab1_lib.crescent_city_bb_fab1(sch_1):\RC24\"
				( spacingCSetRef "@sapphirecity_baseboard_lib.sapphirecity_baseboard(sch_1):\DDR4_DIMM\" )
				( attribute "LINE_TO_LINE_SPACING" "10.00"
					( Origin gBackEnd )
				)
				( regionRef "@sapphirecity_baseboard_lib.sapphirecity_baseboard(sch_1):\DDR4_DIMM\" )
				( netClassRef "@sapphirecity_baseboard_lib.sapphirecity_baseboard(sch_1):\DDR4_CHN_C_DQ_DQS_BYTE7\" )
			)
			( regionClass "@crescent_city_bb_fab1_lib.crescent_city_bb_fab1(sch_1):\RC64\"
				( spacingCSetRef "@sapphirecity_baseboard_lib.sapphirecity_baseboard(sch_1):\DDR4_DIMM\" )
				( attribute "LINE_TO_LINE_SPACING" "10.00"
					( Origin gBackEnd )
				)
				( regionRef "@sapphirecity_baseboard_lib.sapphirecity_baseboard(sch_1):\DDR4_DIMM\" )
				( netClassRef "@sapphirecity_baseboard_lib.sapphirecity_baseboard(sch_1):\DDR4_CHN_C_ECC\" )
			)
			( regionClass "@crescent_city_bb_fab1_lib.crescent_city_bb_fab1(sch_1):\RC65\"
				( spacingCSetRef "@sapphirecity_baseboard_lib.sapphirecity_baseboard(sch_1):\DDR4_DIMM\" )
				( attribute "LINE_TO_LINE_SPACING" "10.00"
					( Origin gBackEnd )
				)
				( regionRef "@sapphirecity_baseboard_lib.sapphirecity_baseboard(sch_1):\DDR4_DIMM\" )
				( netClassRef "@sapphirecity_baseboard_lib.sapphirecity_baseboard(sch_1):\DDR4_CHN_D_CLK\" )
			)
			( regionClass "@crescent_city_bb_fab1_lib.crescent_city_bb_fab1(sch_1):\RC66\"
				( spacingCSetRef "@sapphirecity_baseboard_lib.sapphirecity_baseboard(sch_1):\DDR4_DIMM\" )
				( attribute "LINE_TO_LINE_SPACING" "10.00"
					( Origin gBackEnd )
				)
				( regionRef "@sapphirecity_baseboard_lib.sapphirecity_baseboard(sch_1):\DDR4_DIMM\" )
				( netClassRef "@sapphirecity_baseboard_lib.sapphirecity_baseboard(sch_1):\DDR4_CHN_D_CMD_ADD\" )
			)
			( regionClass "@crescent_city_bb_fab1_lib.crescent_city_bb_fab1(sch_1):\RC67\"
				( spacingCSetRef "@sapphirecity_baseboard_lib.sapphirecity_baseboard(sch_1):\DDR4_DIMM\" )
				( attribute "LINE_TO_LINE_SPACING" "10.00"
					( Origin gBackEnd )
				)
				( regionRef "@sapphirecity_baseboard_lib.sapphirecity_baseboard(sch_1):\DDR4_DIMM\" )
				( netClassRef "@sapphirecity_baseboard_lib.sapphirecity_baseboard(sch_1):\DDR4_CHN_D_CTRL\" )
			)
			( regionClass "@crescent_city_bb_fab1_lib.crescent_city_bb_fab1(sch_1):\RC27\"
				( spacingCSetRef "@sapphirecity_baseboard_lib.sapphirecity_baseboard(sch_1):\DDR4_DIMM\" )
				( attribute "LINE_TO_LINE_SPACING" "10.00"
					( Origin gBackEnd )
				)
				( regionRef "@sapphirecity_baseboard_lib.sapphirecity_baseboard(sch_1):\DDR4_DIMM\" )
				( netClassRef "@sapphirecity_baseboard_lib.sapphirecity_baseboard(sch_1):\DDR4_CHN_D_DQ_DQS_BYTE0\" )
			)
			( regionClass "@crescent_city_bb_fab1_lib.crescent_city_bb_fab1(sch_1):\RC28\"
				( spacingCSetRef "@sapphirecity_baseboard_lib.sapphirecity_baseboard(sch_1):\DDR4_DIMM\" )
				( attribute "LINE_TO_LINE_SPACING" "10.00"
					( Origin gBackEnd )
				)
				( regionRef "@sapphirecity_baseboard_lib.sapphirecity_baseboard(sch_1):\DDR4_DIMM\" )
				( netClassRef "@sapphirecity_baseboard_lib.sapphirecity_baseboard(sch_1):\DDR4_CHN_D_DQ_DQS_BYTE1\" )
			)
			( regionClass "@crescent_city_bb_fab1_lib.crescent_city_bb_fab1(sch_1):\RC29\"
				( spacingCSetRef "@sapphirecity_baseboard_lib.sapphirecity_baseboard(sch_1):\DDR4_DIMM\" )
				( attribute "LINE_TO_LINE_SPACING" "10.00"
					( Origin gBackEnd )
				)
				( regionRef "@sapphirecity_baseboard_lib.sapphirecity_baseboard(sch_1):\DDR4_DIMM\" )
				( netClassRef "@sapphirecity_baseboard_lib.sapphirecity_baseboard(sch_1):\DDR4_CHN_D_DQ_DQS_BYTE2\" )
			)
			( regionClass "@crescent_city_bb_fab1_lib.crescent_city_bb_fab1(sch_1):\RC30\"
				( spacingCSetRef "@sapphirecity_baseboard_lib.sapphirecity_baseboard(sch_1):\DDR4_DIMM\" )
				( attribute "LINE_TO_LINE_SPACING" "10.00"
					( Origin gBackEnd )
				)
				( regionRef "@sapphirecity_baseboard_lib.sapphirecity_baseboard(sch_1):\DDR4_DIMM\" )
				( netClassRef "@sapphirecity_baseboard_lib.sapphirecity_baseboard(sch_1):\DDR4_CHN_D_DQ_DQS_BYTE3\" )
			)
			( regionClass "@crescent_city_bb_fab1_lib.crescent_city_bb_fab1(sch_1):\RC31\"
				( spacingCSetRef "@sapphirecity_baseboard_lib.sapphirecity_baseboard(sch_1):\DDR4_DIMM\" )
				( attribute "LINE_TO_LINE_SPACING" "10.00"
					( Origin gBackEnd )
				)
				( regionRef "@sapphirecity_baseboard_lib.sapphirecity_baseboard(sch_1):\DDR4_DIMM\" )
				( netClassRef "@sapphirecity_baseboard_lib.sapphirecity_baseboard(sch_1):\DDR4_CHN_D_DQ_DQS_BYTE4\" )
			)
			( regionClass "@crescent_city_bb_fab1_lib.crescent_city_bb_fab1(sch_1):\RC32\"
				( spacingCSetRef "@sapphirecity_baseboard_lib.sapphirecity_baseboard(sch_1):\DDR4_DIMM\" )
				( attribute "LINE_TO_LINE_SPACING" "10.00"
					( Origin gBackEnd )
				)
				( regionRef "@sapphirecity_baseboard_lib.sapphirecity_baseboard(sch_1):\DDR4_DIMM\" )
				( netClassRef "@sapphirecity_baseboard_lib.sapphirecity_baseboard(sch_1):\DDR4_CHN_D_DQ_DQS_BYTE5\" )
			)
			( regionClass "@crescent_city_bb_fab1_lib.crescent_city_bb_fab1(sch_1):\RC33\"
				( spacingCSetRef "@sapphirecity_baseboard_lib.sapphirecity_baseboard(sch_1):\DDR4_DIMM\" )
				( attribute "LINE_TO_LINE_SPACING" "10.00"
					( Origin gBackEnd )
				)
				( regionRef "@sapphirecity_baseboard_lib.sapphirecity_baseboard(sch_1):\DDR4_DIMM\" )
				( netClassRef "@sapphirecity_baseboard_lib.sapphirecity_baseboard(sch_1):\DDR4_CHN_D_DQ_DQS_BYTE6\" )
			)
			( regionClass "@crescent_city_bb_fab1_lib.crescent_city_bb_fab1(sch_1):\RC34\"
				( spacingCSetRef "@sapphirecity_baseboard_lib.sapphirecity_baseboard(sch_1):\DDR4_DIMM\" )
				( attribute "LINE_TO_LINE_SPACING" "10.00"
					( Origin gBackEnd )
				)
				( regionRef "@sapphirecity_baseboard_lib.sapphirecity_baseboard(sch_1):\DDR4_DIMM\" )
				( netClassRef "@sapphirecity_baseboard_lib.sapphirecity_baseboard(sch_1):\DDR4_CHN_D_DQ_DQS_BYTE7\" )
			)
			( regionClass "@crescent_city_bb_fab1_lib.crescent_city_bb_fab1(sch_1):\RC35\"
				( spacingCSetRef "@sapphirecity_baseboard_lib.sapphirecity_baseboard(sch_1):\DDR4_DIMM\" )
				( attribute "LINE_TO_LINE_SPACING" "10.00"
					( Origin gBackEnd )
				)
				( regionRef "@sapphirecity_baseboard_lib.sapphirecity_baseboard(sch_1):\DDR4_DIMM\" )
				( netClassRef "@sapphirecity_baseboard_lib.sapphirecity_baseboard(sch_1):\DDR4_CHN_D_ECC\" )
			)
			( regionClass "@crescent_city_bb_fab1_lib.crescent_city_bb_fab1(sch_1):\RC68\"
				( spacingCSetRef "@sapphirecity_baseboard_lib.sapphirecity_baseboard(sch_1):\DDR4_DIMM\" )
				( attribute "LINE_TO_LINE_SPACING" "10.00"
					( Origin gBackEnd )
				)
				( regionRef "@sapphirecity_baseboard_lib.sapphirecity_baseboard(sch_1):\DDR4_DIMM\" )
				( netClassRef "@sapphirecity_baseboard_lib.sapphirecity_baseboard(sch_1):\DDR4_CHN_E_CLK\" )
			)
			( regionClass "@crescent_city_bb_fab1_lib.crescent_city_bb_fab1(sch_1):\RC69\"
				( spacingCSetRef "@sapphirecity_baseboard_lib.sapphirecity_baseboard(sch_1):\DDR4_DIMM\" )
				( attribute "LINE_TO_LINE_SPACING" "10.00"
					( Origin gBackEnd )
				)
				( regionRef "@sapphirecity_baseboard_lib.sapphirecity_baseboard(sch_1):\DDR4_DIMM\" )
				( netClassRef "@sapphirecity_baseboard_lib.sapphirecity_baseboard(sch_1):\DDR4_CHN_E_CMD_ADD\" )
			)
			( regionClass "@crescent_city_bb_fab1_lib.crescent_city_bb_fab1(sch_1):\RC25\"
				( spacingCSetRef "@sapphirecity_baseboard_lib.sapphirecity_baseboard(sch_1):\DDR4_DIMM\" )
				( attribute "LINE_TO_LINE_SPACING" "10.00"
					( Origin gBackEnd )
				)
				( regionRef "@sapphirecity_baseboard_lib.sapphirecity_baseboard(sch_1):\DDR4_DIMM\" )
				( netClassRef "@sapphirecity_baseboard_lib.sapphirecity_baseboard(sch_1):\DDR4_CHN_E_CTRL\" )
			)
			( regionClass "@crescent_city_bb_fab1_lib.crescent_city_bb_fab1(sch_1):\RC36\"
				( spacingCSetRef "@sapphirecity_baseboard_lib.sapphirecity_baseboard(sch_1):\DDR4_DIMM\" )
				( attribute "LINE_TO_LINE_SPACING" "10.00"
					( Origin gBackEnd )
				)
				( regionRef "@sapphirecity_baseboard_lib.sapphirecity_baseboard(sch_1):\DDR4_DIMM\" )
				( netClassRef "@sapphirecity_baseboard_lib.sapphirecity_baseboard(sch_1):\DDR4_CHN_E_DQ_DQS_BYTE0\" )
			)
			( regionClass "@crescent_city_bb_fab1_lib.crescent_city_bb_fab1(sch_1):\RC37\"
				( spacingCSetRef "@sapphirecity_baseboard_lib.sapphirecity_baseboard(sch_1):\DDR4_DIMM\" )
				( attribute "LINE_TO_LINE_SPACING" "10.00"
					( Origin gBackEnd )
				)
				( regionRef "@sapphirecity_baseboard_lib.sapphirecity_baseboard(sch_1):\DDR4_DIMM\" )
				( netClassRef "@sapphirecity_baseboard_lib.sapphirecity_baseboard(sch_1):\DDR4_CHN_E_DQ_DQS_BYTE1\" )
			)
			( regionClass "@crescent_city_bb_fab1_lib.crescent_city_bb_fab1(sch_1):\RC38\"
				( spacingCSetRef "@sapphirecity_baseboard_lib.sapphirecity_baseboard(sch_1):\DDR4_DIMM\" )
				( attribute "LINE_TO_LINE_SPACING" "10.00"
					( Origin gBackEnd )
				)
				( regionRef "@sapphirecity_baseboard_lib.sapphirecity_baseboard(sch_1):\DDR4_DIMM\" )
				( netClassRef "@sapphirecity_baseboard_lib.sapphirecity_baseboard(sch_1):\DDR4_CHN_E_DQ_DQS_BYTE2\" )
			)
			( regionClass "@crescent_city_bb_fab1_lib.crescent_city_bb_fab1(sch_1):\RC39\"
				( spacingCSetRef "@sapphirecity_baseboard_lib.sapphirecity_baseboard(sch_1):\DDR4_DIMM\" )
				( attribute "LINE_TO_LINE_SPACING" "10.00"
					( Origin gBackEnd )
				)
				( regionRef "@sapphirecity_baseboard_lib.sapphirecity_baseboard(sch_1):\DDR4_DIMM\" )
				( netClassRef "@sapphirecity_baseboard_lib.sapphirecity_baseboard(sch_1):\DDR4_CHN_E_DQ_DQS_BYTE3\" )
			)
			( regionClass "@crescent_city_bb_fab1_lib.crescent_city_bb_fab1(sch_1):\RC40\"
				( spacingCSetRef "@sapphirecity_baseboard_lib.sapphirecity_baseboard(sch_1):\DDR4_DIMM\" )
				( attribute "LINE_TO_LINE_SPACING" "10.00"
					( Origin gBackEnd )
				)
				( regionRef "@sapphirecity_baseboard_lib.sapphirecity_baseboard(sch_1):\DDR4_DIMM\" )
				( netClassRef "@sapphirecity_baseboard_lib.sapphirecity_baseboard(sch_1):\DDR4_CHN_E_DQ_DQS_BYTE4\" )
			)
			( regionClass "@crescent_city_bb_fab1_lib.crescent_city_bb_fab1(sch_1):\RC41\"
				( spacingCSetRef "@sapphirecity_baseboard_lib.sapphirecity_baseboard(sch_1):\DDR4_DIMM\" )
				( attribute "LINE_TO_LINE_SPACING" "10.00"
					( Origin gBackEnd )
				)
				( regionRef "@sapphirecity_baseboard_lib.sapphirecity_baseboard(sch_1):\DDR4_DIMM\" )
				( netClassRef "@sapphirecity_baseboard_lib.sapphirecity_baseboard(sch_1):\DDR4_CHN_E_DQ_DQS_BYTE5\" )
			)
			( regionClass "@crescent_city_bb_fab1_lib.crescent_city_bb_fab1(sch_1):\RC42\"
				( spacingCSetRef "@sapphirecity_baseboard_lib.sapphirecity_baseboard(sch_1):\DDR4_DIMM\" )
				( attribute "LINE_TO_LINE_SPACING" "10.00"
					( Origin gBackEnd )
				)
				( regionRef "@sapphirecity_baseboard_lib.sapphirecity_baseboard(sch_1):\DDR4_DIMM\" )
				( netClassRef "@sapphirecity_baseboard_lib.sapphirecity_baseboard(sch_1):\DDR4_CHN_E_DQ_DQS_BYTE6\" )
			)
			( regionClass "@crescent_city_bb_fab1_lib.crescent_city_bb_fab1(sch_1):\RC43\"
				( spacingCSetRef "@sapphirecity_baseboard_lib.sapphirecity_baseboard(sch_1):\DDR4_DIMM\" )
				( attribute "LINE_TO_LINE_SPACING" "10.00"
					( Origin gBackEnd )
				)
				( regionRef "@sapphirecity_baseboard_lib.sapphirecity_baseboard(sch_1):\DDR4_DIMM\" )
				( netClassRef "@sapphirecity_baseboard_lib.sapphirecity_baseboard(sch_1):\DDR4_CHN_E_DQ_DQS_BYTE7\" )
			)
			( regionClass "@crescent_city_bb_fab1_lib.crescent_city_bb_fab1(sch_1):\RC44\"
				( spacingCSetRef "@sapphirecity_baseboard_lib.sapphirecity_baseboard(sch_1):\DDR4_DIMM\" )
				( attribute "LINE_TO_LINE_SPACING" "10.00"
					( Origin gBackEnd )
				)
				( regionRef "@sapphirecity_baseboard_lib.sapphirecity_baseboard(sch_1):\DDR4_DIMM\" )
				( netClassRef "@sapphirecity_baseboard_lib.sapphirecity_baseboard(sch_1):\DDR4_CHN_E_ECC\" )
			)
			( regionClass "@crescent_city_bb_fab1_lib.crescent_city_bb_fab1(sch_1):\RC26\"
				( spacingCSetRef "@sapphirecity_baseboard_lib.sapphirecity_baseboard(sch_1):\DDR4_DIMM\" )
				( attribute "LINE_TO_LINE_SPACING" "10.00"
					( Origin gBackEnd )
				)
				( regionRef "@sapphirecity_baseboard_lib.sapphirecity_baseboard(sch_1):\DDR4_DIMM\" )
				( netClassRef "@sapphirecity_baseboard_lib.sapphirecity_baseboard(sch_1):\DDR4_CHN_F_CLK\" )
			)
			( regionClass "@crescent_city_bb_fab1_lib.crescent_city_bb_fab1(sch_1):\RC70\"
				( spacingCSetRef "@sapphirecity_baseboard_lib.sapphirecity_baseboard(sch_1):\DDR4_DIMM\" )
				( attribute "LINE_TO_LINE_SPACING" "10.00"
					( Origin gBackEnd )
				)
				( regionRef "@sapphirecity_baseboard_lib.sapphirecity_baseboard(sch_1):\DDR4_DIMM\" )
				( netClassRef "@sapphirecity_baseboard_lib.sapphirecity_baseboard(sch_1):\DDR4_CHN_F_CMD_ADD\" )
			)
			( regionClass "@crescent_city_bb_fab1_lib.crescent_city_bb_fab1(sch_1):\RC71\"
				( spacingCSetRef "@sapphirecity_baseboard_lib.sapphirecity_baseboard(sch_1):\DDR4_DIMM\" )
				( attribute "LINE_TO_LINE_SPACING" "10.00"
					( Origin gBackEnd )
				)
				( regionRef "@sapphirecity_baseboard_lib.sapphirecity_baseboard(sch_1):\DDR4_DIMM\" )
				( netClassRef "@sapphirecity_baseboard_lib.sapphirecity_baseboard(sch_1):\DDR4_CHN_F_CTRL\" )
			)
			( regionClass "@crescent_city_bb_fab1_lib.crescent_city_bb_fab1(sch_1):\RC45\"
				( spacingCSetRef "@sapphirecity_baseboard_lib.sapphirecity_baseboard(sch_1):\DDR4_DIMM\" )
				( attribute "LINE_TO_LINE_SPACING" "10.00"
					( Origin gBackEnd )
				)
				( regionRef "@sapphirecity_baseboard_lib.sapphirecity_baseboard(sch_1):\DDR4_DIMM\" )
				( netClassRef "@sapphirecity_baseboard_lib.sapphirecity_baseboard(sch_1):\DDR4_CHN_F_DQ_DQS_BYTE0\" )
			)
			( regionClass "@crescent_city_bb_fab1_lib.crescent_city_bb_fab1(sch_1):\RC46\"
				( spacingCSetRef "@sapphirecity_baseboard_lib.sapphirecity_baseboard(sch_1):\DDR4_DIMM\" )
				( attribute "LINE_TO_LINE_SPACING" "10.00"
					( Origin gBackEnd )
				)
				( regionRef "@sapphirecity_baseboard_lib.sapphirecity_baseboard(sch_1):\DDR4_DIMM\" )
				( netClassRef "@sapphirecity_baseboard_lib.sapphirecity_baseboard(sch_1):\DDR4_CHN_F_DQ_DQS_BYTE1\" )
			)
			( regionClass "@crescent_city_bb_fab1_lib.crescent_city_bb_fab1(sch_1):\RC47\"
				( spacingCSetRef "@sapphirecity_baseboard_lib.sapphirecity_baseboard(sch_1):\DDR4_DIMM\" )
				( attribute "LINE_TO_LINE_SPACING" "10.00"
					( Origin gBackEnd )
				)
				( regionRef "@sapphirecity_baseboard_lib.sapphirecity_baseboard(sch_1):\DDR4_DIMM\" )
				( netClassRef "@sapphirecity_baseboard_lib.sapphirecity_baseboard(sch_1):\DDR4_CHN_F_DQ_DQS_BYTE2\" )
			)
			( regionClass "@crescent_city_bb_fab1_lib.crescent_city_bb_fab1(sch_1):\RC48\"
				( spacingCSetRef "@sapphirecity_baseboard_lib.sapphirecity_baseboard(sch_1):\DDR4_DIMM\" )
				( attribute "LINE_TO_LINE_SPACING" "10.00"
					( Origin gBackEnd )
				)
				( regionRef "@sapphirecity_baseboard_lib.sapphirecity_baseboard(sch_1):\DDR4_DIMM\" )
				( netClassRef "@sapphirecity_baseboard_lib.sapphirecity_baseboard(sch_1):\DDR4_CHN_F_DQ_DQS_BYTE3\" )
			)
			( regionClass "@crescent_city_bb_fab1_lib.crescent_city_bb_fab1(sch_1):\RC49\"
				( spacingCSetRef "@sapphirecity_baseboard_lib.sapphirecity_baseboard(sch_1):\DDR4_DIMM\" )
				( attribute "LINE_TO_LINE_SPACING" "10.00"
					( Origin gBackEnd )
				)
				( regionRef "@sapphirecity_baseboard_lib.sapphirecity_baseboard(sch_1):\DDR4_DIMM\" )
				( netClassRef "@sapphirecity_baseboard_lib.sapphirecity_baseboard(sch_1):\DDR4_CHN_F_DQ_DQS_BYTE4\" )
			)
			( regionClass "@crescent_city_bb_fab1_lib.crescent_city_bb_fab1(sch_1):\RC50\"
				( spacingCSetRef "@sapphirecity_baseboard_lib.sapphirecity_baseboard(sch_1):\DDR4_DIMM\" )
				( attribute "LINE_TO_LINE_SPACING" "10.00"
					( Origin gBackEnd )
				)
				( regionRef "@sapphirecity_baseboard_lib.sapphirecity_baseboard(sch_1):\DDR4_DIMM\" )
				( netClassRef "@sapphirecity_baseboard_lib.sapphirecity_baseboard(sch_1):\DDR4_CHN_F_DQ_DQS_BYTE5\" )
			)
			( regionClass "@crescent_city_bb_fab1_lib.crescent_city_bb_fab1(sch_1):\RC51\"
				( spacingCSetRef "@sapphirecity_baseboard_lib.sapphirecity_baseboard(sch_1):\DDR4_DIMM\" )
				( attribute "LINE_TO_LINE_SPACING" "10.00"
					( Origin gBackEnd )
				)
				( regionRef "@sapphirecity_baseboard_lib.sapphirecity_baseboard(sch_1):\DDR4_DIMM\" )
				( netClassRef "@sapphirecity_baseboard_lib.sapphirecity_baseboard(sch_1):\DDR4_CHN_F_DQ_DQS_BYTE6\" )
			)
			( regionClass "@crescent_city_bb_fab1_lib.crescent_city_bb_fab1(sch_1):\RC52\"
				( spacingCSetRef "@sapphirecity_baseboard_lib.sapphirecity_baseboard(sch_1):\DDR4_DIMM\" )
				( attribute "LINE_TO_LINE_SPACING" "10.00"
					( Origin gBackEnd )
				)
				( regionRef "@sapphirecity_baseboard_lib.sapphirecity_baseboard(sch_1):\DDR4_DIMM\" )
				( netClassRef "@sapphirecity_baseboard_lib.sapphirecity_baseboard(sch_1):\DDR4_CHN_F_DQ_DQS_BYTE7\" )
			)
			( regionClass "@crescent_city_bb_fab1_lib.crescent_city_bb_fab1(sch_1):\RC53\"
				( spacingCSetRef "@sapphirecity_baseboard_lib.sapphirecity_baseboard(sch_1):\DDR4_DIMM\" )
				( attribute "LINE_TO_LINE_SPACING" "10.00"
					( Origin gBackEnd )
				)
				( regionRef "@sapphirecity_baseboard_lib.sapphirecity_baseboard(sch_1):\DDR4_DIMM\" )
				( netClassRef "@sapphirecity_baseboard_lib.sapphirecity_baseboard(sch_1):\DDR4_CHN_F_ECC\" )
			)
			( regionClass "@crescent_city_bb_fab1_lib.crescent_city_bb_fab1(sch_1):\RC72\"
				( spacingCSetRef "@sapphirecity_baseboard_lib.sapphirecity_baseboard(sch_1):\DDR4_DIMM\" )
				( attribute "LINE_TO_LINE_SPACING" "10.00"
					( Origin gBackEnd )
				)
				( regionRef "@sapphirecity_baseboard_lib.sapphirecity_baseboard(sch_1):\DDR4_DIMM\" )
				( netClassRef "@sapphirecity_baseboard_lib.sapphirecity_baseboard(sch_1):\DDR4_CHN_G_CLK\" )
			)
			( regionClass "@crescent_city_bb_fab1_lib.crescent_city_bb_fab1(sch_1):\RC73\"
				( spacingCSetRef "@sapphirecity_baseboard_lib.sapphirecity_baseboard(sch_1):\DDR4_DIMM\" )
				( attribute "LINE_TO_LINE_SPACING" "10.00"
					( Origin gBackEnd )
				)
				( regionRef "@sapphirecity_baseboard_lib.sapphirecity_baseboard(sch_1):\DDR4_DIMM\" )
				( netClassRef "@sapphirecity_baseboard_lib.sapphirecity_baseboard(sch_1):\DDR4_CHN_G_CMD_ADD\" )
			)
			( regionClass "@crescent_city_bb_fab1_lib.crescent_city_bb_fab1(sch_1):\RC74\"
				( spacingCSetRef "@sapphirecity_baseboard_lib.sapphirecity_baseboard(sch_1):\DDR4_DIMM\" )
				( attribute "LINE_TO_LINE_SPACING" "10.00"
					( Origin gBackEnd )
				)
				( regionRef "@sapphirecity_baseboard_lib.sapphirecity_baseboard(sch_1):\DDR4_DIMM\" )
				( netClassRef "@sapphirecity_baseboard_lib.sapphirecity_baseboard(sch_1):\DDR4_CHN_G_CTRL\" )
			)
			( regionClass "@crescent_city_bb_fab1_lib.crescent_city_bb_fab1(sch_1):\RC90\"
				( spacingCSetRef "@sapphirecity_baseboard_lib.sapphirecity_baseboard(sch_1):\DDR4_DIMM\" )
				( attribute "LINE_TO_LINE_SPACING" "10.00"
					( Origin gBackEnd )
				)
				( regionRef "@sapphirecity_baseboard_lib.sapphirecity_baseboard(sch_1):\DDR4_DIMM\" )
				( netClassRef "@sapphirecity_baseboard_lib.sapphirecity_baseboard(sch_1):\DDR4_CHN_G_DQ_DQS_BYTE0\" )
			)
			( regionClass "@crescent_city_bb_fab1_lib.crescent_city_bb_fab1(sch_1):\RC91\"
				( spacingCSetRef "@sapphirecity_baseboard_lib.sapphirecity_baseboard(sch_1):\DDR4_DIMM\" )
				( attribute "LINE_TO_LINE_SPACING" "10.00"
					( Origin gBackEnd )
				)
				( regionRef "@sapphirecity_baseboard_lib.sapphirecity_baseboard(sch_1):\DDR4_DIMM\" )
				( netClassRef "@sapphirecity_baseboard_lib.sapphirecity_baseboard(sch_1):\DDR4_CHN_G_DQ_DQS_BYTE1\" )
			)
			( regionClass "@crescent_city_bb_fab1_lib.crescent_city_bb_fab1(sch_1):\RC92\"
				( spacingCSetRef "@sapphirecity_baseboard_lib.sapphirecity_baseboard(sch_1):\DDR4_DIMM\" )
				( attribute "LINE_TO_LINE_SPACING" "10.00"
					( Origin gBackEnd )
				)
				( regionRef "@sapphirecity_baseboard_lib.sapphirecity_baseboard(sch_1):\DDR4_DIMM\" )
				( netClassRef "@sapphirecity_baseboard_lib.sapphirecity_baseboard(sch_1):\DDR4_CHN_G_DQ_DQS_BYTE2\" )
			)
			( regionClass "@crescent_city_bb_fab1_lib.crescent_city_bb_fab1(sch_1):\RC93\"
				( spacingCSetRef "@sapphirecity_baseboard_lib.sapphirecity_baseboard(sch_1):\DDR4_DIMM\" )
				( attribute "LINE_TO_LINE_SPACING" "10.00"
					( Origin gBackEnd )
				)
				( regionRef "@sapphirecity_baseboard_lib.sapphirecity_baseboard(sch_1):\DDR4_DIMM\" )
				( netClassRef "@sapphirecity_baseboard_lib.sapphirecity_baseboard(sch_1):\DDR4_CHN_G_DQ_DQS_BYTE3\" )
			)
			( regionClass "@crescent_city_bb_fab1_lib.crescent_city_bb_fab1(sch_1):\RC94\"
				( spacingCSetRef "@sapphirecity_baseboard_lib.sapphirecity_baseboard(sch_1):\DDR4_DIMM\" )
				( attribute "LINE_TO_LINE_SPACING" "10.00"
					( Origin gBackEnd )
				)
				( regionRef "@sapphirecity_baseboard_lib.sapphirecity_baseboard(sch_1):\DDR4_DIMM\" )
				( netClassRef "@sapphirecity_baseboard_lib.sapphirecity_baseboard(sch_1):\DDR4_CHN_G_DQ_DQS_BYTE4\" )
			)
			( regionClass "@crescent_city_bb_fab1_lib.crescent_city_bb_fab1(sch_1):\RC95\"
				( spacingCSetRef "@sapphirecity_baseboard_lib.sapphirecity_baseboard(sch_1):\DDR4_DIMM\" )
				( attribute "LINE_TO_LINE_SPACING" "10.00"
					( Origin gBackEnd )
				)
				( regionRef "@sapphirecity_baseboard_lib.sapphirecity_baseboard(sch_1):\DDR4_DIMM\" )
				( netClassRef "@sapphirecity_baseboard_lib.sapphirecity_baseboard(sch_1):\DDR4_CHN_G_DQ_DQS_BYTE5\" )
			)
			( regionClass "@crescent_city_bb_fab1_lib.crescent_city_bb_fab1(sch_1):\RC96\"
				( spacingCSetRef "@sapphirecity_baseboard_lib.sapphirecity_baseboard(sch_1):\DDR4_DIMM\" )
				( attribute "LINE_TO_LINE_SPACING" "10.00"
					( Origin gBackEnd )
				)
				( regionRef "@sapphirecity_baseboard_lib.sapphirecity_baseboard(sch_1):\DDR4_DIMM\" )
				( netClassRef "@sapphirecity_baseboard_lib.sapphirecity_baseboard(sch_1):\DDR4_CHN_G_DQ_DQS_BYTE6\" )
			)
			( regionClass "@crescent_city_bb_fab1_lib.crescent_city_bb_fab1(sch_1):\RC97\"
				( spacingCSetRef "@sapphirecity_baseboard_lib.sapphirecity_baseboard(sch_1):\DDR4_DIMM\" )
				( attribute "LINE_TO_LINE_SPACING" "10.00"
					( Origin gBackEnd )
				)
				( regionRef "@sapphirecity_baseboard_lib.sapphirecity_baseboard(sch_1):\DDR4_DIMM\" )
				( netClassRef "@sapphirecity_baseboard_lib.sapphirecity_baseboard(sch_1):\DDR4_CHN_G_DQ_DQS_BYTE7\" )
			)
			( regionClass "@crescent_city_bb_fab1_lib.crescent_city_bb_fab1(sch_1):\RC98\"
				( spacingCSetRef "@sapphirecity_baseboard_lib.sapphirecity_baseboard(sch_1):\DDR4_DIMM\" )
				( attribute "LINE_TO_LINE_SPACING" "10.00"
					( Origin gBackEnd )
				)
				( regionRef "@sapphirecity_baseboard_lib.sapphirecity_baseboard(sch_1):\DDR4_DIMM\" )
				( netClassRef "@sapphirecity_baseboard_lib.sapphirecity_baseboard(sch_1):\DDR4_CHN_G_ECC\" )
			)
			( regionClass "@crescent_city_bb_fab1_lib.crescent_city_bb_fab1(sch_1):\RC75\"
				( spacingCSetRef "@sapphirecity_baseboard_lib.sapphirecity_baseboard(sch_1):\DDR4_DIMM\" )
				( attribute "LINE_TO_LINE_SPACING" "10.00"
					( Origin gBackEnd )
				)
				( regionRef "@sapphirecity_baseboard_lib.sapphirecity_baseboard(sch_1):\DDR4_DIMM\" )
				( netClassRef "@sapphirecity_baseboard_lib.sapphirecity_baseboard(sch_1):\DDR4_CHN_H_CLK\" )
			)
			( regionClass "@crescent_city_bb_fab1_lib.crescent_city_bb_fab1(sch_1):\RC76\"
				( spacingCSetRef "@sapphirecity_baseboard_lib.sapphirecity_baseboard(sch_1):\DDR4_DIMM\" )
				( attribute "LINE_TO_LINE_SPACING" "10.00"
					( Origin gBackEnd )
				)
				( regionRef "@sapphirecity_baseboard_lib.sapphirecity_baseboard(sch_1):\DDR4_DIMM\" )
				( netClassRef "@sapphirecity_baseboard_lib.sapphirecity_baseboard(sch_1):\DDR4_CHN_H_CMD_ADD\" )
			)
			( regionClass "@crescent_city_bb_fab1_lib.crescent_city_bb_fab1(sch_1):\RC77\"
				( spacingCSetRef "@sapphirecity_baseboard_lib.sapphirecity_baseboard(sch_1):\DDR4_DIMM\" )
				( attribute "LINE_TO_LINE_SPACING" "10.00"
					( Origin gBackEnd )
				)
				( regionRef "@sapphirecity_baseboard_lib.sapphirecity_baseboard(sch_1):\DDR4_DIMM\" )
				( netClassRef "@sapphirecity_baseboard_lib.sapphirecity_baseboard(sch_1):\DDR4_CHN_H_CTRL\" )
			)
			( regionClass "@crescent_city_bb_fab1_lib.crescent_city_bb_fab1(sch_1):\RC99\"
				( spacingCSetRef "@sapphirecity_baseboard_lib.sapphirecity_baseboard(sch_1):\DDR4_DIMM\" )
				( attribute "LINE_TO_LINE_SPACING" "10.00"
					( Origin gBackEnd )
				)
				( regionRef "@sapphirecity_baseboard_lib.sapphirecity_baseboard(sch_1):\DDR4_DIMM\" )
				( netClassRef "@sapphirecity_baseboard_lib.sapphirecity_baseboard(sch_1):\DDR4_CHN_H_DQ_DQS_BYTE0\" )
			)
			( regionClass "@crescent_city_bb_fab1_lib.crescent_city_bb_fab1(sch_1):\RC100\"
				( spacingCSetRef "@sapphirecity_baseboard_lib.sapphirecity_baseboard(sch_1):\DDR4_DIMM\" )
				( attribute "LINE_TO_LINE_SPACING" "10.00"
					( Origin gBackEnd )
				)
				( regionRef "@sapphirecity_baseboard_lib.sapphirecity_baseboard(sch_1):\DDR4_DIMM\" )
				( netClassRef "@sapphirecity_baseboard_lib.sapphirecity_baseboard(sch_1):\DDR4_CHN_H_DQ_DQS_BYTE1\" )
			)
			( regionClass "@crescent_city_bb_fab1_lib.crescent_city_bb_fab1(sch_1):\RC101\"
				( spacingCSetRef "@sapphirecity_baseboard_lib.sapphirecity_baseboard(sch_1):\DDR4_DIMM\" )
				( attribute "LINE_TO_LINE_SPACING" "10.00"
					( Origin gBackEnd )
				)
				( regionRef "@sapphirecity_baseboard_lib.sapphirecity_baseboard(sch_1):\DDR4_DIMM\" )
				( netClassRef "@sapphirecity_baseboard_lib.sapphirecity_baseboard(sch_1):\DDR4_CHN_H_DQ_DQS_BYTE2\" )
			)
			( regionClass "@crescent_city_bb_fab1_lib.crescent_city_bb_fab1(sch_1):\RC102\"
				( spacingCSetRef "@sapphirecity_baseboard_lib.sapphirecity_baseboard(sch_1):\DDR4_DIMM\" )
				( attribute "LINE_TO_LINE_SPACING" "10.00"
					( Origin gBackEnd )
				)
				( regionRef "@sapphirecity_baseboard_lib.sapphirecity_baseboard(sch_1):\DDR4_DIMM\" )
				( netClassRef "@sapphirecity_baseboard_lib.sapphirecity_baseboard(sch_1):\DDR4_CHN_H_DQ_DQS_BYTE3\" )
			)
			( regionClass "@crescent_city_bb_fab1_lib.crescent_city_bb_fab1(sch_1):\RC103\"
				( spacingCSetRef "@sapphirecity_baseboard_lib.sapphirecity_baseboard(sch_1):\DDR4_DIMM\" )
				( attribute "LINE_TO_LINE_SPACING" "10.00"
					( Origin gBackEnd )
				)
				( regionRef "@sapphirecity_baseboard_lib.sapphirecity_baseboard(sch_1):\DDR4_DIMM\" )
				( netClassRef "@sapphirecity_baseboard_lib.sapphirecity_baseboard(sch_1):\DDR4_CHN_H_DQ_DQS_BYTE4\" )
			)
			( regionClass "@crescent_city_bb_fab1_lib.crescent_city_bb_fab1(sch_1):\RC104\"
				( spacingCSetRef "@sapphirecity_baseboard_lib.sapphirecity_baseboard(sch_1):\DDR4_DIMM\" )
				( attribute "LINE_TO_LINE_SPACING" "10.00"
					( Origin gBackEnd )
				)
				( regionRef "@sapphirecity_baseboard_lib.sapphirecity_baseboard(sch_1):\DDR4_DIMM\" )
				( netClassRef "@sapphirecity_baseboard_lib.sapphirecity_baseboard(sch_1):\DDR4_CHN_H_DQ_DQS_BYTE5\" )
			)
			( regionClass "@crescent_city_bb_fab1_lib.crescent_city_bb_fab1(sch_1):\RC105\"
				( spacingCSetRef "@sapphirecity_baseboard_lib.sapphirecity_baseboard(sch_1):\DDR4_DIMM\" )
				( attribute "LINE_TO_LINE_SPACING" "10.00"
					( Origin gBackEnd )
				)
				( regionRef "@sapphirecity_baseboard_lib.sapphirecity_baseboard(sch_1):\DDR4_DIMM\" )
				( netClassRef "@sapphirecity_baseboard_lib.sapphirecity_baseboard(sch_1):\DDR4_CHN_H_DQ_DQS_BYTE6\" )
			)
			( regionClass "@crescent_city_bb_fab1_lib.crescent_city_bb_fab1(sch_1):\RC106\"
				( spacingCSetRef "@sapphirecity_baseboard_lib.sapphirecity_baseboard(sch_1):\DDR4_DIMM\" )
				( attribute "LINE_TO_LINE_SPACING" "10.00"
					( Origin gBackEnd )
				)
				( regionRef "@sapphirecity_baseboard_lib.sapphirecity_baseboard(sch_1):\DDR4_DIMM\" )
				( netClassRef "@sapphirecity_baseboard_lib.sapphirecity_baseboard(sch_1):\DDR4_CHN_H_DQ_DQS_BYTE7\" )
			)
			( regionClass "@crescent_city_bb_fab1_lib.crescent_city_bb_fab1(sch_1):\RC107\"
				( spacingCSetRef "@sapphirecity_baseboard_lib.sapphirecity_baseboard(sch_1):\DDR4_DIMM\" )
				( attribute "LINE_TO_LINE_SPACING" "10.00"
					( Origin gBackEnd )
				)
				( regionRef "@sapphirecity_baseboard_lib.sapphirecity_baseboard(sch_1):\DDR4_DIMM\" )
				( netClassRef "@sapphirecity_baseboard_lib.sapphirecity_baseboard(sch_1):\DDR4_CHN_H_ECC\" )
			)
			( regionClass "@crescent_city_bb_fab1_lib.crescent_city_bb_fab1(sch_1):\RC78\"
				( spacingCSetRef "@sapphirecity_baseboard_lib.sapphirecity_baseboard(sch_1):\DDR4_DIMM\" )
				( attribute "LINE_TO_LINE_SPACING" "10.00"
					( Origin gBackEnd )
				)
				( regionRef "@sapphirecity_baseboard_lib.sapphirecity_baseboard(sch_1):\DDR4_DIMM\" )
				( netClassRef "@sapphirecity_baseboard_lib.sapphirecity_baseboard(sch_1):\DDR4_CHN_J_CLK\" )
			)
			( regionClass "@crescent_city_bb_fab1_lib.crescent_city_bb_fab1(sch_1):\RC79\"
				( spacingCSetRef "@sapphirecity_baseboard_lib.sapphirecity_baseboard(sch_1):\DDR4_DIMM\" )
				( attribute "LINE_TO_LINE_SPACING" "10.00"
					( Origin gBackEnd )
				)
				( regionRef "@sapphirecity_baseboard_lib.sapphirecity_baseboard(sch_1):\DDR4_DIMM\" )
				( netClassRef "@sapphirecity_baseboard_lib.sapphirecity_baseboard(sch_1):\DDR4_CHN_J_CMD_ADD\" )
			)
			( regionClass "@crescent_city_bb_fab1_lib.crescent_city_bb_fab1(sch_1):\RC80\"
				( spacingCSetRef "@sapphirecity_baseboard_lib.sapphirecity_baseboard(sch_1):\DDR4_DIMM\" )
				( attribute "LINE_TO_LINE_SPACING" "10.00"
					( Origin gBackEnd )
				)
				( regionRef "@sapphirecity_baseboard_lib.sapphirecity_baseboard(sch_1):\DDR4_DIMM\" )
				( netClassRef "@sapphirecity_baseboard_lib.sapphirecity_baseboard(sch_1):\DDR4_CHN_J_CTRL\" )
			)
			( regionClass "@crescent_city_bb_fab1_lib.crescent_city_bb_fab1(sch_1):\RC108\"
				( spacingCSetRef "@sapphirecity_baseboard_lib.sapphirecity_baseboard(sch_1):\DDR4_DIMM\" )
				( attribute "LINE_TO_LINE_SPACING" "10.00"
					( Origin gBackEnd )
				)
				( regionRef "@sapphirecity_baseboard_lib.sapphirecity_baseboard(sch_1):\DDR4_DIMM\" )
				( netClassRef "@sapphirecity_baseboard_lib.sapphirecity_baseboard(sch_1):\DDR4_CHN_J_DQ_DQS_BYTE0\" )
			)
			( regionClass "@crescent_city_bb_fab1_lib.crescent_city_bb_fab1(sch_1):\RC109\"
				( spacingCSetRef "@sapphirecity_baseboard_lib.sapphirecity_baseboard(sch_1):\DDR4_DIMM\" )
				( attribute "LINE_TO_LINE_SPACING" "10.00"
					( Origin gBackEnd )
				)
				( regionRef "@sapphirecity_baseboard_lib.sapphirecity_baseboard(sch_1):\DDR4_DIMM\" )
				( netClassRef "@sapphirecity_baseboard_lib.sapphirecity_baseboard(sch_1):\DDR4_CHN_J_DQ_DQS_BYTE1\" )
			)
			( regionClass "@crescent_city_bb_fab1_lib.crescent_city_bb_fab1(sch_1):\RC110\"
				( spacingCSetRef "@sapphirecity_baseboard_lib.sapphirecity_baseboard(sch_1):\DDR4_DIMM\" )
				( attribute "LINE_TO_LINE_SPACING" "10.00"
					( Origin gBackEnd )
				)
				( regionRef "@sapphirecity_baseboard_lib.sapphirecity_baseboard(sch_1):\DDR4_DIMM\" )
				( netClassRef "@sapphirecity_baseboard_lib.sapphirecity_baseboard(sch_1):\DDR4_CHN_J_DQ_DQS_BYTE2\" )
			)
			( regionClass "@crescent_city_bb_fab1_lib.crescent_city_bb_fab1(sch_1):\RC111\"
				( spacingCSetRef "@sapphirecity_baseboard_lib.sapphirecity_baseboard(sch_1):\DDR4_DIMM\" )
				( attribute "LINE_TO_LINE_SPACING" "10.00"
					( Origin gBackEnd )
				)
				( regionRef "@sapphirecity_baseboard_lib.sapphirecity_baseboard(sch_1):\DDR4_DIMM\" )
				( netClassRef "@sapphirecity_baseboard_lib.sapphirecity_baseboard(sch_1):\DDR4_CHN_J_DQ_DQS_BYTE3\" )
			)
			( regionClass "@crescent_city_bb_fab1_lib.crescent_city_bb_fab1(sch_1):\RC112\"
				( spacingCSetRef "@sapphirecity_baseboard_lib.sapphirecity_baseboard(sch_1):\DDR4_DIMM\" )
				( attribute "LINE_TO_LINE_SPACING" "10.00"
					( Origin gBackEnd )
				)
				( regionRef "@sapphirecity_baseboard_lib.sapphirecity_baseboard(sch_1):\DDR4_DIMM\" )
				( netClassRef "@sapphirecity_baseboard_lib.sapphirecity_baseboard(sch_1):\DDR4_CHN_J_DQ_DQS_BYTE4\" )
			)
			( regionClass "@crescent_city_bb_fab1_lib.crescent_city_bb_fab1(sch_1):\RC113\"
				( spacingCSetRef "@sapphirecity_baseboard_lib.sapphirecity_baseboard(sch_1):\DDR4_DIMM\" )
				( attribute "LINE_TO_LINE_SPACING" "10.00"
					( Origin gBackEnd )
				)
				( regionRef "@sapphirecity_baseboard_lib.sapphirecity_baseboard(sch_1):\DDR4_DIMM\" )
				( netClassRef "@sapphirecity_baseboard_lib.sapphirecity_baseboard(sch_1):\DDR4_CHN_J_DQ_DQS_BYTE5\" )
			)
			( regionClass "@crescent_city_bb_fab1_lib.crescent_city_bb_fab1(sch_1):\RC114\"
				( spacingCSetRef "@sapphirecity_baseboard_lib.sapphirecity_baseboard(sch_1):\DDR4_DIMM\" )
				( attribute "LINE_TO_LINE_SPACING" "10.00"
					( Origin gBackEnd )
				)
				( regionRef "@sapphirecity_baseboard_lib.sapphirecity_baseboard(sch_1):\DDR4_DIMM\" )
				( netClassRef "@sapphirecity_baseboard_lib.sapphirecity_baseboard(sch_1):\DDR4_CHN_J_DQ_DQS_BYTE6\" )
			)
			( regionClass "@crescent_city_bb_fab1_lib.crescent_city_bb_fab1(sch_1):\RC115\"
				( spacingCSetRef "@sapphirecity_baseboard_lib.sapphirecity_baseboard(sch_1):\DDR4_DIMM\" )
				( attribute "LINE_TO_LINE_SPACING" "10.00"
					( Origin gBackEnd )
				)
				( regionRef "@sapphirecity_baseboard_lib.sapphirecity_baseboard(sch_1):\DDR4_DIMM\" )
				( netClassRef "@sapphirecity_baseboard_lib.sapphirecity_baseboard(sch_1):\DDR4_CHN_J_DQ_DQS_BYTE7\" )
			)
			( regionClass "@crescent_city_bb_fab1_lib.crescent_city_bb_fab1(sch_1):\RC116\"
				( spacingCSetRef "@sapphirecity_baseboard_lib.sapphirecity_baseboard(sch_1):\DDR4_DIMM\" )
				( attribute "LINE_TO_LINE_SPACING" "10.00"
					( Origin gBackEnd )
				)
				( regionRef "@sapphirecity_baseboard_lib.sapphirecity_baseboard(sch_1):\DDR4_DIMM\" )
				( netClassRef "@sapphirecity_baseboard_lib.sapphirecity_baseboard(sch_1):\DDR4_CHN_J_ECC\" )
			)
			( regionClass "@crescent_city_bb_fab1_lib.crescent_city_bb_fab1(sch_1):\RC81\"
				( spacingCSetRef "@sapphirecity_baseboard_lib.sapphirecity_baseboard(sch_1):\DDR4_DIMM\" )
				( attribute "LINE_TO_LINE_SPACING" "10.00"
					( Origin gBackEnd )
				)
				( regionRef "@sapphirecity_baseboard_lib.sapphirecity_baseboard(sch_1):\DDR4_DIMM\" )
				( netClassRef "@sapphirecity_baseboard_lib.sapphirecity_baseboard(sch_1):\DDR4_CHN_K_CLK\" )
			)
			( regionClass "@crescent_city_bb_fab1_lib.crescent_city_bb_fab1(sch_1):\RC82\"
				( spacingCSetRef "@sapphirecity_baseboard_lib.sapphirecity_baseboard(sch_1):\DDR4_DIMM\" )
				( attribute "LINE_TO_LINE_SPACING" "10.00"
					( Origin gBackEnd )
				)
				( regionRef "@sapphirecity_baseboard_lib.sapphirecity_baseboard(sch_1):\DDR4_DIMM\" )
				( netClassRef "@sapphirecity_baseboard_lib.sapphirecity_baseboard(sch_1):\DDR4_CHN_K_CMD_ADD\" )
			)
			( regionClass "@crescent_city_bb_fab1_lib.crescent_city_bb_fab1(sch_1):\RC83\"
				( spacingCSetRef "@sapphirecity_baseboard_lib.sapphirecity_baseboard(sch_1):\DDR4_DIMM\" )
				( attribute "LINE_TO_LINE_SPACING" "10.00"
					( Origin gBackEnd )
				)
				( regionRef "@sapphirecity_baseboard_lib.sapphirecity_baseboard(sch_1):\DDR4_DIMM\" )
				( netClassRef "@sapphirecity_baseboard_lib.sapphirecity_baseboard(sch_1):\DDR4_CHN_K_CTRL\" )
			)
			( regionClass "@crescent_city_bb_fab1_lib.crescent_city_bb_fab1(sch_1):\RC117\"
				( spacingCSetRef "@sapphirecity_baseboard_lib.sapphirecity_baseboard(sch_1):\DDR4_DIMM\" )
				( attribute "LINE_TO_LINE_SPACING" "10.00"
					( Origin gBackEnd )
				)
				( regionRef "@sapphirecity_baseboard_lib.sapphirecity_baseboard(sch_1):\DDR4_DIMM\" )
				( netClassRef "@sapphirecity_baseboard_lib.sapphirecity_baseboard(sch_1):\DDR4_CHN_K_DQ_DQS_BYTE0\" )
			)
			( regionClass "@crescent_city_bb_fab1_lib.crescent_city_bb_fab1(sch_1):\RC118\"
				( spacingCSetRef "@sapphirecity_baseboard_lib.sapphirecity_baseboard(sch_1):\DDR4_DIMM\" )
				( attribute "LINE_TO_LINE_SPACING" "10.00"
					( Origin gBackEnd )
				)
				( regionRef "@sapphirecity_baseboard_lib.sapphirecity_baseboard(sch_1):\DDR4_DIMM\" )
				( netClassRef "@sapphirecity_baseboard_lib.sapphirecity_baseboard(sch_1):\DDR4_CHN_K_DQ_DQS_BYTE1\" )
			)
			( regionClass "@crescent_city_bb_fab1_lib.crescent_city_bb_fab1(sch_1):\RC119\"
				( spacingCSetRef "@sapphirecity_baseboard_lib.sapphirecity_baseboard(sch_1):\DDR4_DIMM\" )
				( attribute "LINE_TO_LINE_SPACING" "10.00"
					( Origin gBackEnd )
				)
				( regionRef "@sapphirecity_baseboard_lib.sapphirecity_baseboard(sch_1):\DDR4_DIMM\" )
				( netClassRef "@sapphirecity_baseboard_lib.sapphirecity_baseboard(sch_1):\DDR4_CHN_K_DQ_DQS_BYTE2\" )
			)
			( regionClass "@crescent_city_bb_fab1_lib.crescent_city_bb_fab1(sch_1):\RC120\"
				( spacingCSetRef "@sapphirecity_baseboard_lib.sapphirecity_baseboard(sch_1):\DDR4_DIMM\" )
				( attribute "LINE_TO_LINE_SPACING" "10.00"
					( Origin gBackEnd )
				)
				( regionRef "@sapphirecity_baseboard_lib.sapphirecity_baseboard(sch_1):\DDR4_DIMM\" )
				( netClassRef "@sapphirecity_baseboard_lib.sapphirecity_baseboard(sch_1):\DDR4_CHN_K_DQ_DQS_BYTE3\" )
			)
			( regionClass "@crescent_city_bb_fab1_lib.crescent_city_bb_fab1(sch_1):\RC121\"
				( spacingCSetRef "@sapphirecity_baseboard_lib.sapphirecity_baseboard(sch_1):\DDR4_DIMM\" )
				( attribute "LINE_TO_LINE_SPACING" "10.00"
					( Origin gBackEnd )
				)
				( regionRef "@sapphirecity_baseboard_lib.sapphirecity_baseboard(sch_1):\DDR4_DIMM\" )
				( netClassRef "@sapphirecity_baseboard_lib.sapphirecity_baseboard(sch_1):\DDR4_CHN_K_DQ_DQS_BYTE4\" )
			)
			( regionClass "@crescent_city_bb_fab1_lib.crescent_city_bb_fab1(sch_1):\RC122\"
				( spacingCSetRef "@sapphirecity_baseboard_lib.sapphirecity_baseboard(sch_1):\DDR4_DIMM\" )
				( attribute "LINE_TO_LINE_SPACING" "10.00"
					( Origin gBackEnd )
				)
				( regionRef "@sapphirecity_baseboard_lib.sapphirecity_baseboard(sch_1):\DDR4_DIMM\" )
				( netClassRef "@sapphirecity_baseboard_lib.sapphirecity_baseboard(sch_1):\DDR4_CHN_K_DQ_DQS_BYTE5\" )
			)
			( regionClass "@crescent_city_bb_fab1_lib.crescent_city_bb_fab1(sch_1):\RC123\"
				( spacingCSetRef "@sapphirecity_baseboard_lib.sapphirecity_baseboard(sch_1):\DDR4_DIMM\" )
				( attribute "LINE_TO_LINE_SPACING" "10.00"
					( Origin gBackEnd )
				)
				( regionRef "@sapphirecity_baseboard_lib.sapphirecity_baseboard(sch_1):\DDR4_DIMM\" )
				( netClassRef "@sapphirecity_baseboard_lib.sapphirecity_baseboard(sch_1):\DDR4_CHN_K_DQ_DQS_BYTE6\" )
			)
			( regionClass "@crescent_city_bb_fab1_lib.crescent_city_bb_fab1(sch_1):\RC124\"
				( spacingCSetRef "@sapphirecity_baseboard_lib.sapphirecity_baseboard(sch_1):\DDR4_DIMM\" )
				( attribute "LINE_TO_LINE_SPACING" "10.00"
					( Origin gBackEnd )
				)
				( regionRef "@sapphirecity_baseboard_lib.sapphirecity_baseboard(sch_1):\DDR4_DIMM\" )
				( netClassRef "@sapphirecity_baseboard_lib.sapphirecity_baseboard(sch_1):\DDR4_CHN_K_DQ_DQS_BYTE7\" )
			)
			( regionClass "@crescent_city_bb_fab1_lib.crescent_city_bb_fab1(sch_1):\RC125\"
				( spacingCSetRef "@sapphirecity_baseboard_lib.sapphirecity_baseboard(sch_1):\DDR4_DIMM\" )
				( attribute "LINE_TO_LINE_SPACING" "10.00"
					( Origin gBackEnd )
				)
				( regionRef "@sapphirecity_baseboard_lib.sapphirecity_baseboard(sch_1):\DDR4_DIMM\" )
				( netClassRef "@sapphirecity_baseboard_lib.sapphirecity_baseboard(sch_1):\DDR4_CHN_K_ECC\" )
			)
			( regionClass "@crescent_city_bb_fab1_lib.crescent_city_bb_fab1(sch_1):\RC84\"
				( spacingCSetRef "@sapphirecity_baseboard_lib.sapphirecity_baseboard(sch_1):\DDR4_DIMM\" )
				( attribute "LINE_TO_LINE_SPACING" "10.00"
					( Origin gBackEnd )
				)
				( regionRef "@sapphirecity_baseboard_lib.sapphirecity_baseboard(sch_1):\DDR4_DIMM\" )
				( netClassRef "@sapphirecity_baseboard_lib.sapphirecity_baseboard(sch_1):\DDR4_CHN_L_CLK\" )
			)
			( regionClass "@crescent_city_bb_fab1_lib.crescent_city_bb_fab1(sch_1):\RC85\"
				( spacingCSetRef "@sapphirecity_baseboard_lib.sapphirecity_baseboard(sch_1):\DDR4_DIMM\" )
				( attribute "LINE_TO_LINE_SPACING" "10.00"
					( Origin gBackEnd )
				)
				( regionRef "@sapphirecity_baseboard_lib.sapphirecity_baseboard(sch_1):\DDR4_DIMM\" )
				( netClassRef "@sapphirecity_baseboard_lib.sapphirecity_baseboard(sch_1):\DDR4_CHN_L_CMD_ADD\" )
			)
			( regionClass "@crescent_city_bb_fab1_lib.crescent_city_bb_fab1(sch_1):\RC86\"
				( spacingCSetRef "@sapphirecity_baseboard_lib.sapphirecity_baseboard(sch_1):\DDR4_DIMM\" )
				( attribute "LINE_TO_LINE_SPACING" "10.00"
					( Origin gBackEnd )
				)
				( regionRef "@sapphirecity_baseboard_lib.sapphirecity_baseboard(sch_1):\DDR4_DIMM\" )
				( netClassRef "@sapphirecity_baseboard_lib.sapphirecity_baseboard(sch_1):\DDR4_CHN_L_CTRL\" )
			)
			( regionClass "@crescent_city_bb_fab1_lib.crescent_city_bb_fab1(sch_1):\RC126\"
				( spacingCSetRef "@sapphirecity_baseboard_lib.sapphirecity_baseboard(sch_1):\DDR4_DIMM\" )
				( attribute "LINE_TO_LINE_SPACING" "10.00"
					( Origin gBackEnd )
				)
				( regionRef "@sapphirecity_baseboard_lib.sapphirecity_baseboard(sch_1):\DDR4_DIMM\" )
				( netClassRef "@sapphirecity_baseboard_lib.sapphirecity_baseboard(sch_1):\DDR4_CHN_L_DQ_DQS_BYTE0\" )
			)
			( regionClass "@crescent_city_bb_fab1_lib.crescent_city_bb_fab1(sch_1):\RC127\"
				( spacingCSetRef "@sapphirecity_baseboard_lib.sapphirecity_baseboard(sch_1):\DDR4_DIMM\" )
				( attribute "LINE_TO_LINE_SPACING" "10.00"
					( Origin gBackEnd )
				)
				( regionRef "@sapphirecity_baseboard_lib.sapphirecity_baseboard(sch_1):\DDR4_DIMM\" )
				( netClassRef "@sapphirecity_baseboard_lib.sapphirecity_baseboard(sch_1):\DDR4_CHN_L_DQ_DQS_BYTE1\" )
			)
			( regionClass "@crescent_city_bb_fab1_lib.crescent_city_bb_fab1(sch_1):\RC128\"
				( spacingCSetRef "@sapphirecity_baseboard_lib.sapphirecity_baseboard(sch_1):\DDR4_DIMM\" )
				( attribute "LINE_TO_LINE_SPACING" "10.00"
					( Origin gBackEnd )
				)
				( regionRef "@sapphirecity_baseboard_lib.sapphirecity_baseboard(sch_1):\DDR4_DIMM\" )
				( netClassRef "@sapphirecity_baseboard_lib.sapphirecity_baseboard(sch_1):\DDR4_CHN_L_DQ_DQS_BYTE2\" )
			)
			( regionClass "@crescent_city_bb_fab1_lib.crescent_city_bb_fab1(sch_1):\RC129\"
				( spacingCSetRef "@sapphirecity_baseboard_lib.sapphirecity_baseboard(sch_1):\DDR4_DIMM\" )
				( attribute "LINE_TO_LINE_SPACING" "10.00"
					( Origin gBackEnd )
				)
				( regionRef "@sapphirecity_baseboard_lib.sapphirecity_baseboard(sch_1):\DDR4_DIMM\" )
				( netClassRef "@sapphirecity_baseboard_lib.sapphirecity_baseboard(sch_1):\DDR4_CHN_L_DQ_DQS_BYTE3\" )
			)
			( regionClass "@crescent_city_bb_fab1_lib.crescent_city_bb_fab1(sch_1):\RC130\"
				( spacingCSetRef "@sapphirecity_baseboard_lib.sapphirecity_baseboard(sch_1):\DDR4_DIMM\" )
				( attribute "LINE_TO_LINE_SPACING" "10.00"
					( Origin gBackEnd )
				)
				( regionRef "@sapphirecity_baseboard_lib.sapphirecity_baseboard(sch_1):\DDR4_DIMM\" )
				( netClassRef "@sapphirecity_baseboard_lib.sapphirecity_baseboard(sch_1):\DDR4_CHN_L_DQ_DQS_BYTE4\" )
			)
			( regionClass "@crescent_city_bb_fab1_lib.crescent_city_bb_fab1(sch_1):\RC131\"
				( spacingCSetRef "@sapphirecity_baseboard_lib.sapphirecity_baseboard(sch_1):\DDR4_DIMM\" )
				( attribute "LINE_TO_LINE_SPACING" "10.00"
					( Origin gBackEnd )
				)
				( regionRef "@sapphirecity_baseboard_lib.sapphirecity_baseboard(sch_1):\DDR4_DIMM\" )
				( netClassRef "@sapphirecity_baseboard_lib.sapphirecity_baseboard(sch_1):\DDR4_CHN_L_DQ_DQS_BYTE5\" )
			)
			( regionClass "@crescent_city_bb_fab1_lib.crescent_city_bb_fab1(sch_1):\RC132\"
				( spacingCSetRef "@sapphirecity_baseboard_lib.sapphirecity_baseboard(sch_1):\DDR4_DIMM\" )
				( attribute "LINE_TO_LINE_SPACING" "10.00"
					( Origin gBackEnd )
				)
				( regionRef "@sapphirecity_baseboard_lib.sapphirecity_baseboard(sch_1):\DDR4_DIMM\" )
				( netClassRef "@sapphirecity_baseboard_lib.sapphirecity_baseboard(sch_1):\DDR4_CHN_L_DQ_DQS_BYTE6\" )
			)
			( regionClass "@crescent_city_bb_fab1_lib.crescent_city_bb_fab1(sch_1):\RC133\"
				( spacingCSetRef "@sapphirecity_baseboard_lib.sapphirecity_baseboard(sch_1):\DDR4_DIMM\" )
				( attribute "LINE_TO_LINE_SPACING" "10.00"
					( Origin gBackEnd )
				)
				( regionRef "@sapphirecity_baseboard_lib.sapphirecity_baseboard(sch_1):\DDR4_DIMM\" )
				( netClassRef "@sapphirecity_baseboard_lib.sapphirecity_baseboard(sch_1):\DDR4_CHN_L_DQ_DQS_BYTE7\" )
			)
			( regionClass "@crescent_city_bb_fab1_lib.crescent_city_bb_fab1(sch_1):\RC134\"
				( spacingCSetRef "@sapphirecity_baseboard_lib.sapphirecity_baseboard(sch_1):\DDR4_DIMM\" )
				( attribute "LINE_TO_LINE_SPACING" "10.00"
					( Origin gBackEnd )
				)
				( regionRef "@sapphirecity_baseboard_lib.sapphirecity_baseboard(sch_1):\DDR4_DIMM\" )
				( netClassRef "@sapphirecity_baseboard_lib.sapphirecity_baseboard(sch_1):\DDR4_CHN_L_ECC\" )
			)
			( regionClass "@crescent_city_bb_fab1_lib.crescent_city_bb_fab1(sch_1):\RC87\"
				( spacingCSetRef "@sapphirecity_baseboard_lib.sapphirecity_baseboard(sch_1):\DDR4_DIMM\" )
				( attribute "LINE_TO_LINE_SPACING" "10.00"
					( Origin gBackEnd )
				)
				( regionRef "@sapphirecity_baseboard_lib.sapphirecity_baseboard(sch_1):\DDR4_DIMM\" )
				( netClassRef "@sapphirecity_baseboard_lib.sapphirecity_baseboard(sch_1):\DDR4_CHN_M_CLK\" )
			)
			( regionClass "@crescent_city_bb_fab1_lib.crescent_city_bb_fab1(sch_1):\RC88\"
				( spacingCSetRef "@sapphirecity_baseboard_lib.sapphirecity_baseboard(sch_1):\DDR4_DIMM\" )
				( attribute "LINE_TO_LINE_SPACING" "10.00"
					( Origin gBackEnd )
				)
				( regionRef "@sapphirecity_baseboard_lib.sapphirecity_baseboard(sch_1):\DDR4_DIMM\" )
				( netClassRef "@sapphirecity_baseboard_lib.sapphirecity_baseboard(sch_1):\DDR4_CHN_M_CMD_ADD\" )
			)
			( regionClass "@crescent_city_bb_fab1_lib.crescent_city_bb_fab1(sch_1):\RC89\"
				( spacingCSetRef "@sapphirecity_baseboard_lib.sapphirecity_baseboard(sch_1):\DDR4_DIMM\" )
				( attribute "LINE_TO_LINE_SPACING" "10.00"
					( Origin gBackEnd )
				)
				( regionRef "@sapphirecity_baseboard_lib.sapphirecity_baseboard(sch_1):\DDR4_DIMM\" )
				( netClassRef "@sapphirecity_baseboard_lib.sapphirecity_baseboard(sch_1):\DDR4_CHN_M_CTRL\" )
			)
			( regionClass "@crescent_city_bb_fab1_lib.crescent_city_bb_fab1(sch_1):\RC135\"
				( spacingCSetRef "@sapphirecity_baseboard_lib.sapphirecity_baseboard(sch_1):\DDR4_DIMM\" )
				( attribute "LINE_TO_LINE_SPACING" "10.00"
					( Origin gBackEnd )
				)
				( regionRef "@sapphirecity_baseboard_lib.sapphirecity_baseboard(sch_1):\DDR4_DIMM\" )
				( netClassRef "@sapphirecity_baseboard_lib.sapphirecity_baseboard(sch_1):\DDR4_CHN_M_DQ_DQS_BYTE0\" )
			)
			( regionClass "@crescent_city_bb_fab1_lib.crescent_city_bb_fab1(sch_1):\RC136\"
				( spacingCSetRef "@sapphirecity_baseboard_lib.sapphirecity_baseboard(sch_1):\DDR4_DIMM\" )
				( attribute "LINE_TO_LINE_SPACING" "10.00"
					( Origin gBackEnd )
				)
				( regionRef "@sapphirecity_baseboard_lib.sapphirecity_baseboard(sch_1):\DDR4_DIMM\" )
				( netClassRef "@sapphirecity_baseboard_lib.sapphirecity_baseboard(sch_1):\DDR4_CHN_M_DQ_DQS_BYTE1\" )
			)
			( regionClass "@crescent_city_bb_fab1_lib.crescent_city_bb_fab1(sch_1):\RC137\"
				( spacingCSetRef "@sapphirecity_baseboard_lib.sapphirecity_baseboard(sch_1):\DDR4_DIMM\" )
				( attribute "LINE_TO_LINE_SPACING" "10.00"
					( Origin gBackEnd )
				)
				( regionRef "@sapphirecity_baseboard_lib.sapphirecity_baseboard(sch_1):\DDR4_DIMM\" )
				( netClassRef "@sapphirecity_baseboard_lib.sapphirecity_baseboard(sch_1):\DDR4_CHN_M_DQ_DQS_BYTE2\" )
			)
			( regionClass "@crescent_city_bb_fab1_lib.crescent_city_bb_fab1(sch_1):\RC138\"
				( spacingCSetRef "@sapphirecity_baseboard_lib.sapphirecity_baseboard(sch_1):\DDR4_DIMM\" )
				( attribute "LINE_TO_LINE_SPACING" "10.00"
					( Origin gBackEnd )
				)
				( regionRef "@sapphirecity_baseboard_lib.sapphirecity_baseboard(sch_1):\DDR4_DIMM\" )
				( netClassRef "@sapphirecity_baseboard_lib.sapphirecity_baseboard(sch_1):\DDR4_CHN_M_DQ_DQS_BYTE3\" )
			)
			( regionClass "@crescent_city_bb_fab1_lib.crescent_city_bb_fab1(sch_1):\RC139\"
				( spacingCSetRef "@sapphirecity_baseboard_lib.sapphirecity_baseboard(sch_1):\DDR4_DIMM\" )
				( attribute "LINE_TO_LINE_SPACING" "10.00"
					( Origin gBackEnd )
				)
				( regionRef "@sapphirecity_baseboard_lib.sapphirecity_baseboard(sch_1):\DDR4_DIMM\" )
				( netClassRef "@sapphirecity_baseboard_lib.sapphirecity_baseboard(sch_1):\DDR4_CHN_M_DQ_DQS_BYTE4\" )
			)
			( regionClass "@crescent_city_bb_fab1_lib.crescent_city_bb_fab1(sch_1):\RC140\"
				( spacingCSetRef "@sapphirecity_baseboard_lib.sapphirecity_baseboard(sch_1):\DDR4_DIMM\" )
				( attribute "LINE_TO_LINE_SPACING" "10.00"
					( Origin gBackEnd )
				)
				( regionRef "@sapphirecity_baseboard_lib.sapphirecity_baseboard(sch_1):\DDR4_DIMM\" )
				( netClassRef "@sapphirecity_baseboard_lib.sapphirecity_baseboard(sch_1):\DDR4_CHN_M_DQ_DQS_BYTE5\" )
			)
			( regionClass "@crescent_city_bb_fab1_lib.crescent_city_bb_fab1(sch_1):\RC141\"
				( spacingCSetRef "@sapphirecity_baseboard_lib.sapphirecity_baseboard(sch_1):\DDR4_DIMM\" )
				( attribute "LINE_TO_LINE_SPACING" "10.00"
					( Origin gBackEnd )
				)
				( regionRef "@sapphirecity_baseboard_lib.sapphirecity_baseboard(sch_1):\DDR4_DIMM\" )
				( netClassRef "@sapphirecity_baseboard_lib.sapphirecity_baseboard(sch_1):\DDR4_CHN_M_DQ_DQS_BYTE6\" )
			)
			( regionClass "@crescent_city_bb_fab1_lib.crescent_city_bb_fab1(sch_1):\RC142\"
				( spacingCSetRef "@sapphirecity_baseboard_lib.sapphirecity_baseboard(sch_1):\DDR4_DIMM\" )
				( attribute "LINE_TO_LINE_SPACING" "10.00"
					( Origin gBackEnd )
				)
				( regionRef "@sapphirecity_baseboard_lib.sapphirecity_baseboard(sch_1):\DDR4_DIMM\" )
				( netClassRef "@sapphirecity_baseboard_lib.sapphirecity_baseboard(sch_1):\DDR4_CHN_M_DQ_DQS_BYTE7\" )
			)
			( regionClass "@crescent_city_bb_fab1_lib.crescent_city_bb_fab1(sch_1):\RC143\"
				( spacingCSetRef "@sapphirecity_baseboard_lib.sapphirecity_baseboard(sch_1):\DDR4_DIMM\" )
				( attribute "LINE_TO_LINE_SPACING" "10.00"
					( Origin gBackEnd )
				)
				( regionRef "@sapphirecity_baseboard_lib.sapphirecity_baseboard(sch_1):\DDR4_DIMM\" )
				( netClassRef "@sapphirecity_baseboard_lib.sapphirecity_baseboard(sch_1):\DDR4_CHN_M_ECC\" )
			)
			( regionClass "@sapphirecity_baseboard_lib.sapphirecity_baseboard(sch_1):\RC4\"
				( regionRef "@sapphirecity_baseboard_lib.sapphirecity_baseboard(sch_1):\DDR4_STUBBY\" )
				( netClassRef "@sapphirecity_baseboard_lib.sapphirecity_baseboard(sch_1):\DDR4_CHN_A_ECC\" )
			)
			( regionClass "@sapphirecity_baseboard_lib.sapphirecity_baseboard(sch_1):\RC6\"
				( regionRef "@sapphirecity_baseboard_lib.sapphirecity_baseboard(sch_1):\DDR4_STUBBY\" )
				( netClassRef "@sapphirecity_baseboard_lib.sapphirecity_baseboard(sch_1):\DDR4_CHN_D_ECC\" )
			)
			( regionClass "@sapphirecity_baseboard_lib.sapphirecity_baseboard(sch_1):\RC8\"
				( regionRef "@sapphirecity_baseboard_lib.sapphirecity_baseboard(sch_1):\DDR4_STUBBY\" )
				( netClassRef "@sapphirecity_baseboard_lib.sapphirecity_baseboard(sch_1):\DDR4_CHN_D_DQ_DQS_BYTE7\" )
			)
			( regionClass "@sapphirecity_baseboard_lib.sapphirecity_baseboard(sch_1):\RC9\"
				( regionRef "@sapphirecity_baseboard_lib.sapphirecity_baseboard(sch_1):\DDR4_STUBBY\" )
				( netClassRef "@sapphirecity_baseboard_lib.sapphirecity_baseboard(sch_1):\DDR4_CHN_D_DQ_DQS_BYTE3\" )
			)
			( regionClass "@sapphirecity_baseboard_lib.sapphirecity_baseboard(sch_1):\RC2\"
				( physicalCSetRef "@sapphirecity_baseboard_lib.sapphirecity_baseboard(sch_1):\DDR4_STUBBY_MICROSTRIP\" )
				( regionRef "@sapphirecity_baseboard_lib.sapphirecity_baseboard(sch_1):\DDR4_STUBBY\" )
				( netClassRef "@sapphirecity_baseboard_lib.sapphirecity_baseboard(sch_1):\DDR4_CHN_A_DQ_DQS_BYTE0\" )
			)
			( regionClass "@sapphirecity_baseboard_lib.sapphirecity_baseboard(sch_1):\RC10\"
				( regionRef "@sapphirecity_baseboard_lib.sapphirecity_baseboard(sch_1):\DDR4_STUBBY\" )
				( netClassRef "@sapphirecity_baseboard_lib.sapphirecity_baseboard(sch_1):\DDR4_CHN_A_DQ_DQS_BYTE3\" )
			)
			( regionClass "@sapphirecity_baseboard_lib.sapphirecity_baseboard(sch_1):\RC3\"
				( physicalCSetRef "@sapphirecity_baseboard_lib.sapphirecity_baseboard(sch_1):\DDR4_STUBBY_MICROSTRIP\" )
				( regionRef "@sapphirecity_baseboard_lib.sapphirecity_baseboard(sch_1):\DDR4_STUBBY\" )
				( netClassRef "@sapphirecity_baseboard_lib.sapphirecity_baseboard(sch_1):\DDR4_CHN_A_DQ_DQS_BYTE4\" )
			)
			( regionClass "@sapphirecity_baseboard_lib.sapphirecity_baseboard(sch_1):\RC1\"
				( regionRef "@sapphirecity_baseboard_lib.sapphirecity_baseboard(sch_1):\DDR4_STUBBY\" )
				( netClassRef "@sapphirecity_baseboard_lib.sapphirecity_baseboard(sch_1):\DDR4_CHN_A_DQ_DQS_BYTE5\" )
			)
			( regionClassClass "@baseboard_fab2_lib.baseboard_fab2(sch_1):\RCC1\"
				( spacingCSetRef "@crescent_city_bb_fab1_lib.crescent_city_bb_fab1(sch_1):\DEFAULT\" )
				( regionRef "@crescent_city_bb_fab1_lib.crescent_city_bb_fab1(sch_1):\UPI_9H\" )
				( netClassRef "@sapphirecity_baseboard_lib.sapphirecity_baseboard(sch_1):\GND\" )
				( netClassRef "@sapphirecity_baseboard_lib.sapphirecity_baseboard(sch_1):\KTI_CPU0_CPU1_P1P0\" )
			)
			( regionClassClass "@baseboard_fab2_lib.baseboard_fab2(sch_1):\RCC2\"
				( spacingCSetRef "@crescent_city_bb_fab1_lib.crescent_city_bb_fab1(sch_1):\DEFAULT\" )
				( regionRef "@crescent_city_bb_fab1_lib.crescent_city_bb_fab1(sch_1):\UPI_9H\" )
				( netClassRef "@sapphirecity_baseboard_lib.sapphirecity_baseboard(sch_1):\GND\" )
				( netClassRef "@sapphirecity_baseboard_lib.sapphirecity_baseboard(sch_1):\KTI_CPU0_CPU1_P0P1\" )
			)
			( regionClassClass "@baseboard_fab2_lib.baseboard_fab2(sch_1):\RCC3\"
				( spacingCSetRef "@crescent_city_bb_fab1_lib.crescent_city_bb_fab1(sch_1):\DEFAULT\" )
				( regionRef "@crescent_city_bb_fab1_lib.crescent_city_bb_fab1(sch_1):\UPI_9H\" )
				( netClassRef "@sapphirecity_baseboard_lib.sapphirecity_baseboard(sch_1):\GND\" )
				( netClassRef "@sapphirecity_baseboard_lib.sapphirecity_baseboard(sch_1):\KTI_CPU1_CPU0_P1P0\" )
			)
			( regionClassClass "@baseboard_fab2_lib.baseboard_fab2(sch_1):\RCC4\"
				( spacingCSetRef "@crescent_city_bb_fab1_lib.crescent_city_bb_fab1(sch_1):\DEFAULT\" )
				( regionRef "@crescent_city_bb_fab1_lib.crescent_city_bb_fab1(sch_1):\UPI_9H\" )
				( netClassRef "@sapphirecity_baseboard_lib.sapphirecity_baseboard(sch_1):\GND\" )
				( netClassRef "@sapphirecity_baseboard_lib.sapphirecity_baseboard(sch_1):\KTI_CPU1_CPU0_P0P1\" )
			)
			( regionClassClass "@crescent_city_bb_fab1_lib.crescent_city_bb_fab1(sch_1):\RCC12\"
				( spacingCSetRef "@crescent_city_bb_fab1_lib.crescent_city_bb_fab1(sch_1):\5MIL_US_&_4MIL_SL\" )
				( regionRef "@crescent_city_bb_fab1_lib.crescent_city_bb_fab1(sch_1):\DDR_ESCAPE\" )
				( netClassRef "@sapphirecity_baseboard_lib.sapphirecity_baseboard(sch_1):\DDR4_CHN_A_DQ_DQS_BYTE7\" )
				( netClassRef "@sapphirecity_baseboard_lib.sapphirecity_baseboard(sch_1):\DDR4_CHN_A_DQ_DQS_BYTE7\" )
			)
			( regionClassClass "@crescent_city_bb_fab1_lib.crescent_city_bb_fab1(sch_1):\RCC105\"
				( spacingCSetRef "@crescent_city_bb_fab1_lib.crescent_city_bb_fab1(sch_1):\5MIL_US_&_4MIL_SL\" )
				( regionRef "@crescent_city_bb_fab1_lib.crescent_city_bb_fab1(sch_1):\DDR_ESCAPE\" )
				( netClassRef "@sapphirecity_baseboard_lib.sapphirecity_baseboard(sch_1):\DDR4_CHN_D_DQ_DQS_BYTE5\" )
				( netClassRef "@sapphirecity_baseboard_lib.sapphirecity_baseboard(sch_1):\DDR4_CHN_D_DQ_DQS_BYTE5\" )
			)
			( regionClassClass "@crescent_city_bb_fab1_lib.crescent_city_bb_fab1(sch_1):\RCC64\"
				( spacingCSetRef "@crescent_city_bb_fab1_lib.crescent_city_bb_fab1(sch_1):\5MIL_US_&_4MIL_SL\" )
				( regionRef "@crescent_city_bb_fab1_lib.crescent_city_bb_fab1(sch_1):\DDR_ESCAPE\" )
				( netClassRef "@sapphirecity_baseboard_lib.sapphirecity_baseboard(sch_1):\DDR4_CHN_G_CLK\" )
				( netClassRef "@sapphirecity_baseboard_lib.sapphirecity_baseboard(sch_1):\DDR4_CHN_G_CLK\" )
			)
			( regionClassClass "@crescent_city_bb_fab1_lib.crescent_city_bb_fab1(sch_1):\RCC65\"
				( spacingCSetRef "@crescent_city_bb_fab1_lib.crescent_city_bb_fab1(sch_1):\5MIL_US_&_4MIL_SL\" )
				( regionRef "@crescent_city_bb_fab1_lib.crescent_city_bb_fab1(sch_1):\DDR_ESCAPE\" )
				( netClassRef "@sapphirecity_baseboard_lib.sapphirecity_baseboard(sch_1):\DDR4_CHN_G_CLK\" )
				( netClassRef "@sapphirecity_baseboard_lib.sapphirecity_baseboard(sch_1):\DDR4_CHN_G_CMD_ADD\" )
			)
			( regionClassClass "@crescent_city_bb_fab1_lib.crescent_city_bb_fab1(sch_1):\RCC66\"
				( spacingCSetRef "@crescent_city_bb_fab1_lib.crescent_city_bb_fab1(sch_1):\5MIL_US_&_4MIL_SL\" )
				( regionRef "@crescent_city_bb_fab1_lib.crescent_city_bb_fab1(sch_1):\DDR_ESCAPE\" )
				( netClassRef "@sapphirecity_baseboard_lib.sapphirecity_baseboard(sch_1):\DDR4_CHN_G_CLK\" )
				( netClassRef "@sapphirecity_baseboard_lib.sapphirecity_baseboard(sch_1):\DDR4_CHN_G_CTRL\" )
			)
			( regionClassClass "@crescent_city_bb_fab1_lib.crescent_city_bb_fab1(sch_1):\RCC145\"
				( spacingCSetRef "@crescent_city_bb_fab1_lib.crescent_city_bb_fab1(sch_1):\5MIL_US_&_4MIL_SL\" )
				( regionRef "@crescent_city_bb_fab1_lib.crescent_city_bb_fab1(sch_1):\DDR_ESCAPE\" )
				( netClassRef "@sapphirecity_baseboard_lib.sapphirecity_baseboard(sch_1):\DDR4_CHN_J_DQ_DQS_BYTE0\" )
				( netClassRef "@sapphirecity_baseboard_lib.sapphirecity_baseboard(sch_1):\DDR4_CHN_J_DQ_DQS_BYTE0\" )
			)
			( regionClassClass "@crescent_city_bb_fab1_lib.crescent_city_bb_fab1(sch_1):\RCC154\"
				( spacingCSetRef "@crescent_city_bb_fab1_lib.crescent_city_bb_fab1(sch_1):\5MIL_US_&_4MIL_SL\" )
				( regionRef "@crescent_city_bb_fab1_lib.crescent_city_bb_fab1(sch_1):\DDR_ESCAPE\" )
				( netClassRef "@sapphirecity_baseboard_lib.sapphirecity_baseboard(sch_1):\DDR4_CHN_K_DQ_DQS_BYTE0\" )
				( netClassRef "@sapphirecity_baseboard_lib.sapphirecity_baseboard(sch_1):\DDR4_CHN_K_DQ_DQS_BYTE0\" )
			)
			( regionClassClass "@crescent_city_bb_fab1_lib.crescent_city_bb_fab1(sch_1):\RCC146\"
				( spacingCSetRef "@crescent_city_bb_fab1_lib.crescent_city_bb_fab1(sch_1):\5MIL_US_&_4MIL_SL\" )
				( regionRef "@crescent_city_bb_fab1_lib.crescent_city_bb_fab1(sch_1):\DDR_ESCAPE\" )
				( netClassRef "@sapphirecity_baseboard_lib.sapphirecity_baseboard(sch_1):\DDR4_CHN_J_DQ_DQS_BYTE1\" )
				( netClassRef "@sapphirecity_baseboard_lib.sapphirecity_baseboard(sch_1):\DDR4_CHN_J_DQ_DQS_BYTE1\" )
			)
			( regionClassClass "@crescent_city_bb_fab1_lib.crescent_city_bb_fab1(sch_1):\RCC147\"
				( spacingCSetRef "@crescent_city_bb_fab1_lib.crescent_city_bb_fab1(sch_1):\5MIL_US_&_4MIL_SL\" )
				( regionRef "@crescent_city_bb_fab1_lib.crescent_city_bb_fab1(sch_1):\DDR_ESCAPE\" )
				( netClassRef "@sapphirecity_baseboard_lib.sapphirecity_baseboard(sch_1):\DDR4_CHN_J_DQ_DQS_BYTE2\" )
				( netClassRef "@sapphirecity_baseboard_lib.sapphirecity_baseboard(sch_1):\DDR4_CHN_J_DQ_DQS_BYTE2\" )
			)
			( regionClassClass "@crescent_city_bb_fab1_lib.crescent_city_bb_fab1(sch_1):\RCC148\"
				( spacingCSetRef "@crescent_city_bb_fab1_lib.crescent_city_bb_fab1(sch_1):\5MIL_US_&_4MIL_SL\" )
				( regionRef "@crescent_city_bb_fab1_lib.crescent_city_bb_fab1(sch_1):\DDR_ESCAPE\" )
				( netClassRef "@sapphirecity_baseboard_lib.sapphirecity_baseboard(sch_1):\DDR4_CHN_J_DQ_DQS_BYTE3\" )
				( netClassRef "@sapphirecity_baseboard_lib.sapphirecity_baseboard(sch_1):\DDR4_CHN_J_DQ_DQS_BYTE3\" )
			)
			( regionClassClass "@crescent_city_bb_fab1_lib.crescent_city_bb_fab1(sch_1):\RCC149\"
				( spacingCSetRef "@crescent_city_bb_fab1_lib.crescent_city_bb_fab1(sch_1):\5MIL_US_&_4MIL_SL\" )
				( regionRef "@crescent_city_bb_fab1_lib.crescent_city_bb_fab1(sch_1):\DDR_ESCAPE\" )
				( netClassRef "@sapphirecity_baseboard_lib.sapphirecity_baseboard(sch_1):\DDR4_CHN_J_DQ_DQS_BYTE4\" )
				( netClassRef "@sapphirecity_baseboard_lib.sapphirecity_baseboard(sch_1):\DDR4_CHN_J_DQ_DQS_BYTE4\" )
			)
			( regionClassClass "@crescent_city_bb_fab1_lib.crescent_city_bb_fab1(sch_1):\RCC150\"
				( spacingCSetRef "@crescent_city_bb_fab1_lib.crescent_city_bb_fab1(sch_1):\5MIL_US_&_4MIL_SL\" )
				( regionRef "@crescent_city_bb_fab1_lib.crescent_city_bb_fab1(sch_1):\DDR_ESCAPE\" )
				( netClassRef "@sapphirecity_baseboard_lib.sapphirecity_baseboard(sch_1):\DDR4_CHN_J_DQ_DQS_BYTE5\" )
				( netClassRef "@sapphirecity_baseboard_lib.sapphirecity_baseboard(sch_1):\DDR4_CHN_J_DQ_DQS_BYTE5\" )
			)
			( regionClassClass "@crescent_city_bb_fab1_lib.crescent_city_bb_fab1(sch_1):\RCC151\"
				( spacingCSetRef "@crescent_city_bb_fab1_lib.crescent_city_bb_fab1(sch_1):\5MIL_US_&_4MIL_SL\" )
				( regionRef "@crescent_city_bb_fab1_lib.crescent_city_bb_fab1(sch_1):\DDR_ESCAPE\" )
				( netClassRef "@sapphirecity_baseboard_lib.sapphirecity_baseboard(sch_1):\DDR4_CHN_J_DQ_DQS_BYTE6\" )
				( netClassRef "@sapphirecity_baseboard_lib.sapphirecity_baseboard(sch_1):\DDR4_CHN_J_DQ_DQS_BYTE6\" )
			)
			( regionClassClass "@crescent_city_bb_fab1_lib.crescent_city_bb_fab1(sch_1):\RCC152\"
				( spacingCSetRef "@crescent_city_bb_fab1_lib.crescent_city_bb_fab1(sch_1):\5MIL_US_&_4MIL_SL\" )
				( regionRef "@crescent_city_bb_fab1_lib.crescent_city_bb_fab1(sch_1):\DDR_ESCAPE\" )
				( netClassRef "@sapphirecity_baseboard_lib.sapphirecity_baseboard(sch_1):\DDR4_CHN_J_DQ_DQS_BYTE7\" )
				( netClassRef "@sapphirecity_baseboard_lib.sapphirecity_baseboard(sch_1):\DDR4_CHN_J_DQ_DQS_BYTE7\" )
			)
			( regionClassClass "@crescent_city_bb_fab1_lib.crescent_city_bb_fab1(sch_1):\RCC155\"
				( spacingCSetRef "@crescent_city_bb_fab1_lib.crescent_city_bb_fab1(sch_1):\5MIL_US_&_4MIL_SL\" )
				( regionRef "@crescent_city_bb_fab1_lib.crescent_city_bb_fab1(sch_1):\DDR_ESCAPE\" )
				( netClassRef "@sapphirecity_baseboard_lib.sapphirecity_baseboard(sch_1):\DDR4_CHN_K_DQ_DQS_BYTE1\" )
				( netClassRef "@sapphirecity_baseboard_lib.sapphirecity_baseboard(sch_1):\DDR4_CHN_K_DQ_DQS_BYTE1\" )
			)
			( regionClassClass "@crescent_city_bb_fab1_lib.crescent_city_bb_fab1(sch_1):\RCC156\"
				( spacingCSetRef "@crescent_city_bb_fab1_lib.crescent_city_bb_fab1(sch_1):\5MIL_US_&_4MIL_SL\" )
				( regionRef "@crescent_city_bb_fab1_lib.crescent_city_bb_fab1(sch_1):\DDR_ESCAPE\" )
				( netClassRef "@sapphirecity_baseboard_lib.sapphirecity_baseboard(sch_1):\DDR4_CHN_K_DQ_DQS_BYTE2\" )
				( netClassRef "@sapphirecity_baseboard_lib.sapphirecity_baseboard(sch_1):\DDR4_CHN_K_DQ_DQS_BYTE2\" )
			)
			( regionClassClass "@crescent_city_bb_fab1_lib.crescent_city_bb_fab1(sch_1):\RCC157\"
				( spacingCSetRef "@crescent_city_bb_fab1_lib.crescent_city_bb_fab1(sch_1):\5MIL_US_&_4MIL_SL\" )
				( regionRef "@crescent_city_bb_fab1_lib.crescent_city_bb_fab1(sch_1):\DDR_ESCAPE\" )
				( netClassRef "@sapphirecity_baseboard_lib.sapphirecity_baseboard(sch_1):\DDR4_CHN_K_DQ_DQS_BYTE3\" )
				( netClassRef "@sapphirecity_baseboard_lib.sapphirecity_baseboard(sch_1):\DDR4_CHN_K_DQ_DQS_BYTE3\" )
			)
			( regionClassClass "@crescent_city_bb_fab1_lib.crescent_city_bb_fab1(sch_1):\RCC158\"
				( spacingCSetRef "@crescent_city_bb_fab1_lib.crescent_city_bb_fab1(sch_1):\5MIL_US_&_4MIL_SL\" )
				( regionRef "@crescent_city_bb_fab1_lib.crescent_city_bb_fab1(sch_1):\DDR_ESCAPE\" )
				( netClassRef "@sapphirecity_baseboard_lib.sapphirecity_baseboard(sch_1):\DDR4_CHN_K_DQ_DQS_BYTE4\" )
				( netClassRef "@sapphirecity_baseboard_lib.sapphirecity_baseboard(sch_1):\DDR4_CHN_K_DQ_DQS_BYTE4\" )
			)
			( regionClassClass "@crescent_city_bb_fab1_lib.crescent_city_bb_fab1(sch_1):\RCC159\"
				( spacingCSetRef "@crescent_city_bb_fab1_lib.crescent_city_bb_fab1(sch_1):\5MIL_US_&_4MIL_SL\" )
				( regionRef "@crescent_city_bb_fab1_lib.crescent_city_bb_fab1(sch_1):\DDR_ESCAPE\" )
				( netClassRef "@sapphirecity_baseboard_lib.sapphirecity_baseboard(sch_1):\DDR4_CHN_K_DQ_DQS_BYTE5\" )
				( netClassRef "@sapphirecity_baseboard_lib.sapphirecity_baseboard(sch_1):\DDR4_CHN_K_DQ_DQS_BYTE5\" )
			)
			( regionClassClass "@crescent_city_bb_fab1_lib.crescent_city_bb_fab1(sch_1):\RCC160\"
				( spacingCSetRef "@crescent_city_bb_fab1_lib.crescent_city_bb_fab1(sch_1):\5MIL_US_&_4MIL_SL\" )
				( regionRef "@crescent_city_bb_fab1_lib.crescent_city_bb_fab1(sch_1):\DDR_ESCAPE\" )
				( netClassRef "@sapphirecity_baseboard_lib.sapphirecity_baseboard(sch_1):\DDR4_CHN_K_DQ_DQS_BYTE6\" )
				( netClassRef "@sapphirecity_baseboard_lib.sapphirecity_baseboard(sch_1):\DDR4_CHN_K_DQ_DQS_BYTE6\" )
			)
			( regionClassClass "@crescent_city_bb_fab1_lib.crescent_city_bb_fab1(sch_1):\RCC161\"
				( spacingCSetRef "@crescent_city_bb_fab1_lib.crescent_city_bb_fab1(sch_1):\5MIL_US_&_4MIL_SL\" )
				( regionRef "@crescent_city_bb_fab1_lib.crescent_city_bb_fab1(sch_1):\DDR_ESCAPE\" )
				( netClassRef "@sapphirecity_baseboard_lib.sapphirecity_baseboard(sch_1):\DDR4_CHN_K_DQ_DQS_BYTE7\" )
				( netClassRef "@sapphirecity_baseboard_lib.sapphirecity_baseboard(sch_1):\DDR4_CHN_K_DQ_DQS_BYTE7\" )
			)
			( regionClassClass "@crescent_city_bb_fab1_lib.crescent_city_bb_fab1(sch_1):\RCC163\"
				( spacingCSetRef "@crescent_city_bb_fab1_lib.crescent_city_bb_fab1(sch_1):\5MIL_US_&_4MIL_SL\" )
				( regionRef "@crescent_city_bb_fab1_lib.crescent_city_bb_fab1(sch_1):\DDR_ESCAPE\" )
				( netClassRef "@sapphirecity_baseboard_lib.sapphirecity_baseboard(sch_1):\DDR4_CHN_L_DQ_DQS_BYTE0\" )
				( netClassRef "@sapphirecity_baseboard_lib.sapphirecity_baseboard(sch_1):\DDR4_CHN_L_DQ_DQS_BYTE0\" )
			)
			( regionClassClass "@crescent_city_bb_fab1_lib.crescent_city_bb_fab1(sch_1):\RCC164\"
				( spacingCSetRef "@crescent_city_bb_fab1_lib.crescent_city_bb_fab1(sch_1):\5MIL_US_&_4MIL_SL\" )
				( regionRef "@crescent_city_bb_fab1_lib.crescent_city_bb_fab1(sch_1):\DDR_ESCAPE\" )
				( netClassRef "@sapphirecity_baseboard_lib.sapphirecity_baseboard(sch_1):\DDR4_CHN_L_DQ_DQS_BYTE1\" )
				( netClassRef "@sapphirecity_baseboard_lib.sapphirecity_baseboard(sch_1):\DDR4_CHN_L_DQ_DQS_BYTE1\" )
			)
			( regionClassClass "@crescent_city_bb_fab1_lib.crescent_city_bb_fab1(sch_1):\RCC165\"
				( spacingCSetRef "@crescent_city_bb_fab1_lib.crescent_city_bb_fab1(sch_1):\5MIL_US_&_4MIL_SL\" )
				( regionRef "@crescent_city_bb_fab1_lib.crescent_city_bb_fab1(sch_1):\DDR_ESCAPE\" )
				( netClassRef "@sapphirecity_baseboard_lib.sapphirecity_baseboard(sch_1):\DDR4_CHN_L_DQ_DQS_BYTE2\" )
				( netClassRef "@sapphirecity_baseboard_lib.sapphirecity_baseboard(sch_1):\DDR4_CHN_L_DQ_DQS_BYTE2\" )
			)
			( regionClassClass "@crescent_city_bb_fab1_lib.crescent_city_bb_fab1(sch_1):\RCC166\"
				( spacingCSetRef "@crescent_city_bb_fab1_lib.crescent_city_bb_fab1(sch_1):\5MIL_US_&_4MIL_SL\" )
				( regionRef "@crescent_city_bb_fab1_lib.crescent_city_bb_fab1(sch_1):\DDR_ESCAPE\" )
				( netClassRef "@sapphirecity_baseboard_lib.sapphirecity_baseboard(sch_1):\DDR4_CHN_L_DQ_DQS_BYTE3\" )
				( netClassRef "@sapphirecity_baseboard_lib.sapphirecity_baseboard(sch_1):\DDR4_CHN_L_DQ_DQS_BYTE3\" )
			)
			( regionClassClass "@crescent_city_bb_fab1_lib.crescent_city_bb_fab1(sch_1):\RCC167\"
				( spacingCSetRef "@crescent_city_bb_fab1_lib.crescent_city_bb_fab1(sch_1):\5MIL_US_&_4MIL_SL\" )
				( regionRef "@crescent_city_bb_fab1_lib.crescent_city_bb_fab1(sch_1):\DDR_ESCAPE\" )
				( netClassRef "@sapphirecity_baseboard_lib.sapphirecity_baseboard(sch_1):\DDR4_CHN_L_DQ_DQS_BYTE4\" )
				( netClassRef "@sapphirecity_baseboard_lib.sapphirecity_baseboard(sch_1):\DDR4_CHN_L_DQ_DQS_BYTE4\" )
			)
			( regionClassClass "@crescent_city_bb_fab1_lib.crescent_city_bb_fab1(sch_1):\RCC168\"
				( spacingCSetRef "@crescent_city_bb_fab1_lib.crescent_city_bb_fab1(sch_1):\5MIL_US_&_4MIL_SL\" )
				( regionRef "@crescent_city_bb_fab1_lib.crescent_city_bb_fab1(sch_1):\DDR_ESCAPE\" )
				( netClassRef "@sapphirecity_baseboard_lib.sapphirecity_baseboard(sch_1):\DDR4_CHN_L_DQ_DQS_BYTE5\" )
				( netClassRef "@sapphirecity_baseboard_lib.sapphirecity_baseboard(sch_1):\DDR4_CHN_L_DQ_DQS_BYTE5\" )
			)
			( regionClassClass "@crescent_city_bb_fab1_lib.crescent_city_bb_fab1(sch_1):\RCC169\"
				( spacingCSetRef "@crescent_city_bb_fab1_lib.crescent_city_bb_fab1(sch_1):\5MIL_US_&_4MIL_SL\" )
				( regionRef "@crescent_city_bb_fab1_lib.crescent_city_bb_fab1(sch_1):\DDR_ESCAPE\" )
				( netClassRef "@sapphirecity_baseboard_lib.sapphirecity_baseboard(sch_1):\DDR4_CHN_L_DQ_DQS_BYTE6\" )
				( netClassRef "@sapphirecity_baseboard_lib.sapphirecity_baseboard(sch_1):\DDR4_CHN_L_DQ_DQS_BYTE6\" )
			)
			( regionClassClass "@crescent_city_bb_fab1_lib.crescent_city_bb_fab1(sch_1):\RCC170\"
				( spacingCSetRef "@crescent_city_bb_fab1_lib.crescent_city_bb_fab1(sch_1):\5MIL_US_&_4MIL_SL\" )
				( regionRef "@crescent_city_bb_fab1_lib.crescent_city_bb_fab1(sch_1):\DDR_ESCAPE\" )
				( netClassRef "@sapphirecity_baseboard_lib.sapphirecity_baseboard(sch_1):\DDR4_CHN_L_DQ_DQS_BYTE7\" )
				( netClassRef "@sapphirecity_baseboard_lib.sapphirecity_baseboard(sch_1):\DDR4_CHN_L_DQ_DQS_BYTE7\" )
			)
			( regionClassClass "@crescent_city_bb_fab1_lib.crescent_city_bb_fab1(sch_1):\RCC172\"
				( spacingCSetRef "@crescent_city_bb_fab1_lib.crescent_city_bb_fab1(sch_1):\5MIL_US_&_4MIL_SL\" )
				( regionRef "@crescent_city_bb_fab1_lib.crescent_city_bb_fab1(sch_1):\DDR_ESCAPE\" )
				( netClassRef "@sapphirecity_baseboard_lib.sapphirecity_baseboard(sch_1):\DDR4_CHN_M_DQ_DQS_BYTE0\" )
				( netClassRef "@sapphirecity_baseboard_lib.sapphirecity_baseboard(sch_1):\DDR4_CHN_M_DQ_DQS_BYTE0\" )
			)
			( regionClassClass "@crescent_city_bb_fab1_lib.crescent_city_bb_fab1(sch_1):\RCC173\"
				( spacingCSetRef "@crescent_city_bb_fab1_lib.crescent_city_bb_fab1(sch_1):\5MIL_US_&_4MIL_SL\" )
				( regionRef "@crescent_city_bb_fab1_lib.crescent_city_bb_fab1(sch_1):\DDR_ESCAPE\" )
				( netClassRef "@sapphirecity_baseboard_lib.sapphirecity_baseboard(sch_1):\DDR4_CHN_M_DQ_DQS_BYTE1\" )
				( netClassRef "@sapphirecity_baseboard_lib.sapphirecity_baseboard(sch_1):\DDR4_CHN_M_DQ_DQS_BYTE1\" )
			)
			( regionClassClass "@crescent_city_bb_fab1_lib.crescent_city_bb_fab1(sch_1):\RCC174\"
				( spacingCSetRef "@crescent_city_bb_fab1_lib.crescent_city_bb_fab1(sch_1):\5MIL_US_&_4MIL_SL\" )
				( regionRef "@crescent_city_bb_fab1_lib.crescent_city_bb_fab1(sch_1):\DDR_ESCAPE\" )
				( netClassRef "@sapphirecity_baseboard_lib.sapphirecity_baseboard(sch_1):\DDR4_CHN_M_DQ_DQS_BYTE2\" )
				( netClassRef "@sapphirecity_baseboard_lib.sapphirecity_baseboard(sch_1):\DDR4_CHN_M_DQ_DQS_BYTE2\" )
			)
			( regionClassClass "@crescent_city_bb_fab1_lib.crescent_city_bb_fab1(sch_1):\RCC175\"
				( spacingCSetRef "@crescent_city_bb_fab1_lib.crescent_city_bb_fab1(sch_1):\5MIL_US_&_4MIL_SL\" )
				( regionRef "@crescent_city_bb_fab1_lib.crescent_city_bb_fab1(sch_1):\DDR_ESCAPE\" )
				( netClassRef "@sapphirecity_baseboard_lib.sapphirecity_baseboard(sch_1):\DDR4_CHN_M_DQ_DQS_BYTE3\" )
				( netClassRef "@sapphirecity_baseboard_lib.sapphirecity_baseboard(sch_1):\DDR4_CHN_M_DQ_DQS_BYTE3\" )
			)
			( regionClassClass "@crescent_city_bb_fab1_lib.crescent_city_bb_fab1(sch_1):\RCC176\"
				( spacingCSetRef "@crescent_city_bb_fab1_lib.crescent_city_bb_fab1(sch_1):\5MIL_US_&_4MIL_SL\" )
				( regionRef "@crescent_city_bb_fab1_lib.crescent_city_bb_fab1(sch_1):\DDR_ESCAPE\" )
				( netClassRef "@sapphirecity_baseboard_lib.sapphirecity_baseboard(sch_1):\DDR4_CHN_M_DQ_DQS_BYTE4\" )
				( netClassRef "@sapphirecity_baseboard_lib.sapphirecity_baseboard(sch_1):\DDR4_CHN_M_DQ_DQS_BYTE4\" )
			)
			( regionClassClass "@crescent_city_bb_fab1_lib.crescent_city_bb_fab1(sch_1):\RCC177\"
				( spacingCSetRef "@crescent_city_bb_fab1_lib.crescent_city_bb_fab1(sch_1):\5MIL_US_&_4MIL_SL\" )
				( regionRef "@crescent_city_bb_fab1_lib.crescent_city_bb_fab1(sch_1):\DDR_ESCAPE\" )
				( netClassRef "@sapphirecity_baseboard_lib.sapphirecity_baseboard(sch_1):\DDR4_CHN_M_DQ_DQS_BYTE5\" )
				( netClassRef "@sapphirecity_baseboard_lib.sapphirecity_baseboard(sch_1):\DDR4_CHN_M_DQ_DQS_BYTE5\" )
			)
			( regionClassClass "@crescent_city_bb_fab1_lib.crescent_city_bb_fab1(sch_1):\RCC178\"
				( spacingCSetRef "@crescent_city_bb_fab1_lib.crescent_city_bb_fab1(sch_1):\5MIL_US_&_4MIL_SL\" )
				( regionRef "@crescent_city_bb_fab1_lib.crescent_city_bb_fab1(sch_1):\DDR_ESCAPE\" )
				( netClassRef "@sapphirecity_baseboard_lib.sapphirecity_baseboard(sch_1):\DDR4_CHN_M_DQ_DQS_BYTE6\" )
				( netClassRef "@sapphirecity_baseboard_lib.sapphirecity_baseboard(sch_1):\DDR4_CHN_M_DQ_DQS_BYTE6\" )
			)
			( regionClassClass "@crescent_city_bb_fab1_lib.crescent_city_bb_fab1(sch_1):\RCC179\"
				( spacingCSetRef "@crescent_city_bb_fab1_lib.crescent_city_bb_fab1(sch_1):\5MIL_US_&_4MIL_SL\" )
				( regionRef "@crescent_city_bb_fab1_lib.crescent_city_bb_fab1(sch_1):\DDR_ESCAPE\" )
				( netClassRef "@sapphirecity_baseboard_lib.sapphirecity_baseboard(sch_1):\DDR4_CHN_M_DQ_DQS_BYTE7\" )
				( netClassRef "@sapphirecity_baseboard_lib.sapphirecity_baseboard(sch_1):\DDR4_CHN_M_DQ_DQS_BYTE7\" )
			)
			( regionClassClass "@crescent_city_bb_fab1_lib.crescent_city_bb_fab1(sch_1):\RCC180\"
				( spacingCSetRef "@crescent_city_bb_fab1_lib.crescent_city_bb_fab1(sch_1):\5MIL_US_&_4MIL_SL\" )
				( regionRef "@crescent_city_bb_fab1_lib.crescent_city_bb_fab1(sch_1):\DDR_ESCAPE\" )
				( netClassRef "@sapphirecity_baseboard_lib.sapphirecity_baseboard(sch_1):\DDR4_CHN_M_ECC\" )
				( netClassRef "@sapphirecity_baseboard_lib.sapphirecity_baseboard(sch_1):\DDR4_CHN_M_ECC\" )
			)
			( regionClassClass "@crescent_city_bb_fab1_lib.crescent_city_bb_fab1(sch_1):\RCC171\"
				( spacingCSetRef "@crescent_city_bb_fab1_lib.crescent_city_bb_fab1(sch_1):\5MIL_US_&_4MIL_SL\" )
				( regionRef "@crescent_city_bb_fab1_lib.crescent_city_bb_fab1(sch_1):\DDR_ESCAPE\" )
				( netClassRef "@sapphirecity_baseboard_lib.sapphirecity_baseboard(sch_1):\DDR4_CHN_L_ECC\" )
				( netClassRef "@sapphirecity_baseboard_lib.sapphirecity_baseboard(sch_1):\DDR4_CHN_L_ECC\" )
			)
			( regionClassClass "@crescent_city_bb_fab1_lib.crescent_city_bb_fab1(sch_1):\RCC162\"
				( spacingCSetRef "@crescent_city_bb_fab1_lib.crescent_city_bb_fab1(sch_1):\5MIL_US_&_4MIL_SL\" )
				( regionRef "@crescent_city_bb_fab1_lib.crescent_city_bb_fab1(sch_1):\DDR_ESCAPE\" )
				( netClassRef "@sapphirecity_baseboard_lib.sapphirecity_baseboard(sch_1):\DDR4_CHN_K_ECC\" )
				( netClassRef "@sapphirecity_baseboard_lib.sapphirecity_baseboard(sch_1):\DDR4_CHN_K_ECC\" )
			)
			( regionClassClass "@crescent_city_bb_fab1_lib.crescent_city_bb_fab1(sch_1):\RCC153\"
				( spacingCSetRef "@crescent_city_bb_fab1_lib.crescent_city_bb_fab1(sch_1):\5MIL_US_&_4MIL_SL\" )
				( regionRef "@crescent_city_bb_fab1_lib.crescent_city_bb_fab1(sch_1):\DDR_ESCAPE\" )
				( netClassRef "@sapphirecity_baseboard_lib.sapphirecity_baseboard(sch_1):\DDR4_CHN_J_ECC\" )
				( netClassRef "@sapphirecity_baseboard_lib.sapphirecity_baseboard(sch_1):\DDR4_CHN_J_ECC\" )
			)
			( regionClassClass "@crescent_city_bb_fab1_lib.crescent_city_bb_fab1(sch_1):\RCC11\"
				( spacingCSetRef "@crescent_city_bb_fab1_lib.crescent_city_bb_fab1(sch_1):\5MIL_US_&_4MIL_SL\" )
				( regionRef "@crescent_city_bb_fab1_lib.crescent_city_bb_fab1(sch_1):\DDR_ESCAPE\" )
				( netClassRef "@sapphirecity_baseboard_lib.sapphirecity_baseboard(sch_1):\DDR4_CHN_A_DQ_DQS_BYTE6\" )
				( netClassRef "@sapphirecity_baseboard_lib.sapphirecity_baseboard(sch_1):\DDR4_CHN_A_DQ_DQS_BYTE6\" )
			)
			( regionClassClass "@crescent_city_bb_fab1_lib.crescent_city_bb_fab1(sch_1):\RCC10\"
				( spacingCSetRef "@crescent_city_bb_fab1_lib.crescent_city_bb_fab1(sch_1):\5MIL_US_&_4MIL_SL\" )
				( regionRef "@crescent_city_bb_fab1_lib.crescent_city_bb_fab1(sch_1):\DDR_ESCAPE\" )
				( netClassRef "@sapphirecity_baseboard_lib.sapphirecity_baseboard(sch_1):\DDR4_CHN_A_DQ_DQS_BYTE5\" )
				( netClassRef "@sapphirecity_baseboard_lib.sapphirecity_baseboard(sch_1):\DDR4_CHN_A_DQ_DQS_BYTE5\" )
			)
			( regionClassClass "@crescent_city_bb_fab1_lib.crescent_city_bb_fab1(sch_1):\RCC9\"
				( spacingCSetRef "@crescent_city_bb_fab1_lib.crescent_city_bb_fab1(sch_1):\5MIL_US_&_4MIL_SL\" )
				( regionRef "@crescent_city_bb_fab1_lib.crescent_city_bb_fab1(sch_1):\DDR_ESCAPE\" )
				( netClassRef "@sapphirecity_baseboard_lib.sapphirecity_baseboard(sch_1):\DDR4_CHN_A_DQ_DQS_BYTE4\" )
				( netClassRef "@sapphirecity_baseboard_lib.sapphirecity_baseboard(sch_1):\DDR4_CHN_A_DQ_DQS_BYTE4\" )
			)
			( regionClassClass "@crescent_city_bb_fab1_lib.crescent_city_bb_fab1(sch_1):\RCC8\"
				( spacingCSetRef "@crescent_city_bb_fab1_lib.crescent_city_bb_fab1(sch_1):\5MIL_US_&_4MIL_SL\" )
				( regionRef "@crescent_city_bb_fab1_lib.crescent_city_bb_fab1(sch_1):\DDR_ESCAPE\" )
				( netClassRef "@sapphirecity_baseboard_lib.sapphirecity_baseboard(sch_1):\DDR4_CHN_A_DQ_DQS_BYTE3\" )
				( netClassRef "@sapphirecity_baseboard_lib.sapphirecity_baseboard(sch_1):\DDR4_CHN_A_DQ_DQS_BYTE3\" )
			)
			( regionClassClass "@crescent_city_bb_fab1_lib.crescent_city_bb_fab1(sch_1):\RCC7\"
				( spacingCSetRef "@crescent_city_bb_fab1_lib.crescent_city_bb_fab1(sch_1):\5MIL_US_&_4MIL_SL\" )
				( regionRef "@crescent_city_bb_fab1_lib.crescent_city_bb_fab1(sch_1):\DDR_ESCAPE\" )
				( netClassRef "@sapphirecity_baseboard_lib.sapphirecity_baseboard(sch_1):\DDR4_CHN_A_DQ_DQS_BYTE2\" )
				( netClassRef "@sapphirecity_baseboard_lib.sapphirecity_baseboard(sch_1):\DDR4_CHN_A_DQ_DQS_BYTE2\" )
			)
			( regionClassClass "@crescent_city_bb_fab1_lib.crescent_city_bb_fab1(sch_1):\RCC6\"
				( spacingCSetRef "@crescent_city_bb_fab1_lib.crescent_city_bb_fab1(sch_1):\5MIL_US_&_4MIL_SL\" )
				( regionRef "@crescent_city_bb_fab1_lib.crescent_city_bb_fab1(sch_1):\DDR_ESCAPE\" )
				( netClassRef "@sapphirecity_baseboard_lib.sapphirecity_baseboard(sch_1):\DDR4_CHN_A_DQ_DQS_BYTE1\" )
				( netClassRef "@sapphirecity_baseboard_lib.sapphirecity_baseboard(sch_1):\DDR4_CHN_A_DQ_DQS_BYTE1\" )
			)
			( regionClassClass "@crescent_city_bb_fab1_lib.crescent_city_bb_fab1(sch_1):\RCC5\"
				( spacingCSetRef "@crescent_city_bb_fab1_lib.crescent_city_bb_fab1(sch_1):\5MIL_US_&_4MIL_SL\" )
				( regionRef "@crescent_city_bb_fab1_lib.crescent_city_bb_fab1(sch_1):\DDR_ESCAPE\" )
				( netClassRef "@sapphirecity_baseboard_lib.sapphirecity_baseboard(sch_1):\DDR4_CHN_A_DQ_DQS_BYTE0\" )
				( netClassRef "@sapphirecity_baseboard_lib.sapphirecity_baseboard(sch_1):\DDR4_CHN_A_DQ_DQS_BYTE0\" )
			)
			( regionClassClass "@crescent_city_bb_fab1_lib.crescent_city_bb_fab1(sch_1):\RCC22\"
				( spacingCSetRef "@crescent_city_bb_fab1_lib.crescent_city_bb_fab1(sch_1):\5MIL_US_&_4MIL_SL\" )
				( regionRef "@crescent_city_bb_fab1_lib.crescent_city_bb_fab1(sch_1):\DDR_ESCAPE\" )
				( netClassRef "@sapphirecity_baseboard_lib.sapphirecity_baseboard(sch_1):\DDR4_CHN_B_DQ_DQS_BYTE7\" )
				( netClassRef "@sapphirecity_baseboard_lib.sapphirecity_baseboard(sch_1):\DDR4_CHN_B_DQ_DQS_BYTE7\" )
			)
			( regionClassClass "@crescent_city_bb_fab1_lib.crescent_city_bb_fab1(sch_1):\RCC2\"
				( spacingCSetRef "@crescent_city_bb_fab1_lib.crescent_city_bb_fab1(sch_1):\5MIL_US_&_4MIL_SL\" )
				( regionRef "@crescent_city_bb_fab1_lib.crescent_city_bb_fab1(sch_1):\DDR_ESCAPE\" )
				( netClassRef "@sapphirecity_baseboard_lib.sapphirecity_baseboard(sch_1):\DDR4_CHN_B_DQ_DQS_BYTE6\" )
				( netClassRef "@sapphirecity_baseboard_lib.sapphirecity_baseboard(sch_1):\DDR4_CHN_B_DQ_DQS_BYTE6\" )
			)
			( regionClassClass "@crescent_city_bb_fab1_lib.crescent_city_bb_fab1(sch_1):\RCC1\"
				( spacingCSetRef "@crescent_city_bb_fab1_lib.crescent_city_bb_fab1(sch_1):\5MIL_US_&_4MIL_SL\" )
				( regionRef "@crescent_city_bb_fab1_lib.crescent_city_bb_fab1(sch_1):\DDR_ESCAPE\" )
				( netClassRef "@sapphirecity_baseboard_lib.sapphirecity_baseboard(sch_1):\DDR4_CHN_B_DQ_DQS_BYTE5\" )
				( netClassRef "@sapphirecity_baseboard_lib.sapphirecity_baseboard(sch_1):\DDR4_CHN_B_DQ_DQS_BYTE5\" )
			)
			( regionClassClass "@crescent_city_bb_fab1_lib.crescent_city_bb_fab1(sch_1):\RCC21\"
				( spacingCSetRef "@crescent_city_bb_fab1_lib.crescent_city_bb_fab1(sch_1):\5MIL_US_&_4MIL_SL\" )
				( regionRef "@crescent_city_bb_fab1_lib.crescent_city_bb_fab1(sch_1):\DDR_ESCAPE\" )
				( netClassRef "@sapphirecity_baseboard_lib.sapphirecity_baseboard(sch_1):\DDR4_CHN_B_DQ_DQS_BYTE4\" )
				( netClassRef "@sapphirecity_baseboard_lib.sapphirecity_baseboard(sch_1):\DDR4_CHN_B_DQ_DQS_BYTE4\" )
			)
			( regionClassClass "@crescent_city_bb_fab1_lib.crescent_city_bb_fab1(sch_1):\RCC20\"
				( spacingCSetRef "@crescent_city_bb_fab1_lib.crescent_city_bb_fab1(sch_1):\5MIL_US_&_4MIL_SL\" )
				( regionRef "@crescent_city_bb_fab1_lib.crescent_city_bb_fab1(sch_1):\DDR_ESCAPE\" )
				( netClassRef "@sapphirecity_baseboard_lib.sapphirecity_baseboard(sch_1):\DDR4_CHN_B_DQ_DQS_BYTE3\" )
				( netClassRef "@sapphirecity_baseboard_lib.sapphirecity_baseboard(sch_1):\DDR4_CHN_B_DQ_DQS_BYTE3\" )
			)
			( regionClassClass "@crescent_city_bb_fab1_lib.crescent_city_bb_fab1(sch_1):\RCC19\"
				( spacingCSetRef "@crescent_city_bb_fab1_lib.crescent_city_bb_fab1(sch_1):\5MIL_US_&_4MIL_SL\" )
				( regionRef "@crescent_city_bb_fab1_lib.crescent_city_bb_fab1(sch_1):\DDR_ESCAPE\" )
				( netClassRef "@sapphirecity_baseboard_lib.sapphirecity_baseboard(sch_1):\DDR4_CHN_B_DQ_DQS_BYTE2\" )
				( netClassRef "@sapphirecity_baseboard_lib.sapphirecity_baseboard(sch_1):\DDR4_CHN_B_DQ_DQS_BYTE2\" )
			)
			( regionClassClass "@crescent_city_bb_fab1_lib.crescent_city_bb_fab1(sch_1):\RCC18\"
				( spacingCSetRef "@crescent_city_bb_fab1_lib.crescent_city_bb_fab1(sch_1):\5MIL_US_&_4MIL_SL\" )
				( regionRef "@crescent_city_bb_fab1_lib.crescent_city_bb_fab1(sch_1):\DDR_ESCAPE\" )
				( netClassRef "@sapphirecity_baseboard_lib.sapphirecity_baseboard(sch_1):\DDR4_CHN_B_DQ_DQS_BYTE1\" )
				( netClassRef "@sapphirecity_baseboard_lib.sapphirecity_baseboard(sch_1):\DDR4_CHN_B_DQ_DQS_BYTE1\" )
			)
			( regionClassClass "@crescent_city_bb_fab1_lib.crescent_city_bb_fab1(sch_1):\RCC17\"
				( spacingCSetRef "@crescent_city_bb_fab1_lib.crescent_city_bb_fab1(sch_1):\5MIL_US_&_4MIL_SL\" )
				( regionRef "@crescent_city_bb_fab1_lib.crescent_city_bb_fab1(sch_1):\DDR_ESCAPE\" )
				( netClassRef "@sapphirecity_baseboard_lib.sapphirecity_baseboard(sch_1):\DDR4_CHN_B_DQ_DQS_BYTE0\" )
				( netClassRef "@sapphirecity_baseboard_lib.sapphirecity_baseboard(sch_1):\DDR4_CHN_B_DQ_DQS_BYTE0\" )
			)
			( regionClassClass "@crescent_city_bb_fab1_lib.crescent_city_bb_fab1(sch_1):\RCC34\"
				( spacingCSetRef "@crescent_city_bb_fab1_lib.crescent_city_bb_fab1(sch_1):\5MIL_US_&_4MIL_SL\" )
				( regionRef "@crescent_city_bb_fab1_lib.crescent_city_bb_fab1(sch_1):\DDR_ESCAPE\" )
				( netClassRef "@sapphirecity_baseboard_lib.sapphirecity_baseboard(sch_1):\DDR4_CHN_C_DQ_DQS_BYTE7\" )
				( netClassRef "@sapphirecity_baseboard_lib.sapphirecity_baseboard(sch_1):\DDR4_CHN_C_DQ_DQS_BYTE7\" )
			)
			( regionClassClass "@crescent_city_bb_fab1_lib.crescent_city_bb_fab1(sch_1):\RCC33\"
				( spacingCSetRef "@crescent_city_bb_fab1_lib.crescent_city_bb_fab1(sch_1):\5MIL_US_&_4MIL_SL\" )
				( regionRef "@crescent_city_bb_fab1_lib.crescent_city_bb_fab1(sch_1):\DDR_ESCAPE\" )
				( netClassRef "@sapphirecity_baseboard_lib.sapphirecity_baseboard(sch_1):\DDR4_CHN_C_DQ_DQS_BYTE6\" )
				( netClassRef "@sapphirecity_baseboard_lib.sapphirecity_baseboard(sch_1):\DDR4_CHN_C_DQ_DQS_BYTE6\" )
			)
			( regionClassClass "@crescent_city_bb_fab1_lib.crescent_city_bb_fab1(sch_1):\RCC32\"
				( spacingCSetRef "@crescent_city_bb_fab1_lib.crescent_city_bb_fab1(sch_1):\5MIL_US_&_4MIL_SL\" )
				( regionRef "@crescent_city_bb_fab1_lib.crescent_city_bb_fab1(sch_1):\DDR_ESCAPE\" )
				( netClassRef "@sapphirecity_baseboard_lib.sapphirecity_baseboard(sch_1):\DDR4_CHN_C_DQ_DQS_BYTE5\" )
				( netClassRef "@sapphirecity_baseboard_lib.sapphirecity_baseboard(sch_1):\DDR4_CHN_C_DQ_DQS_BYTE5\" )
			)
			( regionClassClass "@crescent_city_bb_fab1_lib.crescent_city_bb_fab1(sch_1):\RCC31\"
				( spacingCSetRef "@crescent_city_bb_fab1_lib.crescent_city_bb_fab1(sch_1):\5MIL_US_&_4MIL_SL\" )
				( regionRef "@crescent_city_bb_fab1_lib.crescent_city_bb_fab1(sch_1):\DDR_ESCAPE\" )
				( netClassRef "@sapphirecity_baseboard_lib.sapphirecity_baseboard(sch_1):\DDR4_CHN_C_DQ_DQS_BYTE4\" )
				( netClassRef "@sapphirecity_baseboard_lib.sapphirecity_baseboard(sch_1):\DDR4_CHN_C_DQ_DQS_BYTE4\" )
			)
			( regionClassClass "@crescent_city_bb_fab1_lib.crescent_city_bb_fab1(sch_1):\RCC30\"
				( spacingCSetRef "@crescent_city_bb_fab1_lib.crescent_city_bb_fab1(sch_1):\5MIL_US_&_4MIL_SL\" )
				( regionRef "@crescent_city_bb_fab1_lib.crescent_city_bb_fab1(sch_1):\DDR_ESCAPE\" )
				( netClassRef "@sapphirecity_baseboard_lib.sapphirecity_baseboard(sch_1):\DDR4_CHN_C_DQ_DQS_BYTE3\" )
				( netClassRef "@sapphirecity_baseboard_lib.sapphirecity_baseboard(sch_1):\DDR4_CHN_C_DQ_DQS_BYTE3\" )
			)
			( regionClassClass "@crescent_city_bb_fab1_lib.crescent_city_bb_fab1(sch_1):\RCC29\"
				( spacingCSetRef "@crescent_city_bb_fab1_lib.crescent_city_bb_fab1(sch_1):\5MIL_US_&_4MIL_SL\" )
				( regionRef "@crescent_city_bb_fab1_lib.crescent_city_bb_fab1(sch_1):\DDR_ESCAPE\" )
				( netClassRef "@sapphirecity_baseboard_lib.sapphirecity_baseboard(sch_1):\DDR4_CHN_C_DQ_DQS_BYTE2\" )
				( netClassRef "@sapphirecity_baseboard_lib.sapphirecity_baseboard(sch_1):\DDR4_CHN_C_DQ_DQS_BYTE2\" )
			)
			( regionClassClass "@crescent_city_bb_fab1_lib.crescent_city_bb_fab1(sch_1):\RCC28\"
				( spacingCSetRef "@crescent_city_bb_fab1_lib.crescent_city_bb_fab1(sch_1):\5MIL_US_&_4MIL_SL\" )
				( regionRef "@crescent_city_bb_fab1_lib.crescent_city_bb_fab1(sch_1):\DDR_ESCAPE\" )
				( netClassRef "@sapphirecity_baseboard_lib.sapphirecity_baseboard(sch_1):\DDR4_CHN_C_DQ_DQS_BYTE1\" )
				( netClassRef "@sapphirecity_baseboard_lib.sapphirecity_baseboard(sch_1):\DDR4_CHN_C_DQ_DQS_BYTE1\" )
			)
			( regionClassClass "@crescent_city_bb_fab1_lib.crescent_city_bb_fab1(sch_1):\RCC27\"
				( spacingCSetRef "@crescent_city_bb_fab1_lib.crescent_city_bb_fab1(sch_1):\5MIL_US_&_4MIL_SL\" )
				( regionRef "@crescent_city_bb_fab1_lib.crescent_city_bb_fab1(sch_1):\DDR_ESCAPE\" )
				( netClassRef "@sapphirecity_baseboard_lib.sapphirecity_baseboard(sch_1):\DDR4_CHN_C_DQ_DQS_BYTE0\" )
				( netClassRef "@sapphirecity_baseboard_lib.sapphirecity_baseboard(sch_1):\DDR4_CHN_C_DQ_DQS_BYTE0\" )
			)
			( regionClassClass "@crescent_city_bb_fab1_lib.crescent_city_bb_fab1(sch_1):\RCC43\"
				( spacingCSetRef "@crescent_city_bb_fab1_lib.crescent_city_bb_fab1(sch_1):\5MIL_US_&_4MIL_SL\" )
				( regionRef "@crescent_city_bb_fab1_lib.crescent_city_bb_fab1(sch_1):\DDR_ESCAPE\" )
				( netClassRef "@sapphirecity_baseboard_lib.sapphirecity_baseboard(sch_1):\DDR4_CHN_D_CLK\" )
				( netClassRef "@sapphirecity_baseboard_lib.sapphirecity_baseboard(sch_1):\DDR4_CHN_D_CLK\" )
			)
			( regionClassClass "@crescent_city_bb_fab1_lib.crescent_city_bb_fab1(sch_1):\RCC44\"
				( spacingCSetRef "@crescent_city_bb_fab1_lib.crescent_city_bb_fab1(sch_1):\5MIL_US_&_4MIL_SL\" )
				( regionRef "@crescent_city_bb_fab1_lib.crescent_city_bb_fab1(sch_1):\DDR_ESCAPE\" )
				( netClassRef "@sapphirecity_baseboard_lib.sapphirecity_baseboard(sch_1):\DDR4_CHN_D_CLK\" )
				( netClassRef "@sapphirecity_baseboard_lib.sapphirecity_baseboard(sch_1):\DDR4_CHN_D_CMD_ADD\" )
			)
			( regionClassClass "@crescent_city_bb_fab1_lib.crescent_city_bb_fab1(sch_1):\RCC45\"
				( spacingCSetRef "@crescent_city_bb_fab1_lib.crescent_city_bb_fab1(sch_1):\5MIL_US_&_4MIL_SL\" )
				( regionRef "@crescent_city_bb_fab1_lib.crescent_city_bb_fab1(sch_1):\DDR_ESCAPE\" )
				( netClassRef "@sapphirecity_baseboard_lib.sapphirecity_baseboard(sch_1):\DDR4_CHN_D_CLK\" )
				( netClassRef "@sapphirecity_baseboard_lib.sapphirecity_baseboard(sch_1):\DDR4_CHN_D_CTRL\" )
			)
			( regionClassClass "@crescent_city_bb_fab1_lib.crescent_city_bb_fab1(sch_1):\RCC100\"
				( spacingCSetRef "@crescent_city_bb_fab1_lib.crescent_city_bb_fab1(sch_1):\5MIL_US_&_4MIL_SL\" )
				( regionRef "@crescent_city_bb_fab1_lib.crescent_city_bb_fab1(sch_1):\DDR_ESCAPE\" )
				( netClassRef "@sapphirecity_baseboard_lib.sapphirecity_baseboard(sch_1):\DDR4_CHN_D_DQ_DQS_BYTE0\" )
				( netClassRef "@sapphirecity_baseboard_lib.sapphirecity_baseboard(sch_1):\DDR4_CHN_D_DQ_DQS_BYTE0\" )
			)
			( regionClassClass "@crescent_city_bb_fab1_lib.crescent_city_bb_fab1(sch_1):\RCC36\"
				( spacingCSetRef "@crescent_city_bb_fab1_lib.crescent_city_bb_fab1(sch_1):\5MIL_US_&_4MIL_SL\" )
				( regionRef "@crescent_city_bb_fab1_lib.crescent_city_bb_fab1(sch_1):\DDR_ESCAPE\" )
				( netClassRef "@sapphirecity_baseboard_lib.sapphirecity_baseboard(sch_1):\DDR4_CHN_A_CLK\" )
				( netClassRef "@sapphirecity_baseboard_lib.sapphirecity_baseboard(sch_1):\DDR4_CHN_A_CMD_ADD\" )
			)
			( regionClassClass "@crescent_city_bb_fab1_lib.crescent_city_bb_fab1(sch_1):\RCC37\"
				( spacingCSetRef "@crescent_city_bb_fab1_lib.crescent_city_bb_fab1(sch_1):\5MIL_US_&_4MIL_SL\" )
				( regionRef "@crescent_city_bb_fab1_lib.crescent_city_bb_fab1(sch_1):\DDR_ESCAPE\" )
				( netClassRef "@sapphirecity_baseboard_lib.sapphirecity_baseboard(sch_1):\DDR4_CHN_A_CLK\" )
				( netClassRef "@sapphirecity_baseboard_lib.sapphirecity_baseboard(sch_1):\DDR4_CHN_A_CTRL\" )
			)
			( regionClassClass "@crescent_city_bb_fab1_lib.crescent_city_bb_fab1(sch_1):\RCC39\"
				( spacingCSetRef "@crescent_city_bb_fab1_lib.crescent_city_bb_fab1(sch_1):\5MIL_US_&_4MIL_SL\" )
				( regionRef "@crescent_city_bb_fab1_lib.crescent_city_bb_fab1(sch_1):\DDR_ESCAPE\" )
				( netClassRef "@sapphirecity_baseboard_lib.sapphirecity_baseboard(sch_1):\DDR4_CHN_A_CLK\" )
				( netClassRef "@sapphirecity_baseboard_lib.sapphirecity_baseboard(sch_1):\DDR4_CHN_A_CLK\" )
			)
			( regionClassClass "@crescent_city_bb_fab1_lib.crescent_city_bb_fab1(sch_1):\RCC3\"
				( spacingCSetRef "@crescent_city_bb_fab1_lib.crescent_city_bb_fab1(sch_1):\5MIL_US_&_4MIL_SL\" )
				( regionRef "@crescent_city_bb_fab1_lib.crescent_city_bb_fab1(sch_1):\DDR_ESCAPE\" )
				( netClassRef "@sapphirecity_baseboard_lib.sapphirecity_baseboard(sch_1):\DDR4_CHN_A_CMD_ADD\" )
				( netClassRef "@sapphirecity_baseboard_lib.sapphirecity_baseboard(sch_1):\DDR4_CHN_A_CMD_ADD\" )
			)
			( regionClassClass "@crescent_city_bb_fab1_lib.crescent_city_bb_fab1(sch_1):\RCC38\"
				( spacingCSetRef "@crescent_city_bb_fab1_lib.crescent_city_bb_fab1(sch_1):\5MIL_US_&_4MIL_SL\" )
				( regionRef "@crescent_city_bb_fab1_lib.crescent_city_bb_fab1(sch_1):\DDR_ESCAPE\" )
				( netClassRef "@sapphirecity_baseboard_lib.sapphirecity_baseboard(sch_1):\DDR4_CHN_A_CMD_ADD\" )
				( netClassRef "@sapphirecity_baseboard_lib.sapphirecity_baseboard(sch_1):\DDR4_CHN_A_CTRL\" )
			)
			( regionClassClass "@crescent_city_bb_fab1_lib.crescent_city_bb_fab1(sch_1):\RCC4\"
				( spacingCSetRef "@crescent_city_bb_fab1_lib.crescent_city_bb_fab1(sch_1):\5MIL_US_&_4MIL_SL\" )
				( regionRef "@crescent_city_bb_fab1_lib.crescent_city_bb_fab1(sch_1):\DDR_ESCAPE\" )
				( netClassRef "@sapphirecity_baseboard_lib.sapphirecity_baseboard(sch_1):\DDR4_CHN_A_CTRL\" )
				( netClassRef "@sapphirecity_baseboard_lib.sapphirecity_baseboard(sch_1):\DDR4_CHN_A_CTRL\" )
			)
			( regionClassClass "@crescent_city_bb_fab1_lib.crescent_city_bb_fab1(sch_1):\RCC13\"
				( spacingCSetRef "@crescent_city_bb_fab1_lib.crescent_city_bb_fab1(sch_1):\5MIL_US_&_4MIL_SL\" )
				( regionRef "@crescent_city_bb_fab1_lib.crescent_city_bb_fab1(sch_1):\DDR_ESCAPE\" )
				( netClassRef "@sapphirecity_baseboard_lib.sapphirecity_baseboard(sch_1):\DDR4_CHN_A_ECC\" )
				( netClassRef "@sapphirecity_baseboard_lib.sapphirecity_baseboard(sch_1):\DDR4_CHN_A_ECC\" )
			)
			( regionClassClass "@crescent_city_bb_fab1_lib.crescent_city_bb_fab1(sch_1):\RCC14\"
				( spacingCSetRef "@crescent_city_bb_fab1_lib.crescent_city_bb_fab1(sch_1):\5MIL_US_&_4MIL_SL\" )
				( regionRef "@crescent_city_bb_fab1_lib.crescent_city_bb_fab1(sch_1):\DDR_ESCAPE\" )
				( netClassRef "@sapphirecity_baseboard_lib.sapphirecity_baseboard(sch_1):\DDR4_CHN_B_CLK\" )
				( netClassRef "@sapphirecity_baseboard_lib.sapphirecity_baseboard(sch_1):\DDR4_CHN_B_CLK\" )
			)
			( regionClassClass "@crescent_city_bb_fab1_lib.crescent_city_bb_fab1(sch_1):\RCC40\"
				( spacingCSetRef "@crescent_city_bb_fab1_lib.crescent_city_bb_fab1(sch_1):\5MIL_US_&_4MIL_SL\" )
				( regionRef "@crescent_city_bb_fab1_lib.crescent_city_bb_fab1(sch_1):\DDR_ESCAPE\" )
				( netClassRef "@sapphirecity_baseboard_lib.sapphirecity_baseboard(sch_1):\DDR4_CHN_B_CLK\" )
				( netClassRef "@sapphirecity_baseboard_lib.sapphirecity_baseboard(sch_1):\DDR4_CHN_B_CMD_ADD\" )
			)
			( regionClassClass "@crescent_city_bb_fab1_lib.crescent_city_bb_fab1(sch_1):\RCC41\"
				( spacingCSetRef "@crescent_city_bb_fab1_lib.crescent_city_bb_fab1(sch_1):\5MIL_US_&_4MIL_SL\" )
				( regionRef "@crescent_city_bb_fab1_lib.crescent_city_bb_fab1(sch_1):\DDR_ESCAPE\" )
				( netClassRef "@sapphirecity_baseboard_lib.sapphirecity_baseboard(sch_1):\DDR4_CHN_B_CLK\" )
				( netClassRef "@sapphirecity_baseboard_lib.sapphirecity_baseboard(sch_1):\DDR4_CHN_B_CTRL\" )
			)
			( regionClassClass "@crescent_city_bb_fab1_lib.crescent_city_bb_fab1(sch_1):\RCC15\"
				( spacingCSetRef "@crescent_city_bb_fab1_lib.crescent_city_bb_fab1(sch_1):\5MIL_US_&_4MIL_SL\" )
				( regionRef "@crescent_city_bb_fab1_lib.crescent_city_bb_fab1(sch_1):\DDR_ESCAPE\" )
				( netClassRef "@sapphirecity_baseboard_lib.sapphirecity_baseboard(sch_1):\DDR4_CHN_B_CMD_ADD\" )
				( netClassRef "@sapphirecity_baseboard_lib.sapphirecity_baseboard(sch_1):\DDR4_CHN_B_CMD_ADD\" )
			)
			( regionClassClass "@crescent_city_bb_fab1_lib.crescent_city_bb_fab1(sch_1):\RCC42\"
				( spacingCSetRef "@crescent_city_bb_fab1_lib.crescent_city_bb_fab1(sch_1):\5MIL_US_&_4MIL_SL\" )
				( regionRef "@crescent_city_bb_fab1_lib.crescent_city_bb_fab1(sch_1):\DDR_ESCAPE\" )
				( netClassRef "@sapphirecity_baseboard_lib.sapphirecity_baseboard(sch_1):\DDR4_CHN_B_CMD_ADD\" )
				( netClassRef "@sapphirecity_baseboard_lib.sapphirecity_baseboard(sch_1):\DDR4_CHN_B_CTRL\" )
			)
			( regionClassClass "@crescent_city_bb_fab1_lib.crescent_city_bb_fab1(sch_1):\RCC16\"
				( spacingCSetRef "@crescent_city_bb_fab1_lib.crescent_city_bb_fab1(sch_1):\5MIL_US_&_4MIL_SL\" )
				( regionRef "@crescent_city_bb_fab1_lib.crescent_city_bb_fab1(sch_1):\DDR_ESCAPE\" )
				( netClassRef "@sapphirecity_baseboard_lib.sapphirecity_baseboard(sch_1):\DDR4_CHN_B_CTRL\" )
				( netClassRef "@sapphirecity_baseboard_lib.sapphirecity_baseboard(sch_1):\DDR4_CHN_B_CTRL\" )
			)
			( regionClassClass "@crescent_city_bb_fab1_lib.crescent_city_bb_fab1(sch_1):\RCC23\"
				( spacingCSetRef "@crescent_city_bb_fab1_lib.crescent_city_bb_fab1(sch_1):\5MIL_US_&_4MIL_SL\" )
				( regionRef "@crescent_city_bb_fab1_lib.crescent_city_bb_fab1(sch_1):\DDR_ESCAPE\" )
				( netClassRef "@sapphirecity_baseboard_lib.sapphirecity_baseboard(sch_1):\DDR4_CHN_B_ECC\" )
				( netClassRef "@sapphirecity_baseboard_lib.sapphirecity_baseboard(sch_1):\DDR4_CHN_B_ECC\" )
			)
			( regionClassClass "@crescent_city_bb_fab1_lib.crescent_city_bb_fab1(sch_1):\RCC24\"
				( spacingCSetRef "@crescent_city_bb_fab1_lib.crescent_city_bb_fab1(sch_1):\5MIL_US_&_4MIL_SL\" )
				( regionRef "@crescent_city_bb_fab1_lib.crescent_city_bb_fab1(sch_1):\DDR_ESCAPE\" )
				( netClassRef "@sapphirecity_baseboard_lib.sapphirecity_baseboard(sch_1):\DDR4_CHN_C_CLK\" )
				( netClassRef "@sapphirecity_baseboard_lib.sapphirecity_baseboard(sch_1):\DDR4_CHN_C_CLK\" )
			)
			( regionClassClass "@crescent_city_bb_fab1_lib.crescent_city_bb_fab1(sch_1):\RCC49\"
				( spacingCSetRef "@crescent_city_bb_fab1_lib.crescent_city_bb_fab1(sch_1):\5MIL_US_&_4MIL_SL\" )
				( regionRef "@crescent_city_bb_fab1_lib.crescent_city_bb_fab1(sch_1):\DDR_ESCAPE\" )
				( netClassRef "@sapphirecity_baseboard_lib.sapphirecity_baseboard(sch_1):\DDR4_CHN_C_CLK\" )
				( netClassRef "@sapphirecity_baseboard_lib.sapphirecity_baseboard(sch_1):\DDR4_CHN_C_CMD_ADD\" )
			)
			( regionClassClass "@crescent_city_bb_fab1_lib.crescent_city_bb_fab1(sch_1):\RCC50\"
				( spacingCSetRef "@crescent_city_bb_fab1_lib.crescent_city_bb_fab1(sch_1):\5MIL_US_&_4MIL_SL\" )
				( regionRef "@crescent_city_bb_fab1_lib.crescent_city_bb_fab1(sch_1):\DDR_ESCAPE\" )
				( netClassRef "@sapphirecity_baseboard_lib.sapphirecity_baseboard(sch_1):\DDR4_CHN_C_CLK\" )
				( netClassRef "@sapphirecity_baseboard_lib.sapphirecity_baseboard(sch_1):\DDR4_CHN_C_CTRL\" )
			)
			( regionClassClass "@crescent_city_bb_fab1_lib.crescent_city_bb_fab1(sch_1):\RCC25\"
				( spacingCSetRef "@crescent_city_bb_fab1_lib.crescent_city_bb_fab1(sch_1):\5MIL_US_&_4MIL_SL\" )
				( regionRef "@crescent_city_bb_fab1_lib.crescent_city_bb_fab1(sch_1):\DDR_ESCAPE\" )
				( netClassRef "@sapphirecity_baseboard_lib.sapphirecity_baseboard(sch_1):\DDR4_CHN_C_CMD_ADD\" )
				( netClassRef "@sapphirecity_baseboard_lib.sapphirecity_baseboard(sch_1):\DDR4_CHN_C_CMD_ADD\" )
			)
			( regionClassClass "@crescent_city_bb_fab1_lib.crescent_city_bb_fab1(sch_1):\RCC51\"
				( spacingCSetRef "@crescent_city_bb_fab1_lib.crescent_city_bb_fab1(sch_1):\5MIL_US_&_4MIL_SL\" )
				( regionRef "@crescent_city_bb_fab1_lib.crescent_city_bb_fab1(sch_1):\DDR_ESCAPE\" )
				( netClassRef "@sapphirecity_baseboard_lib.sapphirecity_baseboard(sch_1):\DDR4_CHN_C_CMD_ADD\" )
				( netClassRef "@sapphirecity_baseboard_lib.sapphirecity_baseboard(sch_1):\DDR4_CHN_C_CTRL\" )
			)
			( regionClassClass "@crescent_city_bb_fab1_lib.crescent_city_bb_fab1(sch_1):\RCC26\"
				( spacingCSetRef "@crescent_city_bb_fab1_lib.crescent_city_bb_fab1(sch_1):\5MIL_US_&_4MIL_SL\" )
				( regionRef "@crescent_city_bb_fab1_lib.crescent_city_bb_fab1(sch_1):\DDR_ESCAPE\" )
				( netClassRef "@sapphirecity_baseboard_lib.sapphirecity_baseboard(sch_1):\DDR4_CHN_C_CTRL\" )
				( netClassRef "@sapphirecity_baseboard_lib.sapphirecity_baseboard(sch_1):\DDR4_CHN_C_CTRL\" )
			)
			( regionClassClass "@crescent_city_bb_fab1_lib.crescent_city_bb_fab1(sch_1):\RCC35\"
				( spacingCSetRef "@crescent_city_bb_fab1_lib.crescent_city_bb_fab1(sch_1):\5MIL_US_&_4MIL_SL\" )
				( regionRef "@crescent_city_bb_fab1_lib.crescent_city_bb_fab1(sch_1):\DDR_ESCAPE\" )
				( netClassRef "@sapphirecity_baseboard_lib.sapphirecity_baseboard(sch_1):\DDR4_CHN_C_ECC\" )
				( netClassRef "@sapphirecity_baseboard_lib.sapphirecity_baseboard(sch_1):\DDR4_CHN_C_ECC\" )
			)
			( regionClassClass "@crescent_city_bb_fab1_lib.crescent_city_bb_fab1(sch_1):\RCC46\"
				( spacingCSetRef "@crescent_city_bb_fab1_lib.crescent_city_bb_fab1(sch_1):\5MIL_US_&_4MIL_SL\" )
				( regionRef "@crescent_city_bb_fab1_lib.crescent_city_bb_fab1(sch_1):\DDR_ESCAPE\" )
				( netClassRef "@sapphirecity_baseboard_lib.sapphirecity_baseboard(sch_1):\DDR4_CHN_D_CMD_ADD\" )
				( netClassRef "@sapphirecity_baseboard_lib.sapphirecity_baseboard(sch_1):\DDR4_CHN_D_CMD_ADD\" )
			)
			( regionClassClass "@crescent_city_bb_fab1_lib.crescent_city_bb_fab1(sch_1):\RCC47\"
				( spacingCSetRef "@crescent_city_bb_fab1_lib.crescent_city_bb_fab1(sch_1):\5MIL_US_&_4MIL_SL\" )
				( regionRef "@crescent_city_bb_fab1_lib.crescent_city_bb_fab1(sch_1):\DDR_ESCAPE\" )
				( netClassRef "@sapphirecity_baseboard_lib.sapphirecity_baseboard(sch_1):\DDR4_CHN_D_CMD_ADD\" )
				( netClassRef "@sapphirecity_baseboard_lib.sapphirecity_baseboard(sch_1):\DDR4_CHN_D_CTRL\" )
			)
			( regionClassClass "@crescent_city_bb_fab1_lib.crescent_city_bb_fab1(sch_1):\RCC48\"
				( spacingCSetRef "@crescent_city_bb_fab1_lib.crescent_city_bb_fab1(sch_1):\5MIL_US_&_4MIL_SL\" )
				( regionRef "@crescent_city_bb_fab1_lib.crescent_city_bb_fab1(sch_1):\DDR_ESCAPE\" )
				( netClassRef "@sapphirecity_baseboard_lib.sapphirecity_baseboard(sch_1):\DDR4_CHN_D_CTRL\" )
				( netClassRef "@sapphirecity_baseboard_lib.sapphirecity_baseboard(sch_1):\DDR4_CHN_D_CTRL\" )
			)
			( regionClassClass "@crescent_city_bb_fab1_lib.crescent_city_bb_fab1(sch_1):\RCC52\"
				( spacingCSetRef "@crescent_city_bb_fab1_lib.crescent_city_bb_fab1(sch_1):\5MIL_US_&_4MIL_SL\" )
				( regionRef "@crescent_city_bb_fab1_lib.crescent_city_bb_fab1(sch_1):\DDR_ESCAPE\" )
				( netClassRef "@sapphirecity_baseboard_lib.sapphirecity_baseboard(sch_1):\DDR4_CHN_E_CLK\" )
				( netClassRef "@sapphirecity_baseboard_lib.sapphirecity_baseboard(sch_1):\DDR4_CHN_E_CLK\" )
			)
			( regionClassClass "@crescent_city_bb_fab1_lib.crescent_city_bb_fab1(sch_1):\RCC53\"
				( spacingCSetRef "@crescent_city_bb_fab1_lib.crescent_city_bb_fab1(sch_1):\5MIL_US_&_4MIL_SL\" )
				( regionRef "@crescent_city_bb_fab1_lib.crescent_city_bb_fab1(sch_1):\DDR_ESCAPE\" )
				( netClassRef "@sapphirecity_baseboard_lib.sapphirecity_baseboard(sch_1):\DDR4_CHN_E_CLK\" )
				( netClassRef "@sapphirecity_baseboard_lib.sapphirecity_baseboard(sch_1):\DDR4_CHN_E_CMD_ADD\" )
			)
			( regionClassClass "@crescent_city_bb_fab1_lib.crescent_city_bb_fab1(sch_1):\RCC54\"
				( spacingCSetRef "@crescent_city_bb_fab1_lib.crescent_city_bb_fab1(sch_1):\5MIL_US_&_4MIL_SL\" )
				( regionRef "@crescent_city_bb_fab1_lib.crescent_city_bb_fab1(sch_1):\DDR_ESCAPE\" )
				( netClassRef "@sapphirecity_baseboard_lib.sapphirecity_baseboard(sch_1):\DDR4_CHN_E_CLK\" )
				( netClassRef "@sapphirecity_baseboard_lib.sapphirecity_baseboard(sch_1):\DDR4_CHN_E_CTRL\" )
			)
			( regionClassClass "@crescent_city_bb_fab1_lib.crescent_city_bb_fab1(sch_1):\RCC55\"
				( spacingCSetRef "@crescent_city_bb_fab1_lib.crescent_city_bb_fab1(sch_1):\5MIL_US_&_4MIL_SL\" )
				( regionRef "@crescent_city_bb_fab1_lib.crescent_city_bb_fab1(sch_1):\DDR_ESCAPE\" )
				( netClassRef "@sapphirecity_baseboard_lib.sapphirecity_baseboard(sch_1):\DDR4_CHN_E_CMD_ADD\" )
				( netClassRef "@sapphirecity_baseboard_lib.sapphirecity_baseboard(sch_1):\DDR4_CHN_E_CMD_ADD\" )
			)
			( regionClassClass "@crescent_city_bb_fab1_lib.crescent_city_bb_fab1(sch_1):\RCC56\"
				( spacingCSetRef "@crescent_city_bb_fab1_lib.crescent_city_bb_fab1(sch_1):\5MIL_US_&_4MIL_SL\" )
				( regionRef "@crescent_city_bb_fab1_lib.crescent_city_bb_fab1(sch_1):\DDR_ESCAPE\" )
				( netClassRef "@sapphirecity_baseboard_lib.sapphirecity_baseboard(sch_1):\DDR4_CHN_E_CMD_ADD\" )
				( netClassRef "@sapphirecity_baseboard_lib.sapphirecity_baseboard(sch_1):\DDR4_CHN_E_CTRL\" )
			)
			( regionClassClass "@crescent_city_bb_fab1_lib.crescent_city_bb_fab1(sch_1):\RCC57\"
				( spacingCSetRef "@crescent_city_bb_fab1_lib.crescent_city_bb_fab1(sch_1):\5MIL_US_&_4MIL_SL\" )
				( regionRef "@crescent_city_bb_fab1_lib.crescent_city_bb_fab1(sch_1):\DDR_ESCAPE\" )
				( netClassRef "@sapphirecity_baseboard_lib.sapphirecity_baseboard(sch_1):\DDR4_CHN_E_CTRL\" )
				( netClassRef "@sapphirecity_baseboard_lib.sapphirecity_baseboard(sch_1):\DDR4_CHN_E_CTRL\" )
			)
			( regionClassClass "@crescent_city_bb_fab1_lib.crescent_city_bb_fab1(sch_1):\RCC58\"
				( spacingCSetRef "@crescent_city_bb_fab1_lib.crescent_city_bb_fab1(sch_1):\5MIL_US_&_4MIL_SL\" )
				( regionRef "@crescent_city_bb_fab1_lib.crescent_city_bb_fab1(sch_1):\DDR_ESCAPE\" )
				( netClassRef "@sapphirecity_baseboard_lib.sapphirecity_baseboard(sch_1):\DDR4_CHN_F_CLK\" )
				( netClassRef "@sapphirecity_baseboard_lib.sapphirecity_baseboard(sch_1):\DDR4_CHN_F_CLK\" )
			)
			( regionClassClass "@crescent_city_bb_fab1_lib.crescent_city_bb_fab1(sch_1):\RCC59\"
				( spacingCSetRef "@crescent_city_bb_fab1_lib.crescent_city_bb_fab1(sch_1):\5MIL_US_&_4MIL_SL\" )
				( regionRef "@crescent_city_bb_fab1_lib.crescent_city_bb_fab1(sch_1):\DDR_ESCAPE\" )
				( netClassRef "@sapphirecity_baseboard_lib.sapphirecity_baseboard(sch_1):\DDR4_CHN_F_CLK\" )
				( netClassRef "@sapphirecity_baseboard_lib.sapphirecity_baseboard(sch_1):\DDR4_CHN_F_CMD_ADD\" )
			)
			( regionClassClass "@crescent_city_bb_fab1_lib.crescent_city_bb_fab1(sch_1):\RCC60\"
				( spacingCSetRef "@crescent_city_bb_fab1_lib.crescent_city_bb_fab1(sch_1):\5MIL_US_&_4MIL_SL\" )
				( regionRef "@crescent_city_bb_fab1_lib.crescent_city_bb_fab1(sch_1):\DDR_ESCAPE\" )
				( netClassRef "@sapphirecity_baseboard_lib.sapphirecity_baseboard(sch_1):\DDR4_CHN_F_CLK\" )
				( netClassRef "@sapphirecity_baseboard_lib.sapphirecity_baseboard(sch_1):\DDR4_CHN_F_CTRL\" )
			)
			( regionClassClass "@crescent_city_bb_fab1_lib.crescent_city_bb_fab1(sch_1):\RCC61\"
				( spacingCSetRef "@crescent_city_bb_fab1_lib.crescent_city_bb_fab1(sch_1):\5MIL_US_&_4MIL_SL\" )
				( regionRef "@crescent_city_bb_fab1_lib.crescent_city_bb_fab1(sch_1):\DDR_ESCAPE\" )
				( netClassRef "@sapphirecity_baseboard_lib.sapphirecity_baseboard(sch_1):\DDR4_CHN_F_CMD_ADD\" )
				( netClassRef "@sapphirecity_baseboard_lib.sapphirecity_baseboard(sch_1):\DDR4_CHN_F_CMD_ADD\" )
			)
			( regionClassClass "@crescent_city_bb_fab1_lib.crescent_city_bb_fab1(sch_1):\RCC62\"
				( spacingCSetRef "@crescent_city_bb_fab1_lib.crescent_city_bb_fab1(sch_1):\5MIL_US_&_4MIL_SL\" )
				( regionRef "@crescent_city_bb_fab1_lib.crescent_city_bb_fab1(sch_1):\DDR_ESCAPE\" )
				( netClassRef "@sapphirecity_baseboard_lib.sapphirecity_baseboard(sch_1):\DDR4_CHN_F_CMD_ADD\" )
				( netClassRef "@sapphirecity_baseboard_lib.sapphirecity_baseboard(sch_1):\DDR4_CHN_F_CTRL\" )
			)
			( regionClassClass "@crescent_city_bb_fab1_lib.crescent_city_bb_fab1(sch_1):\RCC63\"
				( spacingCSetRef "@crescent_city_bb_fab1_lib.crescent_city_bb_fab1(sch_1):\5MIL_US_&_4MIL_SL\" )
				( regionRef "@crescent_city_bb_fab1_lib.crescent_city_bb_fab1(sch_1):\DDR_ESCAPE\" )
				( netClassRef "@sapphirecity_baseboard_lib.sapphirecity_baseboard(sch_1):\DDR4_CHN_F_CTRL\" )
				( netClassRef "@sapphirecity_baseboard_lib.sapphirecity_baseboard(sch_1):\DDR4_CHN_F_CTRL\" )
			)
			( regionClassClass "@crescent_city_bb_fab1_lib.crescent_city_bb_fab1(sch_1):\RCC67\"
				( spacingCSetRef "@crescent_city_bb_fab1_lib.crescent_city_bb_fab1(sch_1):\5MIL_US_&_4MIL_SL\" )
				( regionRef "@crescent_city_bb_fab1_lib.crescent_city_bb_fab1(sch_1):\DDR_ESCAPE\" )
				( netClassRef "@sapphirecity_baseboard_lib.sapphirecity_baseboard(sch_1):\DDR4_CHN_G_CMD_ADD\" )
				( netClassRef "@sapphirecity_baseboard_lib.sapphirecity_baseboard(sch_1):\DDR4_CHN_G_CMD_ADD\" )
			)
			( regionClassClass "@crescent_city_bb_fab1_lib.crescent_city_bb_fab1(sch_1):\RCC68\"
				( spacingCSetRef "@crescent_city_bb_fab1_lib.crescent_city_bb_fab1(sch_1):\5MIL_US_&_4MIL_SL\" )
				( regionRef "@crescent_city_bb_fab1_lib.crescent_city_bb_fab1(sch_1):\DDR_ESCAPE\" )
				( netClassRef "@sapphirecity_baseboard_lib.sapphirecity_baseboard(sch_1):\DDR4_CHN_G_CMD_ADD\" )
				( netClassRef "@sapphirecity_baseboard_lib.sapphirecity_baseboard(sch_1):\DDR4_CHN_G_CTRL\" )
			)
			( regionClassClass "@crescent_city_bb_fab1_lib.crescent_city_bb_fab1(sch_1):\RCC69\"
				( spacingCSetRef "@crescent_city_bb_fab1_lib.crescent_city_bb_fab1(sch_1):\5MIL_US_&_4MIL_SL\" )
				( regionRef "@crescent_city_bb_fab1_lib.crescent_city_bb_fab1(sch_1):\DDR_ESCAPE\" )
				( netClassRef "@sapphirecity_baseboard_lib.sapphirecity_baseboard(sch_1):\DDR4_CHN_G_CTRL\" )
				( netClassRef "@sapphirecity_baseboard_lib.sapphirecity_baseboard(sch_1):\DDR4_CHN_G_CTRL\" )
			)
			( regionClassClass "@crescent_city_bb_fab1_lib.crescent_city_bb_fab1(sch_1):\RCC70\"
				( spacingCSetRef "@crescent_city_bb_fab1_lib.crescent_city_bb_fab1(sch_1):\5MIL_US_&_4MIL_SL\" )
				( regionRef "@crescent_city_bb_fab1_lib.crescent_city_bb_fab1(sch_1):\DDR_ESCAPE\" )
				( netClassRef "@sapphirecity_baseboard_lib.sapphirecity_baseboard(sch_1):\DDR4_CHN_H_CLK\" )
				( netClassRef "@sapphirecity_baseboard_lib.sapphirecity_baseboard(sch_1):\DDR4_CHN_H_CLK\" )
			)
			( regionClassClass "@crescent_city_bb_fab1_lib.crescent_city_bb_fab1(sch_1):\RCC71\"
				( spacingCSetRef "@crescent_city_bb_fab1_lib.crescent_city_bb_fab1(sch_1):\5MIL_US_&_4MIL_SL\" )
				( regionRef "@crescent_city_bb_fab1_lib.crescent_city_bb_fab1(sch_1):\DDR_ESCAPE\" )
				( netClassRef "@sapphirecity_baseboard_lib.sapphirecity_baseboard(sch_1):\DDR4_CHN_H_CLK\" )
				( netClassRef "@sapphirecity_baseboard_lib.sapphirecity_baseboard(sch_1):\DDR4_CHN_H_CMD_ADD\" )
			)
			( regionClassClass "@crescent_city_bb_fab1_lib.crescent_city_bb_fab1(sch_1):\RCC72\"
				( spacingCSetRef "@crescent_city_bb_fab1_lib.crescent_city_bb_fab1(sch_1):\5MIL_US_&_4MIL_SL\" )
				( regionRef "@crescent_city_bb_fab1_lib.crescent_city_bb_fab1(sch_1):\DDR_ESCAPE\" )
				( netClassRef "@sapphirecity_baseboard_lib.sapphirecity_baseboard(sch_1):\DDR4_CHN_H_CLK\" )
				( netClassRef "@sapphirecity_baseboard_lib.sapphirecity_baseboard(sch_1):\DDR4_CHN_H_CTRL\" )
			)
			( regionClassClass "@crescent_city_bb_fab1_lib.crescent_city_bb_fab1(sch_1):\RCC73\"
				( spacingCSetRef "@crescent_city_bb_fab1_lib.crescent_city_bb_fab1(sch_1):\5MIL_US_&_4MIL_SL\" )
				( regionRef "@crescent_city_bb_fab1_lib.crescent_city_bb_fab1(sch_1):\DDR_ESCAPE\" )
				( netClassRef "@sapphirecity_baseboard_lib.sapphirecity_baseboard(sch_1):\DDR4_CHN_H_CMD_ADD\" )
				( netClassRef "@sapphirecity_baseboard_lib.sapphirecity_baseboard(sch_1):\DDR4_CHN_H_CMD_ADD\" )
			)
			( regionClassClass "@crescent_city_bb_fab1_lib.crescent_city_bb_fab1(sch_1):\RCC74\"
				( spacingCSetRef "@crescent_city_bb_fab1_lib.crescent_city_bb_fab1(sch_1):\5MIL_US_&_4MIL_SL\" )
				( regionRef "@crescent_city_bb_fab1_lib.crescent_city_bb_fab1(sch_1):\DDR_ESCAPE\" )
				( netClassRef "@sapphirecity_baseboard_lib.sapphirecity_baseboard(sch_1):\DDR4_CHN_H_CMD_ADD\" )
				( netClassRef "@sapphirecity_baseboard_lib.sapphirecity_baseboard(sch_1):\DDR4_CHN_H_CTRL\" )
			)
			( regionClassClass "@crescent_city_bb_fab1_lib.crescent_city_bb_fab1(sch_1):\RCC75\"
				( spacingCSetRef "@crescent_city_bb_fab1_lib.crescent_city_bb_fab1(sch_1):\5MIL_US_&_4MIL_SL\" )
				( regionRef "@crescent_city_bb_fab1_lib.crescent_city_bb_fab1(sch_1):\DDR_ESCAPE\" )
				( netClassRef "@sapphirecity_baseboard_lib.sapphirecity_baseboard(sch_1):\DDR4_CHN_H_CTRL\" )
				( netClassRef "@sapphirecity_baseboard_lib.sapphirecity_baseboard(sch_1):\DDR4_CHN_H_CTRL\" )
			)
			( regionClassClass "@crescent_city_bb_fab1_lib.crescent_city_bb_fab1(sch_1):\RCC108\"
				( spacingCSetRef "@crescent_city_bb_fab1_lib.crescent_city_bb_fab1(sch_1):\5MIL_US_&_4MIL_SL\" )
				( regionRef "@crescent_city_bb_fab1_lib.crescent_city_bb_fab1(sch_1):\DDR_ESCAPE\" )
				( netClassRef "@sapphirecity_baseboard_lib.sapphirecity_baseboard(sch_1):\DDR4_CHN_D_ECC\" )
				( netClassRef "@sapphirecity_baseboard_lib.sapphirecity_baseboard(sch_1):\DDR4_CHN_D_ECC\" )
			)
			( regionClassClass "@crescent_city_bb_fab1_lib.crescent_city_bb_fab1(sch_1):\RCC109\"
				( spacingCSetRef "@crescent_city_bb_fab1_lib.crescent_city_bb_fab1(sch_1):\5MIL_US_&_4MIL_SL\" )
				( regionRef "@crescent_city_bb_fab1_lib.crescent_city_bb_fab1(sch_1):\DDR_ESCAPE\" )
				( netClassRef "@sapphirecity_baseboard_lib.sapphirecity_baseboard(sch_1):\DDR4_CHN_E_DQ_DQS_BYTE0\" )
				( netClassRef "@sapphirecity_baseboard_lib.sapphirecity_baseboard(sch_1):\DDR4_CHN_E_DQ_DQS_BYTE0\" )
			)
			( regionClassClass "@crescent_city_bb_fab1_lib.crescent_city_bb_fab1(sch_1):\RCC110\"
				( spacingCSetRef "@crescent_city_bb_fab1_lib.crescent_city_bb_fab1(sch_1):\5MIL_US_&_4MIL_SL\" )
				( regionRef "@crescent_city_bb_fab1_lib.crescent_city_bb_fab1(sch_1):\DDR_ESCAPE\" )
				( netClassRef "@sapphirecity_baseboard_lib.sapphirecity_baseboard(sch_1):\DDR4_CHN_E_DQ_DQS_BYTE1\" )
				( netClassRef "@sapphirecity_baseboard_lib.sapphirecity_baseboard(sch_1):\DDR4_CHN_E_DQ_DQS_BYTE1\" )
			)
			( regionClassClass "@crescent_city_bb_fab1_lib.crescent_city_bb_fab1(sch_1):\RCC111\"
				( spacingCSetRef "@crescent_city_bb_fab1_lib.crescent_city_bb_fab1(sch_1):\5MIL_US_&_4MIL_SL\" )
				( regionRef "@crescent_city_bb_fab1_lib.crescent_city_bb_fab1(sch_1):\DDR_ESCAPE\" )
				( netClassRef "@sapphirecity_baseboard_lib.sapphirecity_baseboard(sch_1):\DDR4_CHN_E_DQ_DQS_BYTE2\" )
				( netClassRef "@sapphirecity_baseboard_lib.sapphirecity_baseboard(sch_1):\DDR4_CHN_E_DQ_DQS_BYTE2\" )
			)
			( regionClassClass "@crescent_city_bb_fab1_lib.crescent_city_bb_fab1(sch_1):\RCC112\"
				( spacingCSetRef "@crescent_city_bb_fab1_lib.crescent_city_bb_fab1(sch_1):\5MIL_US_&_4MIL_SL\" )
				( regionRef "@crescent_city_bb_fab1_lib.crescent_city_bb_fab1(sch_1):\DDR_ESCAPE\" )
				( netClassRef "@sapphirecity_baseboard_lib.sapphirecity_baseboard(sch_1):\DDR4_CHN_E_DQ_DQS_BYTE3\" )
				( netClassRef "@sapphirecity_baseboard_lib.sapphirecity_baseboard(sch_1):\DDR4_CHN_E_DQ_DQS_BYTE3\" )
			)
			( regionClassClass "@crescent_city_bb_fab1_lib.crescent_city_bb_fab1(sch_1):\RCC113\"
				( spacingCSetRef "@crescent_city_bb_fab1_lib.crescent_city_bb_fab1(sch_1):\5MIL_US_&_4MIL_SL\" )
				( regionRef "@crescent_city_bb_fab1_lib.crescent_city_bb_fab1(sch_1):\DDR_ESCAPE\" )
				( netClassRef "@sapphirecity_baseboard_lib.sapphirecity_baseboard(sch_1):\DDR4_CHN_E_DQ_DQS_BYTE4\" )
				( netClassRef "@sapphirecity_baseboard_lib.sapphirecity_baseboard(sch_1):\DDR4_CHN_E_DQ_DQS_BYTE4\" )
			)
			( regionClassClass "@crescent_city_bb_fab1_lib.crescent_city_bb_fab1(sch_1):\RCC114\"
				( spacingCSetRef "@crescent_city_bb_fab1_lib.crescent_city_bb_fab1(sch_1):\5MIL_US_&_4MIL_SL\" )
				( regionRef "@crescent_city_bb_fab1_lib.crescent_city_bb_fab1(sch_1):\DDR_ESCAPE\" )
				( netClassRef "@sapphirecity_baseboard_lib.sapphirecity_baseboard(sch_1):\DDR4_CHN_E_DQ_DQS_BYTE5\" )
				( netClassRef "@sapphirecity_baseboard_lib.sapphirecity_baseboard(sch_1):\DDR4_CHN_E_DQ_DQS_BYTE5\" )
			)
			( regionClassClass "@crescent_city_bb_fab1_lib.crescent_city_bb_fab1(sch_1):\RCC115\"
				( spacingCSetRef "@crescent_city_bb_fab1_lib.crescent_city_bb_fab1(sch_1):\5MIL_US_&_4MIL_SL\" )
				( regionRef "@crescent_city_bb_fab1_lib.crescent_city_bb_fab1(sch_1):\DDR_ESCAPE\" )
				( netClassRef "@sapphirecity_baseboard_lib.sapphirecity_baseboard(sch_1):\DDR4_CHN_E_DQ_DQS_BYTE6\" )
				( netClassRef "@sapphirecity_baseboard_lib.sapphirecity_baseboard(sch_1):\DDR4_CHN_E_DQ_DQS_BYTE6\" )
			)
			( regionClassClass "@crescent_city_bb_fab1_lib.crescent_city_bb_fab1(sch_1):\RCC116\"
				( spacingCSetRef "@crescent_city_bb_fab1_lib.crescent_city_bb_fab1(sch_1):\5MIL_US_&_4MIL_SL\" )
				( regionRef "@crescent_city_bb_fab1_lib.crescent_city_bb_fab1(sch_1):\DDR_ESCAPE\" )
				( netClassRef "@sapphirecity_baseboard_lib.sapphirecity_baseboard(sch_1):\DDR4_CHN_E_DQ_DQS_BYTE7\" )
				( netClassRef "@sapphirecity_baseboard_lib.sapphirecity_baseboard(sch_1):\DDR4_CHN_E_DQ_DQS_BYTE7\" )
			)
			( regionClassClass "@crescent_city_bb_fab1_lib.crescent_city_bb_fab1(sch_1):\RCC117\"
				( spacingCSetRef "@crescent_city_bb_fab1_lib.crescent_city_bb_fab1(sch_1):\5MIL_US_&_4MIL_SL\" )
				( regionRef "@crescent_city_bb_fab1_lib.crescent_city_bb_fab1(sch_1):\DDR_ESCAPE\" )
				( netClassRef "@sapphirecity_baseboard_lib.sapphirecity_baseboard(sch_1):\DDR4_CHN_E_ECC\" )
				( netClassRef "@sapphirecity_baseboard_lib.sapphirecity_baseboard(sch_1):\DDR4_CHN_E_ECC\" )
			)
			( regionClassClass "@crescent_city_bb_fab1_lib.crescent_city_bb_fab1(sch_1):\RCC118\"
				( spacingCSetRef "@crescent_city_bb_fab1_lib.crescent_city_bb_fab1(sch_1):\5MIL_US_&_4MIL_SL\" )
				( regionRef "@crescent_city_bb_fab1_lib.crescent_city_bb_fab1(sch_1):\DDR_ESCAPE\" )
				( netClassRef "@sapphirecity_baseboard_lib.sapphirecity_baseboard(sch_1):\DDR4_CHN_F_DQ_DQS_BYTE0\" )
				( netClassRef "@sapphirecity_baseboard_lib.sapphirecity_baseboard(sch_1):\DDR4_CHN_F_DQ_DQS_BYTE0\" )
			)
			( regionClassClass "@crescent_city_bb_fab1_lib.crescent_city_bb_fab1(sch_1):\RCC119\"
				( spacingCSetRef "@crescent_city_bb_fab1_lib.crescent_city_bb_fab1(sch_1):\5MIL_US_&_4MIL_SL\" )
				( regionRef "@crescent_city_bb_fab1_lib.crescent_city_bb_fab1(sch_1):\DDR_ESCAPE\" )
				( netClassRef "@sapphirecity_baseboard_lib.sapphirecity_baseboard(sch_1):\DDR4_CHN_F_DQ_DQS_BYTE1\" )
				( netClassRef "@sapphirecity_baseboard_lib.sapphirecity_baseboard(sch_1):\DDR4_CHN_F_DQ_DQS_BYTE1\" )
			)
			( regionClassClass "@crescent_city_bb_fab1_lib.crescent_city_bb_fab1(sch_1):\RCC120\"
				( spacingCSetRef "@crescent_city_bb_fab1_lib.crescent_city_bb_fab1(sch_1):\5MIL_US_&_4MIL_SL\" )
				( regionRef "@crescent_city_bb_fab1_lib.crescent_city_bb_fab1(sch_1):\DDR_ESCAPE\" )
				( netClassRef "@sapphirecity_baseboard_lib.sapphirecity_baseboard(sch_1):\DDR4_CHN_F_DQ_DQS_BYTE2\" )
				( netClassRef "@sapphirecity_baseboard_lib.sapphirecity_baseboard(sch_1):\DDR4_CHN_F_DQ_DQS_BYTE2\" )
			)
			( regionClassClass "@crescent_city_bb_fab1_lib.crescent_city_bb_fab1(sch_1):\RCC121\"
				( spacingCSetRef "@crescent_city_bb_fab1_lib.crescent_city_bb_fab1(sch_1):\5MIL_US_&_4MIL_SL\" )
				( regionRef "@crescent_city_bb_fab1_lib.crescent_city_bb_fab1(sch_1):\DDR_ESCAPE\" )
				( netClassRef "@sapphirecity_baseboard_lib.sapphirecity_baseboard(sch_1):\DDR4_CHN_F_DQ_DQS_BYTE3\" )
				( netClassRef "@sapphirecity_baseboard_lib.sapphirecity_baseboard(sch_1):\DDR4_CHN_F_DQ_DQS_BYTE3\" )
			)
			( regionClassClass "@crescent_city_bb_fab1_lib.crescent_city_bb_fab1(sch_1):\RCC122\"
				( spacingCSetRef "@crescent_city_bb_fab1_lib.crescent_city_bb_fab1(sch_1):\5MIL_US_&_4MIL_SL\" )
				( regionRef "@crescent_city_bb_fab1_lib.crescent_city_bb_fab1(sch_1):\DDR_ESCAPE\" )
				( netClassRef "@sapphirecity_baseboard_lib.sapphirecity_baseboard(sch_1):\DDR4_CHN_F_DQ_DQS_BYTE4\" )
				( netClassRef "@sapphirecity_baseboard_lib.sapphirecity_baseboard(sch_1):\DDR4_CHN_F_DQ_DQS_BYTE4\" )
			)
			( regionClassClass "@crescent_city_bb_fab1_lib.crescent_city_bb_fab1(sch_1):\RCC123\"
				( spacingCSetRef "@crescent_city_bb_fab1_lib.crescent_city_bb_fab1(sch_1):\5MIL_US_&_4MIL_SL\" )
				( regionRef "@crescent_city_bb_fab1_lib.crescent_city_bb_fab1(sch_1):\DDR_ESCAPE\" )
				( netClassRef "@sapphirecity_baseboard_lib.sapphirecity_baseboard(sch_1):\DDR4_CHN_F_DQ_DQS_BYTE5\" )
				( netClassRef "@sapphirecity_baseboard_lib.sapphirecity_baseboard(sch_1):\DDR4_CHN_F_DQ_DQS_BYTE5\" )
			)
			( regionClassClass "@crescent_city_bb_fab1_lib.crescent_city_bb_fab1(sch_1):\RCC124\"
				( spacingCSetRef "@crescent_city_bb_fab1_lib.crescent_city_bb_fab1(sch_1):\5MIL_US_&_4MIL_SL\" )
				( regionRef "@crescent_city_bb_fab1_lib.crescent_city_bb_fab1(sch_1):\DDR_ESCAPE\" )
				( netClassRef "@sapphirecity_baseboard_lib.sapphirecity_baseboard(sch_1):\DDR4_CHN_F_DQ_DQS_BYTE6\" )
				( netClassRef "@sapphirecity_baseboard_lib.sapphirecity_baseboard(sch_1):\DDR4_CHN_F_DQ_DQS_BYTE6\" )
			)
			( regionClassClass "@crescent_city_bb_fab1_lib.crescent_city_bb_fab1(sch_1):\RCC125\"
				( spacingCSetRef "@crescent_city_bb_fab1_lib.crescent_city_bb_fab1(sch_1):\5MIL_US_&_4MIL_SL\" )
				( regionRef "@crescent_city_bb_fab1_lib.crescent_city_bb_fab1(sch_1):\DDR_ESCAPE\" )
				( netClassRef "@sapphirecity_baseboard_lib.sapphirecity_baseboard(sch_1):\DDR4_CHN_F_DQ_DQS_BYTE7\" )
				( netClassRef "@sapphirecity_baseboard_lib.sapphirecity_baseboard(sch_1):\DDR4_CHN_F_DQ_DQS_BYTE7\" )
			)
			( regionClassClass "@crescent_city_bb_fab1_lib.crescent_city_bb_fab1(sch_1):\RCC126\"
				( spacingCSetRef "@crescent_city_bb_fab1_lib.crescent_city_bb_fab1(sch_1):\5MIL_US_&_4MIL_SL\" )
				( regionRef "@crescent_city_bb_fab1_lib.crescent_city_bb_fab1(sch_1):\DDR_ESCAPE\" )
				( netClassRef "@sapphirecity_baseboard_lib.sapphirecity_baseboard(sch_1):\DDR4_CHN_F_ECC\" )
				( netClassRef "@sapphirecity_baseboard_lib.sapphirecity_baseboard(sch_1):\DDR4_CHN_F_ECC\" )
			)
			( regionClassClass "@crescent_city_bb_fab1_lib.crescent_city_bb_fab1(sch_1):\RCC127\"
				( spacingCSetRef "@crescent_city_bb_fab1_lib.crescent_city_bb_fab1(sch_1):\5MIL_US_&_4MIL_SL\" )
				( regionRef "@crescent_city_bb_fab1_lib.crescent_city_bb_fab1(sch_1):\DDR_ESCAPE\" )
				( netClassRef "@sapphirecity_baseboard_lib.sapphirecity_baseboard(sch_1):\DDR4_CHN_G_DQ_DQS_BYTE0\" )
				( netClassRef "@sapphirecity_baseboard_lib.sapphirecity_baseboard(sch_1):\DDR4_CHN_G_DQ_DQS_BYTE0\" )
			)
			( regionClassClass "@crescent_city_bb_fab1_lib.crescent_city_bb_fab1(sch_1):\RCC128\"
				( spacingCSetRef "@crescent_city_bb_fab1_lib.crescent_city_bb_fab1(sch_1):\5MIL_US_&_4MIL_SL\" )
				( regionRef "@crescent_city_bb_fab1_lib.crescent_city_bb_fab1(sch_1):\DDR_ESCAPE\" )
				( netClassRef "@sapphirecity_baseboard_lib.sapphirecity_baseboard(sch_1):\DDR4_CHN_G_DQ_DQS_BYTE1\" )
				( netClassRef "@sapphirecity_baseboard_lib.sapphirecity_baseboard(sch_1):\DDR4_CHN_G_DQ_DQS_BYTE1\" )
			)
			( regionClassClass "@crescent_city_bb_fab1_lib.crescent_city_bb_fab1(sch_1):\RCC129\"
				( spacingCSetRef "@crescent_city_bb_fab1_lib.crescent_city_bb_fab1(sch_1):\5MIL_US_&_4MIL_SL\" )
				( regionRef "@crescent_city_bb_fab1_lib.crescent_city_bb_fab1(sch_1):\DDR_ESCAPE\" )
				( netClassRef "@sapphirecity_baseboard_lib.sapphirecity_baseboard(sch_1):\DDR4_CHN_G_DQ_DQS_BYTE2\" )
				( netClassRef "@sapphirecity_baseboard_lib.sapphirecity_baseboard(sch_1):\DDR4_CHN_G_DQ_DQS_BYTE2\" )
			)
			( regionClassClass "@crescent_city_bb_fab1_lib.crescent_city_bb_fab1(sch_1):\RCC130\"
				( spacingCSetRef "@crescent_city_bb_fab1_lib.crescent_city_bb_fab1(sch_1):\5MIL_US_&_4MIL_SL\" )
				( regionRef "@crescent_city_bb_fab1_lib.crescent_city_bb_fab1(sch_1):\DDR_ESCAPE\" )
				( netClassRef "@sapphirecity_baseboard_lib.sapphirecity_baseboard(sch_1):\DDR4_CHN_G_DQ_DQS_BYTE3\" )
				( netClassRef "@sapphirecity_baseboard_lib.sapphirecity_baseboard(sch_1):\DDR4_CHN_G_DQ_DQS_BYTE3\" )
			)
			( regionClassClass "@crescent_city_bb_fab1_lib.crescent_city_bb_fab1(sch_1):\RCC131\"
				( spacingCSetRef "@crescent_city_bb_fab1_lib.crescent_city_bb_fab1(sch_1):\5MIL_US_&_4MIL_SL\" )
				( regionRef "@crescent_city_bb_fab1_lib.crescent_city_bb_fab1(sch_1):\DDR_ESCAPE\" )
				( netClassRef "@sapphirecity_baseboard_lib.sapphirecity_baseboard(sch_1):\DDR4_CHN_G_DQ_DQS_BYTE4\" )
				( netClassRef "@sapphirecity_baseboard_lib.sapphirecity_baseboard(sch_1):\DDR4_CHN_G_DQ_DQS_BYTE4\" )
			)
			( regionClassClass "@crescent_city_bb_fab1_lib.crescent_city_bb_fab1(sch_1):\RCC132\"
				( spacingCSetRef "@crescent_city_bb_fab1_lib.crescent_city_bb_fab1(sch_1):\5MIL_US_&_4MIL_SL\" )
				( regionRef "@crescent_city_bb_fab1_lib.crescent_city_bb_fab1(sch_1):\DDR_ESCAPE\" )
				( netClassRef "@sapphirecity_baseboard_lib.sapphirecity_baseboard(sch_1):\DDR4_CHN_G_DQ_DQS_BYTE5\" )
				( netClassRef "@sapphirecity_baseboard_lib.sapphirecity_baseboard(sch_1):\DDR4_CHN_G_DQ_DQS_BYTE5\" )
			)
			( regionClassClass "@crescent_city_bb_fab1_lib.crescent_city_bb_fab1(sch_1):\RCC133\"
				( spacingCSetRef "@crescent_city_bb_fab1_lib.crescent_city_bb_fab1(sch_1):\5MIL_US_&_4MIL_SL\" )
				( regionRef "@crescent_city_bb_fab1_lib.crescent_city_bb_fab1(sch_1):\DDR_ESCAPE\" )
				( netClassRef "@sapphirecity_baseboard_lib.sapphirecity_baseboard(sch_1):\DDR4_CHN_G_DQ_DQS_BYTE6\" )
				( netClassRef "@sapphirecity_baseboard_lib.sapphirecity_baseboard(sch_1):\DDR4_CHN_G_DQ_DQS_BYTE6\" )
			)
			( regionClassClass "@crescent_city_bb_fab1_lib.crescent_city_bb_fab1(sch_1):\RCC134\"
				( spacingCSetRef "@crescent_city_bb_fab1_lib.crescent_city_bb_fab1(sch_1):\5MIL_US_&_4MIL_SL\" )
				( regionRef "@crescent_city_bb_fab1_lib.crescent_city_bb_fab1(sch_1):\DDR_ESCAPE\" )
				( netClassRef "@sapphirecity_baseboard_lib.sapphirecity_baseboard(sch_1):\DDR4_CHN_G_DQ_DQS_BYTE7\" )
				( netClassRef "@sapphirecity_baseboard_lib.sapphirecity_baseboard(sch_1):\DDR4_CHN_G_DQ_DQS_BYTE7\" )
			)
			( regionClassClass "@crescent_city_bb_fab1_lib.crescent_city_bb_fab1(sch_1):\RCC135\"
				( spacingCSetRef "@crescent_city_bb_fab1_lib.crescent_city_bb_fab1(sch_1):\5MIL_US_&_4MIL_SL\" )
				( regionRef "@crescent_city_bb_fab1_lib.crescent_city_bb_fab1(sch_1):\DDR_ESCAPE\" )
				( netClassRef "@sapphirecity_baseboard_lib.sapphirecity_baseboard(sch_1):\DDR4_CHN_G_ECC\" )
				( netClassRef "@sapphirecity_baseboard_lib.sapphirecity_baseboard(sch_1):\DDR4_CHN_G_ECC\" )
			)
			( regionClassClass "@crescent_city_bb_fab1_lib.crescent_city_bb_fab1(sch_1):\RCC136\"
				( spacingCSetRef "@crescent_city_bb_fab1_lib.crescent_city_bb_fab1(sch_1):\5MIL_US_&_4MIL_SL\" )
				( regionRef "@crescent_city_bb_fab1_lib.crescent_city_bb_fab1(sch_1):\DDR_ESCAPE\" )
				( netClassRef "@sapphirecity_baseboard_lib.sapphirecity_baseboard(sch_1):\DDR4_CHN_H_DQ_DQS_BYTE0\" )
				( netClassRef "@sapphirecity_baseboard_lib.sapphirecity_baseboard(sch_1):\DDR4_CHN_H_DQ_DQS_BYTE0\" )
			)
			( regionClassClass "@crescent_city_bb_fab1_lib.crescent_city_bb_fab1(sch_1):\RCC137\"
				( spacingCSetRef "@crescent_city_bb_fab1_lib.crescent_city_bb_fab1(sch_1):\5MIL_US_&_4MIL_SL\" )
				( regionRef "@crescent_city_bb_fab1_lib.crescent_city_bb_fab1(sch_1):\DDR_ESCAPE\" )
				( netClassRef "@sapphirecity_baseboard_lib.sapphirecity_baseboard(sch_1):\DDR4_CHN_H_DQ_DQS_BYTE1\" )
				( netClassRef "@sapphirecity_baseboard_lib.sapphirecity_baseboard(sch_1):\DDR4_CHN_H_DQ_DQS_BYTE1\" )
			)
			( regionClassClass "@crescent_city_bb_fab1_lib.crescent_city_bb_fab1(sch_1):\RCC138\"
				( spacingCSetRef "@crescent_city_bb_fab1_lib.crescent_city_bb_fab1(sch_1):\5MIL_US_&_4MIL_SL\" )
				( regionRef "@crescent_city_bb_fab1_lib.crescent_city_bb_fab1(sch_1):\DDR_ESCAPE\" )
				( netClassRef "@sapphirecity_baseboard_lib.sapphirecity_baseboard(sch_1):\DDR4_CHN_H_DQ_DQS_BYTE2\" )
				( netClassRef "@sapphirecity_baseboard_lib.sapphirecity_baseboard(sch_1):\DDR4_CHN_H_DQ_DQS_BYTE2\" )
			)
			( regionClassClass "@crescent_city_bb_fab1_lib.crescent_city_bb_fab1(sch_1):\RCC139\"
				( spacingCSetRef "@crescent_city_bb_fab1_lib.crescent_city_bb_fab1(sch_1):\5MIL_US_&_4MIL_SL\" )
				( regionRef "@crescent_city_bb_fab1_lib.crescent_city_bb_fab1(sch_1):\DDR_ESCAPE\" )
				( netClassRef "@sapphirecity_baseboard_lib.sapphirecity_baseboard(sch_1):\DDR4_CHN_H_DQ_DQS_BYTE3\" )
				( netClassRef "@sapphirecity_baseboard_lib.sapphirecity_baseboard(sch_1):\DDR4_CHN_H_DQ_DQS_BYTE3\" )
			)
			( regionClassClass "@crescent_city_bb_fab1_lib.crescent_city_bb_fab1(sch_1):\RCC140\"
				( spacingCSetRef "@crescent_city_bb_fab1_lib.crescent_city_bb_fab1(sch_1):\5MIL_US_&_4MIL_SL\" )
				( regionRef "@crescent_city_bb_fab1_lib.crescent_city_bb_fab1(sch_1):\DDR_ESCAPE\" )
				( netClassRef "@sapphirecity_baseboard_lib.sapphirecity_baseboard(sch_1):\DDR4_CHN_H_DQ_DQS_BYTE4\" )
				( netClassRef "@sapphirecity_baseboard_lib.sapphirecity_baseboard(sch_1):\DDR4_CHN_H_DQ_DQS_BYTE4\" )
			)
			( regionClassClass "@crescent_city_bb_fab1_lib.crescent_city_bb_fab1(sch_1):\RCC141\"
				( spacingCSetRef "@crescent_city_bb_fab1_lib.crescent_city_bb_fab1(sch_1):\5MIL_US_&_4MIL_SL\" )
				( regionRef "@crescent_city_bb_fab1_lib.crescent_city_bb_fab1(sch_1):\DDR_ESCAPE\" )
				( netClassRef "@sapphirecity_baseboard_lib.sapphirecity_baseboard(sch_1):\DDR4_CHN_H_DQ_DQS_BYTE5\" )
				( netClassRef "@sapphirecity_baseboard_lib.sapphirecity_baseboard(sch_1):\DDR4_CHN_H_DQ_DQS_BYTE5\" )
			)
			( regionClassClass "@crescent_city_bb_fab1_lib.crescent_city_bb_fab1(sch_1):\RCC142\"
				( spacingCSetRef "@crescent_city_bb_fab1_lib.crescent_city_bb_fab1(sch_1):\5MIL_US_&_4MIL_SL\" )
				( regionRef "@crescent_city_bb_fab1_lib.crescent_city_bb_fab1(sch_1):\DDR_ESCAPE\" )
				( netClassRef "@sapphirecity_baseboard_lib.sapphirecity_baseboard(sch_1):\DDR4_CHN_H_DQ_DQS_BYTE6\" )
				( netClassRef "@sapphirecity_baseboard_lib.sapphirecity_baseboard(sch_1):\DDR4_CHN_H_DQ_DQS_BYTE6\" )
			)
			( regionClassClass "@crescent_city_bb_fab1_lib.crescent_city_bb_fab1(sch_1):\RCC143\"
				( spacingCSetRef "@crescent_city_bb_fab1_lib.crescent_city_bb_fab1(sch_1):\5MIL_US_&_4MIL_SL\" )
				( regionRef "@crescent_city_bb_fab1_lib.crescent_city_bb_fab1(sch_1):\DDR_ESCAPE\" )
				( netClassRef "@sapphirecity_baseboard_lib.sapphirecity_baseboard(sch_1):\DDR4_CHN_H_DQ_DQS_BYTE7\" )
				( netClassRef "@sapphirecity_baseboard_lib.sapphirecity_baseboard(sch_1):\DDR4_CHN_H_DQ_DQS_BYTE7\" )
			)
			( regionClassClass "@crescent_city_bb_fab1_lib.crescent_city_bb_fab1(sch_1):\RCC144\"
				( spacingCSetRef "@crescent_city_bb_fab1_lib.crescent_city_bb_fab1(sch_1):\5MIL_US_&_4MIL_SL\" )
				( regionRef "@crescent_city_bb_fab1_lib.crescent_city_bb_fab1(sch_1):\DDR_ESCAPE\" )
				( netClassRef "@sapphirecity_baseboard_lib.sapphirecity_baseboard(sch_1):\DDR4_CHN_H_ECC\" )
				( netClassRef "@sapphirecity_baseboard_lib.sapphirecity_baseboard(sch_1):\DDR4_CHN_H_ECC\" )
			)
			( regionClassClass "@crescent_city_bb_fab1_lib.crescent_city_bb_fab1(sch_1):\RCC107\"
				( spacingCSetRef "@crescent_city_bb_fab1_lib.crescent_city_bb_fab1(sch_1):\5MIL_US_&_4MIL_SL\" )
				( regionRef "@crescent_city_bb_fab1_lib.crescent_city_bb_fab1(sch_1):\DDR_ESCAPE\" )
				( netClassRef "@sapphirecity_baseboard_lib.sapphirecity_baseboard(sch_1):\DDR4_CHN_D_DQ_DQS_BYTE7\" )
				( netClassRef "@sapphirecity_baseboard_lib.sapphirecity_baseboard(sch_1):\DDR4_CHN_D_DQ_DQS_BYTE7\" )
			)
			( regionClassClass "@crescent_city_bb_fab1_lib.crescent_city_bb_fab1(sch_1):\RCC106\"
				( spacingCSetRef "@crescent_city_bb_fab1_lib.crescent_city_bb_fab1(sch_1):\5MIL_US_&_4MIL_SL\" )
				( regionRef "@crescent_city_bb_fab1_lib.crescent_city_bb_fab1(sch_1):\DDR_ESCAPE\" )
				( netClassRef "@sapphirecity_baseboard_lib.sapphirecity_baseboard(sch_1):\DDR4_CHN_D_DQ_DQS_BYTE6\" )
				( netClassRef "@sapphirecity_baseboard_lib.sapphirecity_baseboard(sch_1):\DDR4_CHN_D_DQ_DQS_BYTE6\" )
			)
			( regionClassClass "@crescent_city_bb_fab1_lib.crescent_city_bb_fab1(sch_1):\RCC104\"
				( spacingCSetRef "@crescent_city_bb_fab1_lib.crescent_city_bb_fab1(sch_1):\5MIL_US_&_4MIL_SL\" )
				( regionRef "@crescent_city_bb_fab1_lib.crescent_city_bb_fab1(sch_1):\DDR_ESCAPE\" )
				( netClassRef "@sapphirecity_baseboard_lib.sapphirecity_baseboard(sch_1):\DDR4_CHN_D_DQ_DQS_BYTE4\" )
				( netClassRef "@sapphirecity_baseboard_lib.sapphirecity_baseboard(sch_1):\DDR4_CHN_D_DQ_DQS_BYTE4\" )
			)
			( regionClassClass "@crescent_city_bb_fab1_lib.crescent_city_bb_fab1(sch_1):\RCC103\"
				( spacingCSetRef "@crescent_city_bb_fab1_lib.crescent_city_bb_fab1(sch_1):\5MIL_US_&_4MIL_SL\" )
				( regionRef "@crescent_city_bb_fab1_lib.crescent_city_bb_fab1(sch_1):\DDR_ESCAPE\" )
				( netClassRef "@sapphirecity_baseboard_lib.sapphirecity_baseboard(sch_1):\DDR4_CHN_D_DQ_DQS_BYTE3\" )
				( netClassRef "@sapphirecity_baseboard_lib.sapphirecity_baseboard(sch_1):\DDR4_CHN_D_DQ_DQS_BYTE3\" )
			)
			( regionClassClass "@crescent_city_bb_fab1_lib.crescent_city_bb_fab1(sch_1):\RCC102\"
				( spacingCSetRef "@crescent_city_bb_fab1_lib.crescent_city_bb_fab1(sch_1):\5MIL_US_&_4MIL_SL\" )
				( regionRef "@crescent_city_bb_fab1_lib.crescent_city_bb_fab1(sch_1):\DDR_ESCAPE\" )
				( netClassRef "@sapphirecity_baseboard_lib.sapphirecity_baseboard(sch_1):\DDR4_CHN_D_DQ_DQS_BYTE2\" )
				( netClassRef "@sapphirecity_baseboard_lib.sapphirecity_baseboard(sch_1):\DDR4_CHN_D_DQ_DQS_BYTE2\" )
			)
			( regionClassClass "@crescent_city_bb_fab1_lib.crescent_city_bb_fab1(sch_1):\RCC101\"
				( spacingCSetRef "@crescent_city_bb_fab1_lib.crescent_city_bb_fab1(sch_1):\5MIL_US_&_4MIL_SL\" )
				( regionRef "@crescent_city_bb_fab1_lib.crescent_city_bb_fab1(sch_1):\DDR_ESCAPE\" )
				( netClassRef "@sapphirecity_baseboard_lib.sapphirecity_baseboard(sch_1):\DDR4_CHN_D_DQ_DQS_BYTE1\" )
				( netClassRef "@sapphirecity_baseboard_lib.sapphirecity_baseboard(sch_1):\DDR4_CHN_D_DQ_DQS_BYTE1\" )
			)
			( regionClassClass "@crescent_city_bb_fab1_lib.crescent_city_bb_fab1(sch_1):\RCC76\"
				( spacingCSetRef "@crescent_city_bb_fab1_lib.crescent_city_bb_fab1(sch_1):\5MIL_US_&_4MIL_SL\" )
				( regionRef "@crescent_city_bb_fab1_lib.crescent_city_bb_fab1(sch_1):\DDR_ESCAPE\" )
				( netClassRef "@sapphirecity_baseboard_lib.sapphirecity_baseboard(sch_1):\DDR4_CHN_J_CLK\" )
				( netClassRef "@sapphirecity_baseboard_lib.sapphirecity_baseboard(sch_1):\DDR4_CHN_J_CLK\" )
			)
			( regionClassClass "@crescent_city_bb_fab1_lib.crescent_city_bb_fab1(sch_1):\RCC77\"
				( spacingCSetRef "@crescent_city_bb_fab1_lib.crescent_city_bb_fab1(sch_1):\5MIL_US_&_4MIL_SL\" )
				( regionRef "@crescent_city_bb_fab1_lib.crescent_city_bb_fab1(sch_1):\DDR_ESCAPE\" )
				( netClassRef "@sapphirecity_baseboard_lib.sapphirecity_baseboard(sch_1):\DDR4_CHN_J_CLK\" )
				( netClassRef "@sapphirecity_baseboard_lib.sapphirecity_baseboard(sch_1):\DDR4_CHN_J_CMD_ADD\" )
			)
			( regionClassClass "@crescent_city_bb_fab1_lib.crescent_city_bb_fab1(sch_1):\RCC78\"
				( spacingCSetRef "@crescent_city_bb_fab1_lib.crescent_city_bb_fab1(sch_1):\5MIL_US_&_4MIL_SL\" )
				( regionRef "@crescent_city_bb_fab1_lib.crescent_city_bb_fab1(sch_1):\DDR_ESCAPE\" )
				( netClassRef "@sapphirecity_baseboard_lib.sapphirecity_baseboard(sch_1):\DDR4_CHN_J_CLK\" )
				( netClassRef "@sapphirecity_baseboard_lib.sapphirecity_baseboard(sch_1):\DDR4_CHN_J_CTRL\" )
			)
			( regionClassClass "@crescent_city_bb_fab1_lib.crescent_city_bb_fab1(sch_1):\RCC82\"
				( spacingCSetRef "@crescent_city_bb_fab1_lib.crescent_city_bb_fab1(sch_1):\5MIL_US_&_4MIL_SL\" )
				( regionRef "@crescent_city_bb_fab1_lib.crescent_city_bb_fab1(sch_1):\DDR_ESCAPE\" )
				( netClassRef "@sapphirecity_baseboard_lib.sapphirecity_baseboard(sch_1):\DDR4_CHN_K_CLK\" )
				( netClassRef "@sapphirecity_baseboard_lib.sapphirecity_baseboard(sch_1):\DDR4_CHN_K_CLK\" )
			)
			( regionClassClass "@crescent_city_bb_fab1_lib.crescent_city_bb_fab1(sch_1):\RCC83\"
				( spacingCSetRef "@crescent_city_bb_fab1_lib.crescent_city_bb_fab1(sch_1):\5MIL_US_&_4MIL_SL\" )
				( regionRef "@crescent_city_bb_fab1_lib.crescent_city_bb_fab1(sch_1):\DDR_ESCAPE\" )
				( netClassRef "@sapphirecity_baseboard_lib.sapphirecity_baseboard(sch_1):\DDR4_CHN_K_CLK\" )
				( netClassRef "@sapphirecity_baseboard_lib.sapphirecity_baseboard(sch_1):\DDR4_CHN_K_CMD_ADD\" )
			)
			( regionClassClass "@crescent_city_bb_fab1_lib.crescent_city_bb_fab1(sch_1):\RCC84\"
				( spacingCSetRef "@crescent_city_bb_fab1_lib.crescent_city_bb_fab1(sch_1):\5MIL_US_&_4MIL_SL\" )
				( regionRef "@crescent_city_bb_fab1_lib.crescent_city_bb_fab1(sch_1):\DDR_ESCAPE\" )
				( netClassRef "@sapphirecity_baseboard_lib.sapphirecity_baseboard(sch_1):\DDR4_CHN_K_CLK\" )
				( netClassRef "@sapphirecity_baseboard_lib.sapphirecity_baseboard(sch_1):\DDR4_CHN_K_CTRL\" )
			)
			( regionClassClass "@crescent_city_bb_fab1_lib.crescent_city_bb_fab1(sch_1):\RCC88\"
				( spacingCSetRef "@crescent_city_bb_fab1_lib.crescent_city_bb_fab1(sch_1):\5MIL_US_&_4MIL_SL\" )
				( regionRef "@crescent_city_bb_fab1_lib.crescent_city_bb_fab1(sch_1):\DDR_ESCAPE\" )
				( netClassRef "@sapphirecity_baseboard_lib.sapphirecity_baseboard(sch_1):\DDR4_CHN_L_CLK\" )
				( netClassRef "@sapphirecity_baseboard_lib.sapphirecity_baseboard(sch_1):\DDR4_CHN_L_CLK\" )
			)
			( regionClassClass "@crescent_city_bb_fab1_lib.crescent_city_bb_fab1(sch_1):\RCC89\"
				( spacingCSetRef "@crescent_city_bb_fab1_lib.crescent_city_bb_fab1(sch_1):\5MIL_US_&_4MIL_SL\" )
				( regionRef "@crescent_city_bb_fab1_lib.crescent_city_bb_fab1(sch_1):\DDR_ESCAPE\" )
				( netClassRef "@sapphirecity_baseboard_lib.sapphirecity_baseboard(sch_1):\DDR4_CHN_L_CLK\" )
				( netClassRef "@sapphirecity_baseboard_lib.sapphirecity_baseboard(sch_1):\DDR4_CHN_L_CMD_ADD\" )
			)
			( regionClassClass "@crescent_city_bb_fab1_lib.crescent_city_bb_fab1(sch_1):\RCC90\"
				( spacingCSetRef "@crescent_city_bb_fab1_lib.crescent_city_bb_fab1(sch_1):\5MIL_US_&_4MIL_SL\" )
				( regionRef "@crescent_city_bb_fab1_lib.crescent_city_bb_fab1(sch_1):\DDR_ESCAPE\" )
				( netClassRef "@sapphirecity_baseboard_lib.sapphirecity_baseboard(sch_1):\DDR4_CHN_L_CLK\" )
				( netClassRef "@sapphirecity_baseboard_lib.sapphirecity_baseboard(sch_1):\DDR4_CHN_L_CTRL\" )
			)
			( regionClassClass "@crescent_city_bb_fab1_lib.crescent_city_bb_fab1(sch_1):\RCC94\"
				( spacingCSetRef "@crescent_city_bb_fab1_lib.crescent_city_bb_fab1(sch_1):\5MIL_US_&_4MIL_SL\" )
				( regionRef "@crescent_city_bb_fab1_lib.crescent_city_bb_fab1(sch_1):\DDR_ESCAPE\" )
				( netClassRef "@sapphirecity_baseboard_lib.sapphirecity_baseboard(sch_1):\DDR4_CHN_M_CLK\" )
				( netClassRef "@sapphirecity_baseboard_lib.sapphirecity_baseboard(sch_1):\DDR4_CHN_M_CLK\" )
			)
			( regionClassClass "@crescent_city_bb_fab1_lib.crescent_city_bb_fab1(sch_1):\RCC95\"
				( spacingCSetRef "@crescent_city_bb_fab1_lib.crescent_city_bb_fab1(sch_1):\5MIL_US_&_4MIL_SL\" )
				( regionRef "@crescent_city_bb_fab1_lib.crescent_city_bb_fab1(sch_1):\DDR_ESCAPE\" )
				( netClassRef "@sapphirecity_baseboard_lib.sapphirecity_baseboard(sch_1):\DDR4_CHN_M_CLK\" )
				( netClassRef "@sapphirecity_baseboard_lib.sapphirecity_baseboard(sch_1):\DDR4_CHN_M_CMD_ADD\" )
			)
			( regionClassClass "@crescent_city_bb_fab1_lib.crescent_city_bb_fab1(sch_1):\RCC96\"
				( spacingCSetRef "@crescent_city_bb_fab1_lib.crescent_city_bb_fab1(sch_1):\5MIL_US_&_4MIL_SL\" )
				( regionRef "@crescent_city_bb_fab1_lib.crescent_city_bb_fab1(sch_1):\DDR_ESCAPE\" )
				( netClassRef "@sapphirecity_baseboard_lib.sapphirecity_baseboard(sch_1):\DDR4_CHN_M_CLK\" )
				( netClassRef "@sapphirecity_baseboard_lib.sapphirecity_baseboard(sch_1):\DDR4_CHN_M_CTRL\" )
			)
			( regionClassClass "@crescent_city_bb_fab1_lib.crescent_city_bb_fab1(sch_1):\RCC79\"
				( spacingCSetRef "@crescent_city_bb_fab1_lib.crescent_city_bb_fab1(sch_1):\5MIL_US_&_4MIL_SL\" )
				( regionRef "@crescent_city_bb_fab1_lib.crescent_city_bb_fab1(sch_1):\DDR_ESCAPE\" )
				( netClassRef "@sapphirecity_baseboard_lib.sapphirecity_baseboard(sch_1):\DDR4_CHN_J_CMD_ADD\" )
				( netClassRef "@sapphirecity_baseboard_lib.sapphirecity_baseboard(sch_1):\DDR4_CHN_J_CMD_ADD\" )
			)
			( regionClassClass "@crescent_city_bb_fab1_lib.crescent_city_bb_fab1(sch_1):\RCC80\"
				( spacingCSetRef "@crescent_city_bb_fab1_lib.crescent_city_bb_fab1(sch_1):\5MIL_US_&_4MIL_SL\" )
				( regionRef "@crescent_city_bb_fab1_lib.crescent_city_bb_fab1(sch_1):\DDR_ESCAPE\" )
				( netClassRef "@sapphirecity_baseboard_lib.sapphirecity_baseboard(sch_1):\DDR4_CHN_J_CMD_ADD\" )
				( netClassRef "@sapphirecity_baseboard_lib.sapphirecity_baseboard(sch_1):\DDR4_CHN_J_CTRL\" )
			)
			( regionClassClass "@crescent_city_bb_fab1_lib.crescent_city_bb_fab1(sch_1):\RCC85\"
				( spacingCSetRef "@crescent_city_bb_fab1_lib.crescent_city_bb_fab1(sch_1):\5MIL_US_&_4MIL_SL\" )
				( regionRef "@crescent_city_bb_fab1_lib.crescent_city_bb_fab1(sch_1):\DDR_ESCAPE\" )
				( netClassRef "@sapphirecity_baseboard_lib.sapphirecity_baseboard(sch_1):\DDR4_CHN_K_CMD_ADD\" )
				( netClassRef "@sapphirecity_baseboard_lib.sapphirecity_baseboard(sch_1):\DDR4_CHN_K_CMD_ADD\" )
			)
			( regionClassClass "@crescent_city_bb_fab1_lib.crescent_city_bb_fab1(sch_1):\RCC86\"
				( spacingCSetRef "@crescent_city_bb_fab1_lib.crescent_city_bb_fab1(sch_1):\5MIL_US_&_4MIL_SL\" )
				( regionRef "@crescent_city_bb_fab1_lib.crescent_city_bb_fab1(sch_1):\DDR_ESCAPE\" )
				( netClassRef "@sapphirecity_baseboard_lib.sapphirecity_baseboard(sch_1):\DDR4_CHN_K_CMD_ADD\" )
				( netClassRef "@sapphirecity_baseboard_lib.sapphirecity_baseboard(sch_1):\DDR4_CHN_K_CTRL\" )
			)
			( regionClassClass "@crescent_city_bb_fab1_lib.crescent_city_bb_fab1(sch_1):\RCC91\"
				( spacingCSetRef "@crescent_city_bb_fab1_lib.crescent_city_bb_fab1(sch_1):\5MIL_US_&_4MIL_SL\" )
				( regionRef "@crescent_city_bb_fab1_lib.crescent_city_bb_fab1(sch_1):\DDR_ESCAPE\" )
				( netClassRef "@sapphirecity_baseboard_lib.sapphirecity_baseboard(sch_1):\DDR4_CHN_L_CMD_ADD\" )
				( netClassRef "@sapphirecity_baseboard_lib.sapphirecity_baseboard(sch_1):\DDR4_CHN_L_CMD_ADD\" )
			)
			( regionClassClass "@crescent_city_bb_fab1_lib.crescent_city_bb_fab1(sch_1):\RCC92\"
				( spacingCSetRef "@crescent_city_bb_fab1_lib.crescent_city_bb_fab1(sch_1):\5MIL_US_&_4MIL_SL\" )
				( regionRef "@crescent_city_bb_fab1_lib.crescent_city_bb_fab1(sch_1):\DDR_ESCAPE\" )
				( netClassRef "@sapphirecity_baseboard_lib.sapphirecity_baseboard(sch_1):\DDR4_CHN_L_CMD_ADD\" )
				( netClassRef "@sapphirecity_baseboard_lib.sapphirecity_baseboard(sch_1):\DDR4_CHN_L_CTRL\" )
			)
			( regionClassClass "@crescent_city_bb_fab1_lib.crescent_city_bb_fab1(sch_1):\RCC97\"
				( spacingCSetRef "@crescent_city_bb_fab1_lib.crescent_city_bb_fab1(sch_1):\5MIL_US_&_4MIL_SL\" )
				( regionRef "@crescent_city_bb_fab1_lib.crescent_city_bb_fab1(sch_1):\DDR_ESCAPE\" )
				( netClassRef "@sapphirecity_baseboard_lib.sapphirecity_baseboard(sch_1):\DDR4_CHN_M_CMD_ADD\" )
				( netClassRef "@sapphirecity_baseboard_lib.sapphirecity_baseboard(sch_1):\DDR4_CHN_M_CMD_ADD\" )
			)
			( regionClassClass "@crescent_city_bb_fab1_lib.crescent_city_bb_fab1(sch_1):\RCC98\"
				( spacingCSetRef "@crescent_city_bb_fab1_lib.crescent_city_bb_fab1(sch_1):\5MIL_US_&_4MIL_SL\" )
				( regionRef "@crescent_city_bb_fab1_lib.crescent_city_bb_fab1(sch_1):\DDR_ESCAPE\" )
				( netClassRef "@sapphirecity_baseboard_lib.sapphirecity_baseboard(sch_1):\DDR4_CHN_M_CMD_ADD\" )
				( netClassRef "@sapphirecity_baseboard_lib.sapphirecity_baseboard(sch_1):\DDR4_CHN_M_CTRL\" )
			)
			( regionClassClass "@crescent_city_bb_fab1_lib.crescent_city_bb_fab1(sch_1):\RCC81\"
				( spacingCSetRef "@crescent_city_bb_fab1_lib.crescent_city_bb_fab1(sch_1):\5MIL_US_&_4MIL_SL\" )
				( regionRef "@crescent_city_bb_fab1_lib.crescent_city_bb_fab1(sch_1):\DDR_ESCAPE\" )
				( netClassRef "@sapphirecity_baseboard_lib.sapphirecity_baseboard(sch_1):\DDR4_CHN_J_CTRL\" )
				( netClassRef "@sapphirecity_baseboard_lib.sapphirecity_baseboard(sch_1):\DDR4_CHN_J_CTRL\" )
			)
			( regionClassClass "@crescent_city_bb_fab1_lib.crescent_city_bb_fab1(sch_1):\RCC87\"
				( spacingCSetRef "@crescent_city_bb_fab1_lib.crescent_city_bb_fab1(sch_1):\5MIL_US_&_4MIL_SL\" )
				( regionRef "@crescent_city_bb_fab1_lib.crescent_city_bb_fab1(sch_1):\DDR_ESCAPE\" )
				( netClassRef "@sapphirecity_baseboard_lib.sapphirecity_baseboard(sch_1):\DDR4_CHN_K_CTRL\" )
				( netClassRef "@sapphirecity_baseboard_lib.sapphirecity_baseboard(sch_1):\DDR4_CHN_K_CTRL\" )
			)
			( regionClassClass "@crescent_city_bb_fab1_lib.crescent_city_bb_fab1(sch_1):\RCC93\"
				( spacingCSetRef "@crescent_city_bb_fab1_lib.crescent_city_bb_fab1(sch_1):\5MIL_US_&_4MIL_SL\" )
				( regionRef "@crescent_city_bb_fab1_lib.crescent_city_bb_fab1(sch_1):\DDR_ESCAPE\" )
				( netClassRef "@sapphirecity_baseboard_lib.sapphirecity_baseboard(sch_1):\DDR4_CHN_L_CTRL\" )
				( netClassRef "@sapphirecity_baseboard_lib.sapphirecity_baseboard(sch_1):\DDR4_CHN_L_CTRL\" )
			)
			( regionClassClass "@crescent_city_bb_fab1_lib.crescent_city_bb_fab1(sch_1):\RCC99\"
				( spacingCSetRef "@crescent_city_bb_fab1_lib.crescent_city_bb_fab1(sch_1):\5MIL_US_&_4MIL_SL\" )
				( regionRef "@crescent_city_bb_fab1_lib.crescent_city_bb_fab1(sch_1):\DDR_ESCAPE\" )
				( netClassRef "@sapphirecity_baseboard_lib.sapphirecity_baseboard(sch_1):\DDR4_CHN_M_CTRL\" )
				( netClassRef "@sapphirecity_baseboard_lib.sapphirecity_baseboard(sch_1):\DDR4_CHN_M_CTRL\" )
			)
			( regionClassClass "@sapphirecity_baseboard_lib.sapphirecity_baseboard(sch_1):\RCC1\"
				( attribute "LINE_TO_LINE_SPACING" "8.00"
					( Origin gBackEnd )
				)
				( regionRef "@sapphirecity_baseboard_lib.sapphirecity_baseboard(sch_1):\CPU_BRKT\" )
				( netClassRef "@sapphirecity_baseboard_lib.sapphirecity_baseboard(sch_1):\DDR4_CHN_A_CLK\" )
				( netClassRef "@sapphirecity_baseboard_lib.sapphirecity_baseboard(sch_1):\DDR4_CHN_A_ECC\" )
			)
			( regionClassClass "@sapphirecity_baseboard_lib.sapphirecity_baseboard(sch_1):\RCC2\"
				( attribute "LINE_TO_LINE_SPACING" "8.00"
					( Origin gBackEnd )
				)
				( regionRef "@sapphirecity_baseboard_lib.sapphirecity_baseboard(sch_1):\CPU_BRKT\" )
				( netClassRef "@sapphirecity_baseboard_lib.sapphirecity_baseboard(sch_1):\DDR4_CHN_A_CLK\" )
				( netClassRef "@sapphirecity_baseboard_lib.sapphirecity_baseboard(sch_1):\DDR4_CHN_A_DQ_DQS_BYTE7\" )
			)
			( regionClassClass "@sapphirecity_baseboard_lib.sapphirecity_baseboard(sch_1):\RCC3\"
				( attribute "LINE_TO_LINE_SPACING" "8.00"
					( Origin gBackEnd )
				)
				( regionRef "@sapphirecity_baseboard_lib.sapphirecity_baseboard(sch_1):\CPU_BRKT\" )
				( netClassRef "@sapphirecity_baseboard_lib.sapphirecity_baseboard(sch_1):\DDR4_CHN_A_CLK\" )
				( netClassRef "@sapphirecity_baseboard_lib.sapphirecity_baseboard(sch_1):\DDR4_CHN_A_DQ_DQS_BYTE6\" )
			)
			( regionClassClass "@sapphirecity_baseboard_lib.sapphirecity_baseboard(sch_1):\RCC4\"
				( attribute "LINE_TO_LINE_SPACING" "8.00"
					( Origin gBackEnd )
				)
				( regionRef "@sapphirecity_baseboard_lib.sapphirecity_baseboard(sch_1):\CPU_BRKT\" )
				( netClassRef "@sapphirecity_baseboard_lib.sapphirecity_baseboard(sch_1):\DDR4_CHN_A_CLK\" )
				( netClassRef "@sapphirecity_baseboard_lib.sapphirecity_baseboard(sch_1):\DDR4_CHN_A_DQ_DQS_BYTE5\" )
			)
			( regionClassClass "@sapphirecity_baseboard_lib.sapphirecity_baseboard(sch_1):\RCC5\"
				( attribute "LINE_TO_LINE_SPACING" "8.00"
					( Origin gBackEnd )
				)
				( regionRef "@sapphirecity_baseboard_lib.sapphirecity_baseboard(sch_1):\CPU_BRKT\" )
				( netClassRef "@sapphirecity_baseboard_lib.sapphirecity_baseboard(sch_1):\DDR4_CHN_A_CLK\" )
				( netClassRef "@sapphirecity_baseboard_lib.sapphirecity_baseboard(sch_1):\DDR4_CHN_A_DQ_DQS_BYTE4\" )
			)
			( regionClassClass "@sapphirecity_baseboard_lib.sapphirecity_baseboard(sch_1):\RCC6\"
				( attribute "LINE_TO_LINE_SPACING" "8.00"
					( Origin gBackEnd )
				)
				( regionRef "@sapphirecity_baseboard_lib.sapphirecity_baseboard(sch_1):\CPU_BRKT\" )
				( netClassRef "@sapphirecity_baseboard_lib.sapphirecity_baseboard(sch_1):\DDR4_CHN_A_CLK\" )
				( netClassRef "@sapphirecity_baseboard_lib.sapphirecity_baseboard(sch_1):\DDR4_CHN_A_DQ_DQS_BYTE3\" )
			)
			( regionClassClass "@sapphirecity_baseboard_lib.sapphirecity_baseboard(sch_1):\RCC7\"
				( attribute "LINE_TO_LINE_SPACING" "8.00"
					( Origin gBackEnd )
				)
				( regionRef "@sapphirecity_baseboard_lib.sapphirecity_baseboard(sch_1):\CPU_BRKT\" )
				( netClassRef "@sapphirecity_baseboard_lib.sapphirecity_baseboard(sch_1):\DDR4_CHN_A_CLK\" )
				( netClassRef "@sapphirecity_baseboard_lib.sapphirecity_baseboard(sch_1):\DDR4_CHN_A_DQ_DQS_BYTE2\" )
			)
			( regionClassClass "@sapphirecity_baseboard_lib.sapphirecity_baseboard(sch_1):\RCC8\"
				( attribute "LINE_TO_LINE_SPACING" "8.00"
					( Origin gBackEnd )
				)
				( regionRef "@sapphirecity_baseboard_lib.sapphirecity_baseboard(sch_1):\CPU_BRKT\" )
				( netClassRef "@sapphirecity_baseboard_lib.sapphirecity_baseboard(sch_1):\DDR4_CHN_A_CLK\" )
				( netClassRef "@sapphirecity_baseboard_lib.sapphirecity_baseboard(sch_1):\DDR4_CHN_A_DQ_DQS_BYTE1\" )
			)
			( regionClassClass "@sapphirecity_baseboard_lib.sapphirecity_baseboard(sch_1):\RCC9\"
				( attribute "LINE_TO_LINE_SPACING" "8.00"
					( Origin gBackEnd )
				)
				( regionRef "@sapphirecity_baseboard_lib.sapphirecity_baseboard(sch_1):\CPU_BRKT\" )
				( netClassRef "@sapphirecity_baseboard_lib.sapphirecity_baseboard(sch_1):\DDR4_CHN_A_CLK\" )
				( netClassRef "@sapphirecity_baseboard_lib.sapphirecity_baseboard(sch_1):\DDR4_CHN_A_DQ_DQS_BYTE0\" )
			)
			( regionClassClass "@sapphirecity_baseboard_lib.sapphirecity_baseboard(sch_1):\RCC10\"
				( attribute "LINE_TO_LINE_SPACING" "8.00"
					( Origin gBackEnd )
				)
				( regionRef "@sapphirecity_baseboard_lib.sapphirecity_baseboard(sch_1):\CPU_BRKT\" )
				( netClassRef "@sapphirecity_baseboard_lib.sapphirecity_baseboard(sch_1):\DDR4_CHN_A_CLK\" )
				( netClassRef "@sapphirecity_baseboard_lib.sapphirecity_baseboard(sch_1):\DDR4_CHN_A_CTRL\" )
			)
			( regionClassClass "@sapphirecity_baseboard_lib.sapphirecity_baseboard(sch_1):\RCC11\"
				( attribute "LINE_TO_LINE_SPACING" "8.00"
					( Origin gBackEnd )
				)
				( regionRef "@sapphirecity_baseboard_lib.sapphirecity_baseboard(sch_1):\CPU_BRKT\" )
				( netClassRef "@sapphirecity_baseboard_lib.sapphirecity_baseboard(sch_1):\DDR4_CHN_A_CLK\" )
				( netClassRef "@sapphirecity_baseboard_lib.sapphirecity_baseboard(sch_1):\DDR4_CHN_A_CMD_ADD\" )
			)
			( regionClassClass "@sapphirecity_baseboard_lib.sapphirecity_baseboard(sch_1):\RCC12\"
				( attribute "LINE_TO_LINE_SPACING" "8.00"
					( Origin gBackEnd )
				)
				( regionRef "@sapphirecity_baseboard_lib.sapphirecity_baseboard(sch_1):\CPU_BRKT\" )
				( netClassRef "@sapphirecity_baseboard_lib.sapphirecity_baseboard(sch_1):\DDR4_CHN_A_CLK\" )
				( netClassRef "@sapphirecity_baseboard_lib.sapphirecity_baseboard(sch_1):\DDR4_CHN_A_CLK\" )
			)
			( regionClassClass "@sapphirecity_baseboard_lib.sapphirecity_baseboard(sch_1):\RCC13\"
				( attribute "LINE_TO_LINE_SPACING" "8.00"
					( Origin gBackEnd )
				)
				( regionRef "@sapphirecity_baseboard_lib.sapphirecity_baseboard(sch_1):\CPU_BRKT\" )
				( netClassRef "@sapphirecity_baseboard_lib.sapphirecity_baseboard(sch_1):\DDR4_CHN_A_CMD_ADD\" )
				( netClassRef "@sapphirecity_baseboard_lib.sapphirecity_baseboard(sch_1):\DDR4_CHN_A_ECC\" )
			)
			( regionClassClass "@sapphirecity_baseboard_lib.sapphirecity_baseboard(sch_1):\RCC14\"
				( attribute "LINE_TO_LINE_SPACING" "8.00"
					( Origin gBackEnd )
				)
				( regionRef "@sapphirecity_baseboard_lib.sapphirecity_baseboard(sch_1):\CPU_BRKT\" )
				( netClassRef "@sapphirecity_baseboard_lib.sapphirecity_baseboard(sch_1):\DDR4_CHN_A_CMD_ADD\" )
				( netClassRef "@sapphirecity_baseboard_lib.sapphirecity_baseboard(sch_1):\DDR4_CHN_A_DQ_DQS_BYTE7\" )
			)
			( regionClassClass "@sapphirecity_baseboard_lib.sapphirecity_baseboard(sch_1):\RCC15\"
				( attribute "LINE_TO_LINE_SPACING" "8.00"
					( Origin gBackEnd )
				)
				( regionRef "@sapphirecity_baseboard_lib.sapphirecity_baseboard(sch_1):\CPU_BRKT\" )
				( netClassRef "@sapphirecity_baseboard_lib.sapphirecity_baseboard(sch_1):\DDR4_CHN_A_CMD_ADD\" )
				( netClassRef "@sapphirecity_baseboard_lib.sapphirecity_baseboard(sch_1):\DDR4_CHN_A_DQ_DQS_BYTE6\" )
			)
			( regionClassClass "@sapphirecity_baseboard_lib.sapphirecity_baseboard(sch_1):\RCC16\"
				( attribute "LINE_TO_LINE_SPACING" "8.00"
					( Origin gBackEnd )
				)
				( regionRef "@sapphirecity_baseboard_lib.sapphirecity_baseboard(sch_1):\CPU_BRKT\" )
				( netClassRef "@sapphirecity_baseboard_lib.sapphirecity_baseboard(sch_1):\DDR4_CHN_A_CMD_ADD\" )
				( netClassRef "@sapphirecity_baseboard_lib.sapphirecity_baseboard(sch_1):\DDR4_CHN_A_DQ_DQS_BYTE5\" )
			)
			( regionClassClass "@sapphirecity_baseboard_lib.sapphirecity_baseboard(sch_1):\RCC17\"
				( attribute "LINE_TO_LINE_SPACING" "8.00"
					( Origin gBackEnd )
				)
				( regionRef "@sapphirecity_baseboard_lib.sapphirecity_baseboard(sch_1):\CPU_BRKT\" )
				( netClassRef "@sapphirecity_baseboard_lib.sapphirecity_baseboard(sch_1):\DDR4_CHN_A_CMD_ADD\" )
				( netClassRef "@sapphirecity_baseboard_lib.sapphirecity_baseboard(sch_1):\DDR4_CHN_A_DQ_DQS_BYTE4\" )
			)
			( regionClassClass "@sapphirecity_baseboard_lib.sapphirecity_baseboard(sch_1):\RCC18\"
				( attribute "LINE_TO_LINE_SPACING" "8.00"
					( Origin gBackEnd )
				)
				( regionRef "@sapphirecity_baseboard_lib.sapphirecity_baseboard(sch_1):\CPU_BRKT\" )
				( netClassRef "@sapphirecity_baseboard_lib.sapphirecity_baseboard(sch_1):\DDR4_CHN_A_CMD_ADD\" )
				( netClassRef "@sapphirecity_baseboard_lib.sapphirecity_baseboard(sch_1):\DDR4_CHN_A_DQ_DQS_BYTE3\" )
			)
			( regionClassClass "@sapphirecity_baseboard_lib.sapphirecity_baseboard(sch_1):\RCC19\"
				( attribute "LINE_TO_LINE_SPACING" "8.00"
					( Origin gBackEnd )
				)
				( regionRef "@sapphirecity_baseboard_lib.sapphirecity_baseboard(sch_1):\CPU_BRKT\" )
				( netClassRef "@sapphirecity_baseboard_lib.sapphirecity_baseboard(sch_1):\DDR4_CHN_A_CMD_ADD\" )
				( netClassRef "@sapphirecity_baseboard_lib.sapphirecity_baseboard(sch_1):\DDR4_CHN_A_DQ_DQS_BYTE2\" )
			)
			( regionClassClass "@sapphirecity_baseboard_lib.sapphirecity_baseboard(sch_1):\RCC20\"
				( attribute "LINE_TO_LINE_SPACING" "8.00"
					( Origin gBackEnd )
				)
				( regionRef "@sapphirecity_baseboard_lib.sapphirecity_baseboard(sch_1):\CPU_BRKT\" )
				( netClassRef "@sapphirecity_baseboard_lib.sapphirecity_baseboard(sch_1):\DDR4_CHN_A_CMD_ADD\" )
				( netClassRef "@sapphirecity_baseboard_lib.sapphirecity_baseboard(sch_1):\DDR4_CHN_A_DQ_DQS_BYTE1\" )
			)
			( regionClassClass "@sapphirecity_baseboard_lib.sapphirecity_baseboard(sch_1):\RCC21\"
				( attribute "LINE_TO_LINE_SPACING" "8.00"
					( Origin gBackEnd )
				)
				( regionRef "@sapphirecity_baseboard_lib.sapphirecity_baseboard(sch_1):\CPU_BRKT\" )
				( netClassRef "@sapphirecity_baseboard_lib.sapphirecity_baseboard(sch_1):\DDR4_CHN_A_CMD_ADD\" )
				( netClassRef "@sapphirecity_baseboard_lib.sapphirecity_baseboard(sch_1):\DDR4_CHN_A_DQ_DQS_BYTE0\" )
			)
			( regionClassClass "@sapphirecity_baseboard_lib.sapphirecity_baseboard(sch_1):\RCC22\"
				( attribute "LINE_TO_LINE_SPACING" "8.00"
					( Origin gBackEnd )
				)
				( regionRef "@sapphirecity_baseboard_lib.sapphirecity_baseboard(sch_1):\CPU_BRKT\" )
				( netClassRef "@sapphirecity_baseboard_lib.sapphirecity_baseboard(sch_1):\DDR4_CHN_A_CMD_ADD\" )
				( netClassRef "@sapphirecity_baseboard_lib.sapphirecity_baseboard(sch_1):\DDR4_CHN_A_CTRL\" )
			)
			( regionClassClass "@sapphirecity_baseboard_lib.sapphirecity_baseboard(sch_1):\RCC23\"
				( attribute "LINE_TO_LINE_SPACING" "8.00"
					( Origin gBackEnd )
				)
				( regionRef "@sapphirecity_baseboard_lib.sapphirecity_baseboard(sch_1):\CPU_BRKT\" )
				( netClassRef "@sapphirecity_baseboard_lib.sapphirecity_baseboard(sch_1):\DDR4_CHN_A_CMD_ADD\" )
				( netClassRef "@sapphirecity_baseboard_lib.sapphirecity_baseboard(sch_1):\DDR4_CHN_A_CMD_ADD\" )
			)
			( regionClassClass "@sapphirecity_baseboard_lib.sapphirecity_baseboard(sch_1):\RCC24\"
				( attribute "LINE_TO_LINE_SPACING" "8.00"
					( Origin gBackEnd )
				)
				( regionRef "@sapphirecity_baseboard_lib.sapphirecity_baseboard(sch_1):\CPU_BRKT\" )
				( netClassRef "@sapphirecity_baseboard_lib.sapphirecity_baseboard(sch_1):\DDR4_CHN_A_CTRL\" )
				( netClassRef "@sapphirecity_baseboard_lib.sapphirecity_baseboard(sch_1):\DDR4_CHN_A_ECC\" )
			)
			( regionClassClass "@sapphirecity_baseboard_lib.sapphirecity_baseboard(sch_1):\RCC25\"
				( attribute "LINE_TO_LINE_SPACING" "8.00"
					( Origin gBackEnd )
				)
				( regionRef "@sapphirecity_baseboard_lib.sapphirecity_baseboard(sch_1):\CPU_BRKT\" )
				( netClassRef "@sapphirecity_baseboard_lib.sapphirecity_baseboard(sch_1):\DDR4_CHN_A_CTRL\" )
				( netClassRef "@sapphirecity_baseboard_lib.sapphirecity_baseboard(sch_1):\DDR4_CHN_A_DQ_DQS_BYTE7\" )
			)
			( regionClassClass "@sapphirecity_baseboard_lib.sapphirecity_baseboard(sch_1):\RCC26\"
				( attribute "LINE_TO_LINE_SPACING" "8.00"
					( Origin gBackEnd )
				)
				( regionRef "@sapphirecity_baseboard_lib.sapphirecity_baseboard(sch_1):\CPU_BRKT\" )
				( netClassRef "@sapphirecity_baseboard_lib.sapphirecity_baseboard(sch_1):\DDR4_CHN_A_CTRL\" )
				( netClassRef "@sapphirecity_baseboard_lib.sapphirecity_baseboard(sch_1):\DDR4_CHN_A_DQ_DQS_BYTE6\" )
			)
			( regionClassClass "@sapphirecity_baseboard_lib.sapphirecity_baseboard(sch_1):\RCC27\"
				( attribute "LINE_TO_LINE_SPACING" "8.00"
					( Origin gBackEnd )
				)
				( regionRef "@sapphirecity_baseboard_lib.sapphirecity_baseboard(sch_1):\CPU_BRKT\" )
				( netClassRef "@sapphirecity_baseboard_lib.sapphirecity_baseboard(sch_1):\DDR4_CHN_A_CTRL\" )
				( netClassRef "@sapphirecity_baseboard_lib.sapphirecity_baseboard(sch_1):\DDR4_CHN_A_DQ_DQS_BYTE5\" )
			)
			( regionClassClass "@sapphirecity_baseboard_lib.sapphirecity_baseboard(sch_1):\RCC28\"
				( attribute "LINE_TO_LINE_SPACING" "8.00"
					( Origin gBackEnd )
				)
				( regionRef "@sapphirecity_baseboard_lib.sapphirecity_baseboard(sch_1):\CPU_BRKT\" )
				( netClassRef "@sapphirecity_baseboard_lib.sapphirecity_baseboard(sch_1):\DDR4_CHN_A_CTRL\" )
				( netClassRef "@sapphirecity_baseboard_lib.sapphirecity_baseboard(sch_1):\DDR4_CHN_A_DQ_DQS_BYTE4\" )
			)
			( regionClassClass "@sapphirecity_baseboard_lib.sapphirecity_baseboard(sch_1):\RCC29\"
				( attribute "LINE_TO_LINE_SPACING" "8.00"
					( Origin gBackEnd )
				)
				( regionRef "@sapphirecity_baseboard_lib.sapphirecity_baseboard(sch_1):\CPU_BRKT\" )
				( netClassRef "@sapphirecity_baseboard_lib.sapphirecity_baseboard(sch_1):\DDR4_CHN_A_CTRL\" )
				( netClassRef "@sapphirecity_baseboard_lib.sapphirecity_baseboard(sch_1):\DDR4_CHN_A_DQ_DQS_BYTE3\" )
			)
			( regionClassClass "@sapphirecity_baseboard_lib.sapphirecity_baseboard(sch_1):\RCC30\"
				( attribute "LINE_TO_LINE_SPACING" "8.00"
					( Origin gBackEnd )
				)
				( regionRef "@sapphirecity_baseboard_lib.sapphirecity_baseboard(sch_1):\CPU_BRKT\" )
				( netClassRef "@sapphirecity_baseboard_lib.sapphirecity_baseboard(sch_1):\DDR4_CHN_A_CTRL\" )
				( netClassRef "@sapphirecity_baseboard_lib.sapphirecity_baseboard(sch_1):\DDR4_CHN_A_DQ_DQS_BYTE2\" )
			)
			( regionClassClass "@sapphirecity_baseboard_lib.sapphirecity_baseboard(sch_1):\RCC31\"
				( attribute "LINE_TO_LINE_SPACING" "8.00"
					( Origin gBackEnd )
				)
				( regionRef "@sapphirecity_baseboard_lib.sapphirecity_baseboard(sch_1):\CPU_BRKT\" )
				( netClassRef "@sapphirecity_baseboard_lib.sapphirecity_baseboard(sch_1):\DDR4_CHN_A_CTRL\" )
				( netClassRef "@sapphirecity_baseboard_lib.sapphirecity_baseboard(sch_1):\DDR4_CHN_A_DQ_DQS_BYTE1\" )
			)
			( regionClassClass "@sapphirecity_baseboard_lib.sapphirecity_baseboard(sch_1):\RCC32\"
				( attribute "LINE_TO_LINE_SPACING" "8.00"
					( Origin gBackEnd )
				)
				( regionRef "@sapphirecity_baseboard_lib.sapphirecity_baseboard(sch_1):\CPU_BRKT\" )
				( netClassRef "@sapphirecity_baseboard_lib.sapphirecity_baseboard(sch_1):\DDR4_CHN_A_CTRL\" )
				( netClassRef "@sapphirecity_baseboard_lib.sapphirecity_baseboard(sch_1):\DDR4_CHN_A_DQ_DQS_BYTE0\" )
			)
			( regionClassClass "@sapphirecity_baseboard_lib.sapphirecity_baseboard(sch_1):\RCC33\"
				( attribute "LINE_TO_LINE_SPACING" "8.00"
					( Origin gBackEnd )
				)
				( regionRef "@sapphirecity_baseboard_lib.sapphirecity_baseboard(sch_1):\CPU_BRKT\" )
				( netClassRef "@sapphirecity_baseboard_lib.sapphirecity_baseboard(sch_1):\DDR4_CHN_A_CTRL\" )
				( netClassRef "@sapphirecity_baseboard_lib.sapphirecity_baseboard(sch_1):\DDR4_CHN_A_CTRL\" )
			)
			( regionClassClass "@sapphirecity_baseboard_lib.sapphirecity_baseboard(sch_1):\RCC34\"
				( attribute "LINE_TO_LINE_SPACING" "8.00"
					( Origin gBackEnd )
				)
				( regionRef "@sapphirecity_baseboard_lib.sapphirecity_baseboard(sch_1):\CPU_BRKT\" )
				( netClassRef "@sapphirecity_baseboard_lib.sapphirecity_baseboard(sch_1):\DDR4_CHN_A_ECC\" )
				( netClassRef "@sapphirecity_baseboard_lib.sapphirecity_baseboard(sch_1):\DDR4_CHN_A_ECC\" )
			)
			( regionClassClass "@sapphirecity_baseboard_lib.sapphirecity_baseboard(sch_1):\RCC35\"
				( attribute "LINE_TO_LINE_SPACING" "8.00"
					( Origin gBackEnd )
				)
				( regionRef "@sapphirecity_baseboard_lib.sapphirecity_baseboard(sch_1):\CPU_BRKT\" )
				( netClassRef "@sapphirecity_baseboard_lib.sapphirecity_baseboard(sch_1):\DDR4_CHN_A_DQ_DQS_BYTE7\" )
				( netClassRef "@sapphirecity_baseboard_lib.sapphirecity_baseboard(sch_1):\DDR4_CHN_A_ECC\" )
			)
			( regionClassClass "@sapphirecity_baseboard_lib.sapphirecity_baseboard(sch_1):\RCC36\"
				( attribute "LINE_TO_LINE_SPACING" "8.00"
					( Origin gBackEnd )
				)
				( regionRef "@sapphirecity_baseboard_lib.sapphirecity_baseboard(sch_1):\CPU_BRKT\" )
				( netClassRef "@sapphirecity_baseboard_lib.sapphirecity_baseboard(sch_1):\DDR4_CHN_A_DQ_DQS_BYTE6\" )
				( netClassRef "@sapphirecity_baseboard_lib.sapphirecity_baseboard(sch_1):\DDR4_CHN_A_ECC\" )
			)
			( regionClassClass "@sapphirecity_baseboard_lib.sapphirecity_baseboard(sch_1):\RCC37\"
				( attribute "LINE_TO_LINE_SPACING" "8.00"
					( Origin gBackEnd )
				)
				( regionRef "@sapphirecity_baseboard_lib.sapphirecity_baseboard(sch_1):\CPU_BRKT\" )
				( netClassRef "@sapphirecity_baseboard_lib.sapphirecity_baseboard(sch_1):\DDR4_CHN_A_DQ_DQS_BYTE5\" )
				( netClassRef "@sapphirecity_baseboard_lib.sapphirecity_baseboard(sch_1):\DDR4_CHN_A_ECC\" )
			)
			( regionClassClass "@sapphirecity_baseboard_lib.sapphirecity_baseboard(sch_1):\RCC38\"
				( attribute "LINE_TO_LINE_SPACING" "8.00"
					( Origin gBackEnd )
				)
				( regionRef "@sapphirecity_baseboard_lib.sapphirecity_baseboard(sch_1):\CPU_BRKT\" )
				( netClassRef "@sapphirecity_baseboard_lib.sapphirecity_baseboard(sch_1):\DDR4_CHN_A_DQ_DQS_BYTE4\" )
				( netClassRef "@sapphirecity_baseboard_lib.sapphirecity_baseboard(sch_1):\DDR4_CHN_A_ECC\" )
			)
			( regionClassClass "@sapphirecity_baseboard_lib.sapphirecity_baseboard(sch_1):\RCC39\"
				( attribute "LINE_TO_LINE_SPACING" "8.00"
					( Origin gBackEnd )
				)
				( regionRef "@sapphirecity_baseboard_lib.sapphirecity_baseboard(sch_1):\CPU_BRKT\" )
				( netClassRef "@sapphirecity_baseboard_lib.sapphirecity_baseboard(sch_1):\DDR4_CHN_A_DQ_DQS_BYTE3\" )
				( netClassRef "@sapphirecity_baseboard_lib.sapphirecity_baseboard(sch_1):\DDR4_CHN_A_ECC\" )
			)
			( regionClassClass "@sapphirecity_baseboard_lib.sapphirecity_baseboard(sch_1):\RCC40\"
				( attribute "LINE_TO_LINE_SPACING" "8.00"
					( Origin gBackEnd )
				)
				( regionRef "@sapphirecity_baseboard_lib.sapphirecity_baseboard(sch_1):\CPU_BRKT\" )
				( netClassRef "@sapphirecity_baseboard_lib.sapphirecity_baseboard(sch_1):\DDR4_CHN_A_DQ_DQS_BYTE2\" )
				( netClassRef "@sapphirecity_baseboard_lib.sapphirecity_baseboard(sch_1):\DDR4_CHN_A_ECC\" )
			)
			( regionClassClass "@sapphirecity_baseboard_lib.sapphirecity_baseboard(sch_1):\RCC41\"
				( attribute "LINE_TO_LINE_SPACING" "8.00"
					( Origin gBackEnd )
				)
				( regionRef "@sapphirecity_baseboard_lib.sapphirecity_baseboard(sch_1):\CPU_BRKT\" )
				( netClassRef "@sapphirecity_baseboard_lib.sapphirecity_baseboard(sch_1):\DDR4_CHN_A_DQ_DQS_BYTE1\" )
				( netClassRef "@sapphirecity_baseboard_lib.sapphirecity_baseboard(sch_1):\DDR4_CHN_A_ECC\" )
			)
			( regionClassClass "@sapphirecity_baseboard_lib.sapphirecity_baseboard(sch_1):\RCC42\"
				( attribute "LINE_TO_LINE_SPACING" "8.00"
					( Origin gBackEnd )
				)
				( regionRef "@sapphirecity_baseboard_lib.sapphirecity_baseboard(sch_1):\CPU_BRKT\" )
				( netClassRef "@sapphirecity_baseboard_lib.sapphirecity_baseboard(sch_1):\DDR4_CHN_A_DQ_DQS_BYTE0\" )
				( netClassRef "@sapphirecity_baseboard_lib.sapphirecity_baseboard(sch_1):\DDR4_CHN_A_ECC\" )
			)
			( regionClassClass "@sapphirecity_baseboard_lib.sapphirecity_baseboard(sch_1):\RCC43\"
				( attribute "LINE_TO_LINE_SPACING" "8.00"
					( Origin gBackEnd )
				)
				( regionRef "@sapphirecity_baseboard_lib.sapphirecity_baseboard(sch_1):\CPU_BRKT\" )
				( netClassRef "@sapphirecity_baseboard_lib.sapphirecity_baseboard(sch_1):\DDR4_CHN_B_CLK\" )
				( netClassRef "@sapphirecity_baseboard_lib.sapphirecity_baseboard(sch_1):\DDR4_CHN_B_ECC\" )
			)
			( regionClassClass "@sapphirecity_baseboard_lib.sapphirecity_baseboard(sch_1):\RCC44\"
				( attribute "LINE_TO_LINE_SPACING" "8.00"
					( Origin gBackEnd )
				)
				( regionRef "@sapphirecity_baseboard_lib.sapphirecity_baseboard(sch_1):\CPU_BRKT\" )
				( netClassRef "@sapphirecity_baseboard_lib.sapphirecity_baseboard(sch_1):\DDR4_CHN_B_CLK\" )
				( netClassRef "@sapphirecity_baseboard_lib.sapphirecity_baseboard(sch_1):\DDR4_CHN_B_DQ_DQS_BYTE7\" )
			)
			( regionClassClass "@sapphirecity_baseboard_lib.sapphirecity_baseboard(sch_1):\RCC45\"
				( attribute "LINE_TO_LINE_SPACING" "8.00"
					( Origin gBackEnd )
				)
				( regionRef "@sapphirecity_baseboard_lib.sapphirecity_baseboard(sch_1):\CPU_BRKT\" )
				( netClassRef "@sapphirecity_baseboard_lib.sapphirecity_baseboard(sch_1):\DDR4_CHN_B_CLK\" )
				( netClassRef "@sapphirecity_baseboard_lib.sapphirecity_baseboard(sch_1):\DDR4_CHN_B_DQ_DQS_BYTE6\" )
			)
			( regionClassClass "@sapphirecity_baseboard_lib.sapphirecity_baseboard(sch_1):\RCC46\"
				( attribute "LINE_TO_LINE_SPACING" "8.00"
					( Origin gBackEnd )
				)
				( regionRef "@sapphirecity_baseboard_lib.sapphirecity_baseboard(sch_1):\CPU_BRKT\" )
				( netClassRef "@sapphirecity_baseboard_lib.sapphirecity_baseboard(sch_1):\DDR4_CHN_B_CLK\" )
				( netClassRef "@sapphirecity_baseboard_lib.sapphirecity_baseboard(sch_1):\DDR4_CHN_B_DQ_DQS_BYTE5\" )
			)
			( regionClassClass "@sapphirecity_baseboard_lib.sapphirecity_baseboard(sch_1):\RCC47\"
				( attribute "LINE_TO_LINE_SPACING" "8.00"
					( Origin gBackEnd )
				)
				( regionRef "@sapphirecity_baseboard_lib.sapphirecity_baseboard(sch_1):\CPU_BRKT\" )
				( netClassRef "@sapphirecity_baseboard_lib.sapphirecity_baseboard(sch_1):\DDR4_CHN_B_CLK\" )
				( netClassRef "@sapphirecity_baseboard_lib.sapphirecity_baseboard(sch_1):\DDR4_CHN_B_DQ_DQS_BYTE4\" )
			)
			( regionClassClass "@sapphirecity_baseboard_lib.sapphirecity_baseboard(sch_1):\RCC48\"
				( attribute "LINE_TO_LINE_SPACING" "8.00"
					( Origin gBackEnd )
				)
				( regionRef "@sapphirecity_baseboard_lib.sapphirecity_baseboard(sch_1):\CPU_BRKT\" )
				( netClassRef "@sapphirecity_baseboard_lib.sapphirecity_baseboard(sch_1):\DDR4_CHN_B_CLK\" )
				( netClassRef "@sapphirecity_baseboard_lib.sapphirecity_baseboard(sch_1):\DDR4_CHN_B_DQ_DQS_BYTE3\" )
			)
			( regionClassClass "@sapphirecity_baseboard_lib.sapphirecity_baseboard(sch_1):\RCC49\"
				( attribute "LINE_TO_LINE_SPACING" "8.00"
					( Origin gBackEnd )
				)
				( regionRef "@sapphirecity_baseboard_lib.sapphirecity_baseboard(sch_1):\CPU_BRKT\" )
				( netClassRef "@sapphirecity_baseboard_lib.sapphirecity_baseboard(sch_1):\DDR4_CHN_B_CLK\" )
				( netClassRef "@sapphirecity_baseboard_lib.sapphirecity_baseboard(sch_1):\DDR4_CHN_B_DQ_DQS_BYTE2\" )
			)
			( regionClassClass "@sapphirecity_baseboard_lib.sapphirecity_baseboard(sch_1):\RCC50\"
				( attribute "LINE_TO_LINE_SPACING" "8.00"
					( Origin gBackEnd )
				)
				( regionRef "@sapphirecity_baseboard_lib.sapphirecity_baseboard(sch_1):\CPU_BRKT\" )
				( netClassRef "@sapphirecity_baseboard_lib.sapphirecity_baseboard(sch_1):\DDR4_CHN_B_CLK\" )
				( netClassRef "@sapphirecity_baseboard_lib.sapphirecity_baseboard(sch_1):\DDR4_CHN_B_DQ_DQS_BYTE1\" )
			)
			( regionClassClass "@sapphirecity_baseboard_lib.sapphirecity_baseboard(sch_1):\RCC51\"
				( attribute "LINE_TO_LINE_SPACING" "8.00"
					( Origin gBackEnd )
				)
				( regionRef "@sapphirecity_baseboard_lib.sapphirecity_baseboard(sch_1):\CPU_BRKT\" )
				( netClassRef "@sapphirecity_baseboard_lib.sapphirecity_baseboard(sch_1):\DDR4_CHN_B_CLK\" )
				( netClassRef "@sapphirecity_baseboard_lib.sapphirecity_baseboard(sch_1):\DDR4_CHN_B_DQ_DQS_BYTE0\" )
			)
			( regionClassClass "@sapphirecity_baseboard_lib.sapphirecity_baseboard(sch_1):\RCC52\"
				( attribute "LINE_TO_LINE_SPACING" "8.00"
					( Origin gBackEnd )
				)
				( regionRef "@sapphirecity_baseboard_lib.sapphirecity_baseboard(sch_1):\CPU_BRKT\" )
				( netClassRef "@sapphirecity_baseboard_lib.sapphirecity_baseboard(sch_1):\DDR4_CHN_B_CLK\" )
				( netClassRef "@sapphirecity_baseboard_lib.sapphirecity_baseboard(sch_1):\DDR4_CHN_B_CTRL\" )
			)
			( regionClassClass "@sapphirecity_baseboard_lib.sapphirecity_baseboard(sch_1):\RCC53\"
				( attribute "LINE_TO_LINE_SPACING" "8.00"
					( Origin gBackEnd )
				)
				( regionRef "@sapphirecity_baseboard_lib.sapphirecity_baseboard(sch_1):\CPU_BRKT\" )
				( netClassRef "@sapphirecity_baseboard_lib.sapphirecity_baseboard(sch_1):\DDR4_CHN_B_CLK\" )
				( netClassRef "@sapphirecity_baseboard_lib.sapphirecity_baseboard(sch_1):\DDR4_CHN_B_CMD_ADD\" )
			)
			( regionClassClass "@sapphirecity_baseboard_lib.sapphirecity_baseboard(sch_1):\RCC54\"
				( attribute "LINE_TO_LINE_SPACING" "8.00"
					( Origin gBackEnd )
				)
				( regionRef "@sapphirecity_baseboard_lib.sapphirecity_baseboard(sch_1):\CPU_BRKT\" )
				( netClassRef "@sapphirecity_baseboard_lib.sapphirecity_baseboard(sch_1):\DDR4_CHN_B_CLK\" )
				( netClassRef "@sapphirecity_baseboard_lib.sapphirecity_baseboard(sch_1):\DDR4_CHN_B_CLK\" )
			)
			( regionClassClass "@sapphirecity_baseboard_lib.sapphirecity_baseboard(sch_1):\RCC55\"
				( attribute "LINE_TO_LINE_SPACING" "8.00"
					( Origin gBackEnd )
				)
				( regionRef "@sapphirecity_baseboard_lib.sapphirecity_baseboard(sch_1):\CPU_BRKT\" )
				( netClassRef "@sapphirecity_baseboard_lib.sapphirecity_baseboard(sch_1):\DDR4_CHN_B_CMD_ADD\" )
				( netClassRef "@sapphirecity_baseboard_lib.sapphirecity_baseboard(sch_1):\DDR4_CHN_B_ECC\" )
			)
			( regionClassClass "@sapphirecity_baseboard_lib.sapphirecity_baseboard(sch_1):\RCC56\"
				( attribute "LINE_TO_LINE_SPACING" "8.00"
					( Origin gBackEnd )
				)
				( regionRef "@sapphirecity_baseboard_lib.sapphirecity_baseboard(sch_1):\CPU_BRKT\" )
				( netClassRef "@sapphirecity_baseboard_lib.sapphirecity_baseboard(sch_1):\DDR4_CHN_B_CMD_ADD\" )
				( netClassRef "@sapphirecity_baseboard_lib.sapphirecity_baseboard(sch_1):\DDR4_CHN_B_DQ_DQS_BYTE7\" )
			)
			( regionClassClass "@sapphirecity_baseboard_lib.sapphirecity_baseboard(sch_1):\RCC57\"
				( attribute "LINE_TO_LINE_SPACING" "8.00"
					( Origin gBackEnd )
				)
				( regionRef "@sapphirecity_baseboard_lib.sapphirecity_baseboard(sch_1):\CPU_BRKT\" )
				( netClassRef "@sapphirecity_baseboard_lib.sapphirecity_baseboard(sch_1):\DDR4_CHN_B_CMD_ADD\" )
				( netClassRef "@sapphirecity_baseboard_lib.sapphirecity_baseboard(sch_1):\DDR4_CHN_B_DQ_DQS_BYTE6\" )
			)
			( regionClassClass "@sapphirecity_baseboard_lib.sapphirecity_baseboard(sch_1):\RCC58\"
				( attribute "LINE_TO_LINE_SPACING" "8.00"
					( Origin gBackEnd )
				)
				( regionRef "@sapphirecity_baseboard_lib.sapphirecity_baseboard(sch_1):\CPU_BRKT\" )
				( netClassRef "@sapphirecity_baseboard_lib.sapphirecity_baseboard(sch_1):\DDR4_CHN_B_CMD_ADD\" )
				( netClassRef "@sapphirecity_baseboard_lib.sapphirecity_baseboard(sch_1):\DDR4_CHN_B_DQ_DQS_BYTE5\" )
			)
			( regionClassClass "@sapphirecity_baseboard_lib.sapphirecity_baseboard(sch_1):\RCC59\"
				( attribute "LINE_TO_LINE_SPACING" "8.00"
					( Origin gBackEnd )
				)
				( regionRef "@sapphirecity_baseboard_lib.sapphirecity_baseboard(sch_1):\CPU_BRKT\" )
				( netClassRef "@sapphirecity_baseboard_lib.sapphirecity_baseboard(sch_1):\DDR4_CHN_B_CMD_ADD\" )
				( netClassRef "@sapphirecity_baseboard_lib.sapphirecity_baseboard(sch_1):\DDR4_CHN_B_DQ_DQS_BYTE4\" )
			)
			( regionClassClass "@sapphirecity_baseboard_lib.sapphirecity_baseboard(sch_1):\RCC60\"
				( attribute "LINE_TO_LINE_SPACING" "8.00"
					( Origin gBackEnd )
				)
				( regionRef "@sapphirecity_baseboard_lib.sapphirecity_baseboard(sch_1):\CPU_BRKT\" )
				( netClassRef "@sapphirecity_baseboard_lib.sapphirecity_baseboard(sch_1):\DDR4_CHN_B_CMD_ADD\" )
				( netClassRef "@sapphirecity_baseboard_lib.sapphirecity_baseboard(sch_1):\DDR4_CHN_B_DQ_DQS_BYTE3\" )
			)
			( regionClassClass "@sapphirecity_baseboard_lib.sapphirecity_baseboard(sch_1):\RCC61\"
				( attribute "LINE_TO_LINE_SPACING" "8.00"
					( Origin gBackEnd )
				)
				( regionRef "@sapphirecity_baseboard_lib.sapphirecity_baseboard(sch_1):\CPU_BRKT\" )
				( netClassRef "@sapphirecity_baseboard_lib.sapphirecity_baseboard(sch_1):\DDR4_CHN_B_CMD_ADD\" )
				( netClassRef "@sapphirecity_baseboard_lib.sapphirecity_baseboard(sch_1):\DDR4_CHN_B_DQ_DQS_BYTE2\" )
			)
			( regionClassClass "@sapphirecity_baseboard_lib.sapphirecity_baseboard(sch_1):\RCC62\"
				( attribute "LINE_TO_LINE_SPACING" "8.00"
					( Origin gBackEnd )
				)
				( regionRef "@sapphirecity_baseboard_lib.sapphirecity_baseboard(sch_1):\CPU_BRKT\" )
				( netClassRef "@sapphirecity_baseboard_lib.sapphirecity_baseboard(sch_1):\DDR4_CHN_B_CMD_ADD\" )
				( netClassRef "@sapphirecity_baseboard_lib.sapphirecity_baseboard(sch_1):\DDR4_CHN_B_DQ_DQS_BYTE1\" )
			)
			( regionClassClass "@sapphirecity_baseboard_lib.sapphirecity_baseboard(sch_1):\RCC63\"
				( attribute "LINE_TO_LINE_SPACING" "8.00"
					( Origin gBackEnd )
				)
				( regionRef "@sapphirecity_baseboard_lib.sapphirecity_baseboard(sch_1):\CPU_BRKT\" )
				( netClassRef "@sapphirecity_baseboard_lib.sapphirecity_baseboard(sch_1):\DDR4_CHN_B_CMD_ADD\" )
				( netClassRef "@sapphirecity_baseboard_lib.sapphirecity_baseboard(sch_1):\DDR4_CHN_B_DQ_DQS_BYTE0\" )
			)
			( regionClassClass "@sapphirecity_baseboard_lib.sapphirecity_baseboard(sch_1):\RCC64\"
				( attribute "LINE_TO_LINE_SPACING" "8.00"
					( Origin gBackEnd )
				)
				( regionRef "@sapphirecity_baseboard_lib.sapphirecity_baseboard(sch_1):\CPU_BRKT\" )
				( netClassRef "@sapphirecity_baseboard_lib.sapphirecity_baseboard(sch_1):\DDR4_CHN_B_CMD_ADD\" )
				( netClassRef "@sapphirecity_baseboard_lib.sapphirecity_baseboard(sch_1):\DDR4_CHN_B_CTRL\" )
			)
			( regionClassClass "@sapphirecity_baseboard_lib.sapphirecity_baseboard(sch_1):\RCC65\"
				( attribute "LINE_TO_LINE_SPACING" "8.00"
					( Origin gBackEnd )
				)
				( regionRef "@sapphirecity_baseboard_lib.sapphirecity_baseboard(sch_1):\CPU_BRKT\" )
				( netClassRef "@sapphirecity_baseboard_lib.sapphirecity_baseboard(sch_1):\DDR4_CHN_B_CMD_ADD\" )
				( netClassRef "@sapphirecity_baseboard_lib.sapphirecity_baseboard(sch_1):\DDR4_CHN_B_CMD_ADD\" )
			)
			( regionClassClass "@sapphirecity_baseboard_lib.sapphirecity_baseboard(sch_1):\RCC66\"
				( attribute "LINE_TO_LINE_SPACING" "8.00"
					( Origin gBackEnd )
				)
				( regionRef "@sapphirecity_baseboard_lib.sapphirecity_baseboard(sch_1):\CPU_BRKT\" )
				( netClassRef "@sapphirecity_baseboard_lib.sapphirecity_baseboard(sch_1):\DDR4_CHN_B_CTRL\" )
				( netClassRef "@sapphirecity_baseboard_lib.sapphirecity_baseboard(sch_1):\DDR4_CHN_B_ECC\" )
			)
			( regionClassClass "@sapphirecity_baseboard_lib.sapphirecity_baseboard(sch_1):\RCC67\"
				( attribute "LINE_TO_LINE_SPACING" "8.00"
					( Origin gBackEnd )
				)
				( regionRef "@sapphirecity_baseboard_lib.sapphirecity_baseboard(sch_1):\CPU_BRKT\" )
				( netClassRef "@sapphirecity_baseboard_lib.sapphirecity_baseboard(sch_1):\DDR4_CHN_B_CTRL\" )
				( netClassRef "@sapphirecity_baseboard_lib.sapphirecity_baseboard(sch_1):\DDR4_CHN_B_DQ_DQS_BYTE7\" )
			)
			( regionClassClass "@sapphirecity_baseboard_lib.sapphirecity_baseboard(sch_1):\RCC68\"
				( attribute "LINE_TO_LINE_SPACING" "8.00"
					( Origin gBackEnd )
				)
				( regionRef "@sapphirecity_baseboard_lib.sapphirecity_baseboard(sch_1):\CPU_BRKT\" )
				( netClassRef "@sapphirecity_baseboard_lib.sapphirecity_baseboard(sch_1):\DDR4_CHN_B_CTRL\" )
				( netClassRef "@sapphirecity_baseboard_lib.sapphirecity_baseboard(sch_1):\DDR4_CHN_B_DQ_DQS_BYTE6\" )
			)
			( regionClassClass "@sapphirecity_baseboard_lib.sapphirecity_baseboard(sch_1):\RCC69\"
				( attribute "LINE_TO_LINE_SPACING" "8.00"
					( Origin gBackEnd )
				)
				( regionRef "@sapphirecity_baseboard_lib.sapphirecity_baseboard(sch_1):\CPU_BRKT\" )
				( netClassRef "@sapphirecity_baseboard_lib.sapphirecity_baseboard(sch_1):\DDR4_CHN_B_CTRL\" )
				( netClassRef "@sapphirecity_baseboard_lib.sapphirecity_baseboard(sch_1):\DDR4_CHN_B_DQ_DQS_BYTE5\" )
			)
			( regionClassClass "@sapphirecity_baseboard_lib.sapphirecity_baseboard(sch_1):\RCC70\"
				( attribute "LINE_TO_LINE_SPACING" "8.00"
					( Origin gBackEnd )
				)
				( regionRef "@sapphirecity_baseboard_lib.sapphirecity_baseboard(sch_1):\CPU_BRKT\" )
				( netClassRef "@sapphirecity_baseboard_lib.sapphirecity_baseboard(sch_1):\DDR4_CHN_B_CTRL\" )
				( netClassRef "@sapphirecity_baseboard_lib.sapphirecity_baseboard(sch_1):\DDR4_CHN_B_DQ_DQS_BYTE4\" )
			)
			( regionClassClass "@sapphirecity_baseboard_lib.sapphirecity_baseboard(sch_1):\RCC71\"
				( attribute "LINE_TO_LINE_SPACING" "8.00"
					( Origin gBackEnd )
				)
				( regionRef "@sapphirecity_baseboard_lib.sapphirecity_baseboard(sch_1):\CPU_BRKT\" )
				( netClassRef "@sapphirecity_baseboard_lib.sapphirecity_baseboard(sch_1):\DDR4_CHN_B_CTRL\" )
				( netClassRef "@sapphirecity_baseboard_lib.sapphirecity_baseboard(sch_1):\DDR4_CHN_B_DQ_DQS_BYTE3\" )
			)
			( regionClassClass "@sapphirecity_baseboard_lib.sapphirecity_baseboard(sch_1):\RCC72\"
				( attribute "LINE_TO_LINE_SPACING" "8.00"
					( Origin gBackEnd )
				)
				( regionRef "@sapphirecity_baseboard_lib.sapphirecity_baseboard(sch_1):\CPU_BRKT\" )
				( netClassRef "@sapphirecity_baseboard_lib.sapphirecity_baseboard(sch_1):\DDR4_CHN_B_CTRL\" )
				( netClassRef "@sapphirecity_baseboard_lib.sapphirecity_baseboard(sch_1):\DDR4_CHN_B_DQ_DQS_BYTE2\" )
			)
			( regionClassClass "@sapphirecity_baseboard_lib.sapphirecity_baseboard(sch_1):\RCC73\"
				( attribute "LINE_TO_LINE_SPACING" "8.00"
					( Origin gBackEnd )
				)
				( regionRef "@sapphirecity_baseboard_lib.sapphirecity_baseboard(sch_1):\CPU_BRKT\" )
				( netClassRef "@sapphirecity_baseboard_lib.sapphirecity_baseboard(sch_1):\DDR4_CHN_B_CTRL\" )
				( netClassRef "@sapphirecity_baseboard_lib.sapphirecity_baseboard(sch_1):\DDR4_CHN_B_DQ_DQS_BYTE1\" )
			)
			( regionClassClass "@sapphirecity_baseboard_lib.sapphirecity_baseboard(sch_1):\RCC74\"
				( attribute "LINE_TO_LINE_SPACING" "8.00"
					( Origin gBackEnd )
				)
				( regionRef "@sapphirecity_baseboard_lib.sapphirecity_baseboard(sch_1):\CPU_BRKT\" )
				( netClassRef "@sapphirecity_baseboard_lib.sapphirecity_baseboard(sch_1):\DDR4_CHN_B_CTRL\" )
				( netClassRef "@sapphirecity_baseboard_lib.sapphirecity_baseboard(sch_1):\DDR4_CHN_B_DQ_DQS_BYTE0\" )
			)
			( regionClassClass "@sapphirecity_baseboard_lib.sapphirecity_baseboard(sch_1):\RCC75\"
				( attribute "LINE_TO_LINE_SPACING" "8.00"
					( Origin gBackEnd )
				)
				( regionRef "@sapphirecity_baseboard_lib.sapphirecity_baseboard(sch_1):\CPU_BRKT\" )
				( netClassRef "@sapphirecity_baseboard_lib.sapphirecity_baseboard(sch_1):\DDR4_CHN_B_CTRL\" )
				( netClassRef "@sapphirecity_baseboard_lib.sapphirecity_baseboard(sch_1):\DDR4_CHN_B_CTRL\" )
			)
			( regionClassClass "@sapphirecity_baseboard_lib.sapphirecity_baseboard(sch_1):\RCC76\"
				( attribute "LINE_TO_LINE_SPACING" "8.00"
					( Origin gBackEnd )
				)
				( regionRef "@sapphirecity_baseboard_lib.sapphirecity_baseboard(sch_1):\CPU_BRKT\" )
				( netClassRef "@sapphirecity_baseboard_lib.sapphirecity_baseboard(sch_1):\DDR4_CHN_B_ECC\" )
				( netClassRef "@sapphirecity_baseboard_lib.sapphirecity_baseboard(sch_1):\DDR4_CHN_B_ECC\" )
			)
			( regionClassClass "@sapphirecity_baseboard_lib.sapphirecity_baseboard(sch_1):\RCC77\"
				( attribute "LINE_TO_LINE_SPACING" "8.00"
					( Origin gBackEnd )
				)
				( regionRef "@sapphirecity_baseboard_lib.sapphirecity_baseboard(sch_1):\CPU_BRKT\" )
				( netClassRef "@sapphirecity_baseboard_lib.sapphirecity_baseboard(sch_1):\DDR4_CHN_B_DQ_DQS_BYTE7\" )
				( netClassRef "@sapphirecity_baseboard_lib.sapphirecity_baseboard(sch_1):\DDR4_CHN_B_ECC\" )
			)
			( regionClassClass "@sapphirecity_baseboard_lib.sapphirecity_baseboard(sch_1):\RCC78\"
				( attribute "LINE_TO_LINE_SPACING" "8.00"
					( Origin gBackEnd )
				)
				( regionRef "@sapphirecity_baseboard_lib.sapphirecity_baseboard(sch_1):\CPU_BRKT\" )
				( netClassRef "@sapphirecity_baseboard_lib.sapphirecity_baseboard(sch_1):\DDR4_CHN_B_DQ_DQS_BYTE6\" )
				( netClassRef "@sapphirecity_baseboard_lib.sapphirecity_baseboard(sch_1):\DDR4_CHN_B_ECC\" )
			)
			( regionClassClass "@sapphirecity_baseboard_lib.sapphirecity_baseboard(sch_1):\RCC79\"
				( attribute "LINE_TO_LINE_SPACING" "8.00"
					( Origin gBackEnd )
				)
				( regionRef "@sapphirecity_baseboard_lib.sapphirecity_baseboard(sch_1):\CPU_BRKT\" )
				( netClassRef "@sapphirecity_baseboard_lib.sapphirecity_baseboard(sch_1):\DDR4_CHN_B_DQ_DQS_BYTE5\" )
				( netClassRef "@sapphirecity_baseboard_lib.sapphirecity_baseboard(sch_1):\DDR4_CHN_B_ECC\" )
			)
			( regionClassClass "@sapphirecity_baseboard_lib.sapphirecity_baseboard(sch_1):\RCC80\"
				( attribute "LINE_TO_LINE_SPACING" "8.00"
					( Origin gBackEnd )
				)
				( regionRef "@sapphirecity_baseboard_lib.sapphirecity_baseboard(sch_1):\CPU_BRKT\" )
				( netClassRef "@sapphirecity_baseboard_lib.sapphirecity_baseboard(sch_1):\DDR4_CHN_B_DQ_DQS_BYTE4\" )
				( netClassRef "@sapphirecity_baseboard_lib.sapphirecity_baseboard(sch_1):\DDR4_CHN_B_ECC\" )
			)
			( regionClassClass "@sapphirecity_baseboard_lib.sapphirecity_baseboard(sch_1):\RCC81\"
				( attribute "LINE_TO_LINE_SPACING" "8.00"
					( Origin gBackEnd )
				)
				( regionRef "@sapphirecity_baseboard_lib.sapphirecity_baseboard(sch_1):\CPU_BRKT\" )
				( netClassRef "@sapphirecity_baseboard_lib.sapphirecity_baseboard(sch_1):\DDR4_CHN_B_DQ_DQS_BYTE3\" )
				( netClassRef "@sapphirecity_baseboard_lib.sapphirecity_baseboard(sch_1):\DDR4_CHN_B_ECC\" )
			)
			( regionClassClass "@sapphirecity_baseboard_lib.sapphirecity_baseboard(sch_1):\RCC82\"
				( attribute "LINE_TO_LINE_SPACING" "8.00"
					( Origin gBackEnd )
				)
				( regionRef "@sapphirecity_baseboard_lib.sapphirecity_baseboard(sch_1):\CPU_BRKT\" )
				( netClassRef "@sapphirecity_baseboard_lib.sapphirecity_baseboard(sch_1):\DDR4_CHN_B_DQ_DQS_BYTE2\" )
				( netClassRef "@sapphirecity_baseboard_lib.sapphirecity_baseboard(sch_1):\DDR4_CHN_B_ECC\" )
			)
			( regionClassClass "@sapphirecity_baseboard_lib.sapphirecity_baseboard(sch_1):\RCC83\"
				( attribute "LINE_TO_LINE_SPACING" "8.00"
					( Origin gBackEnd )
				)
				( regionRef "@sapphirecity_baseboard_lib.sapphirecity_baseboard(sch_1):\CPU_BRKT\" )
				( netClassRef "@sapphirecity_baseboard_lib.sapphirecity_baseboard(sch_1):\DDR4_CHN_B_DQ_DQS_BYTE1\" )
				( netClassRef "@sapphirecity_baseboard_lib.sapphirecity_baseboard(sch_1):\DDR4_CHN_B_ECC\" )
			)
			( regionClassClass "@sapphirecity_baseboard_lib.sapphirecity_baseboard(sch_1):\RCC84\"
				( attribute "LINE_TO_LINE_SPACING" "8.00"
					( Origin gBackEnd )
				)
				( regionRef "@sapphirecity_baseboard_lib.sapphirecity_baseboard(sch_1):\CPU_BRKT\" )
				( netClassRef "@sapphirecity_baseboard_lib.sapphirecity_baseboard(sch_1):\DDR4_CHN_B_DQ_DQS_BYTE0\" )
				( netClassRef "@sapphirecity_baseboard_lib.sapphirecity_baseboard(sch_1):\DDR4_CHN_B_ECC\" )
			)
			( regionClassClass "@sapphirecity_baseboard_lib.sapphirecity_baseboard(sch_1):\RCC85\"
				( attribute "LINE_TO_LINE_SPACING" "8.00"
					( Origin gBackEnd )
				)
				( regionRef "@sapphirecity_baseboard_lib.sapphirecity_baseboard(sch_1):\CPU_BRKT\" )
				( netClassRef "@sapphirecity_baseboard_lib.sapphirecity_baseboard(sch_1):\DDR4_CHN_C_CLK\" )
				( netClassRef "@sapphirecity_baseboard_lib.sapphirecity_baseboard(sch_1):\DDR4_CHN_C_ECC\" )
			)
			( regionClassClass "@sapphirecity_baseboard_lib.sapphirecity_baseboard(sch_1):\RCC86\"
				( attribute "LINE_TO_LINE_SPACING" "8.00"
					( Origin gBackEnd )
				)
				( regionRef "@sapphirecity_baseboard_lib.sapphirecity_baseboard(sch_1):\CPU_BRKT\" )
				( netClassRef "@sapphirecity_baseboard_lib.sapphirecity_baseboard(sch_1):\DDR4_CHN_C_CLK\" )
				( netClassRef "@sapphirecity_baseboard_lib.sapphirecity_baseboard(sch_1):\DDR4_CHN_C_DQ_DQS_BYTE7\" )
			)
			( regionClassClass "@sapphirecity_baseboard_lib.sapphirecity_baseboard(sch_1):\RCC87\"
				( attribute "LINE_TO_LINE_SPACING" "8.00"
					( Origin gBackEnd )
				)
				( regionRef "@sapphirecity_baseboard_lib.sapphirecity_baseboard(sch_1):\CPU_BRKT\" )
				( netClassRef "@sapphirecity_baseboard_lib.sapphirecity_baseboard(sch_1):\DDR4_CHN_C_CLK\" )
				( netClassRef "@sapphirecity_baseboard_lib.sapphirecity_baseboard(sch_1):\DDR4_CHN_C_DQ_DQS_BYTE6\" )
			)
			( regionClassClass "@sapphirecity_baseboard_lib.sapphirecity_baseboard(sch_1):\RCC88\"
				( attribute "LINE_TO_LINE_SPACING" "8.00"
					( Origin gBackEnd )
				)
				( regionRef "@sapphirecity_baseboard_lib.sapphirecity_baseboard(sch_1):\CPU_BRKT\" )
				( netClassRef "@sapphirecity_baseboard_lib.sapphirecity_baseboard(sch_1):\DDR4_CHN_C_CLK\" )
				( netClassRef "@sapphirecity_baseboard_lib.sapphirecity_baseboard(sch_1):\DDR4_CHN_C_DQ_DQS_BYTE5\" )
			)
			( regionClassClass "@sapphirecity_baseboard_lib.sapphirecity_baseboard(sch_1):\RCC89\"
				( attribute "LINE_TO_LINE_SPACING" "8.00"
					( Origin gBackEnd )
				)
				( regionRef "@sapphirecity_baseboard_lib.sapphirecity_baseboard(sch_1):\CPU_BRKT\" )
				( netClassRef "@sapphirecity_baseboard_lib.sapphirecity_baseboard(sch_1):\DDR4_CHN_C_CLK\" )
				( netClassRef "@sapphirecity_baseboard_lib.sapphirecity_baseboard(sch_1):\DDR4_CHN_C_DQ_DQS_BYTE4\" )
			)
			( regionClassClass "@sapphirecity_baseboard_lib.sapphirecity_baseboard(sch_1):\RCC90\"
				( attribute "LINE_TO_LINE_SPACING" "8.00"
					( Origin gBackEnd )
				)
				( regionRef "@sapphirecity_baseboard_lib.sapphirecity_baseboard(sch_1):\CPU_BRKT\" )
				( netClassRef "@sapphirecity_baseboard_lib.sapphirecity_baseboard(sch_1):\DDR4_CHN_C_CLK\" )
				( netClassRef "@sapphirecity_baseboard_lib.sapphirecity_baseboard(sch_1):\DDR4_CHN_C_DQ_DQS_BYTE3\" )
			)
			( regionClassClass "@sapphirecity_baseboard_lib.sapphirecity_baseboard(sch_1):\RCC91\"
				( attribute "LINE_TO_LINE_SPACING" "8.00"
					( Origin gBackEnd )
				)
				( regionRef "@sapphirecity_baseboard_lib.sapphirecity_baseboard(sch_1):\CPU_BRKT\" )
				( netClassRef "@sapphirecity_baseboard_lib.sapphirecity_baseboard(sch_1):\DDR4_CHN_C_CLK\" )
				( netClassRef "@sapphirecity_baseboard_lib.sapphirecity_baseboard(sch_1):\DDR4_CHN_C_DQ_DQS_BYTE2\" )
			)
			( regionClassClass "@sapphirecity_baseboard_lib.sapphirecity_baseboard(sch_1):\RCC92\"
				( attribute "LINE_TO_LINE_SPACING" "8.00"
					( Origin gBackEnd )
				)
				( regionRef "@sapphirecity_baseboard_lib.sapphirecity_baseboard(sch_1):\CPU_BRKT\" )
				( netClassRef "@sapphirecity_baseboard_lib.sapphirecity_baseboard(sch_1):\DDR4_CHN_C_CLK\" )
				( netClassRef "@sapphirecity_baseboard_lib.sapphirecity_baseboard(sch_1):\DDR4_CHN_C_DQ_DQS_BYTE1\" )
			)
			( regionClassClass "@sapphirecity_baseboard_lib.sapphirecity_baseboard(sch_1):\RCC93\"
				( attribute "LINE_TO_LINE_SPACING" "8.00"
					( Origin gBackEnd )
				)
				( regionRef "@sapphirecity_baseboard_lib.sapphirecity_baseboard(sch_1):\CPU_BRKT\" )
				( netClassRef "@sapphirecity_baseboard_lib.sapphirecity_baseboard(sch_1):\DDR4_CHN_C_CLK\" )
				( netClassRef "@sapphirecity_baseboard_lib.sapphirecity_baseboard(sch_1):\DDR4_CHN_C_DQ_DQS_BYTE0\" )
			)
			( regionClassClass "@sapphirecity_baseboard_lib.sapphirecity_baseboard(sch_1):\RCC94\"
				( attribute "LINE_TO_LINE_SPACING" "8.00"
					( Origin gBackEnd )
				)
				( regionRef "@sapphirecity_baseboard_lib.sapphirecity_baseboard(sch_1):\CPU_BRKT\" )
				( netClassRef "@sapphirecity_baseboard_lib.sapphirecity_baseboard(sch_1):\DDR4_CHN_C_CLK\" )
				( netClassRef "@sapphirecity_baseboard_lib.sapphirecity_baseboard(sch_1):\DDR4_CHN_C_CTRL\" )
			)
			( regionClassClass "@sapphirecity_baseboard_lib.sapphirecity_baseboard(sch_1):\RCC95\"
				( attribute "LINE_TO_LINE_SPACING" "8.00"
					( Origin gBackEnd )
				)
				( regionRef "@sapphirecity_baseboard_lib.sapphirecity_baseboard(sch_1):\CPU_BRKT\" )
				( netClassRef "@sapphirecity_baseboard_lib.sapphirecity_baseboard(sch_1):\DDR4_CHN_C_CLK\" )
				( netClassRef "@sapphirecity_baseboard_lib.sapphirecity_baseboard(sch_1):\DDR4_CHN_C_CMD_ADD\" )
			)
			( regionClassClass "@sapphirecity_baseboard_lib.sapphirecity_baseboard(sch_1):\RCC96\"
				( attribute "LINE_TO_LINE_SPACING" "8.00"
					( Origin gBackEnd )
				)
				( regionRef "@sapphirecity_baseboard_lib.sapphirecity_baseboard(sch_1):\CPU_BRKT\" )
				( netClassRef "@sapphirecity_baseboard_lib.sapphirecity_baseboard(sch_1):\DDR4_CHN_C_CLK\" )
				( netClassRef "@sapphirecity_baseboard_lib.sapphirecity_baseboard(sch_1):\DDR4_CHN_C_CLK\" )
			)
			( regionClassClass "@sapphirecity_baseboard_lib.sapphirecity_baseboard(sch_1):\RCC97\"
				( attribute "LINE_TO_LINE_SPACING" "8.00"
					( Origin gBackEnd )
				)
				( regionRef "@sapphirecity_baseboard_lib.sapphirecity_baseboard(sch_1):\CPU_BRKT\" )
				( netClassRef "@sapphirecity_baseboard_lib.sapphirecity_baseboard(sch_1):\DDR4_CHN_C_CMD_ADD\" )
				( netClassRef "@sapphirecity_baseboard_lib.sapphirecity_baseboard(sch_1):\DDR4_CHN_C_ECC\" )
			)
			( regionClassClass "@sapphirecity_baseboard_lib.sapphirecity_baseboard(sch_1):\RCC98\"
				( attribute "LINE_TO_LINE_SPACING" "8.00"
					( Origin gBackEnd )
				)
				( regionRef "@sapphirecity_baseboard_lib.sapphirecity_baseboard(sch_1):\CPU_BRKT\" )
				( netClassRef "@sapphirecity_baseboard_lib.sapphirecity_baseboard(sch_1):\DDR4_CHN_C_CMD_ADD\" )
				( netClassRef "@sapphirecity_baseboard_lib.sapphirecity_baseboard(sch_1):\DDR4_CHN_C_DQ_DQS_BYTE7\" )
			)
			( regionClassClass "@sapphirecity_baseboard_lib.sapphirecity_baseboard(sch_1):\RCC99\"
				( attribute "LINE_TO_LINE_SPACING" "8.00"
					( Origin gBackEnd )
				)
				( regionRef "@sapphirecity_baseboard_lib.sapphirecity_baseboard(sch_1):\CPU_BRKT\" )
				( netClassRef "@sapphirecity_baseboard_lib.sapphirecity_baseboard(sch_1):\DDR4_CHN_C_CMD_ADD\" )
				( netClassRef "@sapphirecity_baseboard_lib.sapphirecity_baseboard(sch_1):\DDR4_CHN_C_DQ_DQS_BYTE6\" )
			)
			( regionClassClass "@sapphirecity_baseboard_lib.sapphirecity_baseboard(sch_1):\RCC100\"
				( attribute "LINE_TO_LINE_SPACING" "8.00"
					( Origin gBackEnd )
				)
				( regionRef "@sapphirecity_baseboard_lib.sapphirecity_baseboard(sch_1):\CPU_BRKT\" )
				( netClassRef "@sapphirecity_baseboard_lib.sapphirecity_baseboard(sch_1):\DDR4_CHN_C_CMD_ADD\" )
				( netClassRef "@sapphirecity_baseboard_lib.sapphirecity_baseboard(sch_1):\DDR4_CHN_C_DQ_DQS_BYTE5\" )
			)
			( regionClassClass "@sapphirecity_baseboard_lib.sapphirecity_baseboard(sch_1):\RCC101\"
				( attribute "LINE_TO_LINE_SPACING" "8.00"
					( Origin gBackEnd )
				)
				( regionRef "@sapphirecity_baseboard_lib.sapphirecity_baseboard(sch_1):\CPU_BRKT\" )
				( netClassRef "@sapphirecity_baseboard_lib.sapphirecity_baseboard(sch_1):\DDR4_CHN_C_CMD_ADD\" )
				( netClassRef "@sapphirecity_baseboard_lib.sapphirecity_baseboard(sch_1):\DDR4_CHN_C_DQ_DQS_BYTE4\" )
			)
			( regionClassClass "@sapphirecity_baseboard_lib.sapphirecity_baseboard(sch_1):\RCC102\"
				( attribute "LINE_TO_LINE_SPACING" "8.00"
					( Origin gBackEnd )
				)
				( regionRef "@sapphirecity_baseboard_lib.sapphirecity_baseboard(sch_1):\CPU_BRKT\" )
				( netClassRef "@sapphirecity_baseboard_lib.sapphirecity_baseboard(sch_1):\DDR4_CHN_C_CMD_ADD\" )
				( netClassRef "@sapphirecity_baseboard_lib.sapphirecity_baseboard(sch_1):\DDR4_CHN_C_DQ_DQS_BYTE3\" )
			)
			( regionClassClass "@sapphirecity_baseboard_lib.sapphirecity_baseboard(sch_1):\RCC103\"
				( attribute "LINE_TO_LINE_SPACING" "8.00"
					( Origin gBackEnd )
				)
				( regionRef "@sapphirecity_baseboard_lib.sapphirecity_baseboard(sch_1):\CPU_BRKT\" )
				( netClassRef "@sapphirecity_baseboard_lib.sapphirecity_baseboard(sch_1):\DDR4_CHN_C_CMD_ADD\" )
				( netClassRef "@sapphirecity_baseboard_lib.sapphirecity_baseboard(sch_1):\DDR4_CHN_C_DQ_DQS_BYTE2\" )
			)
			( regionClassClass "@sapphirecity_baseboard_lib.sapphirecity_baseboard(sch_1):\RCC104\"
				( attribute "LINE_TO_LINE_SPACING" "8.00"
					( Origin gBackEnd )
				)
				( regionRef "@sapphirecity_baseboard_lib.sapphirecity_baseboard(sch_1):\CPU_BRKT\" )
				( netClassRef "@sapphirecity_baseboard_lib.sapphirecity_baseboard(sch_1):\DDR4_CHN_C_CMD_ADD\" )
				( netClassRef "@sapphirecity_baseboard_lib.sapphirecity_baseboard(sch_1):\DDR4_CHN_C_DQ_DQS_BYTE1\" )
			)
			( regionClassClass "@sapphirecity_baseboard_lib.sapphirecity_baseboard(sch_1):\RCC105\"
				( attribute "LINE_TO_LINE_SPACING" "8.00"
					( Origin gBackEnd )
				)
				( regionRef "@sapphirecity_baseboard_lib.sapphirecity_baseboard(sch_1):\CPU_BRKT\" )
				( netClassRef "@sapphirecity_baseboard_lib.sapphirecity_baseboard(sch_1):\DDR4_CHN_C_CMD_ADD\" )
				( netClassRef "@sapphirecity_baseboard_lib.sapphirecity_baseboard(sch_1):\DDR4_CHN_C_DQ_DQS_BYTE0\" )
			)
			( regionClassClass "@sapphirecity_baseboard_lib.sapphirecity_baseboard(sch_1):\RCC106\"
				( attribute "LINE_TO_LINE_SPACING" "8.00"
					( Origin gBackEnd )
				)
				( regionRef "@sapphirecity_baseboard_lib.sapphirecity_baseboard(sch_1):\CPU_BRKT\" )
				( netClassRef "@sapphirecity_baseboard_lib.sapphirecity_baseboard(sch_1):\DDR4_CHN_C_CMD_ADD\" )
				( netClassRef "@sapphirecity_baseboard_lib.sapphirecity_baseboard(sch_1):\DDR4_CHN_C_CTRL\" )
			)
			( regionClassClass "@sapphirecity_baseboard_lib.sapphirecity_baseboard(sch_1):\RCC107\"
				( attribute "LINE_TO_LINE_SPACING" "8.00"
					( Origin gBackEnd )
				)
				( regionRef "@sapphirecity_baseboard_lib.sapphirecity_baseboard(sch_1):\CPU_BRKT\" )
				( netClassRef "@sapphirecity_baseboard_lib.sapphirecity_baseboard(sch_1):\DDR4_CHN_C_CMD_ADD\" )
				( netClassRef "@sapphirecity_baseboard_lib.sapphirecity_baseboard(sch_1):\DDR4_CHN_C_CMD_ADD\" )
			)
			( regionClassClass "@sapphirecity_baseboard_lib.sapphirecity_baseboard(sch_1):\RCC108\"
				( attribute "LINE_TO_LINE_SPACING" "8.00"
					( Origin gBackEnd )
				)
				( regionRef "@sapphirecity_baseboard_lib.sapphirecity_baseboard(sch_1):\CPU_BRKT\" )
				( netClassRef "@sapphirecity_baseboard_lib.sapphirecity_baseboard(sch_1):\DDR4_CHN_C_CTRL\" )
				( netClassRef "@sapphirecity_baseboard_lib.sapphirecity_baseboard(sch_1):\DDR4_CHN_C_ECC\" )
			)
			( regionClassClass "@sapphirecity_baseboard_lib.sapphirecity_baseboard(sch_1):\RCC109\"
				( attribute "LINE_TO_LINE_SPACING" "8.00"
					( Origin gBackEnd )
				)
				( regionRef "@sapphirecity_baseboard_lib.sapphirecity_baseboard(sch_1):\CPU_BRKT\" )
				( netClassRef "@sapphirecity_baseboard_lib.sapphirecity_baseboard(sch_1):\DDR4_CHN_C_CTRL\" )
				( netClassRef "@sapphirecity_baseboard_lib.sapphirecity_baseboard(sch_1):\DDR4_CHN_C_DQ_DQS_BYTE7\" )
			)
			( regionClassClass "@sapphirecity_baseboard_lib.sapphirecity_baseboard(sch_1):\RCC110\"
				( attribute "LINE_TO_LINE_SPACING" "8.00"
					( Origin gBackEnd )
				)
				( regionRef "@sapphirecity_baseboard_lib.sapphirecity_baseboard(sch_1):\CPU_BRKT\" )
				( netClassRef "@sapphirecity_baseboard_lib.sapphirecity_baseboard(sch_1):\DDR4_CHN_C_CTRL\" )
				( netClassRef "@sapphirecity_baseboard_lib.sapphirecity_baseboard(sch_1):\DDR4_CHN_C_DQ_DQS_BYTE6\" )
			)
			( regionClassClass "@sapphirecity_baseboard_lib.sapphirecity_baseboard(sch_1):\RCC111\"
				( attribute "LINE_TO_LINE_SPACING" "8.00"
					( Origin gBackEnd )
				)
				( regionRef "@sapphirecity_baseboard_lib.sapphirecity_baseboard(sch_1):\CPU_BRKT\" )
				( netClassRef "@sapphirecity_baseboard_lib.sapphirecity_baseboard(sch_1):\DDR4_CHN_C_CTRL\" )
				( netClassRef "@sapphirecity_baseboard_lib.sapphirecity_baseboard(sch_1):\DDR4_CHN_C_DQ_DQS_BYTE5\" )
			)
			( regionClassClass "@sapphirecity_baseboard_lib.sapphirecity_baseboard(sch_1):\RCC112\"
				( attribute "LINE_TO_LINE_SPACING" "8.00"
					( Origin gBackEnd )
				)
				( regionRef "@sapphirecity_baseboard_lib.sapphirecity_baseboard(sch_1):\CPU_BRKT\" )
				( netClassRef "@sapphirecity_baseboard_lib.sapphirecity_baseboard(sch_1):\DDR4_CHN_C_CTRL\" )
				( netClassRef "@sapphirecity_baseboard_lib.sapphirecity_baseboard(sch_1):\DDR4_CHN_C_DQ_DQS_BYTE4\" )
			)
			( regionClassClass "@sapphirecity_baseboard_lib.sapphirecity_baseboard(sch_1):\RCC113\"
				( attribute "LINE_TO_LINE_SPACING" "8.00"
					( Origin gBackEnd )
				)
				( regionRef "@sapphirecity_baseboard_lib.sapphirecity_baseboard(sch_1):\CPU_BRKT\" )
				( netClassRef "@sapphirecity_baseboard_lib.sapphirecity_baseboard(sch_1):\DDR4_CHN_C_CTRL\" )
				( netClassRef "@sapphirecity_baseboard_lib.sapphirecity_baseboard(sch_1):\DDR4_CHN_C_DQ_DQS_BYTE3\" )
			)
			( regionClassClass "@sapphirecity_baseboard_lib.sapphirecity_baseboard(sch_1):\RCC114\"
				( attribute "LINE_TO_LINE_SPACING" "8.00"
					( Origin gBackEnd )
				)
				( regionRef "@sapphirecity_baseboard_lib.sapphirecity_baseboard(sch_1):\CPU_BRKT\" )
				( netClassRef "@sapphirecity_baseboard_lib.sapphirecity_baseboard(sch_1):\DDR4_CHN_C_CTRL\" )
				( netClassRef "@sapphirecity_baseboard_lib.sapphirecity_baseboard(sch_1):\DDR4_CHN_C_DQ_DQS_BYTE2\" )
			)
			( regionClassClass "@sapphirecity_baseboard_lib.sapphirecity_baseboard(sch_1):\RCC115\"
				( attribute "LINE_TO_LINE_SPACING" "8.00"
					( Origin gBackEnd )
				)
				( regionRef "@sapphirecity_baseboard_lib.sapphirecity_baseboard(sch_1):\CPU_BRKT\" )
				( netClassRef "@sapphirecity_baseboard_lib.sapphirecity_baseboard(sch_1):\DDR4_CHN_C_CTRL\" )
				( netClassRef "@sapphirecity_baseboard_lib.sapphirecity_baseboard(sch_1):\DDR4_CHN_C_DQ_DQS_BYTE1\" )
			)
			( regionClassClass "@sapphirecity_baseboard_lib.sapphirecity_baseboard(sch_1):\RCC116\"
				( attribute "LINE_TO_LINE_SPACING" "8.00"
					( Origin gBackEnd )
				)
				( regionRef "@sapphirecity_baseboard_lib.sapphirecity_baseboard(sch_1):\CPU_BRKT\" )
				( netClassRef "@sapphirecity_baseboard_lib.sapphirecity_baseboard(sch_1):\DDR4_CHN_C_CTRL\" )
				( netClassRef "@sapphirecity_baseboard_lib.sapphirecity_baseboard(sch_1):\DDR4_CHN_C_DQ_DQS_BYTE0\" )
			)
			( regionClassClass "@sapphirecity_baseboard_lib.sapphirecity_baseboard(sch_1):\RCC117\"
				( attribute "LINE_TO_LINE_SPACING" "8.00"
					( Origin gBackEnd )
				)
				( regionRef "@sapphirecity_baseboard_lib.sapphirecity_baseboard(sch_1):\CPU_BRKT\" )
				( netClassRef "@sapphirecity_baseboard_lib.sapphirecity_baseboard(sch_1):\DDR4_CHN_C_CTRL\" )
				( netClassRef "@sapphirecity_baseboard_lib.sapphirecity_baseboard(sch_1):\DDR4_CHN_C_CTRL\" )
			)
			( regionClassClass "@sapphirecity_baseboard_lib.sapphirecity_baseboard(sch_1):\RCC118\"
				( attribute "LINE_TO_LINE_SPACING" "8.00"
					( Origin gBackEnd )
				)
				( regionRef "@sapphirecity_baseboard_lib.sapphirecity_baseboard(sch_1):\CPU_BRKT\" )
				( netClassRef "@sapphirecity_baseboard_lib.sapphirecity_baseboard(sch_1):\DDR4_CHN_C_ECC\" )
				( netClassRef "@sapphirecity_baseboard_lib.sapphirecity_baseboard(sch_1):\DDR4_CHN_C_ECC\" )
			)
			( regionClassClass "@sapphirecity_baseboard_lib.sapphirecity_baseboard(sch_1):\RCC119\"
				( attribute "LINE_TO_LINE_SPACING" "8.00"
					( Origin gBackEnd )
				)
				( regionRef "@sapphirecity_baseboard_lib.sapphirecity_baseboard(sch_1):\CPU_BRKT\" )
				( netClassRef "@sapphirecity_baseboard_lib.sapphirecity_baseboard(sch_1):\DDR4_CHN_C_DQ_DQS_BYTE7\" )
				( netClassRef "@sapphirecity_baseboard_lib.sapphirecity_baseboard(sch_1):\DDR4_CHN_C_ECC\" )
			)
			( regionClassClass "@sapphirecity_baseboard_lib.sapphirecity_baseboard(sch_1):\RCC120\"
				( attribute "LINE_TO_LINE_SPACING" "8.00"
					( Origin gBackEnd )
				)
				( regionRef "@sapphirecity_baseboard_lib.sapphirecity_baseboard(sch_1):\CPU_BRKT\" )
				( netClassRef "@sapphirecity_baseboard_lib.sapphirecity_baseboard(sch_1):\DDR4_CHN_C_DQ_DQS_BYTE6\" )
				( netClassRef "@sapphirecity_baseboard_lib.sapphirecity_baseboard(sch_1):\DDR4_CHN_C_ECC\" )
			)
			( regionClassClass "@sapphirecity_baseboard_lib.sapphirecity_baseboard(sch_1):\RCC121\"
				( attribute "LINE_TO_LINE_SPACING" "8.00"
					( Origin gBackEnd )
				)
				( regionRef "@sapphirecity_baseboard_lib.sapphirecity_baseboard(sch_1):\CPU_BRKT\" )
				( netClassRef "@sapphirecity_baseboard_lib.sapphirecity_baseboard(sch_1):\DDR4_CHN_C_DQ_DQS_BYTE5\" )
				( netClassRef "@sapphirecity_baseboard_lib.sapphirecity_baseboard(sch_1):\DDR4_CHN_C_ECC\" )
			)
			( regionClassClass "@sapphirecity_baseboard_lib.sapphirecity_baseboard(sch_1):\RCC122\"
				( attribute "LINE_TO_LINE_SPACING" "8.00"
					( Origin gBackEnd )
				)
				( regionRef "@sapphirecity_baseboard_lib.sapphirecity_baseboard(sch_1):\CPU_BRKT\" )
				( netClassRef "@sapphirecity_baseboard_lib.sapphirecity_baseboard(sch_1):\DDR4_CHN_C_DQ_DQS_BYTE4\" )
				( netClassRef "@sapphirecity_baseboard_lib.sapphirecity_baseboard(sch_1):\DDR4_CHN_C_ECC\" )
			)
			( regionClassClass "@sapphirecity_baseboard_lib.sapphirecity_baseboard(sch_1):\RCC123\"
				( attribute "LINE_TO_LINE_SPACING" "8.00"
					( Origin gBackEnd )
				)
				( regionRef "@sapphirecity_baseboard_lib.sapphirecity_baseboard(sch_1):\CPU_BRKT\" )
				( netClassRef "@sapphirecity_baseboard_lib.sapphirecity_baseboard(sch_1):\DDR4_CHN_C_DQ_DQS_BYTE3\" )
				( netClassRef "@sapphirecity_baseboard_lib.sapphirecity_baseboard(sch_1):\DDR4_CHN_C_ECC\" )
			)
			( regionClassClass "@sapphirecity_baseboard_lib.sapphirecity_baseboard(sch_1):\RCC124\"
				( attribute "LINE_TO_LINE_SPACING" "8.00"
					( Origin gBackEnd )
				)
				( regionRef "@sapphirecity_baseboard_lib.sapphirecity_baseboard(sch_1):\CPU_BRKT\" )
				( netClassRef "@sapphirecity_baseboard_lib.sapphirecity_baseboard(sch_1):\DDR4_CHN_C_DQ_DQS_BYTE2\" )
				( netClassRef "@sapphirecity_baseboard_lib.sapphirecity_baseboard(sch_1):\DDR4_CHN_C_ECC\" )
			)
			( regionClassClass "@sapphirecity_baseboard_lib.sapphirecity_baseboard(sch_1):\RCC125\"
				( attribute "LINE_TO_LINE_SPACING" "8.00"
					( Origin gBackEnd )
				)
				( regionRef "@sapphirecity_baseboard_lib.sapphirecity_baseboard(sch_1):\CPU_BRKT\" )
				( netClassRef "@sapphirecity_baseboard_lib.sapphirecity_baseboard(sch_1):\DDR4_CHN_C_DQ_DQS_BYTE1\" )
				( netClassRef "@sapphirecity_baseboard_lib.sapphirecity_baseboard(sch_1):\DDR4_CHN_C_ECC\" )
			)
			( regionClassClass "@sapphirecity_baseboard_lib.sapphirecity_baseboard(sch_1):\RCC126\"
				( attribute "LINE_TO_LINE_SPACING" "8.00"
					( Origin gBackEnd )
				)
				( regionRef "@sapphirecity_baseboard_lib.sapphirecity_baseboard(sch_1):\CPU_BRKT\" )
				( netClassRef "@sapphirecity_baseboard_lib.sapphirecity_baseboard(sch_1):\DDR4_CHN_C_DQ_DQS_BYTE0\" )
				( netClassRef "@sapphirecity_baseboard_lib.sapphirecity_baseboard(sch_1):\DDR4_CHN_C_ECC\" )
			)
			( regionClassClass "@sapphirecity_baseboard_lib.sapphirecity_baseboard(sch_1):\RCC127\"
				( attribute "LINE_TO_LINE_SPACING" "8.00"
					( Origin gBackEnd )
				)
				( regionRef "@sapphirecity_baseboard_lib.sapphirecity_baseboard(sch_1):\CPU_BRKT\" )
				( netClassRef "@sapphirecity_baseboard_lib.sapphirecity_baseboard(sch_1):\DDR4_CHN_D_CLK\" )
				( netClassRef "@sapphirecity_baseboard_lib.sapphirecity_baseboard(sch_1):\DDR4_CHN_D_ECC\" )
			)
			( regionClassClass "@sapphirecity_baseboard_lib.sapphirecity_baseboard(sch_1):\RCC128\"
				( attribute "LINE_TO_LINE_SPACING" "8.00"
					( Origin gBackEnd )
				)
				( regionRef "@sapphirecity_baseboard_lib.sapphirecity_baseboard(sch_1):\CPU_BRKT\" )
				( netClassRef "@sapphirecity_baseboard_lib.sapphirecity_baseboard(sch_1):\DDR4_CHN_D_CLK\" )
				( netClassRef "@sapphirecity_baseboard_lib.sapphirecity_baseboard(sch_1):\DDR4_CHN_D_DQ_DQS_BYTE7\" )
			)
			( regionClassClass "@sapphirecity_baseboard_lib.sapphirecity_baseboard(sch_1):\RCC129\"
				( attribute "LINE_TO_LINE_SPACING" "8.00"
					( Origin gBackEnd )
				)
				( regionRef "@sapphirecity_baseboard_lib.sapphirecity_baseboard(sch_1):\CPU_BRKT\" )
				( netClassRef "@sapphirecity_baseboard_lib.sapphirecity_baseboard(sch_1):\DDR4_CHN_D_CLK\" )
				( netClassRef "@sapphirecity_baseboard_lib.sapphirecity_baseboard(sch_1):\DDR4_CHN_D_DQ_DQS_BYTE6\" )
			)
			( regionClassClass "@sapphirecity_baseboard_lib.sapphirecity_baseboard(sch_1):\RCC130\"
				( attribute "LINE_TO_LINE_SPACING" "8.00"
					( Origin gBackEnd )
				)
				( regionRef "@sapphirecity_baseboard_lib.sapphirecity_baseboard(sch_1):\CPU_BRKT\" )
				( netClassRef "@sapphirecity_baseboard_lib.sapphirecity_baseboard(sch_1):\DDR4_CHN_D_CLK\" )
				( netClassRef "@sapphirecity_baseboard_lib.sapphirecity_baseboard(sch_1):\DDR4_CHN_D_DQ_DQS_BYTE5\" )
			)
			( regionClassClass "@sapphirecity_baseboard_lib.sapphirecity_baseboard(sch_1):\RCC131\"
				( attribute "LINE_TO_LINE_SPACING" "8.00"
					( Origin gBackEnd )
				)
				( regionRef "@sapphirecity_baseboard_lib.sapphirecity_baseboard(sch_1):\CPU_BRKT\" )
				( netClassRef "@sapphirecity_baseboard_lib.sapphirecity_baseboard(sch_1):\DDR4_CHN_D_CLK\" )
				( netClassRef "@sapphirecity_baseboard_lib.sapphirecity_baseboard(sch_1):\DDR4_CHN_D_DQ_DQS_BYTE4\" )
			)
			( regionClassClass "@sapphirecity_baseboard_lib.sapphirecity_baseboard(sch_1):\RCC132\"
				( attribute "LINE_TO_LINE_SPACING" "8.00"
					( Origin gBackEnd )
				)
				( regionRef "@sapphirecity_baseboard_lib.sapphirecity_baseboard(sch_1):\CPU_BRKT\" )
				( netClassRef "@sapphirecity_baseboard_lib.sapphirecity_baseboard(sch_1):\DDR4_CHN_D_CLK\" )
				( netClassRef "@sapphirecity_baseboard_lib.sapphirecity_baseboard(sch_1):\DDR4_CHN_D_DQ_DQS_BYTE3\" )
			)
			( regionClassClass "@sapphirecity_baseboard_lib.sapphirecity_baseboard(sch_1):\RCC133\"
				( attribute "LINE_TO_LINE_SPACING" "8.00"
					( Origin gBackEnd )
				)
				( regionRef "@sapphirecity_baseboard_lib.sapphirecity_baseboard(sch_1):\CPU_BRKT\" )
				( netClassRef "@sapphirecity_baseboard_lib.sapphirecity_baseboard(sch_1):\DDR4_CHN_D_CLK\" )
				( netClassRef "@sapphirecity_baseboard_lib.sapphirecity_baseboard(sch_1):\DDR4_CHN_D_DQ_DQS_BYTE2\" )
			)
			( regionClassClass "@sapphirecity_baseboard_lib.sapphirecity_baseboard(sch_1):\RCC134\"
				( attribute "LINE_TO_LINE_SPACING" "8.00"
					( Origin gBackEnd )
				)
				( regionRef "@sapphirecity_baseboard_lib.sapphirecity_baseboard(sch_1):\CPU_BRKT\" )
				( netClassRef "@sapphirecity_baseboard_lib.sapphirecity_baseboard(sch_1):\DDR4_CHN_D_CLK\" )
				( netClassRef "@sapphirecity_baseboard_lib.sapphirecity_baseboard(sch_1):\DDR4_CHN_D_DQ_DQS_BYTE1\" )
			)
			( regionClassClass "@sapphirecity_baseboard_lib.sapphirecity_baseboard(sch_1):\RCC135\"
				( attribute "LINE_TO_LINE_SPACING" "8.00"
					( Origin gBackEnd )
				)
				( regionRef "@sapphirecity_baseboard_lib.sapphirecity_baseboard(sch_1):\CPU_BRKT\" )
				( netClassRef "@sapphirecity_baseboard_lib.sapphirecity_baseboard(sch_1):\DDR4_CHN_D_CLK\" )
				( netClassRef "@sapphirecity_baseboard_lib.sapphirecity_baseboard(sch_1):\DDR4_CHN_D_DQ_DQS_BYTE0\" )
			)
			( regionClassClass "@sapphirecity_baseboard_lib.sapphirecity_baseboard(sch_1):\RCC136\"
				( attribute "LINE_TO_LINE_SPACING" "8.00"
					( Origin gBackEnd )
				)
				( regionRef "@sapphirecity_baseboard_lib.sapphirecity_baseboard(sch_1):\CPU_BRKT\" )
				( netClassRef "@sapphirecity_baseboard_lib.sapphirecity_baseboard(sch_1):\DDR4_CHN_D_CLK\" )
				( netClassRef "@sapphirecity_baseboard_lib.sapphirecity_baseboard(sch_1):\DDR4_CHN_D_CTRL\" )
			)
			( regionClassClass "@sapphirecity_baseboard_lib.sapphirecity_baseboard(sch_1):\RCC137\"
				( attribute "LINE_TO_LINE_SPACING" "8.00"
					( Origin gBackEnd )
				)
				( regionRef "@sapphirecity_baseboard_lib.sapphirecity_baseboard(sch_1):\CPU_BRKT\" )
				( netClassRef "@sapphirecity_baseboard_lib.sapphirecity_baseboard(sch_1):\DDR4_CHN_D_CLK\" )
				( netClassRef "@sapphirecity_baseboard_lib.sapphirecity_baseboard(sch_1):\DDR4_CHN_D_CMD_ADD\" )
			)
			( regionClassClass "@sapphirecity_baseboard_lib.sapphirecity_baseboard(sch_1):\RCC138\"
				( attribute "LINE_TO_LINE_SPACING" "8.00"
					( Origin gBackEnd )
				)
				( regionRef "@sapphirecity_baseboard_lib.sapphirecity_baseboard(sch_1):\CPU_BRKT\" )
				( netClassRef "@sapphirecity_baseboard_lib.sapphirecity_baseboard(sch_1):\DDR4_CHN_D_CLK\" )
				( netClassRef "@sapphirecity_baseboard_lib.sapphirecity_baseboard(sch_1):\DDR4_CHN_D_CLK\" )
			)
			( regionClassClass "@sapphirecity_baseboard_lib.sapphirecity_baseboard(sch_1):\RCC139\"
				( attribute "LINE_TO_LINE_SPACING" "8.00"
					( Origin gBackEnd )
				)
				( regionRef "@sapphirecity_baseboard_lib.sapphirecity_baseboard(sch_1):\CPU_BRKT\" )
				( netClassRef "@sapphirecity_baseboard_lib.sapphirecity_baseboard(sch_1):\DDR4_CHN_D_CMD_ADD\" )
				( netClassRef "@sapphirecity_baseboard_lib.sapphirecity_baseboard(sch_1):\DDR4_CHN_D_ECC\" )
			)
			( regionClassClass "@sapphirecity_baseboard_lib.sapphirecity_baseboard(sch_1):\RCC140\"
				( attribute "LINE_TO_LINE_SPACING" "8.00"
					( Origin gBackEnd )
				)
				( regionRef "@sapphirecity_baseboard_lib.sapphirecity_baseboard(sch_1):\CPU_BRKT\" )
				( netClassRef "@sapphirecity_baseboard_lib.sapphirecity_baseboard(sch_1):\DDR4_CHN_D_CMD_ADD\" )
				( netClassRef "@sapphirecity_baseboard_lib.sapphirecity_baseboard(sch_1):\DDR4_CHN_D_DQ_DQS_BYTE7\" )
			)
			( regionClassClass "@sapphirecity_baseboard_lib.sapphirecity_baseboard(sch_1):\RCC141\"
				( attribute "LINE_TO_LINE_SPACING" "8.00"
					( Origin gBackEnd )
				)
				( regionRef "@sapphirecity_baseboard_lib.sapphirecity_baseboard(sch_1):\CPU_BRKT\" )
				( netClassRef "@sapphirecity_baseboard_lib.sapphirecity_baseboard(sch_1):\DDR4_CHN_D_CMD_ADD\" )
				( netClassRef "@sapphirecity_baseboard_lib.sapphirecity_baseboard(sch_1):\DDR4_CHN_D_DQ_DQS_BYTE6\" )
			)
			( regionClassClass "@sapphirecity_baseboard_lib.sapphirecity_baseboard(sch_1):\RCC142\"
				( attribute "LINE_TO_LINE_SPACING" "8.00"
					( Origin gBackEnd )
				)
				( regionRef "@sapphirecity_baseboard_lib.sapphirecity_baseboard(sch_1):\CPU_BRKT\" )
				( netClassRef "@sapphirecity_baseboard_lib.sapphirecity_baseboard(sch_1):\DDR4_CHN_D_CMD_ADD\" )
				( netClassRef "@sapphirecity_baseboard_lib.sapphirecity_baseboard(sch_1):\DDR4_CHN_D_DQ_DQS_BYTE5\" )
			)
			( regionClassClass "@sapphirecity_baseboard_lib.sapphirecity_baseboard(sch_1):\RCC143\"
				( attribute "LINE_TO_LINE_SPACING" "8.00"
					( Origin gBackEnd )
				)
				( regionRef "@sapphirecity_baseboard_lib.sapphirecity_baseboard(sch_1):\CPU_BRKT\" )
				( netClassRef "@sapphirecity_baseboard_lib.sapphirecity_baseboard(sch_1):\DDR4_CHN_D_CMD_ADD\" )
				( netClassRef "@sapphirecity_baseboard_lib.sapphirecity_baseboard(sch_1):\DDR4_CHN_D_DQ_DQS_BYTE4\" )
			)
			( regionClassClass "@sapphirecity_baseboard_lib.sapphirecity_baseboard(sch_1):\RCC144\"
				( attribute "LINE_TO_LINE_SPACING" "8.00"
					( Origin gBackEnd )
				)
				( regionRef "@sapphirecity_baseboard_lib.sapphirecity_baseboard(sch_1):\CPU_BRKT\" )
				( netClassRef "@sapphirecity_baseboard_lib.sapphirecity_baseboard(sch_1):\DDR4_CHN_D_CMD_ADD\" )
				( netClassRef "@sapphirecity_baseboard_lib.sapphirecity_baseboard(sch_1):\DDR4_CHN_D_DQ_DQS_BYTE3\" )
			)
			( regionClassClass "@sapphirecity_baseboard_lib.sapphirecity_baseboard(sch_1):\RCC145\"
				( attribute "LINE_TO_LINE_SPACING" "8.00"
					( Origin gBackEnd )
				)
				( regionRef "@sapphirecity_baseboard_lib.sapphirecity_baseboard(sch_1):\CPU_BRKT\" )
				( netClassRef "@sapphirecity_baseboard_lib.sapphirecity_baseboard(sch_1):\DDR4_CHN_D_CMD_ADD\" )
				( netClassRef "@sapphirecity_baseboard_lib.sapphirecity_baseboard(sch_1):\DDR4_CHN_D_DQ_DQS_BYTE2\" )
			)
			( regionClassClass "@sapphirecity_baseboard_lib.sapphirecity_baseboard(sch_1):\RCC146\"
				( attribute "LINE_TO_LINE_SPACING" "8.00"
					( Origin gBackEnd )
				)
				( regionRef "@sapphirecity_baseboard_lib.sapphirecity_baseboard(sch_1):\CPU_BRKT\" )
				( netClassRef "@sapphirecity_baseboard_lib.sapphirecity_baseboard(sch_1):\DDR4_CHN_D_CMD_ADD\" )
				( netClassRef "@sapphirecity_baseboard_lib.sapphirecity_baseboard(sch_1):\DDR4_CHN_D_DQ_DQS_BYTE1\" )
			)
			( regionClassClass "@sapphirecity_baseboard_lib.sapphirecity_baseboard(sch_1):\RCC147\"
				( attribute "LINE_TO_LINE_SPACING" "8.00"
					( Origin gBackEnd )
				)
				( regionRef "@sapphirecity_baseboard_lib.sapphirecity_baseboard(sch_1):\CPU_BRKT\" )
				( netClassRef "@sapphirecity_baseboard_lib.sapphirecity_baseboard(sch_1):\DDR4_CHN_D_CMD_ADD\" )
				( netClassRef "@sapphirecity_baseboard_lib.sapphirecity_baseboard(sch_1):\DDR4_CHN_D_DQ_DQS_BYTE0\" )
			)
			( regionClassClass "@sapphirecity_baseboard_lib.sapphirecity_baseboard(sch_1):\RCC148\"
				( attribute "LINE_TO_LINE_SPACING" "8.00"
					( Origin gBackEnd )
				)
				( regionRef "@sapphirecity_baseboard_lib.sapphirecity_baseboard(sch_1):\CPU_BRKT\" )
				( netClassRef "@sapphirecity_baseboard_lib.sapphirecity_baseboard(sch_1):\DDR4_CHN_D_CMD_ADD\" )
				( netClassRef "@sapphirecity_baseboard_lib.sapphirecity_baseboard(sch_1):\DDR4_CHN_D_CTRL\" )
			)
			( regionClassClass "@sapphirecity_baseboard_lib.sapphirecity_baseboard(sch_1):\RCC149\"
				( attribute "LINE_TO_LINE_SPACING" "8.00"
					( Origin gBackEnd )
				)
				( regionRef "@sapphirecity_baseboard_lib.sapphirecity_baseboard(sch_1):\CPU_BRKT\" )
				( netClassRef "@sapphirecity_baseboard_lib.sapphirecity_baseboard(sch_1):\DDR4_CHN_D_CMD_ADD\" )
				( netClassRef "@sapphirecity_baseboard_lib.sapphirecity_baseboard(sch_1):\DDR4_CHN_D_CMD_ADD\" )
			)
			( regionClassClass "@sapphirecity_baseboard_lib.sapphirecity_baseboard(sch_1):\RCC150\"
				( attribute "LINE_TO_LINE_SPACING" "8.00"
					( Origin gBackEnd )
				)
				( regionRef "@sapphirecity_baseboard_lib.sapphirecity_baseboard(sch_1):\CPU_BRKT\" )
				( netClassRef "@sapphirecity_baseboard_lib.sapphirecity_baseboard(sch_1):\DDR4_CHN_D_CTRL\" )
				( netClassRef "@sapphirecity_baseboard_lib.sapphirecity_baseboard(sch_1):\DDR4_CHN_D_ECC\" )
			)
			( regionClassClass "@sapphirecity_baseboard_lib.sapphirecity_baseboard(sch_1):\RCC151\"
				( attribute "LINE_TO_LINE_SPACING" "8.00"
					( Origin gBackEnd )
				)
				( regionRef "@sapphirecity_baseboard_lib.sapphirecity_baseboard(sch_1):\CPU_BRKT\" )
				( netClassRef "@sapphirecity_baseboard_lib.sapphirecity_baseboard(sch_1):\DDR4_CHN_D_CTRL\" )
				( netClassRef "@sapphirecity_baseboard_lib.sapphirecity_baseboard(sch_1):\DDR4_CHN_D_DQ_DQS_BYTE7\" )
			)
			( regionClassClass "@sapphirecity_baseboard_lib.sapphirecity_baseboard(sch_1):\RCC152\"
				( attribute "LINE_TO_LINE_SPACING" "8.00"
					( Origin gBackEnd )
				)
				( regionRef "@sapphirecity_baseboard_lib.sapphirecity_baseboard(sch_1):\CPU_BRKT\" )
				( netClassRef "@sapphirecity_baseboard_lib.sapphirecity_baseboard(sch_1):\DDR4_CHN_D_CTRL\" )
				( netClassRef "@sapphirecity_baseboard_lib.sapphirecity_baseboard(sch_1):\DDR4_CHN_D_DQ_DQS_BYTE6\" )
			)
			( regionClassClass "@sapphirecity_baseboard_lib.sapphirecity_baseboard(sch_1):\RCC153\"
				( attribute "LINE_TO_LINE_SPACING" "8.00"
					( Origin gBackEnd )
				)
				( regionRef "@sapphirecity_baseboard_lib.sapphirecity_baseboard(sch_1):\CPU_BRKT\" )
				( netClassRef "@sapphirecity_baseboard_lib.sapphirecity_baseboard(sch_1):\DDR4_CHN_D_CTRL\" )
				( netClassRef "@sapphirecity_baseboard_lib.sapphirecity_baseboard(sch_1):\DDR4_CHN_D_DQ_DQS_BYTE5\" )
			)
			( regionClassClass "@sapphirecity_baseboard_lib.sapphirecity_baseboard(sch_1):\RCC154\"
				( attribute "LINE_TO_LINE_SPACING" "8.00"
					( Origin gBackEnd )
				)
				( regionRef "@sapphirecity_baseboard_lib.sapphirecity_baseboard(sch_1):\CPU_BRKT\" )
				( netClassRef "@sapphirecity_baseboard_lib.sapphirecity_baseboard(sch_1):\DDR4_CHN_D_CTRL\" )
				( netClassRef "@sapphirecity_baseboard_lib.sapphirecity_baseboard(sch_1):\DDR4_CHN_D_DQ_DQS_BYTE4\" )
			)
			( regionClassClass "@sapphirecity_baseboard_lib.sapphirecity_baseboard(sch_1):\RCC155\"
				( attribute "LINE_TO_LINE_SPACING" "8.00"
					( Origin gBackEnd )
				)
				( regionRef "@sapphirecity_baseboard_lib.sapphirecity_baseboard(sch_1):\CPU_BRKT\" )
				( netClassRef "@sapphirecity_baseboard_lib.sapphirecity_baseboard(sch_1):\DDR4_CHN_D_CTRL\" )
				( netClassRef "@sapphirecity_baseboard_lib.sapphirecity_baseboard(sch_1):\DDR4_CHN_D_DQ_DQS_BYTE3\" )
			)
			( regionClassClass "@sapphirecity_baseboard_lib.sapphirecity_baseboard(sch_1):\RCC156\"
				( attribute "LINE_TO_LINE_SPACING" "8.00"
					( Origin gBackEnd )
				)
				( regionRef "@sapphirecity_baseboard_lib.sapphirecity_baseboard(sch_1):\CPU_BRKT\" )
				( netClassRef "@sapphirecity_baseboard_lib.sapphirecity_baseboard(sch_1):\DDR4_CHN_D_CTRL\" )
				( netClassRef "@sapphirecity_baseboard_lib.sapphirecity_baseboard(sch_1):\DDR4_CHN_D_DQ_DQS_BYTE2\" )
			)
			( regionClassClass "@sapphirecity_baseboard_lib.sapphirecity_baseboard(sch_1):\RCC157\"
				( attribute "LINE_TO_LINE_SPACING" "8.00"
					( Origin gBackEnd )
				)
				( regionRef "@sapphirecity_baseboard_lib.sapphirecity_baseboard(sch_1):\CPU_BRKT\" )
				( netClassRef "@sapphirecity_baseboard_lib.sapphirecity_baseboard(sch_1):\DDR4_CHN_D_CTRL\" )
				( netClassRef "@sapphirecity_baseboard_lib.sapphirecity_baseboard(sch_1):\DDR4_CHN_D_DQ_DQS_BYTE1\" )
			)
			( regionClassClass "@sapphirecity_baseboard_lib.sapphirecity_baseboard(sch_1):\RCC158\"
				( attribute "LINE_TO_LINE_SPACING" "8.00"
					( Origin gBackEnd )
				)
				( regionRef "@sapphirecity_baseboard_lib.sapphirecity_baseboard(sch_1):\CPU_BRKT\" )
				( netClassRef "@sapphirecity_baseboard_lib.sapphirecity_baseboard(sch_1):\DDR4_CHN_D_CTRL\" )
				( netClassRef "@sapphirecity_baseboard_lib.sapphirecity_baseboard(sch_1):\DDR4_CHN_D_DQ_DQS_BYTE0\" )
			)
			( regionClassClass "@sapphirecity_baseboard_lib.sapphirecity_baseboard(sch_1):\RCC159\"
				( attribute "LINE_TO_LINE_SPACING" "8.00"
					( Origin gBackEnd )
				)
				( regionRef "@sapphirecity_baseboard_lib.sapphirecity_baseboard(sch_1):\CPU_BRKT\" )
				( netClassRef "@sapphirecity_baseboard_lib.sapphirecity_baseboard(sch_1):\DDR4_CHN_D_CTRL\" )
				( netClassRef "@sapphirecity_baseboard_lib.sapphirecity_baseboard(sch_1):\DDR4_CHN_D_CTRL\" )
			)
			( regionClassClass "@sapphirecity_baseboard_lib.sapphirecity_baseboard(sch_1):\RCC160\"
				( attribute "LINE_TO_LINE_SPACING" "8.00"
					( Origin gBackEnd )
				)
				( regionRef "@sapphirecity_baseboard_lib.sapphirecity_baseboard(sch_1):\CPU_BRKT\" )
				( netClassRef "@sapphirecity_baseboard_lib.sapphirecity_baseboard(sch_1):\DDR4_CHN_D_ECC\" )
				( netClassRef "@sapphirecity_baseboard_lib.sapphirecity_baseboard(sch_1):\DDR4_CHN_D_ECC\" )
			)
			( regionClassClass "@sapphirecity_baseboard_lib.sapphirecity_baseboard(sch_1):\RCC161\"
				( attribute "LINE_TO_LINE_SPACING" "8.00"
					( Origin gBackEnd )
				)
				( regionRef "@sapphirecity_baseboard_lib.sapphirecity_baseboard(sch_1):\CPU_BRKT\" )
				( netClassRef "@sapphirecity_baseboard_lib.sapphirecity_baseboard(sch_1):\DDR4_CHN_D_DQ_DQS_BYTE7\" )
				( netClassRef "@sapphirecity_baseboard_lib.sapphirecity_baseboard(sch_1):\DDR4_CHN_D_ECC\" )
			)
			( regionClassClass "@sapphirecity_baseboard_lib.sapphirecity_baseboard(sch_1):\RCC162\"
				( attribute "LINE_TO_LINE_SPACING" "8.00"
					( Origin gBackEnd )
				)
				( regionRef "@sapphirecity_baseboard_lib.sapphirecity_baseboard(sch_1):\CPU_BRKT\" )
				( netClassRef "@sapphirecity_baseboard_lib.sapphirecity_baseboard(sch_1):\DDR4_CHN_D_DQ_DQS_BYTE6\" )
				( netClassRef "@sapphirecity_baseboard_lib.sapphirecity_baseboard(sch_1):\DDR4_CHN_D_ECC\" )
			)
			( regionClassClass "@sapphirecity_baseboard_lib.sapphirecity_baseboard(sch_1):\RCC163\"
				( attribute "LINE_TO_LINE_SPACING" "8.00"
					( Origin gBackEnd )
				)
				( regionRef "@sapphirecity_baseboard_lib.sapphirecity_baseboard(sch_1):\CPU_BRKT\" )
				( netClassRef "@sapphirecity_baseboard_lib.sapphirecity_baseboard(sch_1):\DDR4_CHN_D_DQ_DQS_BYTE5\" )
				( netClassRef "@sapphirecity_baseboard_lib.sapphirecity_baseboard(sch_1):\DDR4_CHN_D_ECC\" )
			)
			( regionClassClass "@sapphirecity_baseboard_lib.sapphirecity_baseboard(sch_1):\RCC164\"
				( attribute "LINE_TO_LINE_SPACING" "8.00"
					( Origin gBackEnd )
				)
				( regionRef "@sapphirecity_baseboard_lib.sapphirecity_baseboard(sch_1):\CPU_BRKT\" )
				( netClassRef "@sapphirecity_baseboard_lib.sapphirecity_baseboard(sch_1):\DDR4_CHN_D_DQ_DQS_BYTE4\" )
				( netClassRef "@sapphirecity_baseboard_lib.sapphirecity_baseboard(sch_1):\DDR4_CHN_D_ECC\" )
			)
			( regionClassClass "@sapphirecity_baseboard_lib.sapphirecity_baseboard(sch_1):\RCC165\"
				( attribute "LINE_TO_LINE_SPACING" "8.00"
					( Origin gBackEnd )
				)
				( regionRef "@sapphirecity_baseboard_lib.sapphirecity_baseboard(sch_1):\CPU_BRKT\" )
				( netClassRef "@sapphirecity_baseboard_lib.sapphirecity_baseboard(sch_1):\DDR4_CHN_D_DQ_DQS_BYTE3\" )
				( netClassRef "@sapphirecity_baseboard_lib.sapphirecity_baseboard(sch_1):\DDR4_CHN_D_ECC\" )
			)
			( regionClassClass "@sapphirecity_baseboard_lib.sapphirecity_baseboard(sch_1):\RCC166\"
				( attribute "LINE_TO_LINE_SPACING" "8.00"
					( Origin gBackEnd )
				)
				( regionRef "@sapphirecity_baseboard_lib.sapphirecity_baseboard(sch_1):\CPU_BRKT\" )
				( netClassRef "@sapphirecity_baseboard_lib.sapphirecity_baseboard(sch_1):\DDR4_CHN_D_DQ_DQS_BYTE2\" )
				( netClassRef "@sapphirecity_baseboard_lib.sapphirecity_baseboard(sch_1):\DDR4_CHN_D_ECC\" )
			)
			( regionClassClass "@sapphirecity_baseboard_lib.sapphirecity_baseboard(sch_1):\RCC167\"
				( attribute "LINE_TO_LINE_SPACING" "8.00"
					( Origin gBackEnd )
				)
				( regionRef "@sapphirecity_baseboard_lib.sapphirecity_baseboard(sch_1):\CPU_BRKT\" )
				( netClassRef "@sapphirecity_baseboard_lib.sapphirecity_baseboard(sch_1):\DDR4_CHN_D_DQ_DQS_BYTE1\" )
				( netClassRef "@sapphirecity_baseboard_lib.sapphirecity_baseboard(sch_1):\DDR4_CHN_D_ECC\" )
			)
			( regionClassClass "@sapphirecity_baseboard_lib.sapphirecity_baseboard(sch_1):\RCC168\"
				( attribute "LINE_TO_LINE_SPACING" "8.00"
					( Origin gBackEnd )
				)
				( regionRef "@sapphirecity_baseboard_lib.sapphirecity_baseboard(sch_1):\CPU_BRKT\" )
				( netClassRef "@sapphirecity_baseboard_lib.sapphirecity_baseboard(sch_1):\DDR4_CHN_D_DQ_DQS_BYTE0\" )
				( netClassRef "@sapphirecity_baseboard_lib.sapphirecity_baseboard(sch_1):\DDR4_CHN_D_ECC\" )
			)
			( regionClassClass "@sapphirecity_baseboard_lib.sapphirecity_baseboard(sch_1):\RCC169\"
				( attribute "LINE_TO_LINE_SPACING" "8.00"
					( Origin gBackEnd )
				)
				( regionRef "@sapphirecity_baseboard_lib.sapphirecity_baseboard(sch_1):\CPU_BRKT\" )
				( netClassRef "@sapphirecity_baseboard_lib.sapphirecity_baseboard(sch_1):\DDR4_CHN_E_CLK\" )
				( netClassRef "@sapphirecity_baseboard_lib.sapphirecity_baseboard(sch_1):\DDR4_CHN_E_ECC\" )
			)
			( regionClassClass "@sapphirecity_baseboard_lib.sapphirecity_baseboard(sch_1):\RCC170\"
				( attribute "LINE_TO_LINE_SPACING" "8.00"
					( Origin gBackEnd )
				)
				( regionRef "@sapphirecity_baseboard_lib.sapphirecity_baseboard(sch_1):\CPU_BRKT\" )
				( netClassRef "@sapphirecity_baseboard_lib.sapphirecity_baseboard(sch_1):\DDR4_CHN_E_CLK\" )
				( netClassRef "@sapphirecity_baseboard_lib.sapphirecity_baseboard(sch_1):\DDR4_CHN_E_DQ_DQS_BYTE7\" )
			)
			( regionClassClass "@sapphirecity_baseboard_lib.sapphirecity_baseboard(sch_1):\RCC171\"
				( attribute "LINE_TO_LINE_SPACING" "8.00"
					( Origin gBackEnd )
				)
				( regionRef "@sapphirecity_baseboard_lib.sapphirecity_baseboard(sch_1):\CPU_BRKT\" )
				( netClassRef "@sapphirecity_baseboard_lib.sapphirecity_baseboard(sch_1):\DDR4_CHN_E_CLK\" )
				( netClassRef "@sapphirecity_baseboard_lib.sapphirecity_baseboard(sch_1):\DDR4_CHN_E_DQ_DQS_BYTE6\" )
			)
			( regionClassClass "@sapphirecity_baseboard_lib.sapphirecity_baseboard(sch_1):\RCC172\"
				( attribute "LINE_TO_LINE_SPACING" "8.00"
					( Origin gBackEnd )
				)
				( regionRef "@sapphirecity_baseboard_lib.sapphirecity_baseboard(sch_1):\CPU_BRKT\" )
				( netClassRef "@sapphirecity_baseboard_lib.sapphirecity_baseboard(sch_1):\DDR4_CHN_E_CLK\" )
				( netClassRef "@sapphirecity_baseboard_lib.sapphirecity_baseboard(sch_1):\DDR4_CHN_E_DQ_DQS_BYTE5\" )
			)
			( regionClassClass "@sapphirecity_baseboard_lib.sapphirecity_baseboard(sch_1):\RCC173\"
				( attribute "LINE_TO_LINE_SPACING" "8.00"
					( Origin gBackEnd )
				)
				( regionRef "@sapphirecity_baseboard_lib.sapphirecity_baseboard(sch_1):\CPU_BRKT\" )
				( netClassRef "@sapphirecity_baseboard_lib.sapphirecity_baseboard(sch_1):\DDR4_CHN_E_CLK\" )
				( netClassRef "@sapphirecity_baseboard_lib.sapphirecity_baseboard(sch_1):\DDR4_CHN_E_DQ_DQS_BYTE4\" )
			)
			( regionClassClass "@sapphirecity_baseboard_lib.sapphirecity_baseboard(sch_1):\RCC174\"
				( attribute "LINE_TO_LINE_SPACING" "8.00"
					( Origin gBackEnd )
				)
				( regionRef "@sapphirecity_baseboard_lib.sapphirecity_baseboard(sch_1):\CPU_BRKT\" )
				( netClassRef "@sapphirecity_baseboard_lib.sapphirecity_baseboard(sch_1):\DDR4_CHN_E_CLK\" )
				( netClassRef "@sapphirecity_baseboard_lib.sapphirecity_baseboard(sch_1):\DDR4_CHN_E_DQ_DQS_BYTE3\" )
			)
			( regionClassClass "@sapphirecity_baseboard_lib.sapphirecity_baseboard(sch_1):\RCC175\"
				( attribute "LINE_TO_LINE_SPACING" "8.00"
					( Origin gBackEnd )
				)
				( regionRef "@sapphirecity_baseboard_lib.sapphirecity_baseboard(sch_1):\CPU_BRKT\" )
				( netClassRef "@sapphirecity_baseboard_lib.sapphirecity_baseboard(sch_1):\DDR4_CHN_E_CLK\" )
				( netClassRef "@sapphirecity_baseboard_lib.sapphirecity_baseboard(sch_1):\DDR4_CHN_E_DQ_DQS_BYTE2\" )
			)
			( regionClassClass "@sapphirecity_baseboard_lib.sapphirecity_baseboard(sch_1):\RCC176\"
				( attribute "LINE_TO_LINE_SPACING" "8.00"
					( Origin gBackEnd )
				)
				( regionRef "@sapphirecity_baseboard_lib.sapphirecity_baseboard(sch_1):\CPU_BRKT\" )
				( netClassRef "@sapphirecity_baseboard_lib.sapphirecity_baseboard(sch_1):\DDR4_CHN_E_CLK\" )
				( netClassRef "@sapphirecity_baseboard_lib.sapphirecity_baseboard(sch_1):\DDR4_CHN_E_DQ_DQS_BYTE1\" )
			)
			( regionClassClass "@sapphirecity_baseboard_lib.sapphirecity_baseboard(sch_1):\RCC177\"
				( attribute "LINE_TO_LINE_SPACING" "8.00"
					( Origin gBackEnd )
				)
				( regionRef "@sapphirecity_baseboard_lib.sapphirecity_baseboard(sch_1):\CPU_BRKT\" )
				( netClassRef "@sapphirecity_baseboard_lib.sapphirecity_baseboard(sch_1):\DDR4_CHN_E_CLK\" )
				( netClassRef "@sapphirecity_baseboard_lib.sapphirecity_baseboard(sch_1):\DDR4_CHN_E_DQ_DQS_BYTE0\" )
			)
			( regionClassClass "@sapphirecity_baseboard_lib.sapphirecity_baseboard(sch_1):\RCC178\"
				( attribute "LINE_TO_LINE_SPACING" "8.00"
					( Origin gBackEnd )
				)
				( regionRef "@sapphirecity_baseboard_lib.sapphirecity_baseboard(sch_1):\CPU_BRKT\" )
				( netClassRef "@sapphirecity_baseboard_lib.sapphirecity_baseboard(sch_1):\DDR4_CHN_E_CLK\" )
				( netClassRef "@sapphirecity_baseboard_lib.sapphirecity_baseboard(sch_1):\DDR4_CHN_E_CTRL\" )
			)
			( regionClassClass "@sapphirecity_baseboard_lib.sapphirecity_baseboard(sch_1):\RCC179\"
				( attribute "LINE_TO_LINE_SPACING" "8.00"
					( Origin gBackEnd )
				)
				( regionRef "@sapphirecity_baseboard_lib.sapphirecity_baseboard(sch_1):\CPU_BRKT\" )
				( netClassRef "@sapphirecity_baseboard_lib.sapphirecity_baseboard(sch_1):\DDR4_CHN_E_CLK\" )
				( netClassRef "@sapphirecity_baseboard_lib.sapphirecity_baseboard(sch_1):\DDR4_CHN_E_CMD_ADD\" )
			)
			( regionClassClass "@sapphirecity_baseboard_lib.sapphirecity_baseboard(sch_1):\RCC180\"
				( attribute "LINE_TO_LINE_SPACING" "8.00"
					( Origin gBackEnd )
				)
				( regionRef "@sapphirecity_baseboard_lib.sapphirecity_baseboard(sch_1):\CPU_BRKT\" )
				( netClassRef "@sapphirecity_baseboard_lib.sapphirecity_baseboard(sch_1):\DDR4_CHN_E_CLK\" )
				( netClassRef "@sapphirecity_baseboard_lib.sapphirecity_baseboard(sch_1):\DDR4_CHN_E_CLK\" )
			)
			( regionClassClass "@sapphirecity_baseboard_lib.sapphirecity_baseboard(sch_1):\RCC181\"
				( attribute "LINE_TO_LINE_SPACING" "8.00"
					( Origin gBackEnd )
				)
				( regionRef "@sapphirecity_baseboard_lib.sapphirecity_baseboard(sch_1):\CPU_BRKT\" )
				( netClassRef "@sapphirecity_baseboard_lib.sapphirecity_baseboard(sch_1):\DDR4_CHN_E_CMD_ADD\" )
				( netClassRef "@sapphirecity_baseboard_lib.sapphirecity_baseboard(sch_1):\DDR4_CHN_E_ECC\" )
			)
			( regionClassClass "@sapphirecity_baseboard_lib.sapphirecity_baseboard(sch_1):\RCC182\"
				( attribute "LINE_TO_LINE_SPACING" "8.00"
					( Origin gBackEnd )
				)
				( regionRef "@sapphirecity_baseboard_lib.sapphirecity_baseboard(sch_1):\CPU_BRKT\" )
				( netClassRef "@sapphirecity_baseboard_lib.sapphirecity_baseboard(sch_1):\DDR4_CHN_E_CMD_ADD\" )
				( netClassRef "@sapphirecity_baseboard_lib.sapphirecity_baseboard(sch_1):\DDR4_CHN_E_DQ_DQS_BYTE7\" )
			)
			( regionClassClass "@sapphirecity_baseboard_lib.sapphirecity_baseboard(sch_1):\RCC183\"
				( attribute "LINE_TO_LINE_SPACING" "8.00"
					( Origin gBackEnd )
				)
				( regionRef "@sapphirecity_baseboard_lib.sapphirecity_baseboard(sch_1):\CPU_BRKT\" )
				( netClassRef "@sapphirecity_baseboard_lib.sapphirecity_baseboard(sch_1):\DDR4_CHN_E_CMD_ADD\" )
				( netClassRef "@sapphirecity_baseboard_lib.sapphirecity_baseboard(sch_1):\DDR4_CHN_E_DQ_DQS_BYTE6\" )
			)
			( regionClassClass "@sapphirecity_baseboard_lib.sapphirecity_baseboard(sch_1):\RCC184\"
				( attribute "LINE_TO_LINE_SPACING" "8.00"
					( Origin gBackEnd )
				)
				( regionRef "@sapphirecity_baseboard_lib.sapphirecity_baseboard(sch_1):\CPU_BRKT\" )
				( netClassRef "@sapphirecity_baseboard_lib.sapphirecity_baseboard(sch_1):\DDR4_CHN_E_CMD_ADD\" )
				( netClassRef "@sapphirecity_baseboard_lib.sapphirecity_baseboard(sch_1):\DDR4_CHN_E_DQ_DQS_BYTE5\" )
			)
			( regionClassClass "@sapphirecity_baseboard_lib.sapphirecity_baseboard(sch_1):\RCC185\"
				( attribute "LINE_TO_LINE_SPACING" "8.00"
					( Origin gBackEnd )
				)
				( regionRef "@sapphirecity_baseboard_lib.sapphirecity_baseboard(sch_1):\CPU_BRKT\" )
				( netClassRef "@sapphirecity_baseboard_lib.sapphirecity_baseboard(sch_1):\DDR4_CHN_E_CMD_ADD\" )
				( netClassRef "@sapphirecity_baseboard_lib.sapphirecity_baseboard(sch_1):\DDR4_CHN_E_DQ_DQS_BYTE4\" )
			)
			( regionClassClass "@sapphirecity_baseboard_lib.sapphirecity_baseboard(sch_1):\RCC186\"
				( attribute "LINE_TO_LINE_SPACING" "8.00"
					( Origin gBackEnd )
				)
				( regionRef "@sapphirecity_baseboard_lib.sapphirecity_baseboard(sch_1):\CPU_BRKT\" )
				( netClassRef "@sapphirecity_baseboard_lib.sapphirecity_baseboard(sch_1):\DDR4_CHN_E_CMD_ADD\" )
				( netClassRef "@sapphirecity_baseboard_lib.sapphirecity_baseboard(sch_1):\DDR4_CHN_E_DQ_DQS_BYTE3\" )
			)
			( regionClassClass "@sapphirecity_baseboard_lib.sapphirecity_baseboard(sch_1):\RCC187\"
				( attribute "LINE_TO_LINE_SPACING" "8.00"
					( Origin gBackEnd )
				)
				( regionRef "@sapphirecity_baseboard_lib.sapphirecity_baseboard(sch_1):\CPU_BRKT\" )
				( netClassRef "@sapphirecity_baseboard_lib.sapphirecity_baseboard(sch_1):\DDR4_CHN_E_CMD_ADD\" )
				( netClassRef "@sapphirecity_baseboard_lib.sapphirecity_baseboard(sch_1):\DDR4_CHN_E_DQ_DQS_BYTE2\" )
			)
			( regionClassClass "@sapphirecity_baseboard_lib.sapphirecity_baseboard(sch_1):\RCC188\"
				( attribute "LINE_TO_LINE_SPACING" "8.00"
					( Origin gBackEnd )
				)
				( regionRef "@sapphirecity_baseboard_lib.sapphirecity_baseboard(sch_1):\CPU_BRKT\" )
				( netClassRef "@sapphirecity_baseboard_lib.sapphirecity_baseboard(sch_1):\DDR4_CHN_E_CMD_ADD\" )
				( netClassRef "@sapphirecity_baseboard_lib.sapphirecity_baseboard(sch_1):\DDR4_CHN_E_DQ_DQS_BYTE1\" )
			)
			( regionClassClass "@sapphirecity_baseboard_lib.sapphirecity_baseboard(sch_1):\RCC189\"
				( attribute "LINE_TO_LINE_SPACING" "8.00"
					( Origin gBackEnd )
				)
				( regionRef "@sapphirecity_baseboard_lib.sapphirecity_baseboard(sch_1):\CPU_BRKT\" )
				( netClassRef "@sapphirecity_baseboard_lib.sapphirecity_baseboard(sch_1):\DDR4_CHN_E_CMD_ADD\" )
				( netClassRef "@sapphirecity_baseboard_lib.sapphirecity_baseboard(sch_1):\DDR4_CHN_E_DQ_DQS_BYTE0\" )
			)
			( regionClassClass "@sapphirecity_baseboard_lib.sapphirecity_baseboard(sch_1):\RCC190\"
				( attribute "LINE_TO_LINE_SPACING" "8.00"
					( Origin gBackEnd )
				)
				( regionRef "@sapphirecity_baseboard_lib.sapphirecity_baseboard(sch_1):\CPU_BRKT\" )
				( netClassRef "@sapphirecity_baseboard_lib.sapphirecity_baseboard(sch_1):\DDR4_CHN_E_CMD_ADD\" )
				( netClassRef "@sapphirecity_baseboard_lib.sapphirecity_baseboard(sch_1):\DDR4_CHN_E_CTRL\" )
			)
			( regionClassClass "@sapphirecity_baseboard_lib.sapphirecity_baseboard(sch_1):\RCC191\"
				( attribute "LINE_TO_LINE_SPACING" "8.00"
					( Origin gBackEnd )
				)
				( regionRef "@sapphirecity_baseboard_lib.sapphirecity_baseboard(sch_1):\CPU_BRKT\" )
				( netClassRef "@sapphirecity_baseboard_lib.sapphirecity_baseboard(sch_1):\DDR4_CHN_E_CMD_ADD\" )
				( netClassRef "@sapphirecity_baseboard_lib.sapphirecity_baseboard(sch_1):\DDR4_CHN_E_CMD_ADD\" )
			)
			( regionClassClass "@sapphirecity_baseboard_lib.sapphirecity_baseboard(sch_1):\RCC192\"
				( attribute "LINE_TO_LINE_SPACING" "8.00"
					( Origin gBackEnd )
				)
				( regionRef "@sapphirecity_baseboard_lib.sapphirecity_baseboard(sch_1):\CPU_BRKT\" )
				( netClassRef "@sapphirecity_baseboard_lib.sapphirecity_baseboard(sch_1):\DDR4_CHN_E_CTRL\" )
				( netClassRef "@sapphirecity_baseboard_lib.sapphirecity_baseboard(sch_1):\DDR4_CHN_E_ECC\" )
			)
			( regionClassClass "@sapphirecity_baseboard_lib.sapphirecity_baseboard(sch_1):\RCC193\"
				( attribute "LINE_TO_LINE_SPACING" "8.00"
					( Origin gBackEnd )
				)
				( regionRef "@sapphirecity_baseboard_lib.sapphirecity_baseboard(sch_1):\CPU_BRKT\" )
				( netClassRef "@sapphirecity_baseboard_lib.sapphirecity_baseboard(sch_1):\DDR4_CHN_E_CTRL\" )
				( netClassRef "@sapphirecity_baseboard_lib.sapphirecity_baseboard(sch_1):\DDR4_CHN_E_DQ_DQS_BYTE7\" )
			)
			( regionClassClass "@sapphirecity_baseboard_lib.sapphirecity_baseboard(sch_1):\RCC194\"
				( attribute "LINE_TO_LINE_SPACING" "8.00"
					( Origin gBackEnd )
				)
				( regionRef "@sapphirecity_baseboard_lib.sapphirecity_baseboard(sch_1):\CPU_BRKT\" )
				( netClassRef "@sapphirecity_baseboard_lib.sapphirecity_baseboard(sch_1):\DDR4_CHN_E_CTRL\" )
				( netClassRef "@sapphirecity_baseboard_lib.sapphirecity_baseboard(sch_1):\DDR4_CHN_E_DQ_DQS_BYTE6\" )
			)
			( regionClassClass "@sapphirecity_baseboard_lib.sapphirecity_baseboard(sch_1):\RCC195\"
				( attribute "LINE_TO_LINE_SPACING" "8.00"
					( Origin gBackEnd )
				)
				( regionRef "@sapphirecity_baseboard_lib.sapphirecity_baseboard(sch_1):\CPU_BRKT\" )
				( netClassRef "@sapphirecity_baseboard_lib.sapphirecity_baseboard(sch_1):\DDR4_CHN_E_CTRL\" )
				( netClassRef "@sapphirecity_baseboard_lib.sapphirecity_baseboard(sch_1):\DDR4_CHN_E_DQ_DQS_BYTE5\" )
			)
			( regionClassClass "@sapphirecity_baseboard_lib.sapphirecity_baseboard(sch_1):\RCC196\"
				( attribute "LINE_TO_LINE_SPACING" "8.00"
					( Origin gBackEnd )
				)
				( regionRef "@sapphirecity_baseboard_lib.sapphirecity_baseboard(sch_1):\CPU_BRKT\" )
				( netClassRef "@sapphirecity_baseboard_lib.sapphirecity_baseboard(sch_1):\DDR4_CHN_E_CTRL\" )
				( netClassRef "@sapphirecity_baseboard_lib.sapphirecity_baseboard(sch_1):\DDR4_CHN_E_DQ_DQS_BYTE4\" )
			)
			( regionClassClass "@sapphirecity_baseboard_lib.sapphirecity_baseboard(sch_1):\RCC197\"
				( attribute "LINE_TO_LINE_SPACING" "8.00"
					( Origin gBackEnd )
				)
				( regionRef "@sapphirecity_baseboard_lib.sapphirecity_baseboard(sch_1):\CPU_BRKT\" )
				( netClassRef "@sapphirecity_baseboard_lib.sapphirecity_baseboard(sch_1):\DDR4_CHN_E_CTRL\" )
				( netClassRef "@sapphirecity_baseboard_lib.sapphirecity_baseboard(sch_1):\DDR4_CHN_E_DQ_DQS_BYTE3\" )
			)
			( regionClassClass "@sapphirecity_baseboard_lib.sapphirecity_baseboard(sch_1):\RCC198\"
				( attribute "LINE_TO_LINE_SPACING" "8.00"
					( Origin gBackEnd )
				)
				( regionRef "@sapphirecity_baseboard_lib.sapphirecity_baseboard(sch_1):\CPU_BRKT\" )
				( netClassRef "@sapphirecity_baseboard_lib.sapphirecity_baseboard(sch_1):\DDR4_CHN_E_CTRL\" )
				( netClassRef "@sapphirecity_baseboard_lib.sapphirecity_baseboard(sch_1):\DDR4_CHN_E_DQ_DQS_BYTE2\" )
			)
			( regionClassClass "@sapphirecity_baseboard_lib.sapphirecity_baseboard(sch_1):\RCC199\"
				( attribute "LINE_TO_LINE_SPACING" "8.00"
					( Origin gBackEnd )
				)
				( regionRef "@sapphirecity_baseboard_lib.sapphirecity_baseboard(sch_1):\CPU_BRKT\" )
				( netClassRef "@sapphirecity_baseboard_lib.sapphirecity_baseboard(sch_1):\DDR4_CHN_E_CTRL\" )
				( netClassRef "@sapphirecity_baseboard_lib.sapphirecity_baseboard(sch_1):\DDR4_CHN_E_DQ_DQS_BYTE1\" )
			)
			( regionClassClass "@sapphirecity_baseboard_lib.sapphirecity_baseboard(sch_1):\RCC200\"
				( attribute "LINE_TO_LINE_SPACING" "8.00"
					( Origin gBackEnd )
				)
				( regionRef "@sapphirecity_baseboard_lib.sapphirecity_baseboard(sch_1):\CPU_BRKT\" )
				( netClassRef "@sapphirecity_baseboard_lib.sapphirecity_baseboard(sch_1):\DDR4_CHN_E_CTRL\" )
				( netClassRef "@sapphirecity_baseboard_lib.sapphirecity_baseboard(sch_1):\DDR4_CHN_E_DQ_DQS_BYTE0\" )
			)
			( regionClassClass "@sapphirecity_baseboard_lib.sapphirecity_baseboard(sch_1):\RCC201\"
				( attribute "LINE_TO_LINE_SPACING" "8.00"
					( Origin gBackEnd )
				)
				( regionRef "@sapphirecity_baseboard_lib.sapphirecity_baseboard(sch_1):\CPU_BRKT\" )
				( netClassRef "@sapphirecity_baseboard_lib.sapphirecity_baseboard(sch_1):\DDR4_CHN_E_CTRL\" )
				( netClassRef "@sapphirecity_baseboard_lib.sapphirecity_baseboard(sch_1):\DDR4_CHN_E_CTRL\" )
			)
			( regionClassClass "@sapphirecity_baseboard_lib.sapphirecity_baseboard(sch_1):\RCC202\"
				( attribute "LINE_TO_LINE_SPACING" "8.00"
					( Origin gBackEnd )
				)
				( regionRef "@sapphirecity_baseboard_lib.sapphirecity_baseboard(sch_1):\CPU_BRKT\" )
				( netClassRef "@sapphirecity_baseboard_lib.sapphirecity_baseboard(sch_1):\DDR4_CHN_E_DQ_DQS_BYTE0\" )
				( netClassRef "@sapphirecity_baseboard_lib.sapphirecity_baseboard(sch_1):\DDR4_CHN_E_ECC\" )
			)
			( regionClassClass "@sapphirecity_baseboard_lib.sapphirecity_baseboard(sch_1):\RCC203\"
				( attribute "LINE_TO_LINE_SPACING" "8.00"
					( Origin gBackEnd )
				)
				( regionRef "@sapphirecity_baseboard_lib.sapphirecity_baseboard(sch_1):\CPU_BRKT\" )
				( netClassRef "@sapphirecity_baseboard_lib.sapphirecity_baseboard(sch_1):\DDR4_CHN_E_DQ_DQS_BYTE0\" )
				( netClassRef "@sapphirecity_baseboard_lib.sapphirecity_baseboard(sch_1):\DDR4_CHN_E_DQ_DQS_BYTE7\" )
			)
			( regionClassClass "@sapphirecity_baseboard_lib.sapphirecity_baseboard(sch_1):\RCC204\"
				( attribute "LINE_TO_LINE_SPACING" "8.00"
					( Origin gBackEnd )
				)
				( regionRef "@sapphirecity_baseboard_lib.sapphirecity_baseboard(sch_1):\CPU_BRKT\" )
				( netClassRef "@sapphirecity_baseboard_lib.sapphirecity_baseboard(sch_1):\DDR4_CHN_E_DQ_DQS_BYTE0\" )
				( netClassRef "@sapphirecity_baseboard_lib.sapphirecity_baseboard(sch_1):\DDR4_CHN_E_DQ_DQS_BYTE6\" )
			)
			( regionClassClass "@sapphirecity_baseboard_lib.sapphirecity_baseboard(sch_1):\RCC205\"
				( attribute "LINE_TO_LINE_SPACING" "8.00"
					( Origin gBackEnd )
				)
				( regionRef "@sapphirecity_baseboard_lib.sapphirecity_baseboard(sch_1):\CPU_BRKT\" )
				( netClassRef "@sapphirecity_baseboard_lib.sapphirecity_baseboard(sch_1):\DDR4_CHN_E_DQ_DQS_BYTE0\" )
				( netClassRef "@sapphirecity_baseboard_lib.sapphirecity_baseboard(sch_1):\DDR4_CHN_E_DQ_DQS_BYTE5\" )
			)
			( regionClassClass "@sapphirecity_baseboard_lib.sapphirecity_baseboard(sch_1):\RCC206\"
				( attribute "LINE_TO_LINE_SPACING" "8.00"
					( Origin gBackEnd )
				)
				( regionRef "@sapphirecity_baseboard_lib.sapphirecity_baseboard(sch_1):\CPU_BRKT\" )
				( netClassRef "@sapphirecity_baseboard_lib.sapphirecity_baseboard(sch_1):\DDR4_CHN_E_DQ_DQS_BYTE0\" )
				( netClassRef "@sapphirecity_baseboard_lib.sapphirecity_baseboard(sch_1):\DDR4_CHN_E_DQ_DQS_BYTE4\" )
			)
			( regionClassClass "@sapphirecity_baseboard_lib.sapphirecity_baseboard(sch_1):\RCC207\"
				( attribute "LINE_TO_LINE_SPACING" "8.00"
					( Origin gBackEnd )
				)
				( regionRef "@sapphirecity_baseboard_lib.sapphirecity_baseboard(sch_1):\CPU_BRKT\" )
				( netClassRef "@sapphirecity_baseboard_lib.sapphirecity_baseboard(sch_1):\DDR4_CHN_E_DQ_DQS_BYTE0\" )
				( netClassRef "@sapphirecity_baseboard_lib.sapphirecity_baseboard(sch_1):\DDR4_CHN_E_DQ_DQS_BYTE3\" )
			)
			( regionClassClass "@sapphirecity_baseboard_lib.sapphirecity_baseboard(sch_1):\RCC208\"
				( attribute "LINE_TO_LINE_SPACING" "8.00"
					( Origin gBackEnd )
				)
				( regionRef "@sapphirecity_baseboard_lib.sapphirecity_baseboard(sch_1):\CPU_BRKT\" )
				( netClassRef "@sapphirecity_baseboard_lib.sapphirecity_baseboard(sch_1):\DDR4_CHN_E_DQ_DQS_BYTE0\" )
				( netClassRef "@sapphirecity_baseboard_lib.sapphirecity_baseboard(sch_1):\DDR4_CHN_E_DQ_DQS_BYTE2\" )
			)
			( regionClassClass "@sapphirecity_baseboard_lib.sapphirecity_baseboard(sch_1):\RCC209\"
				( attribute "LINE_TO_LINE_SPACING" "8.00"
					( Origin gBackEnd )
				)
				( regionRef "@sapphirecity_baseboard_lib.sapphirecity_baseboard(sch_1):\CPU_BRKT\" )
				( netClassRef "@sapphirecity_baseboard_lib.sapphirecity_baseboard(sch_1):\DDR4_CHN_E_DQ_DQS_BYTE0\" )
				( netClassRef "@sapphirecity_baseboard_lib.sapphirecity_baseboard(sch_1):\DDR4_CHN_E_DQ_DQS_BYTE1\" )
			)
			( regionClassClass "@sapphirecity_baseboard_lib.sapphirecity_baseboard(sch_1):\RCC210\"
				( attribute "LINE_TO_LINE_SPACING" "8.00"
					( Origin gBackEnd )
				)
				( regionRef "@sapphirecity_baseboard_lib.sapphirecity_baseboard(sch_1):\CPU_BRKT\" )
				( netClassRef "@sapphirecity_baseboard_lib.sapphirecity_baseboard(sch_1):\DDR4_CHN_E_DQ_DQS_BYTE0\" )
				( netClassRef "@sapphirecity_baseboard_lib.sapphirecity_baseboard(sch_1):\DDR4_CHN_E_DQ_DQS_BYTE0\" )
			)
			( regionClassClass "@sapphirecity_baseboard_lib.sapphirecity_baseboard(sch_1):\RCC211\"
				( attribute "LINE_TO_LINE_SPACING" "8.00"
					( Origin gBackEnd )
				)
				( regionRef "@sapphirecity_baseboard_lib.sapphirecity_baseboard(sch_1):\CPU_BRKT\" )
				( netClassRef "@sapphirecity_baseboard_lib.sapphirecity_baseboard(sch_1):\DDR4_CHN_E_DQ_DQS_BYTE1\" )
				( netClassRef "@sapphirecity_baseboard_lib.sapphirecity_baseboard(sch_1):\DDR4_CHN_E_ECC\" )
			)
			( regionClassClass "@sapphirecity_baseboard_lib.sapphirecity_baseboard(sch_1):\RCC212\"
				( attribute "LINE_TO_LINE_SPACING" "8.00"
					( Origin gBackEnd )
				)
				( regionRef "@sapphirecity_baseboard_lib.sapphirecity_baseboard(sch_1):\CPU_BRKT\" )
				( netClassRef "@sapphirecity_baseboard_lib.sapphirecity_baseboard(sch_1):\DDR4_CHN_E_DQ_DQS_BYTE1\" )
				( netClassRef "@sapphirecity_baseboard_lib.sapphirecity_baseboard(sch_1):\DDR4_CHN_E_DQ_DQS_BYTE7\" )
			)
			( regionClassClass "@sapphirecity_baseboard_lib.sapphirecity_baseboard(sch_1):\RCC213\"
				( attribute "LINE_TO_LINE_SPACING" "8.00"
					( Origin gBackEnd )
				)
				( regionRef "@sapphirecity_baseboard_lib.sapphirecity_baseboard(sch_1):\CPU_BRKT\" )
				( netClassRef "@sapphirecity_baseboard_lib.sapphirecity_baseboard(sch_1):\DDR4_CHN_E_DQ_DQS_BYTE1\" )
				( netClassRef "@sapphirecity_baseboard_lib.sapphirecity_baseboard(sch_1):\DDR4_CHN_E_DQ_DQS_BYTE6\" )
			)
			( regionClassClass "@sapphirecity_baseboard_lib.sapphirecity_baseboard(sch_1):\RCC214\"
				( attribute "LINE_TO_LINE_SPACING" "8.00"
					( Origin gBackEnd )
				)
				( regionRef "@sapphirecity_baseboard_lib.sapphirecity_baseboard(sch_1):\CPU_BRKT\" )
				( netClassRef "@sapphirecity_baseboard_lib.sapphirecity_baseboard(sch_1):\DDR4_CHN_E_DQ_DQS_BYTE1\" )
				( netClassRef "@sapphirecity_baseboard_lib.sapphirecity_baseboard(sch_1):\DDR4_CHN_E_DQ_DQS_BYTE5\" )
			)
			( regionClassClass "@sapphirecity_baseboard_lib.sapphirecity_baseboard(sch_1):\RCC215\"
				( attribute "LINE_TO_LINE_SPACING" "8.00"
					( Origin gBackEnd )
				)
				( regionRef "@sapphirecity_baseboard_lib.sapphirecity_baseboard(sch_1):\CPU_BRKT\" )
				( netClassRef "@sapphirecity_baseboard_lib.sapphirecity_baseboard(sch_1):\DDR4_CHN_E_DQ_DQS_BYTE1\" )
				( netClassRef "@sapphirecity_baseboard_lib.sapphirecity_baseboard(sch_1):\DDR4_CHN_E_DQ_DQS_BYTE4\" )
			)
			( regionClassClass "@sapphirecity_baseboard_lib.sapphirecity_baseboard(sch_1):\RCC216\"
				( attribute "LINE_TO_LINE_SPACING" "8.00"
					( Origin gBackEnd )
				)
				( regionRef "@sapphirecity_baseboard_lib.sapphirecity_baseboard(sch_1):\CPU_BRKT\" )
				( netClassRef "@sapphirecity_baseboard_lib.sapphirecity_baseboard(sch_1):\DDR4_CHN_E_DQ_DQS_BYTE1\" )
				( netClassRef "@sapphirecity_baseboard_lib.sapphirecity_baseboard(sch_1):\DDR4_CHN_E_DQ_DQS_BYTE3\" )
			)
			( regionClassClass "@sapphirecity_baseboard_lib.sapphirecity_baseboard(sch_1):\RCC217\"
				( attribute "LINE_TO_LINE_SPACING" "8.00"
					( Origin gBackEnd )
				)
				( regionRef "@sapphirecity_baseboard_lib.sapphirecity_baseboard(sch_1):\CPU_BRKT\" )
				( netClassRef "@sapphirecity_baseboard_lib.sapphirecity_baseboard(sch_1):\DDR4_CHN_E_DQ_DQS_BYTE1\" )
				( netClassRef "@sapphirecity_baseboard_lib.sapphirecity_baseboard(sch_1):\DDR4_CHN_E_DQ_DQS_BYTE2\" )
			)
			( regionClassClass "@sapphirecity_baseboard_lib.sapphirecity_baseboard(sch_1):\RCC218\"
				( attribute "LINE_TO_LINE_SPACING" "8.00"
					( Origin gBackEnd )
				)
				( regionRef "@sapphirecity_baseboard_lib.sapphirecity_baseboard(sch_1):\CPU_BRKT\" )
				( netClassRef "@sapphirecity_baseboard_lib.sapphirecity_baseboard(sch_1):\DDR4_CHN_E_DQ_DQS_BYTE1\" )
				( netClassRef "@sapphirecity_baseboard_lib.sapphirecity_baseboard(sch_1):\DDR4_CHN_E_DQ_DQS_BYTE1\" )
			)
			( regionClassClass "@sapphirecity_baseboard_lib.sapphirecity_baseboard(sch_1):\RCC219\"
				( attribute "LINE_TO_LINE_SPACING" "8.00"
					( Origin gBackEnd )
				)
				( regionRef "@sapphirecity_baseboard_lib.sapphirecity_baseboard(sch_1):\CPU_BRKT\" )
				( netClassRef "@sapphirecity_baseboard_lib.sapphirecity_baseboard(sch_1):\DDR4_CHN_E_DQ_DQS_BYTE2\" )
				( netClassRef "@sapphirecity_baseboard_lib.sapphirecity_baseboard(sch_1):\DDR4_CHN_E_ECC\" )
			)
			( regionClassClass "@sapphirecity_baseboard_lib.sapphirecity_baseboard(sch_1):\RCC220\"
				( attribute "LINE_TO_LINE_SPACING" "8.00"
					( Origin gBackEnd )
				)
				( regionRef "@sapphirecity_baseboard_lib.sapphirecity_baseboard(sch_1):\CPU_BRKT\" )
				( netClassRef "@sapphirecity_baseboard_lib.sapphirecity_baseboard(sch_1):\DDR4_CHN_E_DQ_DQS_BYTE2\" )
				( netClassRef "@sapphirecity_baseboard_lib.sapphirecity_baseboard(sch_1):\DDR4_CHN_E_DQ_DQS_BYTE7\" )
			)
			( regionClassClass "@sapphirecity_baseboard_lib.sapphirecity_baseboard(sch_1):\RCC221\"
				( attribute "LINE_TO_LINE_SPACING" "8.00"
					( Origin gBackEnd )
				)
				( regionRef "@sapphirecity_baseboard_lib.sapphirecity_baseboard(sch_1):\CPU_BRKT\" )
				( netClassRef "@sapphirecity_baseboard_lib.sapphirecity_baseboard(sch_1):\DDR4_CHN_E_DQ_DQS_BYTE2\" )
				( netClassRef "@sapphirecity_baseboard_lib.sapphirecity_baseboard(sch_1):\DDR4_CHN_E_DQ_DQS_BYTE6\" )
			)
			( regionClassClass "@sapphirecity_baseboard_lib.sapphirecity_baseboard(sch_1):\RCC222\"
				( attribute "LINE_TO_LINE_SPACING" "8.00"
					( Origin gBackEnd )
				)
				( regionRef "@sapphirecity_baseboard_lib.sapphirecity_baseboard(sch_1):\CPU_BRKT\" )
				( netClassRef "@sapphirecity_baseboard_lib.sapphirecity_baseboard(sch_1):\DDR4_CHN_E_DQ_DQS_BYTE2\" )
				( netClassRef "@sapphirecity_baseboard_lib.sapphirecity_baseboard(sch_1):\DDR4_CHN_E_DQ_DQS_BYTE5\" )
			)
			( regionClassClass "@sapphirecity_baseboard_lib.sapphirecity_baseboard(sch_1):\RCC223\"
				( attribute "LINE_TO_LINE_SPACING" "8.00"
					( Origin gBackEnd )
				)
				( regionRef "@sapphirecity_baseboard_lib.sapphirecity_baseboard(sch_1):\CPU_BRKT\" )
				( netClassRef "@sapphirecity_baseboard_lib.sapphirecity_baseboard(sch_1):\DDR4_CHN_E_DQ_DQS_BYTE2\" )
				( netClassRef "@sapphirecity_baseboard_lib.sapphirecity_baseboard(sch_1):\DDR4_CHN_E_DQ_DQS_BYTE4\" )
			)
			( regionClassClass "@sapphirecity_baseboard_lib.sapphirecity_baseboard(sch_1):\RCC224\"
				( attribute "LINE_TO_LINE_SPACING" "8.00"
					( Origin gBackEnd )
				)
				( regionRef "@sapphirecity_baseboard_lib.sapphirecity_baseboard(sch_1):\CPU_BRKT\" )
				( netClassRef "@sapphirecity_baseboard_lib.sapphirecity_baseboard(sch_1):\DDR4_CHN_E_DQ_DQS_BYTE2\" )
				( netClassRef "@sapphirecity_baseboard_lib.sapphirecity_baseboard(sch_1):\DDR4_CHN_E_DQ_DQS_BYTE3\" )
			)
			( regionClassClass "@sapphirecity_baseboard_lib.sapphirecity_baseboard(sch_1):\RCC225\"
				( attribute "LINE_TO_LINE_SPACING" "8.00"
					( Origin gBackEnd )
				)
				( regionRef "@sapphirecity_baseboard_lib.sapphirecity_baseboard(sch_1):\CPU_BRKT\" )
				( netClassRef "@sapphirecity_baseboard_lib.sapphirecity_baseboard(sch_1):\DDR4_CHN_E_DQ_DQS_BYTE2\" )
				( netClassRef "@sapphirecity_baseboard_lib.sapphirecity_baseboard(sch_1):\DDR4_CHN_E_DQ_DQS_BYTE2\" )
			)
			( regionClassClass "@sapphirecity_baseboard_lib.sapphirecity_baseboard(sch_1):\RCC226\"
				( attribute "LINE_TO_LINE_SPACING" "8.00"
					( Origin gBackEnd )
				)
				( regionRef "@sapphirecity_baseboard_lib.sapphirecity_baseboard(sch_1):\CPU_BRKT\" )
				( netClassRef "@sapphirecity_baseboard_lib.sapphirecity_baseboard(sch_1):\DDR4_CHN_E_DQ_DQS_BYTE3\" )
				( netClassRef "@sapphirecity_baseboard_lib.sapphirecity_baseboard(sch_1):\DDR4_CHN_E_ECC\" )
			)
			( regionClassClass "@sapphirecity_baseboard_lib.sapphirecity_baseboard(sch_1):\RCC227\"
				( attribute "LINE_TO_LINE_SPACING" "8.00"
					( Origin gBackEnd )
				)
				( regionRef "@sapphirecity_baseboard_lib.sapphirecity_baseboard(sch_1):\CPU_BRKT\" )
				( netClassRef "@sapphirecity_baseboard_lib.sapphirecity_baseboard(sch_1):\DDR4_CHN_E_DQ_DQS_BYTE3\" )
				( netClassRef "@sapphirecity_baseboard_lib.sapphirecity_baseboard(sch_1):\DDR4_CHN_E_DQ_DQS_BYTE7\" )
			)
			( regionClassClass "@sapphirecity_baseboard_lib.sapphirecity_baseboard(sch_1):\RCC228\"
				( attribute "LINE_TO_LINE_SPACING" "8.00"
					( Origin gBackEnd )
				)
				( regionRef "@sapphirecity_baseboard_lib.sapphirecity_baseboard(sch_1):\CPU_BRKT\" )
				( netClassRef "@sapphirecity_baseboard_lib.sapphirecity_baseboard(sch_1):\DDR4_CHN_E_DQ_DQS_BYTE3\" )
				( netClassRef "@sapphirecity_baseboard_lib.sapphirecity_baseboard(sch_1):\DDR4_CHN_E_DQ_DQS_BYTE6\" )
			)
			( regionClassClass "@sapphirecity_baseboard_lib.sapphirecity_baseboard(sch_1):\RCC229\"
				( attribute "LINE_TO_LINE_SPACING" "8.00"
					( Origin gBackEnd )
				)
				( regionRef "@sapphirecity_baseboard_lib.sapphirecity_baseboard(sch_1):\CPU_BRKT\" )
				( netClassRef "@sapphirecity_baseboard_lib.sapphirecity_baseboard(sch_1):\DDR4_CHN_E_DQ_DQS_BYTE3\" )
				( netClassRef "@sapphirecity_baseboard_lib.sapphirecity_baseboard(sch_1):\DDR4_CHN_E_DQ_DQS_BYTE5\" )
			)
			( regionClassClass "@sapphirecity_baseboard_lib.sapphirecity_baseboard(sch_1):\RCC230\"
				( attribute "LINE_TO_LINE_SPACING" "8.00"
					( Origin gBackEnd )
				)
				( regionRef "@sapphirecity_baseboard_lib.sapphirecity_baseboard(sch_1):\CPU_BRKT\" )
				( netClassRef "@sapphirecity_baseboard_lib.sapphirecity_baseboard(sch_1):\DDR4_CHN_E_DQ_DQS_BYTE3\" )
				( netClassRef "@sapphirecity_baseboard_lib.sapphirecity_baseboard(sch_1):\DDR4_CHN_E_DQ_DQS_BYTE4\" )
			)
			( regionClassClass "@sapphirecity_baseboard_lib.sapphirecity_baseboard(sch_1):\RCC231\"
				( attribute "LINE_TO_LINE_SPACING" "8.00"
					( Origin gBackEnd )
				)
				( regionRef "@sapphirecity_baseboard_lib.sapphirecity_baseboard(sch_1):\CPU_BRKT\" )
				( netClassRef "@sapphirecity_baseboard_lib.sapphirecity_baseboard(sch_1):\DDR4_CHN_E_DQ_DQS_BYTE3\" )
				( netClassRef "@sapphirecity_baseboard_lib.sapphirecity_baseboard(sch_1):\DDR4_CHN_E_DQ_DQS_BYTE3\" )
			)
			( regionClassClass "@sapphirecity_baseboard_lib.sapphirecity_baseboard(sch_1):\RCC232\"
				( attribute "LINE_TO_LINE_SPACING" "8.00"
					( Origin gBackEnd )
				)
				( regionRef "@sapphirecity_baseboard_lib.sapphirecity_baseboard(sch_1):\CPU_BRKT\" )
				( netClassRef "@sapphirecity_baseboard_lib.sapphirecity_baseboard(sch_1):\DDR4_CHN_E_DQ_DQS_BYTE4\" )
				( netClassRef "@sapphirecity_baseboard_lib.sapphirecity_baseboard(sch_1):\DDR4_CHN_E_ECC\" )
			)
			( regionClassClass "@sapphirecity_baseboard_lib.sapphirecity_baseboard(sch_1):\RCC233\"
				( attribute "LINE_TO_LINE_SPACING" "8.00"
					( Origin gBackEnd )
				)
				( regionRef "@sapphirecity_baseboard_lib.sapphirecity_baseboard(sch_1):\CPU_BRKT\" )
				( netClassRef "@sapphirecity_baseboard_lib.sapphirecity_baseboard(sch_1):\DDR4_CHN_E_DQ_DQS_BYTE4\" )
				( netClassRef "@sapphirecity_baseboard_lib.sapphirecity_baseboard(sch_1):\DDR4_CHN_E_DQ_DQS_BYTE7\" )
			)
			( regionClassClass "@sapphirecity_baseboard_lib.sapphirecity_baseboard(sch_1):\RCC234\"
				( attribute "LINE_TO_LINE_SPACING" "8.00"
					( Origin gBackEnd )
				)
				( regionRef "@sapphirecity_baseboard_lib.sapphirecity_baseboard(sch_1):\CPU_BRKT\" )
				( netClassRef "@sapphirecity_baseboard_lib.sapphirecity_baseboard(sch_1):\DDR4_CHN_E_DQ_DQS_BYTE4\" )
				( netClassRef "@sapphirecity_baseboard_lib.sapphirecity_baseboard(sch_1):\DDR4_CHN_E_DQ_DQS_BYTE6\" )
			)
			( regionClassClass "@sapphirecity_baseboard_lib.sapphirecity_baseboard(sch_1):\RCC235\"
				( attribute "LINE_TO_LINE_SPACING" "8.00"
					( Origin gBackEnd )
				)
				( regionRef "@sapphirecity_baseboard_lib.sapphirecity_baseboard(sch_1):\CPU_BRKT\" )
				( netClassRef "@sapphirecity_baseboard_lib.sapphirecity_baseboard(sch_1):\DDR4_CHN_E_DQ_DQS_BYTE4\" )
				( netClassRef "@sapphirecity_baseboard_lib.sapphirecity_baseboard(sch_1):\DDR4_CHN_E_DQ_DQS_BYTE5\" )
			)
			( regionClassClass "@sapphirecity_baseboard_lib.sapphirecity_baseboard(sch_1):\RCC236\"
				( attribute "LINE_TO_LINE_SPACING" "8.00"
					( Origin gBackEnd )
				)
				( regionRef "@sapphirecity_baseboard_lib.sapphirecity_baseboard(sch_1):\CPU_BRKT\" )
				( netClassRef "@sapphirecity_baseboard_lib.sapphirecity_baseboard(sch_1):\DDR4_CHN_E_DQ_DQS_BYTE4\" )
				( netClassRef "@sapphirecity_baseboard_lib.sapphirecity_baseboard(sch_1):\DDR4_CHN_E_DQ_DQS_BYTE4\" )
			)
			( regionClassClass "@sapphirecity_baseboard_lib.sapphirecity_baseboard(sch_1):\RCC237\"
				( attribute "LINE_TO_LINE_SPACING" "8.00"
					( Origin gBackEnd )
				)
				( regionRef "@sapphirecity_baseboard_lib.sapphirecity_baseboard(sch_1):\CPU_BRKT\" )
				( netClassRef "@sapphirecity_baseboard_lib.sapphirecity_baseboard(sch_1):\DDR4_CHN_E_DQ_DQS_BYTE5\" )
				( netClassRef "@sapphirecity_baseboard_lib.sapphirecity_baseboard(sch_1):\DDR4_CHN_E_ECC\" )
			)
			( regionClassClass "@sapphirecity_baseboard_lib.sapphirecity_baseboard(sch_1):\RCC238\"
				( attribute "LINE_TO_LINE_SPACING" "8.00"
					( Origin gBackEnd )
				)
				( regionRef "@sapphirecity_baseboard_lib.sapphirecity_baseboard(sch_1):\CPU_BRKT\" )
				( netClassRef "@sapphirecity_baseboard_lib.sapphirecity_baseboard(sch_1):\DDR4_CHN_E_DQ_DQS_BYTE5\" )
				( netClassRef "@sapphirecity_baseboard_lib.sapphirecity_baseboard(sch_1):\DDR4_CHN_E_DQ_DQS_BYTE7\" )
			)
			( regionClassClass "@sapphirecity_baseboard_lib.sapphirecity_baseboard(sch_1):\RCC239\"
				( attribute "LINE_TO_LINE_SPACING" "8.00"
					( Origin gBackEnd )
				)
				( regionRef "@sapphirecity_baseboard_lib.sapphirecity_baseboard(sch_1):\CPU_BRKT\" )
				( netClassRef "@sapphirecity_baseboard_lib.sapphirecity_baseboard(sch_1):\DDR4_CHN_E_DQ_DQS_BYTE5\" )
				( netClassRef "@sapphirecity_baseboard_lib.sapphirecity_baseboard(sch_1):\DDR4_CHN_E_DQ_DQS_BYTE6\" )
			)
			( regionClassClass "@sapphirecity_baseboard_lib.sapphirecity_baseboard(sch_1):\RCC240\"
				( attribute "LINE_TO_LINE_SPACING" "8.00"
					( Origin gBackEnd )
				)
				( regionRef "@sapphirecity_baseboard_lib.sapphirecity_baseboard(sch_1):\CPU_BRKT\" )
				( netClassRef "@sapphirecity_baseboard_lib.sapphirecity_baseboard(sch_1):\DDR4_CHN_E_DQ_DQS_BYTE5\" )
				( netClassRef "@sapphirecity_baseboard_lib.sapphirecity_baseboard(sch_1):\DDR4_CHN_E_DQ_DQS_BYTE5\" )
			)
			( regionClassClass "@sapphirecity_baseboard_lib.sapphirecity_baseboard(sch_1):\RCC241\"
				( attribute "LINE_TO_LINE_SPACING" "8.00"
					( Origin gBackEnd )
				)
				( regionRef "@sapphirecity_baseboard_lib.sapphirecity_baseboard(sch_1):\CPU_BRKT\" )
				( netClassRef "@sapphirecity_baseboard_lib.sapphirecity_baseboard(sch_1):\DDR4_CHN_E_DQ_DQS_BYTE6\" )
				( netClassRef "@sapphirecity_baseboard_lib.sapphirecity_baseboard(sch_1):\DDR4_CHN_E_ECC\" )
			)
			( regionClassClass "@sapphirecity_baseboard_lib.sapphirecity_baseboard(sch_1):\RCC242\"
				( attribute "LINE_TO_LINE_SPACING" "8.00"
					( Origin gBackEnd )
				)
				( regionRef "@sapphirecity_baseboard_lib.sapphirecity_baseboard(sch_1):\CPU_BRKT\" )
				( netClassRef "@sapphirecity_baseboard_lib.sapphirecity_baseboard(sch_1):\DDR4_CHN_E_DQ_DQS_BYTE6\" )
				( netClassRef "@sapphirecity_baseboard_lib.sapphirecity_baseboard(sch_1):\DDR4_CHN_E_DQ_DQS_BYTE7\" )
			)
			( regionClassClass "@sapphirecity_baseboard_lib.sapphirecity_baseboard(sch_1):\RCC243\"
				( attribute "LINE_TO_LINE_SPACING" "8.00"
					( Origin gBackEnd )
				)
				( regionRef "@sapphirecity_baseboard_lib.sapphirecity_baseboard(sch_1):\CPU_BRKT\" )
				( netClassRef "@sapphirecity_baseboard_lib.sapphirecity_baseboard(sch_1):\DDR4_CHN_E_DQ_DQS_BYTE6\" )
				( netClassRef "@sapphirecity_baseboard_lib.sapphirecity_baseboard(sch_1):\DDR4_CHN_E_DQ_DQS_BYTE6\" )
			)
			( regionClassClass "@sapphirecity_baseboard_lib.sapphirecity_baseboard(sch_1):\RCC244\"
				( attribute "LINE_TO_LINE_SPACING" "8.00"
					( Origin gBackEnd )
				)
				( regionRef "@sapphirecity_baseboard_lib.sapphirecity_baseboard(sch_1):\CPU_BRKT\" )
				( netClassRef "@sapphirecity_baseboard_lib.sapphirecity_baseboard(sch_1):\DDR4_CHN_E_DQ_DQS_BYTE7\" )
				( netClassRef "@sapphirecity_baseboard_lib.sapphirecity_baseboard(sch_1):\DDR4_CHN_E_ECC\" )
			)
			( regionClassClass "@sapphirecity_baseboard_lib.sapphirecity_baseboard(sch_1):\RCC245\"
				( attribute "LINE_TO_LINE_SPACING" "8.00"
					( Origin gBackEnd )
				)
				( regionRef "@sapphirecity_baseboard_lib.sapphirecity_baseboard(sch_1):\CPU_BRKT\" )
				( netClassRef "@sapphirecity_baseboard_lib.sapphirecity_baseboard(sch_1):\DDR4_CHN_E_DQ_DQS_BYTE7\" )
				( netClassRef "@sapphirecity_baseboard_lib.sapphirecity_baseboard(sch_1):\DDR4_CHN_E_DQ_DQS_BYTE7\" )
			)
			( regionClassClass "@sapphirecity_baseboard_lib.sapphirecity_baseboard(sch_1):\RCC246\"
				( attribute "LINE_TO_LINE_SPACING" "8.00"
					( Origin gBackEnd )
				)
				( regionRef "@sapphirecity_baseboard_lib.sapphirecity_baseboard(sch_1):\CPU_BRKT\" )
				( netClassRef "@sapphirecity_baseboard_lib.sapphirecity_baseboard(sch_1):\DDR4_CHN_E_ECC\" )
				( netClassRef "@sapphirecity_baseboard_lib.sapphirecity_baseboard(sch_1):\DDR4_CHN_E_ECC\" )
			)
			( regionClassClass "@sapphirecity_baseboard_lib.sapphirecity_baseboard(sch_1):\RCC247\"
				( attribute "LINE_TO_LINE_SPACING" "8.00"
					( Origin gBackEnd )
				)
				( regionRef "@sapphirecity_baseboard_lib.sapphirecity_baseboard(sch_1):\CPU_BRKT\" )
				( netClassRef "@sapphirecity_baseboard_lib.sapphirecity_baseboard(sch_1):\DDR4_CHN_F_CLK\" )
				( netClassRef "@sapphirecity_baseboard_lib.sapphirecity_baseboard(sch_1):\DDR4_CHN_F_ECC\" )
			)
			( regionClassClass "@sapphirecity_baseboard_lib.sapphirecity_baseboard(sch_1):\RCC248\"
				( attribute "LINE_TO_LINE_SPACING" "8.00"
					( Origin gBackEnd )
				)
				( regionRef "@sapphirecity_baseboard_lib.sapphirecity_baseboard(sch_1):\CPU_BRKT\" )
				( netClassRef "@sapphirecity_baseboard_lib.sapphirecity_baseboard(sch_1):\DDR4_CHN_F_CLK\" )
				( netClassRef "@sapphirecity_baseboard_lib.sapphirecity_baseboard(sch_1):\DDR4_CHN_F_DQ_DQS_BYTE7\" )
			)
			( regionClassClass "@sapphirecity_baseboard_lib.sapphirecity_baseboard(sch_1):\RCC249\"
				( attribute "LINE_TO_LINE_SPACING" "8.00"
					( Origin gBackEnd )
				)
				( regionRef "@sapphirecity_baseboard_lib.sapphirecity_baseboard(sch_1):\CPU_BRKT\" )
				( netClassRef "@sapphirecity_baseboard_lib.sapphirecity_baseboard(sch_1):\DDR4_CHN_F_CLK\" )
				( netClassRef "@sapphirecity_baseboard_lib.sapphirecity_baseboard(sch_1):\DDR4_CHN_F_DQ_DQS_BYTE6\" )
			)
			( regionClassClass "@sapphirecity_baseboard_lib.sapphirecity_baseboard(sch_1):\RCC250\"
				( attribute "LINE_TO_LINE_SPACING" "8.00"
					( Origin gBackEnd )
				)
				( regionRef "@sapphirecity_baseboard_lib.sapphirecity_baseboard(sch_1):\CPU_BRKT\" )
				( netClassRef "@sapphirecity_baseboard_lib.sapphirecity_baseboard(sch_1):\DDR4_CHN_F_CLK\" )
				( netClassRef "@sapphirecity_baseboard_lib.sapphirecity_baseboard(sch_1):\DDR4_CHN_F_DQ_DQS_BYTE5\" )
			)
			( regionClassClass "@sapphirecity_baseboard_lib.sapphirecity_baseboard(sch_1):\RCC251\"
				( attribute "LINE_TO_LINE_SPACING" "8.00"
					( Origin gBackEnd )
				)
				( regionRef "@sapphirecity_baseboard_lib.sapphirecity_baseboard(sch_1):\CPU_BRKT\" )
				( netClassRef "@sapphirecity_baseboard_lib.sapphirecity_baseboard(sch_1):\DDR4_CHN_F_CLK\" )
				( netClassRef "@sapphirecity_baseboard_lib.sapphirecity_baseboard(sch_1):\DDR4_CHN_F_DQ_DQS_BYTE4\" )
			)
			( regionClassClass "@sapphirecity_baseboard_lib.sapphirecity_baseboard(sch_1):\RCC252\"
				( attribute "LINE_TO_LINE_SPACING" "8.00"
					( Origin gBackEnd )
				)
				( regionRef "@sapphirecity_baseboard_lib.sapphirecity_baseboard(sch_1):\CPU_BRKT\" )
				( netClassRef "@sapphirecity_baseboard_lib.sapphirecity_baseboard(sch_1):\DDR4_CHN_F_CLK\" )
				( netClassRef "@sapphirecity_baseboard_lib.sapphirecity_baseboard(sch_1):\DDR4_CHN_F_DQ_DQS_BYTE3\" )
			)
			( regionClassClass "@sapphirecity_baseboard_lib.sapphirecity_baseboard(sch_1):\RCC253\"
				( attribute "LINE_TO_LINE_SPACING" "8.00"
					( Origin gBackEnd )
				)
				( regionRef "@sapphirecity_baseboard_lib.sapphirecity_baseboard(sch_1):\CPU_BRKT\" )
				( netClassRef "@sapphirecity_baseboard_lib.sapphirecity_baseboard(sch_1):\DDR4_CHN_F_CLK\" )
				( netClassRef "@sapphirecity_baseboard_lib.sapphirecity_baseboard(sch_1):\DDR4_CHN_F_DQ_DQS_BYTE2\" )
			)
			( regionClassClass "@sapphirecity_baseboard_lib.sapphirecity_baseboard(sch_1):\RCC254\"
				( attribute "LINE_TO_LINE_SPACING" "8.00"
					( Origin gBackEnd )
				)
				( regionRef "@sapphirecity_baseboard_lib.sapphirecity_baseboard(sch_1):\CPU_BRKT\" )
				( netClassRef "@sapphirecity_baseboard_lib.sapphirecity_baseboard(sch_1):\DDR4_CHN_F_CLK\" )
				( netClassRef "@sapphirecity_baseboard_lib.sapphirecity_baseboard(sch_1):\DDR4_CHN_F_DQ_DQS_BYTE1\" )
			)
			( regionClassClass "@sapphirecity_baseboard_lib.sapphirecity_baseboard(sch_1):\RCC255\"
				( attribute "LINE_TO_LINE_SPACING" "8.00"
					( Origin gBackEnd )
				)
				( regionRef "@sapphirecity_baseboard_lib.sapphirecity_baseboard(sch_1):\CPU_BRKT\" )
				( netClassRef "@sapphirecity_baseboard_lib.sapphirecity_baseboard(sch_1):\DDR4_CHN_F_CLK\" )
				( netClassRef "@sapphirecity_baseboard_lib.sapphirecity_baseboard(sch_1):\DDR4_CHN_F_DQ_DQS_BYTE0\" )
			)
			( regionClassClass "@sapphirecity_baseboard_lib.sapphirecity_baseboard(sch_1):\RCC256\"
				( attribute "LINE_TO_LINE_SPACING" "8.00"
					( Origin gBackEnd )
				)
				( regionRef "@sapphirecity_baseboard_lib.sapphirecity_baseboard(sch_1):\CPU_BRKT\" )
				( netClassRef "@sapphirecity_baseboard_lib.sapphirecity_baseboard(sch_1):\DDR4_CHN_F_CLK\" )
				( netClassRef "@sapphirecity_baseboard_lib.sapphirecity_baseboard(sch_1):\DDR4_CHN_F_CTRL\" )
			)
			( regionClassClass "@sapphirecity_baseboard_lib.sapphirecity_baseboard(sch_1):\RCC257\"
				( attribute "LINE_TO_LINE_SPACING" "8.00"
					( Origin gBackEnd )
				)
				( regionRef "@sapphirecity_baseboard_lib.sapphirecity_baseboard(sch_1):\CPU_BRKT\" )
				( netClassRef "@sapphirecity_baseboard_lib.sapphirecity_baseboard(sch_1):\DDR4_CHN_F_CLK\" )
				( netClassRef "@sapphirecity_baseboard_lib.sapphirecity_baseboard(sch_1):\DDR4_CHN_F_CMD_ADD\" )
			)
			( regionClassClass "@sapphirecity_baseboard_lib.sapphirecity_baseboard(sch_1):\RCC258\"
				( attribute "LINE_TO_LINE_SPACING" "8.00"
					( Origin gBackEnd )
				)
				( regionRef "@sapphirecity_baseboard_lib.sapphirecity_baseboard(sch_1):\CPU_BRKT\" )
				( netClassRef "@sapphirecity_baseboard_lib.sapphirecity_baseboard(sch_1):\DDR4_CHN_F_CLK\" )
				( netClassRef "@sapphirecity_baseboard_lib.sapphirecity_baseboard(sch_1):\DDR4_CHN_F_CLK\" )
			)
			( regionClassClass "@sapphirecity_baseboard_lib.sapphirecity_baseboard(sch_1):\RCC259\"
				( attribute "LINE_TO_LINE_SPACING" "8.00"
					( Origin gBackEnd )
				)
				( regionRef "@sapphirecity_baseboard_lib.sapphirecity_baseboard(sch_1):\CPU_BRKT\" )
				( netClassRef "@sapphirecity_baseboard_lib.sapphirecity_baseboard(sch_1):\DDR4_CHN_F_CMD_ADD\" )
				( netClassRef "@sapphirecity_baseboard_lib.sapphirecity_baseboard(sch_1):\DDR4_CHN_F_ECC\" )
			)
			( regionClassClass "@sapphirecity_baseboard_lib.sapphirecity_baseboard(sch_1):\RCC260\"
				( attribute "LINE_TO_LINE_SPACING" "8.00"
					( Origin gBackEnd )
				)
				( regionRef "@sapphirecity_baseboard_lib.sapphirecity_baseboard(sch_1):\CPU_BRKT\" )
				( netClassRef "@sapphirecity_baseboard_lib.sapphirecity_baseboard(sch_1):\DDR4_CHN_F_CMD_ADD\" )
				( netClassRef "@sapphirecity_baseboard_lib.sapphirecity_baseboard(sch_1):\DDR4_CHN_F_DQ_DQS_BYTE7\" )
			)
			( regionClassClass "@sapphirecity_baseboard_lib.sapphirecity_baseboard(sch_1):\RCC261\"
				( attribute "LINE_TO_LINE_SPACING" "8.00"
					( Origin gBackEnd )
				)
				( regionRef "@sapphirecity_baseboard_lib.sapphirecity_baseboard(sch_1):\CPU_BRKT\" )
				( netClassRef "@sapphirecity_baseboard_lib.sapphirecity_baseboard(sch_1):\DDR4_CHN_F_CMD_ADD\" )
				( netClassRef "@sapphirecity_baseboard_lib.sapphirecity_baseboard(sch_1):\DDR4_CHN_F_DQ_DQS_BYTE6\" )
			)
			( regionClassClass "@sapphirecity_baseboard_lib.sapphirecity_baseboard(sch_1):\RCC262\"
				( attribute "LINE_TO_LINE_SPACING" "8.00"
					( Origin gBackEnd )
				)
				( regionRef "@sapphirecity_baseboard_lib.sapphirecity_baseboard(sch_1):\CPU_BRKT\" )
				( netClassRef "@sapphirecity_baseboard_lib.sapphirecity_baseboard(sch_1):\DDR4_CHN_F_CMD_ADD\" )
				( netClassRef "@sapphirecity_baseboard_lib.sapphirecity_baseboard(sch_1):\DDR4_CHN_F_DQ_DQS_BYTE5\" )
			)
			( regionClassClass "@sapphirecity_baseboard_lib.sapphirecity_baseboard(sch_1):\RCC263\"
				( attribute "LINE_TO_LINE_SPACING" "8.00"
					( Origin gBackEnd )
				)
				( regionRef "@sapphirecity_baseboard_lib.sapphirecity_baseboard(sch_1):\CPU_BRKT\" )
				( netClassRef "@sapphirecity_baseboard_lib.sapphirecity_baseboard(sch_1):\DDR4_CHN_F_CMD_ADD\" )
				( netClassRef "@sapphirecity_baseboard_lib.sapphirecity_baseboard(sch_1):\DDR4_CHN_F_DQ_DQS_BYTE4\" )
			)
			( regionClassClass "@sapphirecity_baseboard_lib.sapphirecity_baseboard(sch_1):\RCC264\"
				( attribute "LINE_TO_LINE_SPACING" "8.00"
					( Origin gBackEnd )
				)
				( regionRef "@sapphirecity_baseboard_lib.sapphirecity_baseboard(sch_1):\CPU_BRKT\" )
				( netClassRef "@sapphirecity_baseboard_lib.sapphirecity_baseboard(sch_1):\DDR4_CHN_F_CMD_ADD\" )
				( netClassRef "@sapphirecity_baseboard_lib.sapphirecity_baseboard(sch_1):\DDR4_CHN_F_DQ_DQS_BYTE3\" )
			)
			( regionClassClass "@sapphirecity_baseboard_lib.sapphirecity_baseboard(sch_1):\RCC265\"
				( attribute "LINE_TO_LINE_SPACING" "8.00"
					( Origin gBackEnd )
				)
				( regionRef "@sapphirecity_baseboard_lib.sapphirecity_baseboard(sch_1):\CPU_BRKT\" )
				( netClassRef "@sapphirecity_baseboard_lib.sapphirecity_baseboard(sch_1):\DDR4_CHN_F_CMD_ADD\" )
				( netClassRef "@sapphirecity_baseboard_lib.sapphirecity_baseboard(sch_1):\DDR4_CHN_F_DQ_DQS_BYTE2\" )
			)
			( regionClassClass "@sapphirecity_baseboard_lib.sapphirecity_baseboard(sch_1):\RCC266\"
				( attribute "LINE_TO_LINE_SPACING" "8.00"
					( Origin gBackEnd )
				)
				( regionRef "@sapphirecity_baseboard_lib.sapphirecity_baseboard(sch_1):\CPU_BRKT\" )
				( netClassRef "@sapphirecity_baseboard_lib.sapphirecity_baseboard(sch_1):\DDR4_CHN_F_CMD_ADD\" )
				( netClassRef "@sapphirecity_baseboard_lib.sapphirecity_baseboard(sch_1):\DDR4_CHN_F_DQ_DQS_BYTE1\" )
			)
			( regionClassClass "@sapphirecity_baseboard_lib.sapphirecity_baseboard(sch_1):\RCC267\"
				( attribute "LINE_TO_LINE_SPACING" "8.00"
					( Origin gBackEnd )
				)
				( regionRef "@sapphirecity_baseboard_lib.sapphirecity_baseboard(sch_1):\CPU_BRKT\" )
				( netClassRef "@sapphirecity_baseboard_lib.sapphirecity_baseboard(sch_1):\DDR4_CHN_F_CMD_ADD\" )
				( netClassRef "@sapphirecity_baseboard_lib.sapphirecity_baseboard(sch_1):\DDR4_CHN_F_DQ_DQS_BYTE0\" )
			)
			( regionClassClass "@sapphirecity_baseboard_lib.sapphirecity_baseboard(sch_1):\RCC268\"
				( attribute "LINE_TO_LINE_SPACING" "8.00"
					( Origin gBackEnd )
				)
				( regionRef "@sapphirecity_baseboard_lib.sapphirecity_baseboard(sch_1):\CPU_BRKT\" )
				( netClassRef "@sapphirecity_baseboard_lib.sapphirecity_baseboard(sch_1):\DDR4_CHN_F_CMD_ADD\" )
				( netClassRef "@sapphirecity_baseboard_lib.sapphirecity_baseboard(sch_1):\DDR4_CHN_F_CTRL\" )
			)
			( regionClassClass "@sapphirecity_baseboard_lib.sapphirecity_baseboard(sch_1):\RCC269\"
				( attribute "LINE_TO_LINE_SPACING" "8.00"
					( Origin gBackEnd )
				)
				( regionRef "@sapphirecity_baseboard_lib.sapphirecity_baseboard(sch_1):\CPU_BRKT\" )
				( netClassRef "@sapphirecity_baseboard_lib.sapphirecity_baseboard(sch_1):\DDR4_CHN_F_CMD_ADD\" )
				( netClassRef "@sapphirecity_baseboard_lib.sapphirecity_baseboard(sch_1):\DDR4_CHN_F_CMD_ADD\" )
			)
			( regionClassClass "@sapphirecity_baseboard_lib.sapphirecity_baseboard(sch_1):\RCC270\"
				( attribute "LINE_TO_LINE_SPACING" "8.00"
					( Origin gBackEnd )
				)
				( regionRef "@sapphirecity_baseboard_lib.sapphirecity_baseboard(sch_1):\CPU_BRKT\" )
				( netClassRef "@sapphirecity_baseboard_lib.sapphirecity_baseboard(sch_1):\DDR4_CHN_F_CTRL\" )
				( netClassRef "@sapphirecity_baseboard_lib.sapphirecity_baseboard(sch_1):\DDR4_CHN_F_ECC\" )
			)
			( regionClassClass "@sapphirecity_baseboard_lib.sapphirecity_baseboard(sch_1):\RCC271\"
				( attribute "LINE_TO_LINE_SPACING" "8.00"
					( Origin gBackEnd )
				)
				( regionRef "@sapphirecity_baseboard_lib.sapphirecity_baseboard(sch_1):\CPU_BRKT\" )
				( netClassRef "@sapphirecity_baseboard_lib.sapphirecity_baseboard(sch_1):\DDR4_CHN_F_CTRL\" )
				( netClassRef "@sapphirecity_baseboard_lib.sapphirecity_baseboard(sch_1):\DDR4_CHN_F_DQ_DQS_BYTE7\" )
			)
			( regionClassClass "@sapphirecity_baseboard_lib.sapphirecity_baseboard(sch_1):\RCC272\"
				( attribute "LINE_TO_LINE_SPACING" "8.00"
					( Origin gBackEnd )
				)
				( regionRef "@sapphirecity_baseboard_lib.sapphirecity_baseboard(sch_1):\CPU_BRKT\" )
				( netClassRef "@sapphirecity_baseboard_lib.sapphirecity_baseboard(sch_1):\DDR4_CHN_F_CTRL\" )
				( netClassRef "@sapphirecity_baseboard_lib.sapphirecity_baseboard(sch_1):\DDR4_CHN_F_DQ_DQS_BYTE6\" )
			)
			( regionClassClass "@sapphirecity_baseboard_lib.sapphirecity_baseboard(sch_1):\RCC273\"
				( attribute "LINE_TO_LINE_SPACING" "8.00"
					( Origin gBackEnd )
				)
				( regionRef "@sapphirecity_baseboard_lib.sapphirecity_baseboard(sch_1):\CPU_BRKT\" )
				( netClassRef "@sapphirecity_baseboard_lib.sapphirecity_baseboard(sch_1):\DDR4_CHN_F_CTRL\" )
				( netClassRef "@sapphirecity_baseboard_lib.sapphirecity_baseboard(sch_1):\DDR4_CHN_F_DQ_DQS_BYTE5\" )
			)
			( regionClassClass "@sapphirecity_baseboard_lib.sapphirecity_baseboard(sch_1):\RCC274\"
				( attribute "LINE_TO_LINE_SPACING" "8.00"
					( Origin gBackEnd )
				)
				( regionRef "@sapphirecity_baseboard_lib.sapphirecity_baseboard(sch_1):\CPU_BRKT\" )
				( netClassRef "@sapphirecity_baseboard_lib.sapphirecity_baseboard(sch_1):\DDR4_CHN_F_CTRL\" )
				( netClassRef "@sapphirecity_baseboard_lib.sapphirecity_baseboard(sch_1):\DDR4_CHN_F_DQ_DQS_BYTE4\" )
			)
			( regionClassClass "@sapphirecity_baseboard_lib.sapphirecity_baseboard(sch_1):\RCC275\"
				( attribute "LINE_TO_LINE_SPACING" "8.00"
					( Origin gBackEnd )
				)
				( regionRef "@sapphirecity_baseboard_lib.sapphirecity_baseboard(sch_1):\CPU_BRKT\" )
				( netClassRef "@sapphirecity_baseboard_lib.sapphirecity_baseboard(sch_1):\DDR4_CHN_F_CTRL\" )
				( netClassRef "@sapphirecity_baseboard_lib.sapphirecity_baseboard(sch_1):\DDR4_CHN_F_DQ_DQS_BYTE3\" )
			)
			( regionClassClass "@sapphirecity_baseboard_lib.sapphirecity_baseboard(sch_1):\RCC276\"
				( attribute "LINE_TO_LINE_SPACING" "8.00"
					( Origin gBackEnd )
				)
				( regionRef "@sapphirecity_baseboard_lib.sapphirecity_baseboard(sch_1):\CPU_BRKT\" )
				( netClassRef "@sapphirecity_baseboard_lib.sapphirecity_baseboard(sch_1):\DDR4_CHN_F_CTRL\" )
				( netClassRef "@sapphirecity_baseboard_lib.sapphirecity_baseboard(sch_1):\DDR4_CHN_F_DQ_DQS_BYTE2\" )
			)
			( regionClassClass "@sapphirecity_baseboard_lib.sapphirecity_baseboard(sch_1):\RCC277\"
				( attribute "LINE_TO_LINE_SPACING" "8.00"
					( Origin gBackEnd )
				)
				( regionRef "@sapphirecity_baseboard_lib.sapphirecity_baseboard(sch_1):\CPU_BRKT\" )
				( netClassRef "@sapphirecity_baseboard_lib.sapphirecity_baseboard(sch_1):\DDR4_CHN_F_CTRL\" )
				( netClassRef "@sapphirecity_baseboard_lib.sapphirecity_baseboard(sch_1):\DDR4_CHN_F_DQ_DQS_BYTE1\" )
			)
			( regionClassClass "@sapphirecity_baseboard_lib.sapphirecity_baseboard(sch_1):\RCC278\"
				( attribute "LINE_TO_LINE_SPACING" "8.00"
					( Origin gBackEnd )
				)
				( regionRef "@sapphirecity_baseboard_lib.sapphirecity_baseboard(sch_1):\CPU_BRKT\" )
				( netClassRef "@sapphirecity_baseboard_lib.sapphirecity_baseboard(sch_1):\DDR4_CHN_F_CTRL\" )
				( netClassRef "@sapphirecity_baseboard_lib.sapphirecity_baseboard(sch_1):\DDR4_CHN_F_DQ_DQS_BYTE0\" )
			)
			( regionClassClass "@sapphirecity_baseboard_lib.sapphirecity_baseboard(sch_1):\RCC279\"
				( attribute "LINE_TO_LINE_SPACING" "8.00"
					( Origin gBackEnd )
				)
				( regionRef "@sapphirecity_baseboard_lib.sapphirecity_baseboard(sch_1):\CPU_BRKT\" )
				( netClassRef "@sapphirecity_baseboard_lib.sapphirecity_baseboard(sch_1):\DDR4_CHN_F_CTRL\" )
				( netClassRef "@sapphirecity_baseboard_lib.sapphirecity_baseboard(sch_1):\DDR4_CHN_F_CTRL\" )
			)
			( regionClassClass "@sapphirecity_baseboard_lib.sapphirecity_baseboard(sch_1):\RCC280\"
				( attribute "LINE_TO_LINE_SPACING" "8.00"
					( Origin gBackEnd )
				)
				( regionRef "@sapphirecity_baseboard_lib.sapphirecity_baseboard(sch_1):\CPU_BRKT\" )
				( netClassRef "@sapphirecity_baseboard_lib.sapphirecity_baseboard(sch_1):\DDR4_CHN_F_DQ_DQS_BYTE0\" )
				( netClassRef "@sapphirecity_baseboard_lib.sapphirecity_baseboard(sch_1):\DDR4_CHN_F_ECC\" )
			)
			( regionClassClass "@sapphirecity_baseboard_lib.sapphirecity_baseboard(sch_1):\RCC281\"
				( attribute "LINE_TO_LINE_SPACING" "8.00"
					( Origin gBackEnd )
				)
				( regionRef "@sapphirecity_baseboard_lib.sapphirecity_baseboard(sch_1):\CPU_BRKT\" )
				( netClassRef "@sapphirecity_baseboard_lib.sapphirecity_baseboard(sch_1):\DDR4_CHN_F_DQ_DQS_BYTE0\" )
				( netClassRef "@sapphirecity_baseboard_lib.sapphirecity_baseboard(sch_1):\DDR4_CHN_F_DQ_DQS_BYTE7\" )
			)
			( regionClassClass "@sapphirecity_baseboard_lib.sapphirecity_baseboard(sch_1):\RCC282\"
				( attribute "LINE_TO_LINE_SPACING" "8.00"
					( Origin gBackEnd )
				)
				( regionRef "@sapphirecity_baseboard_lib.sapphirecity_baseboard(sch_1):\CPU_BRKT\" )
				( netClassRef "@sapphirecity_baseboard_lib.sapphirecity_baseboard(sch_1):\DDR4_CHN_F_DQ_DQS_BYTE0\" )
				( netClassRef "@sapphirecity_baseboard_lib.sapphirecity_baseboard(sch_1):\DDR4_CHN_F_DQ_DQS_BYTE6\" )
			)
			( regionClassClass "@sapphirecity_baseboard_lib.sapphirecity_baseboard(sch_1):\RCC283\"
				( attribute "LINE_TO_LINE_SPACING" "8.00"
					( Origin gBackEnd )
				)
				( regionRef "@sapphirecity_baseboard_lib.sapphirecity_baseboard(sch_1):\CPU_BRKT\" )
				( netClassRef "@sapphirecity_baseboard_lib.sapphirecity_baseboard(sch_1):\DDR4_CHN_F_DQ_DQS_BYTE0\" )
				( netClassRef "@sapphirecity_baseboard_lib.sapphirecity_baseboard(sch_1):\DDR4_CHN_F_DQ_DQS_BYTE5\" )
			)
			( regionClassClass "@sapphirecity_baseboard_lib.sapphirecity_baseboard(sch_1):\RCC284\"
				( attribute "LINE_TO_LINE_SPACING" "8.00"
					( Origin gBackEnd )
				)
				( regionRef "@sapphirecity_baseboard_lib.sapphirecity_baseboard(sch_1):\CPU_BRKT\" )
				( netClassRef "@sapphirecity_baseboard_lib.sapphirecity_baseboard(sch_1):\DDR4_CHN_F_DQ_DQS_BYTE0\" )
				( netClassRef "@sapphirecity_baseboard_lib.sapphirecity_baseboard(sch_1):\DDR4_CHN_F_DQ_DQS_BYTE4\" )
			)
			( regionClassClass "@sapphirecity_baseboard_lib.sapphirecity_baseboard(sch_1):\RCC285\"
				( attribute "LINE_TO_LINE_SPACING" "8.00"
					( Origin gBackEnd )
				)
				( regionRef "@sapphirecity_baseboard_lib.sapphirecity_baseboard(sch_1):\CPU_BRKT\" )
				( netClassRef "@sapphirecity_baseboard_lib.sapphirecity_baseboard(sch_1):\DDR4_CHN_F_DQ_DQS_BYTE0\" )
				( netClassRef "@sapphirecity_baseboard_lib.sapphirecity_baseboard(sch_1):\DDR4_CHN_F_DQ_DQS_BYTE3\" )
			)
			( regionClassClass "@sapphirecity_baseboard_lib.sapphirecity_baseboard(sch_1):\RCC286\"
				( attribute "LINE_TO_LINE_SPACING" "8.00"
					( Origin gBackEnd )
				)
				( regionRef "@sapphirecity_baseboard_lib.sapphirecity_baseboard(sch_1):\CPU_BRKT\" )
				( netClassRef "@sapphirecity_baseboard_lib.sapphirecity_baseboard(sch_1):\DDR4_CHN_F_DQ_DQS_BYTE0\" )
				( netClassRef "@sapphirecity_baseboard_lib.sapphirecity_baseboard(sch_1):\DDR4_CHN_F_DQ_DQS_BYTE2\" )
			)
			( regionClassClass "@sapphirecity_baseboard_lib.sapphirecity_baseboard(sch_1):\RCC287\"
				( attribute "LINE_TO_LINE_SPACING" "8.00"
					( Origin gBackEnd )
				)
				( regionRef "@sapphirecity_baseboard_lib.sapphirecity_baseboard(sch_1):\CPU_BRKT\" )
				( netClassRef "@sapphirecity_baseboard_lib.sapphirecity_baseboard(sch_1):\DDR4_CHN_F_DQ_DQS_BYTE0\" )
				( netClassRef "@sapphirecity_baseboard_lib.sapphirecity_baseboard(sch_1):\DDR4_CHN_F_DQ_DQS_BYTE1\" )
			)
			( regionClassClass "@sapphirecity_baseboard_lib.sapphirecity_baseboard(sch_1):\RCC288\"
				( attribute "LINE_TO_LINE_SPACING" "8.00"
					( Origin gBackEnd )
				)
				( regionRef "@sapphirecity_baseboard_lib.sapphirecity_baseboard(sch_1):\CPU_BRKT\" )
				( netClassRef "@sapphirecity_baseboard_lib.sapphirecity_baseboard(sch_1):\DDR4_CHN_F_DQ_DQS_BYTE0\" )
				( netClassRef "@sapphirecity_baseboard_lib.sapphirecity_baseboard(sch_1):\DDR4_CHN_F_DQ_DQS_BYTE0\" )
			)
			( regionClassClass "@sapphirecity_baseboard_lib.sapphirecity_baseboard(sch_1):\RCC289\"
				( attribute "LINE_TO_LINE_SPACING" "8.00"
					( Origin gBackEnd )
				)
				( regionRef "@sapphirecity_baseboard_lib.sapphirecity_baseboard(sch_1):\CPU_BRKT\" )
				( netClassRef "@sapphirecity_baseboard_lib.sapphirecity_baseboard(sch_1):\DDR4_CHN_F_DQ_DQS_BYTE1\" )
				( netClassRef "@sapphirecity_baseboard_lib.sapphirecity_baseboard(sch_1):\DDR4_CHN_F_ECC\" )
			)
			( regionClassClass "@sapphirecity_baseboard_lib.sapphirecity_baseboard(sch_1):\RCC290\"
				( attribute "LINE_TO_LINE_SPACING" "8.00"
					( Origin gBackEnd )
				)
				( regionRef "@sapphirecity_baseboard_lib.sapphirecity_baseboard(sch_1):\CPU_BRKT\" )
				( netClassRef "@sapphirecity_baseboard_lib.sapphirecity_baseboard(sch_1):\DDR4_CHN_F_DQ_DQS_BYTE1\" )
				( netClassRef "@sapphirecity_baseboard_lib.sapphirecity_baseboard(sch_1):\DDR4_CHN_F_DQ_DQS_BYTE7\" )
			)
			( regionClassClass "@sapphirecity_baseboard_lib.sapphirecity_baseboard(sch_1):\RCC291\"
				( attribute "LINE_TO_LINE_SPACING" "8.00"
					( Origin gBackEnd )
				)
				( regionRef "@sapphirecity_baseboard_lib.sapphirecity_baseboard(sch_1):\CPU_BRKT\" )
				( netClassRef "@sapphirecity_baseboard_lib.sapphirecity_baseboard(sch_1):\DDR4_CHN_F_DQ_DQS_BYTE1\" )
				( netClassRef "@sapphirecity_baseboard_lib.sapphirecity_baseboard(sch_1):\DDR4_CHN_F_DQ_DQS_BYTE6\" )
			)
			( regionClassClass "@sapphirecity_baseboard_lib.sapphirecity_baseboard(sch_1):\RCC292\"
				( attribute "LINE_TO_LINE_SPACING" "8.00"
					( Origin gBackEnd )
				)
				( regionRef "@sapphirecity_baseboard_lib.sapphirecity_baseboard(sch_1):\CPU_BRKT\" )
				( netClassRef "@sapphirecity_baseboard_lib.sapphirecity_baseboard(sch_1):\DDR4_CHN_F_DQ_DQS_BYTE1\" )
				( netClassRef "@sapphirecity_baseboard_lib.sapphirecity_baseboard(sch_1):\DDR4_CHN_F_DQ_DQS_BYTE5\" )
			)
			( regionClassClass "@sapphirecity_baseboard_lib.sapphirecity_baseboard(sch_1):\RCC293\"
				( attribute "LINE_TO_LINE_SPACING" "8.00"
					( Origin gBackEnd )
				)
				( regionRef "@sapphirecity_baseboard_lib.sapphirecity_baseboard(sch_1):\CPU_BRKT\" )
				( netClassRef "@sapphirecity_baseboard_lib.sapphirecity_baseboard(sch_1):\DDR4_CHN_F_DQ_DQS_BYTE1\" )
				( netClassRef "@sapphirecity_baseboard_lib.sapphirecity_baseboard(sch_1):\DDR4_CHN_F_DQ_DQS_BYTE4\" )
			)
			( regionClassClass "@sapphirecity_baseboard_lib.sapphirecity_baseboard(sch_1):\RCC294\"
				( attribute "LINE_TO_LINE_SPACING" "8.00"
					( Origin gBackEnd )
				)
				( regionRef "@sapphirecity_baseboard_lib.sapphirecity_baseboard(sch_1):\CPU_BRKT\" )
				( netClassRef "@sapphirecity_baseboard_lib.sapphirecity_baseboard(sch_1):\DDR4_CHN_F_DQ_DQS_BYTE1\" )
				( netClassRef "@sapphirecity_baseboard_lib.sapphirecity_baseboard(sch_1):\DDR4_CHN_F_DQ_DQS_BYTE3\" )
			)
			( regionClassClass "@sapphirecity_baseboard_lib.sapphirecity_baseboard(sch_1):\RCC295\"
				( attribute "LINE_TO_LINE_SPACING" "8.00"
					( Origin gBackEnd )
				)
				( regionRef "@sapphirecity_baseboard_lib.sapphirecity_baseboard(sch_1):\CPU_BRKT\" )
				( netClassRef "@sapphirecity_baseboard_lib.sapphirecity_baseboard(sch_1):\DDR4_CHN_F_DQ_DQS_BYTE1\" )
				( netClassRef "@sapphirecity_baseboard_lib.sapphirecity_baseboard(sch_1):\DDR4_CHN_F_DQ_DQS_BYTE2\" )
			)
			( regionClassClass "@sapphirecity_baseboard_lib.sapphirecity_baseboard(sch_1):\RCC296\"
				( attribute "LINE_TO_LINE_SPACING" "8.00"
					( Origin gBackEnd )
				)
				( regionRef "@sapphirecity_baseboard_lib.sapphirecity_baseboard(sch_1):\CPU_BRKT\" )
				( netClassRef "@sapphirecity_baseboard_lib.sapphirecity_baseboard(sch_1):\DDR4_CHN_F_DQ_DQS_BYTE1\" )
				( netClassRef "@sapphirecity_baseboard_lib.sapphirecity_baseboard(sch_1):\DDR4_CHN_F_DQ_DQS_BYTE1\" )
			)
			( regionClassClass "@sapphirecity_baseboard_lib.sapphirecity_baseboard(sch_1):\RCC297\"
				( attribute "LINE_TO_LINE_SPACING" "8.00"
					( Origin gBackEnd )
				)
				( regionRef "@sapphirecity_baseboard_lib.sapphirecity_baseboard(sch_1):\CPU_BRKT\" )
				( netClassRef "@sapphirecity_baseboard_lib.sapphirecity_baseboard(sch_1):\DDR4_CHN_F_DQ_DQS_BYTE2\" )
				( netClassRef "@sapphirecity_baseboard_lib.sapphirecity_baseboard(sch_1):\DDR4_CHN_F_ECC\" )
			)
			( regionClassClass "@sapphirecity_baseboard_lib.sapphirecity_baseboard(sch_1):\RCC298\"
				( attribute "LINE_TO_LINE_SPACING" "8.00"
					( Origin gBackEnd )
				)
				( regionRef "@sapphirecity_baseboard_lib.sapphirecity_baseboard(sch_1):\CPU_BRKT\" )
				( netClassRef "@sapphirecity_baseboard_lib.sapphirecity_baseboard(sch_1):\DDR4_CHN_F_DQ_DQS_BYTE2\" )
				( netClassRef "@sapphirecity_baseboard_lib.sapphirecity_baseboard(sch_1):\DDR4_CHN_F_DQ_DQS_BYTE7\" )
			)
			( regionClassClass "@sapphirecity_baseboard_lib.sapphirecity_baseboard(sch_1):\RCC299\"
				( attribute "LINE_TO_LINE_SPACING" "8.00"
					( Origin gBackEnd )
				)
				( regionRef "@sapphirecity_baseboard_lib.sapphirecity_baseboard(sch_1):\CPU_BRKT\" )
				( netClassRef "@sapphirecity_baseboard_lib.sapphirecity_baseboard(sch_1):\DDR4_CHN_F_DQ_DQS_BYTE2\" )
				( netClassRef "@sapphirecity_baseboard_lib.sapphirecity_baseboard(sch_1):\DDR4_CHN_F_DQ_DQS_BYTE6\" )
			)
			( regionClassClass "@sapphirecity_baseboard_lib.sapphirecity_baseboard(sch_1):\RCC300\"
				( attribute "LINE_TO_LINE_SPACING" "8.00"
					( Origin gBackEnd )
				)
				( regionRef "@sapphirecity_baseboard_lib.sapphirecity_baseboard(sch_1):\CPU_BRKT\" )
				( netClassRef "@sapphirecity_baseboard_lib.sapphirecity_baseboard(sch_1):\DDR4_CHN_F_DQ_DQS_BYTE2\" )
				( netClassRef "@sapphirecity_baseboard_lib.sapphirecity_baseboard(sch_1):\DDR4_CHN_F_DQ_DQS_BYTE5\" )
			)
			( regionClassClass "@sapphirecity_baseboard_lib.sapphirecity_baseboard(sch_1):\RCC301\"
				( attribute "LINE_TO_LINE_SPACING" "8.00"
					( Origin gBackEnd )
				)
				( regionRef "@sapphirecity_baseboard_lib.sapphirecity_baseboard(sch_1):\CPU_BRKT\" )
				( netClassRef "@sapphirecity_baseboard_lib.sapphirecity_baseboard(sch_1):\DDR4_CHN_F_DQ_DQS_BYTE2\" )
				( netClassRef "@sapphirecity_baseboard_lib.sapphirecity_baseboard(sch_1):\DDR4_CHN_F_DQ_DQS_BYTE4\" )
			)
			( regionClassClass "@sapphirecity_baseboard_lib.sapphirecity_baseboard(sch_1):\RCC302\"
				( attribute "LINE_TO_LINE_SPACING" "8.00"
					( Origin gBackEnd )
				)
				( regionRef "@sapphirecity_baseboard_lib.sapphirecity_baseboard(sch_1):\CPU_BRKT\" )
				( netClassRef "@sapphirecity_baseboard_lib.sapphirecity_baseboard(sch_1):\DDR4_CHN_F_DQ_DQS_BYTE2\" )
				( netClassRef "@sapphirecity_baseboard_lib.sapphirecity_baseboard(sch_1):\DDR4_CHN_F_DQ_DQS_BYTE3\" )
			)
			( regionClassClass "@sapphirecity_baseboard_lib.sapphirecity_baseboard(sch_1):\RCC303\"
				( attribute "LINE_TO_LINE_SPACING" "8.00"
					( Origin gBackEnd )
				)
				( regionRef "@sapphirecity_baseboard_lib.sapphirecity_baseboard(sch_1):\CPU_BRKT\" )
				( netClassRef "@sapphirecity_baseboard_lib.sapphirecity_baseboard(sch_1):\DDR4_CHN_F_DQ_DQS_BYTE2\" )
				( netClassRef "@sapphirecity_baseboard_lib.sapphirecity_baseboard(sch_1):\DDR4_CHN_F_DQ_DQS_BYTE2\" )
			)
			( regionClassClass "@sapphirecity_baseboard_lib.sapphirecity_baseboard(sch_1):\RCC304\"
				( attribute "LINE_TO_LINE_SPACING" "8.00"
					( Origin gBackEnd )
				)
				( regionRef "@sapphirecity_baseboard_lib.sapphirecity_baseboard(sch_1):\CPU_BRKT\" )
				( netClassRef "@sapphirecity_baseboard_lib.sapphirecity_baseboard(sch_1):\DDR4_CHN_F_DQ_DQS_BYTE3\" )
				( netClassRef "@sapphirecity_baseboard_lib.sapphirecity_baseboard(sch_1):\DDR4_CHN_F_ECC\" )
			)
			( regionClassClass "@sapphirecity_baseboard_lib.sapphirecity_baseboard(sch_1):\RCC305\"
				( attribute "LINE_TO_LINE_SPACING" "8.00"
					( Origin gBackEnd )
				)
				( regionRef "@sapphirecity_baseboard_lib.sapphirecity_baseboard(sch_1):\CPU_BRKT\" )
				( netClassRef "@sapphirecity_baseboard_lib.sapphirecity_baseboard(sch_1):\DDR4_CHN_F_DQ_DQS_BYTE3\" )
				( netClassRef "@sapphirecity_baseboard_lib.sapphirecity_baseboard(sch_1):\DDR4_CHN_F_DQ_DQS_BYTE7\" )
			)
			( regionClassClass "@sapphirecity_baseboard_lib.sapphirecity_baseboard(sch_1):\RCC306\"
				( attribute "LINE_TO_LINE_SPACING" "8.00"
					( Origin gBackEnd )
				)
				( regionRef "@sapphirecity_baseboard_lib.sapphirecity_baseboard(sch_1):\CPU_BRKT\" )
				( netClassRef "@sapphirecity_baseboard_lib.sapphirecity_baseboard(sch_1):\DDR4_CHN_F_DQ_DQS_BYTE3\" )
				( netClassRef "@sapphirecity_baseboard_lib.sapphirecity_baseboard(sch_1):\DDR4_CHN_F_DQ_DQS_BYTE6\" )
			)
			( regionClassClass "@sapphirecity_baseboard_lib.sapphirecity_baseboard(sch_1):\RCC307\"
				( attribute "LINE_TO_LINE_SPACING" "8.00"
					( Origin gBackEnd )
				)
				( regionRef "@sapphirecity_baseboard_lib.sapphirecity_baseboard(sch_1):\CPU_BRKT\" )
				( netClassRef "@sapphirecity_baseboard_lib.sapphirecity_baseboard(sch_1):\DDR4_CHN_F_DQ_DQS_BYTE3\" )
				( netClassRef "@sapphirecity_baseboard_lib.sapphirecity_baseboard(sch_1):\DDR4_CHN_F_DQ_DQS_BYTE5\" )
			)
			( regionClassClass "@sapphirecity_baseboard_lib.sapphirecity_baseboard(sch_1):\RCC308\"
				( attribute "LINE_TO_LINE_SPACING" "8.00"
					( Origin gBackEnd )
				)
				( regionRef "@sapphirecity_baseboard_lib.sapphirecity_baseboard(sch_1):\CPU_BRKT\" )
				( netClassRef "@sapphirecity_baseboard_lib.sapphirecity_baseboard(sch_1):\DDR4_CHN_F_DQ_DQS_BYTE3\" )
				( netClassRef "@sapphirecity_baseboard_lib.sapphirecity_baseboard(sch_1):\DDR4_CHN_F_DQ_DQS_BYTE4\" )
			)
			( regionClassClass "@sapphirecity_baseboard_lib.sapphirecity_baseboard(sch_1):\RCC309\"
				( attribute "LINE_TO_LINE_SPACING" "8.00"
					( Origin gBackEnd )
				)
				( regionRef "@sapphirecity_baseboard_lib.sapphirecity_baseboard(sch_1):\CPU_BRKT\" )
				( netClassRef "@sapphirecity_baseboard_lib.sapphirecity_baseboard(sch_1):\DDR4_CHN_F_DQ_DQS_BYTE3\" )
				( netClassRef "@sapphirecity_baseboard_lib.sapphirecity_baseboard(sch_1):\DDR4_CHN_F_DQ_DQS_BYTE3\" )
			)
			( regionClassClass "@sapphirecity_baseboard_lib.sapphirecity_baseboard(sch_1):\RCC310\"
				( attribute "LINE_TO_LINE_SPACING" "8.00"
					( Origin gBackEnd )
				)
				( regionRef "@sapphirecity_baseboard_lib.sapphirecity_baseboard(sch_1):\CPU_BRKT\" )
				( netClassRef "@sapphirecity_baseboard_lib.sapphirecity_baseboard(sch_1):\DDR4_CHN_F_DQ_DQS_BYTE4\" )
				( netClassRef "@sapphirecity_baseboard_lib.sapphirecity_baseboard(sch_1):\DDR4_CHN_F_ECC\" )
			)
			( regionClassClass "@sapphirecity_baseboard_lib.sapphirecity_baseboard(sch_1):\RCC311\"
				( attribute "LINE_TO_LINE_SPACING" "8.00"
					( Origin gBackEnd )
				)
				( regionRef "@sapphirecity_baseboard_lib.sapphirecity_baseboard(sch_1):\CPU_BRKT\" )
				( netClassRef "@sapphirecity_baseboard_lib.sapphirecity_baseboard(sch_1):\DDR4_CHN_F_DQ_DQS_BYTE4\" )
				( netClassRef "@sapphirecity_baseboard_lib.sapphirecity_baseboard(sch_1):\DDR4_CHN_F_DQ_DQS_BYTE7\" )
			)
			( regionClassClass "@sapphirecity_baseboard_lib.sapphirecity_baseboard(sch_1):\RCC312\"
				( attribute "LINE_TO_LINE_SPACING" "8.00"
					( Origin gBackEnd )
				)
				( regionRef "@sapphirecity_baseboard_lib.sapphirecity_baseboard(sch_1):\CPU_BRKT\" )
				( netClassRef "@sapphirecity_baseboard_lib.sapphirecity_baseboard(sch_1):\DDR4_CHN_F_DQ_DQS_BYTE4\" )
				( netClassRef "@sapphirecity_baseboard_lib.sapphirecity_baseboard(sch_1):\DDR4_CHN_F_DQ_DQS_BYTE6\" )
			)
			( regionClassClass "@sapphirecity_baseboard_lib.sapphirecity_baseboard(sch_1):\RCC313\"
				( attribute "LINE_TO_LINE_SPACING" "8.00"
					( Origin gBackEnd )
				)
				( regionRef "@sapphirecity_baseboard_lib.sapphirecity_baseboard(sch_1):\CPU_BRKT\" )
				( netClassRef "@sapphirecity_baseboard_lib.sapphirecity_baseboard(sch_1):\DDR4_CHN_F_DQ_DQS_BYTE4\" )
				( netClassRef "@sapphirecity_baseboard_lib.sapphirecity_baseboard(sch_1):\DDR4_CHN_F_DQ_DQS_BYTE5\" )
			)
			( regionClassClass "@sapphirecity_baseboard_lib.sapphirecity_baseboard(sch_1):\RCC314\"
				( attribute "LINE_TO_LINE_SPACING" "8.00"
					( Origin gBackEnd )
				)
				( regionRef "@sapphirecity_baseboard_lib.sapphirecity_baseboard(sch_1):\CPU_BRKT\" )
				( netClassRef "@sapphirecity_baseboard_lib.sapphirecity_baseboard(sch_1):\DDR4_CHN_F_DQ_DQS_BYTE4\" )
				( netClassRef "@sapphirecity_baseboard_lib.sapphirecity_baseboard(sch_1):\DDR4_CHN_F_DQ_DQS_BYTE4\" )
			)
			( regionClassClass "@sapphirecity_baseboard_lib.sapphirecity_baseboard(sch_1):\RCC315\"
				( attribute "LINE_TO_LINE_SPACING" "8.00"
					( Origin gBackEnd )
				)
				( regionRef "@sapphirecity_baseboard_lib.sapphirecity_baseboard(sch_1):\CPU_BRKT\" )
				( netClassRef "@sapphirecity_baseboard_lib.sapphirecity_baseboard(sch_1):\DDR4_CHN_F_DQ_DQS_BYTE5\" )
				( netClassRef "@sapphirecity_baseboard_lib.sapphirecity_baseboard(sch_1):\DDR4_CHN_F_ECC\" )
			)
			( regionClassClass "@sapphirecity_baseboard_lib.sapphirecity_baseboard(sch_1):\RCC316\"
				( attribute "LINE_TO_LINE_SPACING" "8.00"
					( Origin gBackEnd )
				)
				( regionRef "@sapphirecity_baseboard_lib.sapphirecity_baseboard(sch_1):\CPU_BRKT\" )
				( netClassRef "@sapphirecity_baseboard_lib.sapphirecity_baseboard(sch_1):\DDR4_CHN_F_DQ_DQS_BYTE5\" )
				( netClassRef "@sapphirecity_baseboard_lib.sapphirecity_baseboard(sch_1):\DDR4_CHN_F_DQ_DQS_BYTE7\" )
			)
			( regionClassClass "@sapphirecity_baseboard_lib.sapphirecity_baseboard(sch_1):\RCC317\"
				( attribute "LINE_TO_LINE_SPACING" "8.00"
					( Origin gBackEnd )
				)
				( regionRef "@sapphirecity_baseboard_lib.sapphirecity_baseboard(sch_1):\CPU_BRKT\" )
				( netClassRef "@sapphirecity_baseboard_lib.sapphirecity_baseboard(sch_1):\DDR4_CHN_F_DQ_DQS_BYTE5\" )
				( netClassRef "@sapphirecity_baseboard_lib.sapphirecity_baseboard(sch_1):\DDR4_CHN_F_DQ_DQS_BYTE6\" )
			)
			( regionClassClass "@sapphirecity_baseboard_lib.sapphirecity_baseboard(sch_1):\RCC318\"
				( attribute "LINE_TO_LINE_SPACING" "8.00"
					( Origin gBackEnd )
				)
				( regionRef "@sapphirecity_baseboard_lib.sapphirecity_baseboard(sch_1):\CPU_BRKT\" )
				( netClassRef "@sapphirecity_baseboard_lib.sapphirecity_baseboard(sch_1):\DDR4_CHN_F_DQ_DQS_BYTE5\" )
				( netClassRef "@sapphirecity_baseboard_lib.sapphirecity_baseboard(sch_1):\DDR4_CHN_F_DQ_DQS_BYTE5\" )
			)
			( regionClassClass "@sapphirecity_baseboard_lib.sapphirecity_baseboard(sch_1):\RCC319\"
				( attribute "LINE_TO_LINE_SPACING" "8.00"
					( Origin gBackEnd )
				)
				( regionRef "@sapphirecity_baseboard_lib.sapphirecity_baseboard(sch_1):\CPU_BRKT\" )
				( netClassRef "@sapphirecity_baseboard_lib.sapphirecity_baseboard(sch_1):\DDR4_CHN_F_DQ_DQS_BYTE6\" )
				( netClassRef "@sapphirecity_baseboard_lib.sapphirecity_baseboard(sch_1):\DDR4_CHN_F_ECC\" )
			)
			( regionClassClass "@sapphirecity_baseboard_lib.sapphirecity_baseboard(sch_1):\RCC320\"
				( attribute "LINE_TO_LINE_SPACING" "8.00"
					( Origin gBackEnd )
				)
				( regionRef "@sapphirecity_baseboard_lib.sapphirecity_baseboard(sch_1):\CPU_BRKT\" )
				( netClassRef "@sapphirecity_baseboard_lib.sapphirecity_baseboard(sch_1):\DDR4_CHN_F_DQ_DQS_BYTE6\" )
				( netClassRef "@sapphirecity_baseboard_lib.sapphirecity_baseboard(sch_1):\DDR4_CHN_F_DQ_DQS_BYTE7\" )
			)
			( regionClassClass "@sapphirecity_baseboard_lib.sapphirecity_baseboard(sch_1):\RCC321\"
				( attribute "LINE_TO_LINE_SPACING" "8.00"
					( Origin gBackEnd )
				)
				( regionRef "@sapphirecity_baseboard_lib.sapphirecity_baseboard(sch_1):\CPU_BRKT\" )
				( netClassRef "@sapphirecity_baseboard_lib.sapphirecity_baseboard(sch_1):\DDR4_CHN_F_DQ_DQS_BYTE6\" )
				( netClassRef "@sapphirecity_baseboard_lib.sapphirecity_baseboard(sch_1):\DDR4_CHN_F_DQ_DQS_BYTE6\" )
			)
			( regionClassClass "@sapphirecity_baseboard_lib.sapphirecity_baseboard(sch_1):\RCC322\"
				( attribute "LINE_TO_LINE_SPACING" "8.00"
					( Origin gBackEnd )
				)
				( regionRef "@sapphirecity_baseboard_lib.sapphirecity_baseboard(sch_1):\CPU_BRKT\" )
				( netClassRef "@sapphirecity_baseboard_lib.sapphirecity_baseboard(sch_1):\DDR4_CHN_F_DQ_DQS_BYTE7\" )
				( netClassRef "@sapphirecity_baseboard_lib.sapphirecity_baseboard(sch_1):\DDR4_CHN_F_ECC\" )
			)
			( regionClassClass "@sapphirecity_baseboard_lib.sapphirecity_baseboard(sch_1):\RCC323\"
				( attribute "LINE_TO_LINE_SPACING" "8.00"
					( Origin gBackEnd )
				)
				( regionRef "@sapphirecity_baseboard_lib.sapphirecity_baseboard(sch_1):\CPU_BRKT\" )
				( netClassRef "@sapphirecity_baseboard_lib.sapphirecity_baseboard(sch_1):\DDR4_CHN_F_DQ_DQS_BYTE7\" )
				( netClassRef "@sapphirecity_baseboard_lib.sapphirecity_baseboard(sch_1):\DDR4_CHN_F_DQ_DQS_BYTE7\" )
			)
			( regionClassClass "@sapphirecity_baseboard_lib.sapphirecity_baseboard(sch_1):\RCC324\"
				( attribute "LINE_TO_LINE_SPACING" "8.00"
					( Origin gBackEnd )
				)
				( regionRef "@sapphirecity_baseboard_lib.sapphirecity_baseboard(sch_1):\CPU_BRKT\" )
				( netClassRef "@sapphirecity_baseboard_lib.sapphirecity_baseboard(sch_1):\DDR4_CHN_F_ECC\" )
				( netClassRef "@sapphirecity_baseboard_lib.sapphirecity_baseboard(sch_1):\DDR4_CHN_F_ECC\" )
			)
			( regionClassClass "@sapphirecity_baseboard_lib.sapphirecity_baseboard(sch_1):\RCC325\"
				( attribute "LINE_TO_LINE_SPACING" "8.00"
					( Origin gBackEnd )
				)
				( regionRef "@sapphirecity_baseboard_lib.sapphirecity_baseboard(sch_1):\CPU_BRKT\" )
				( netClassRef "@sapphirecity_baseboard_lib.sapphirecity_baseboard(sch_1):\DDR4_CHN_G_CLK\" )
				( netClassRef "@sapphirecity_baseboard_lib.sapphirecity_baseboard(sch_1):\DDR4_CHN_G_ECC\" )
			)
			( regionClassClass "@sapphirecity_baseboard_lib.sapphirecity_baseboard(sch_1):\RCC326\"
				( attribute "LINE_TO_LINE_SPACING" "8.00"
					( Origin gBackEnd )
				)
				( regionRef "@sapphirecity_baseboard_lib.sapphirecity_baseboard(sch_1):\CPU_BRKT\" )
				( netClassRef "@sapphirecity_baseboard_lib.sapphirecity_baseboard(sch_1):\DDR4_CHN_G_CLK\" )
				( netClassRef "@sapphirecity_baseboard_lib.sapphirecity_baseboard(sch_1):\DDR4_CHN_G_DQ_DQS_BYTE7\" )
			)
			( regionClassClass "@sapphirecity_baseboard_lib.sapphirecity_baseboard(sch_1):\RCC327\"
				( attribute "LINE_TO_LINE_SPACING" "8.00"
					( Origin gBackEnd )
				)
				( regionRef "@sapphirecity_baseboard_lib.sapphirecity_baseboard(sch_1):\CPU_BRKT\" )
				( netClassRef "@sapphirecity_baseboard_lib.sapphirecity_baseboard(sch_1):\DDR4_CHN_G_CLK\" )
				( netClassRef "@sapphirecity_baseboard_lib.sapphirecity_baseboard(sch_1):\DDR4_CHN_G_DQ_DQS_BYTE6\" )
			)
			( regionClassClass "@sapphirecity_baseboard_lib.sapphirecity_baseboard(sch_1):\RCC328\"
				( attribute "LINE_TO_LINE_SPACING" "8.00"
					( Origin gBackEnd )
				)
				( regionRef "@sapphirecity_baseboard_lib.sapphirecity_baseboard(sch_1):\CPU_BRKT\" )
				( netClassRef "@sapphirecity_baseboard_lib.sapphirecity_baseboard(sch_1):\DDR4_CHN_G_CLK\" )
				( netClassRef "@sapphirecity_baseboard_lib.sapphirecity_baseboard(sch_1):\DDR4_CHN_G_DQ_DQS_BYTE5\" )
			)
			( regionClassClass "@sapphirecity_baseboard_lib.sapphirecity_baseboard(sch_1):\RCC329\"
				( attribute "LINE_TO_LINE_SPACING" "8.00"
					( Origin gBackEnd )
				)
				( regionRef "@sapphirecity_baseboard_lib.sapphirecity_baseboard(sch_1):\CPU_BRKT\" )
				( netClassRef "@sapphirecity_baseboard_lib.sapphirecity_baseboard(sch_1):\DDR4_CHN_G_CLK\" )
				( netClassRef "@sapphirecity_baseboard_lib.sapphirecity_baseboard(sch_1):\DDR4_CHN_G_DQ_DQS_BYTE4\" )
			)
			( regionClassClass "@sapphirecity_baseboard_lib.sapphirecity_baseboard(sch_1):\RCC330\"
				( attribute "LINE_TO_LINE_SPACING" "8.00"
					( Origin gBackEnd )
				)
				( regionRef "@sapphirecity_baseboard_lib.sapphirecity_baseboard(sch_1):\CPU_BRKT\" )
				( netClassRef "@sapphirecity_baseboard_lib.sapphirecity_baseboard(sch_1):\DDR4_CHN_G_CLK\" )
				( netClassRef "@sapphirecity_baseboard_lib.sapphirecity_baseboard(sch_1):\DDR4_CHN_G_DQ_DQS_BYTE3\" )
			)
			( regionClassClass "@sapphirecity_baseboard_lib.sapphirecity_baseboard(sch_1):\RCC331\"
				( attribute "LINE_TO_LINE_SPACING" "8.00"
					( Origin gBackEnd )
				)
				( regionRef "@sapphirecity_baseboard_lib.sapphirecity_baseboard(sch_1):\CPU_BRKT\" )
				( netClassRef "@sapphirecity_baseboard_lib.sapphirecity_baseboard(sch_1):\DDR4_CHN_G_CLK\" )
				( netClassRef "@sapphirecity_baseboard_lib.sapphirecity_baseboard(sch_1):\DDR4_CHN_G_DQ_DQS_BYTE2\" )
			)
			( regionClassClass "@sapphirecity_baseboard_lib.sapphirecity_baseboard(sch_1):\RCC332\"
				( attribute "LINE_TO_LINE_SPACING" "8.00"
					( Origin gBackEnd )
				)
				( regionRef "@sapphirecity_baseboard_lib.sapphirecity_baseboard(sch_1):\CPU_BRKT\" )
				( netClassRef "@sapphirecity_baseboard_lib.sapphirecity_baseboard(sch_1):\DDR4_CHN_G_CLK\" )
				( netClassRef "@sapphirecity_baseboard_lib.sapphirecity_baseboard(sch_1):\DDR4_CHN_G_DQ_DQS_BYTE1\" )
			)
			( regionClassClass "@sapphirecity_baseboard_lib.sapphirecity_baseboard(sch_1):\RCC333\"
				( attribute "LINE_TO_LINE_SPACING" "8.00"
					( Origin gBackEnd )
				)
				( regionRef "@sapphirecity_baseboard_lib.sapphirecity_baseboard(sch_1):\CPU_BRKT\" )
				( netClassRef "@sapphirecity_baseboard_lib.sapphirecity_baseboard(sch_1):\DDR4_CHN_G_CLK\" )
				( netClassRef "@sapphirecity_baseboard_lib.sapphirecity_baseboard(sch_1):\DDR4_CHN_G_DQ_DQS_BYTE0\" )
			)
			( regionClassClass "@sapphirecity_baseboard_lib.sapphirecity_baseboard(sch_1):\RCC334\"
				( attribute "LINE_TO_LINE_SPACING" "8.00"
					( Origin gBackEnd )
				)
				( regionRef "@sapphirecity_baseboard_lib.sapphirecity_baseboard(sch_1):\CPU_BRKT\" )
				( netClassRef "@sapphirecity_baseboard_lib.sapphirecity_baseboard(sch_1):\DDR4_CHN_G_CLK\" )
				( netClassRef "@sapphirecity_baseboard_lib.sapphirecity_baseboard(sch_1):\DDR4_CHN_G_CTRL\" )
			)
			( regionClassClass "@sapphirecity_baseboard_lib.sapphirecity_baseboard(sch_1):\RCC335\"
				( attribute "LINE_TO_LINE_SPACING" "8.00"
					( Origin gBackEnd )
				)
				( regionRef "@sapphirecity_baseboard_lib.sapphirecity_baseboard(sch_1):\CPU_BRKT\" )
				( netClassRef "@sapphirecity_baseboard_lib.sapphirecity_baseboard(sch_1):\DDR4_CHN_G_CLK\" )
				( netClassRef "@sapphirecity_baseboard_lib.sapphirecity_baseboard(sch_1):\DDR4_CHN_G_CMD_ADD\" )
			)
			( regionClassClass "@sapphirecity_baseboard_lib.sapphirecity_baseboard(sch_1):\RCC336\"
				( attribute "LINE_TO_LINE_SPACING" "8.00"
					( Origin gBackEnd )
				)
				( regionRef "@sapphirecity_baseboard_lib.sapphirecity_baseboard(sch_1):\CPU_BRKT\" )
				( netClassRef "@sapphirecity_baseboard_lib.sapphirecity_baseboard(sch_1):\DDR4_CHN_G_CLK\" )
				( netClassRef "@sapphirecity_baseboard_lib.sapphirecity_baseboard(sch_1):\DDR4_CHN_G_CLK\" )
			)
			( regionClassClass "@sapphirecity_baseboard_lib.sapphirecity_baseboard(sch_1):\RCC337\"
				( attribute "LINE_TO_LINE_SPACING" "8.00"
					( Origin gBackEnd )
				)
				( regionRef "@sapphirecity_baseboard_lib.sapphirecity_baseboard(sch_1):\CPU_BRKT\" )
				( netClassRef "@sapphirecity_baseboard_lib.sapphirecity_baseboard(sch_1):\DDR4_CHN_G_CMD_ADD\" )
				( netClassRef "@sapphirecity_baseboard_lib.sapphirecity_baseboard(sch_1):\DDR4_CHN_G_ECC\" )
			)
			( regionClassClass "@sapphirecity_baseboard_lib.sapphirecity_baseboard(sch_1):\RCC338\"
				( attribute "LINE_TO_LINE_SPACING" "8.00"
					( Origin gBackEnd )
				)
				( regionRef "@sapphirecity_baseboard_lib.sapphirecity_baseboard(sch_1):\CPU_BRKT\" )
				( netClassRef "@sapphirecity_baseboard_lib.sapphirecity_baseboard(sch_1):\DDR4_CHN_G_CMD_ADD\" )
				( netClassRef "@sapphirecity_baseboard_lib.sapphirecity_baseboard(sch_1):\DDR4_CHN_G_DQ_DQS_BYTE7\" )
			)
			( regionClassClass "@sapphirecity_baseboard_lib.sapphirecity_baseboard(sch_1):\RCC339\"
				( attribute "LINE_TO_LINE_SPACING" "8.00"
					( Origin gBackEnd )
				)
				( regionRef "@sapphirecity_baseboard_lib.sapphirecity_baseboard(sch_1):\CPU_BRKT\" )
				( netClassRef "@sapphirecity_baseboard_lib.sapphirecity_baseboard(sch_1):\DDR4_CHN_G_CMD_ADD\" )
				( netClassRef "@sapphirecity_baseboard_lib.sapphirecity_baseboard(sch_1):\DDR4_CHN_G_DQ_DQS_BYTE6\" )
			)
			( regionClassClass "@sapphirecity_baseboard_lib.sapphirecity_baseboard(sch_1):\RCC340\"
				( attribute "LINE_TO_LINE_SPACING" "8.00"
					( Origin gBackEnd )
				)
				( regionRef "@sapphirecity_baseboard_lib.sapphirecity_baseboard(sch_1):\CPU_BRKT\" )
				( netClassRef "@sapphirecity_baseboard_lib.sapphirecity_baseboard(sch_1):\DDR4_CHN_G_CMD_ADD\" )
				( netClassRef "@sapphirecity_baseboard_lib.sapphirecity_baseboard(sch_1):\DDR4_CHN_G_DQ_DQS_BYTE5\" )
			)
			( regionClassClass "@sapphirecity_baseboard_lib.sapphirecity_baseboard(sch_1):\RCC341\"
				( attribute "LINE_TO_LINE_SPACING" "8.00"
					( Origin gBackEnd )
				)
				( regionRef "@sapphirecity_baseboard_lib.sapphirecity_baseboard(sch_1):\CPU_BRKT\" )
				( netClassRef "@sapphirecity_baseboard_lib.sapphirecity_baseboard(sch_1):\DDR4_CHN_G_CMD_ADD\" )
				( netClassRef "@sapphirecity_baseboard_lib.sapphirecity_baseboard(sch_1):\DDR4_CHN_G_DQ_DQS_BYTE4\" )
			)
			( regionClassClass "@sapphirecity_baseboard_lib.sapphirecity_baseboard(sch_1):\RCC342\"
				( attribute "LINE_TO_LINE_SPACING" "8.00"
					( Origin gBackEnd )
				)
				( regionRef "@sapphirecity_baseboard_lib.sapphirecity_baseboard(sch_1):\CPU_BRKT\" )
				( netClassRef "@sapphirecity_baseboard_lib.sapphirecity_baseboard(sch_1):\DDR4_CHN_G_CMD_ADD\" )
				( netClassRef "@sapphirecity_baseboard_lib.sapphirecity_baseboard(sch_1):\DDR4_CHN_G_DQ_DQS_BYTE3\" )
			)
			( regionClassClass "@sapphirecity_baseboard_lib.sapphirecity_baseboard(sch_1):\RCC343\"
				( attribute "LINE_TO_LINE_SPACING" "8.00"
					( Origin gBackEnd )
				)
				( regionRef "@sapphirecity_baseboard_lib.sapphirecity_baseboard(sch_1):\CPU_BRKT\" )
				( netClassRef "@sapphirecity_baseboard_lib.sapphirecity_baseboard(sch_1):\DDR4_CHN_G_CMD_ADD\" )
				( netClassRef "@sapphirecity_baseboard_lib.sapphirecity_baseboard(sch_1):\DDR4_CHN_G_DQ_DQS_BYTE2\" )
			)
			( regionClassClass "@sapphirecity_baseboard_lib.sapphirecity_baseboard(sch_1):\RCC344\"
				( attribute "LINE_TO_LINE_SPACING" "8.00"
					( Origin gBackEnd )
				)
				( regionRef "@sapphirecity_baseboard_lib.sapphirecity_baseboard(sch_1):\CPU_BRKT\" )
				( netClassRef "@sapphirecity_baseboard_lib.sapphirecity_baseboard(sch_1):\DDR4_CHN_G_CMD_ADD\" )
				( netClassRef "@sapphirecity_baseboard_lib.sapphirecity_baseboard(sch_1):\DDR4_CHN_G_DQ_DQS_BYTE1\" )
			)
			( regionClassClass "@sapphirecity_baseboard_lib.sapphirecity_baseboard(sch_1):\RCC345\"
				( attribute "LINE_TO_LINE_SPACING" "8.00"
					( Origin gBackEnd )
				)
				( regionRef "@sapphirecity_baseboard_lib.sapphirecity_baseboard(sch_1):\CPU_BRKT\" )
				( netClassRef "@sapphirecity_baseboard_lib.sapphirecity_baseboard(sch_1):\DDR4_CHN_G_CMD_ADD\" )
				( netClassRef "@sapphirecity_baseboard_lib.sapphirecity_baseboard(sch_1):\DDR4_CHN_G_DQ_DQS_BYTE0\" )
			)
			( regionClassClass "@sapphirecity_baseboard_lib.sapphirecity_baseboard(sch_1):\RCC346\"
				( attribute "LINE_TO_LINE_SPACING" "8.00"
					( Origin gBackEnd )
				)
				( regionRef "@sapphirecity_baseboard_lib.sapphirecity_baseboard(sch_1):\CPU_BRKT\" )
				( netClassRef "@sapphirecity_baseboard_lib.sapphirecity_baseboard(sch_1):\DDR4_CHN_G_CMD_ADD\" )
				( netClassRef "@sapphirecity_baseboard_lib.sapphirecity_baseboard(sch_1):\DDR4_CHN_G_CTRL\" )
			)
			( regionClassClass "@sapphirecity_baseboard_lib.sapphirecity_baseboard(sch_1):\RCC347\"
				( attribute "LINE_TO_LINE_SPACING" "8.00"
					( Origin gBackEnd )
				)
				( regionRef "@sapphirecity_baseboard_lib.sapphirecity_baseboard(sch_1):\CPU_BRKT\" )
				( netClassRef "@sapphirecity_baseboard_lib.sapphirecity_baseboard(sch_1):\DDR4_CHN_G_CMD_ADD\" )
				( netClassRef "@sapphirecity_baseboard_lib.sapphirecity_baseboard(sch_1):\DDR4_CHN_G_CMD_ADD\" )
			)
			( regionClassClass "@sapphirecity_baseboard_lib.sapphirecity_baseboard(sch_1):\RCC348\"
				( attribute "LINE_TO_LINE_SPACING" "8.00"
					( Origin gBackEnd )
				)
				( regionRef "@sapphirecity_baseboard_lib.sapphirecity_baseboard(sch_1):\CPU_BRKT\" )
				( netClassRef "@sapphirecity_baseboard_lib.sapphirecity_baseboard(sch_1):\DDR4_CHN_G_CTRL\" )
				( netClassRef "@sapphirecity_baseboard_lib.sapphirecity_baseboard(sch_1):\DDR4_CHN_G_ECC\" )
			)
			( regionClassClass "@sapphirecity_baseboard_lib.sapphirecity_baseboard(sch_1):\RCC349\"
				( attribute "LINE_TO_LINE_SPACING" "8.00"
					( Origin gBackEnd )
				)
				( regionRef "@sapphirecity_baseboard_lib.sapphirecity_baseboard(sch_1):\CPU_BRKT\" )
				( netClassRef "@sapphirecity_baseboard_lib.sapphirecity_baseboard(sch_1):\DDR4_CHN_G_CTRL\" )
				( netClassRef "@sapphirecity_baseboard_lib.sapphirecity_baseboard(sch_1):\DDR4_CHN_G_DQ_DQS_BYTE7\" )
			)
			( regionClassClass "@sapphirecity_baseboard_lib.sapphirecity_baseboard(sch_1):\RCC350\"
				( attribute "LINE_TO_LINE_SPACING" "8.00"
					( Origin gBackEnd )
				)
				( regionRef "@sapphirecity_baseboard_lib.sapphirecity_baseboard(sch_1):\CPU_BRKT\" )
				( netClassRef "@sapphirecity_baseboard_lib.sapphirecity_baseboard(sch_1):\DDR4_CHN_G_CTRL\" )
				( netClassRef "@sapphirecity_baseboard_lib.sapphirecity_baseboard(sch_1):\DDR4_CHN_G_DQ_DQS_BYTE6\" )
			)
			( regionClassClass "@sapphirecity_baseboard_lib.sapphirecity_baseboard(sch_1):\RCC351\"
				( attribute "LINE_TO_LINE_SPACING" "8.00"
					( Origin gBackEnd )
				)
				( regionRef "@sapphirecity_baseboard_lib.sapphirecity_baseboard(sch_1):\CPU_BRKT\" )
				( netClassRef "@sapphirecity_baseboard_lib.sapphirecity_baseboard(sch_1):\DDR4_CHN_G_CTRL\" )
				( netClassRef "@sapphirecity_baseboard_lib.sapphirecity_baseboard(sch_1):\DDR4_CHN_G_DQ_DQS_BYTE5\" )
			)
			( regionClassClass "@sapphirecity_baseboard_lib.sapphirecity_baseboard(sch_1):\RCC352\"
				( attribute "LINE_TO_LINE_SPACING" "8.00"
					( Origin gBackEnd )
				)
				( regionRef "@sapphirecity_baseboard_lib.sapphirecity_baseboard(sch_1):\CPU_BRKT\" )
				( netClassRef "@sapphirecity_baseboard_lib.sapphirecity_baseboard(sch_1):\DDR4_CHN_G_CTRL\" )
				( netClassRef "@sapphirecity_baseboard_lib.sapphirecity_baseboard(sch_1):\DDR4_CHN_G_DQ_DQS_BYTE4\" )
			)
			( regionClassClass "@sapphirecity_baseboard_lib.sapphirecity_baseboard(sch_1):\RCC353\"
				( attribute "LINE_TO_LINE_SPACING" "8.00"
					( Origin gBackEnd )
				)
				( regionRef "@sapphirecity_baseboard_lib.sapphirecity_baseboard(sch_1):\CPU_BRKT\" )
				( netClassRef "@sapphirecity_baseboard_lib.sapphirecity_baseboard(sch_1):\DDR4_CHN_G_CTRL\" )
				( netClassRef "@sapphirecity_baseboard_lib.sapphirecity_baseboard(sch_1):\DDR4_CHN_G_DQ_DQS_BYTE3\" )
			)
			( regionClassClass "@sapphirecity_baseboard_lib.sapphirecity_baseboard(sch_1):\RCC354\"
				( attribute "LINE_TO_LINE_SPACING" "8.00"
					( Origin gBackEnd )
				)
				( regionRef "@sapphirecity_baseboard_lib.sapphirecity_baseboard(sch_1):\CPU_BRKT\" )
				( netClassRef "@sapphirecity_baseboard_lib.sapphirecity_baseboard(sch_1):\DDR4_CHN_G_CTRL\" )
				( netClassRef "@sapphirecity_baseboard_lib.sapphirecity_baseboard(sch_1):\DDR4_CHN_G_DQ_DQS_BYTE2\" )
			)
			( regionClassClass "@sapphirecity_baseboard_lib.sapphirecity_baseboard(sch_1):\RCC355\"
				( attribute "LINE_TO_LINE_SPACING" "8.00"
					( Origin gBackEnd )
				)
				( regionRef "@sapphirecity_baseboard_lib.sapphirecity_baseboard(sch_1):\CPU_BRKT\" )
				( netClassRef "@sapphirecity_baseboard_lib.sapphirecity_baseboard(sch_1):\DDR4_CHN_G_CTRL\" )
				( netClassRef "@sapphirecity_baseboard_lib.sapphirecity_baseboard(sch_1):\DDR4_CHN_G_DQ_DQS_BYTE1\" )
			)
			( regionClassClass "@sapphirecity_baseboard_lib.sapphirecity_baseboard(sch_1):\RCC356\"
				( attribute "LINE_TO_LINE_SPACING" "8.00"
					( Origin gBackEnd )
				)
				( regionRef "@sapphirecity_baseboard_lib.sapphirecity_baseboard(sch_1):\CPU_BRKT\" )
				( netClassRef "@sapphirecity_baseboard_lib.sapphirecity_baseboard(sch_1):\DDR4_CHN_G_CTRL\" )
				( netClassRef "@sapphirecity_baseboard_lib.sapphirecity_baseboard(sch_1):\DDR4_CHN_G_DQ_DQS_BYTE0\" )
			)
			( regionClassClass "@sapphirecity_baseboard_lib.sapphirecity_baseboard(sch_1):\RCC357\"
				( attribute "LINE_TO_LINE_SPACING" "8.00"
					( Origin gBackEnd )
				)
				( regionRef "@sapphirecity_baseboard_lib.sapphirecity_baseboard(sch_1):\CPU_BRKT\" )
				( netClassRef "@sapphirecity_baseboard_lib.sapphirecity_baseboard(sch_1):\DDR4_CHN_G_CTRL\" )
				( netClassRef "@sapphirecity_baseboard_lib.sapphirecity_baseboard(sch_1):\DDR4_CHN_G_CTRL\" )
			)
			( regionClassClass "@sapphirecity_baseboard_lib.sapphirecity_baseboard(sch_1):\RCC358\"
				( attribute "LINE_TO_LINE_SPACING" "8.00"
					( Origin gBackEnd )
				)
				( regionRef "@sapphirecity_baseboard_lib.sapphirecity_baseboard(sch_1):\CPU_BRKT\" )
				( netClassRef "@sapphirecity_baseboard_lib.sapphirecity_baseboard(sch_1):\DDR4_CHN_G_DQ_DQS_BYTE0\" )
				( netClassRef "@sapphirecity_baseboard_lib.sapphirecity_baseboard(sch_1):\DDR4_CHN_G_ECC\" )
			)
			( regionClassClass "@sapphirecity_baseboard_lib.sapphirecity_baseboard(sch_1):\RCC359\"
				( attribute "LINE_TO_LINE_SPACING" "8.00"
					( Origin gBackEnd )
				)
				( regionRef "@sapphirecity_baseboard_lib.sapphirecity_baseboard(sch_1):\CPU_BRKT\" )
				( netClassRef "@sapphirecity_baseboard_lib.sapphirecity_baseboard(sch_1):\DDR4_CHN_G_DQ_DQS_BYTE0\" )
				( netClassRef "@sapphirecity_baseboard_lib.sapphirecity_baseboard(sch_1):\DDR4_CHN_G_DQ_DQS_BYTE7\" )
			)
			( regionClassClass "@sapphirecity_baseboard_lib.sapphirecity_baseboard(sch_1):\RCC360\"
				( attribute "LINE_TO_LINE_SPACING" "8.00"
					( Origin gBackEnd )
				)
				( regionRef "@sapphirecity_baseboard_lib.sapphirecity_baseboard(sch_1):\CPU_BRKT\" )
				( netClassRef "@sapphirecity_baseboard_lib.sapphirecity_baseboard(sch_1):\DDR4_CHN_G_DQ_DQS_BYTE0\" )
				( netClassRef "@sapphirecity_baseboard_lib.sapphirecity_baseboard(sch_1):\DDR4_CHN_G_DQ_DQS_BYTE6\" )
			)
			( regionClassClass "@sapphirecity_baseboard_lib.sapphirecity_baseboard(sch_1):\RCC361\"
				( attribute "LINE_TO_LINE_SPACING" "8.00"
					( Origin gBackEnd )
				)
				( regionRef "@sapphirecity_baseboard_lib.sapphirecity_baseboard(sch_1):\CPU_BRKT\" )
				( netClassRef "@sapphirecity_baseboard_lib.sapphirecity_baseboard(sch_1):\DDR4_CHN_G_DQ_DQS_BYTE0\" )
				( netClassRef "@sapphirecity_baseboard_lib.sapphirecity_baseboard(sch_1):\DDR4_CHN_G_DQ_DQS_BYTE5\" )
			)
			( regionClassClass "@sapphirecity_baseboard_lib.sapphirecity_baseboard(sch_1):\RCC362\"
				( attribute "LINE_TO_LINE_SPACING" "8.00"
					( Origin gBackEnd )
				)
				( regionRef "@sapphirecity_baseboard_lib.sapphirecity_baseboard(sch_1):\CPU_BRKT\" )
				( netClassRef "@sapphirecity_baseboard_lib.sapphirecity_baseboard(sch_1):\DDR4_CHN_G_DQ_DQS_BYTE0\" )
				( netClassRef "@sapphirecity_baseboard_lib.sapphirecity_baseboard(sch_1):\DDR4_CHN_G_DQ_DQS_BYTE4\" )
			)
			( regionClassClass "@sapphirecity_baseboard_lib.sapphirecity_baseboard(sch_1):\RCC363\"
				( attribute "LINE_TO_LINE_SPACING" "8.00"
					( Origin gBackEnd )
				)
				( regionRef "@sapphirecity_baseboard_lib.sapphirecity_baseboard(sch_1):\CPU_BRKT\" )
				( netClassRef "@sapphirecity_baseboard_lib.sapphirecity_baseboard(sch_1):\DDR4_CHN_G_DQ_DQS_BYTE0\" )
				( netClassRef "@sapphirecity_baseboard_lib.sapphirecity_baseboard(sch_1):\DDR4_CHN_G_DQ_DQS_BYTE3\" )
			)
			( regionClassClass "@sapphirecity_baseboard_lib.sapphirecity_baseboard(sch_1):\RCC364\"
				( attribute "LINE_TO_LINE_SPACING" "8.00"
					( Origin gBackEnd )
				)
				( regionRef "@sapphirecity_baseboard_lib.sapphirecity_baseboard(sch_1):\CPU_BRKT\" )
				( netClassRef "@sapphirecity_baseboard_lib.sapphirecity_baseboard(sch_1):\DDR4_CHN_G_DQ_DQS_BYTE0\" )
				( netClassRef "@sapphirecity_baseboard_lib.sapphirecity_baseboard(sch_1):\DDR4_CHN_G_DQ_DQS_BYTE2\" )
			)
			( regionClassClass "@sapphirecity_baseboard_lib.sapphirecity_baseboard(sch_1):\RCC365\"
				( attribute "LINE_TO_LINE_SPACING" "8.00"
					( Origin gBackEnd )
				)
				( regionRef "@sapphirecity_baseboard_lib.sapphirecity_baseboard(sch_1):\CPU_BRKT\" )
				( netClassRef "@sapphirecity_baseboard_lib.sapphirecity_baseboard(sch_1):\DDR4_CHN_G_DQ_DQS_BYTE0\" )
				( netClassRef "@sapphirecity_baseboard_lib.sapphirecity_baseboard(sch_1):\DDR4_CHN_G_DQ_DQS_BYTE1\" )
			)
			( regionClassClass "@sapphirecity_baseboard_lib.sapphirecity_baseboard(sch_1):\RCC366\"
				( attribute "LINE_TO_LINE_SPACING" "8.00"
					( Origin gBackEnd )
				)
				( regionRef "@sapphirecity_baseboard_lib.sapphirecity_baseboard(sch_1):\CPU_BRKT\" )
				( netClassRef "@sapphirecity_baseboard_lib.sapphirecity_baseboard(sch_1):\DDR4_CHN_G_DQ_DQS_BYTE0\" )
				( netClassRef "@sapphirecity_baseboard_lib.sapphirecity_baseboard(sch_1):\DDR4_CHN_G_DQ_DQS_BYTE0\" )
			)
			( regionClassClass "@sapphirecity_baseboard_lib.sapphirecity_baseboard(sch_1):\RCC367\"
				( attribute "LINE_TO_LINE_SPACING" "8.00"
					( Origin gBackEnd )
				)
				( regionRef "@sapphirecity_baseboard_lib.sapphirecity_baseboard(sch_1):\CPU_BRKT\" )
				( netClassRef "@sapphirecity_baseboard_lib.sapphirecity_baseboard(sch_1):\DDR4_CHN_G_DQ_DQS_BYTE1\" )
				( netClassRef "@sapphirecity_baseboard_lib.sapphirecity_baseboard(sch_1):\DDR4_CHN_G_ECC\" )
			)
			( regionClassClass "@sapphirecity_baseboard_lib.sapphirecity_baseboard(sch_1):\RCC368\"
				( attribute "LINE_TO_LINE_SPACING" "8.00"
					( Origin gBackEnd )
				)
				( regionRef "@sapphirecity_baseboard_lib.sapphirecity_baseboard(sch_1):\CPU_BRKT\" )
				( netClassRef "@sapphirecity_baseboard_lib.sapphirecity_baseboard(sch_1):\DDR4_CHN_G_DQ_DQS_BYTE1\" )
				( netClassRef "@sapphirecity_baseboard_lib.sapphirecity_baseboard(sch_1):\DDR4_CHN_G_DQ_DQS_BYTE7\" )
			)
			( regionClassClass "@sapphirecity_baseboard_lib.sapphirecity_baseboard(sch_1):\RCC369\"
				( attribute "LINE_TO_LINE_SPACING" "8.00"
					( Origin gBackEnd )
				)
				( regionRef "@sapphirecity_baseboard_lib.sapphirecity_baseboard(sch_1):\CPU_BRKT\" )
				( netClassRef "@sapphirecity_baseboard_lib.sapphirecity_baseboard(sch_1):\DDR4_CHN_G_DQ_DQS_BYTE1\" )
				( netClassRef "@sapphirecity_baseboard_lib.sapphirecity_baseboard(sch_1):\DDR4_CHN_G_DQ_DQS_BYTE6\" )
			)
			( regionClassClass "@sapphirecity_baseboard_lib.sapphirecity_baseboard(sch_1):\RCC370\"
				( attribute "LINE_TO_LINE_SPACING" "8.00"
					( Origin gBackEnd )
				)
				( regionRef "@sapphirecity_baseboard_lib.sapphirecity_baseboard(sch_1):\CPU_BRKT\" )
				( netClassRef "@sapphirecity_baseboard_lib.sapphirecity_baseboard(sch_1):\DDR4_CHN_G_DQ_DQS_BYTE1\" )
				( netClassRef "@sapphirecity_baseboard_lib.sapphirecity_baseboard(sch_1):\DDR4_CHN_G_DQ_DQS_BYTE5\" )
			)
			( regionClassClass "@sapphirecity_baseboard_lib.sapphirecity_baseboard(sch_1):\RCC371\"
				( attribute "LINE_TO_LINE_SPACING" "8.00"
					( Origin gBackEnd )
				)
				( regionRef "@sapphirecity_baseboard_lib.sapphirecity_baseboard(sch_1):\CPU_BRKT\" )
				( netClassRef "@sapphirecity_baseboard_lib.sapphirecity_baseboard(sch_1):\DDR4_CHN_G_DQ_DQS_BYTE1\" )
				( netClassRef "@sapphirecity_baseboard_lib.sapphirecity_baseboard(sch_1):\DDR4_CHN_G_DQ_DQS_BYTE4\" )
			)
			( regionClassClass "@sapphirecity_baseboard_lib.sapphirecity_baseboard(sch_1):\RCC372\"
				( attribute "LINE_TO_LINE_SPACING" "8.00"
					( Origin gBackEnd )
				)
				( regionRef "@sapphirecity_baseboard_lib.sapphirecity_baseboard(sch_1):\CPU_BRKT\" )
				( netClassRef "@sapphirecity_baseboard_lib.sapphirecity_baseboard(sch_1):\DDR4_CHN_G_DQ_DQS_BYTE1\" )
				( netClassRef "@sapphirecity_baseboard_lib.sapphirecity_baseboard(sch_1):\DDR4_CHN_G_DQ_DQS_BYTE3\" )
			)
			( regionClassClass "@sapphirecity_baseboard_lib.sapphirecity_baseboard(sch_1):\RCC373\"
				( attribute "LINE_TO_LINE_SPACING" "8.00"
					( Origin gBackEnd )
				)
				( regionRef "@sapphirecity_baseboard_lib.sapphirecity_baseboard(sch_1):\CPU_BRKT\" )
				( netClassRef "@sapphirecity_baseboard_lib.sapphirecity_baseboard(sch_1):\DDR4_CHN_G_DQ_DQS_BYTE1\" )
				( netClassRef "@sapphirecity_baseboard_lib.sapphirecity_baseboard(sch_1):\DDR4_CHN_G_DQ_DQS_BYTE2\" )
			)
			( regionClassClass "@sapphirecity_baseboard_lib.sapphirecity_baseboard(sch_1):\RCC374\"
				( attribute "LINE_TO_LINE_SPACING" "8.00"
					( Origin gBackEnd )
				)
				( regionRef "@sapphirecity_baseboard_lib.sapphirecity_baseboard(sch_1):\CPU_BRKT\" )
				( netClassRef "@sapphirecity_baseboard_lib.sapphirecity_baseboard(sch_1):\DDR4_CHN_G_DQ_DQS_BYTE1\" )
				( netClassRef "@sapphirecity_baseboard_lib.sapphirecity_baseboard(sch_1):\DDR4_CHN_G_DQ_DQS_BYTE1\" )
			)
			( regionClassClass "@sapphirecity_baseboard_lib.sapphirecity_baseboard(sch_1):\RCC375\"
				( attribute "LINE_TO_LINE_SPACING" "8.00"
					( Origin gBackEnd )
				)
				( regionRef "@sapphirecity_baseboard_lib.sapphirecity_baseboard(sch_1):\CPU_BRKT\" )
				( netClassRef "@sapphirecity_baseboard_lib.sapphirecity_baseboard(sch_1):\DDR4_CHN_G_DQ_DQS_BYTE2\" )
				( netClassRef "@sapphirecity_baseboard_lib.sapphirecity_baseboard(sch_1):\DDR4_CHN_G_ECC\" )
			)
			( regionClassClass "@sapphirecity_baseboard_lib.sapphirecity_baseboard(sch_1):\RCC376\"
				( attribute "LINE_TO_LINE_SPACING" "8.00"
					( Origin gBackEnd )
				)
				( regionRef "@sapphirecity_baseboard_lib.sapphirecity_baseboard(sch_1):\CPU_BRKT\" )
				( netClassRef "@sapphirecity_baseboard_lib.sapphirecity_baseboard(sch_1):\DDR4_CHN_G_DQ_DQS_BYTE2\" )
				( netClassRef "@sapphirecity_baseboard_lib.sapphirecity_baseboard(sch_1):\DDR4_CHN_G_DQ_DQS_BYTE7\" )
			)
			( regionClassClass "@sapphirecity_baseboard_lib.sapphirecity_baseboard(sch_1):\RCC377\"
				( attribute "LINE_TO_LINE_SPACING" "8.00"
					( Origin gBackEnd )
				)
				( regionRef "@sapphirecity_baseboard_lib.sapphirecity_baseboard(sch_1):\CPU_BRKT\" )
				( netClassRef "@sapphirecity_baseboard_lib.sapphirecity_baseboard(sch_1):\DDR4_CHN_G_DQ_DQS_BYTE2\" )
				( netClassRef "@sapphirecity_baseboard_lib.sapphirecity_baseboard(sch_1):\DDR4_CHN_G_DQ_DQS_BYTE6\" )
			)
			( regionClassClass "@sapphirecity_baseboard_lib.sapphirecity_baseboard(sch_1):\RCC378\"
				( attribute "LINE_TO_LINE_SPACING" "8.00"
					( Origin gBackEnd )
				)
				( regionRef "@sapphirecity_baseboard_lib.sapphirecity_baseboard(sch_1):\CPU_BRKT\" )
				( netClassRef "@sapphirecity_baseboard_lib.sapphirecity_baseboard(sch_1):\DDR4_CHN_G_DQ_DQS_BYTE2\" )
				( netClassRef "@sapphirecity_baseboard_lib.sapphirecity_baseboard(sch_1):\DDR4_CHN_G_DQ_DQS_BYTE5\" )
			)
			( regionClassClass "@sapphirecity_baseboard_lib.sapphirecity_baseboard(sch_1):\RCC379\"
				( attribute "LINE_TO_LINE_SPACING" "8.00"
					( Origin gBackEnd )
				)
				( regionRef "@sapphirecity_baseboard_lib.sapphirecity_baseboard(sch_1):\CPU_BRKT\" )
				( netClassRef "@sapphirecity_baseboard_lib.sapphirecity_baseboard(sch_1):\DDR4_CHN_G_DQ_DQS_BYTE2\" )
				( netClassRef "@sapphirecity_baseboard_lib.sapphirecity_baseboard(sch_1):\DDR4_CHN_G_DQ_DQS_BYTE4\" )
			)
			( regionClassClass "@sapphirecity_baseboard_lib.sapphirecity_baseboard(sch_1):\RCC380\"
				( attribute "LINE_TO_LINE_SPACING" "8.00"
					( Origin gBackEnd )
				)
				( regionRef "@sapphirecity_baseboard_lib.sapphirecity_baseboard(sch_1):\CPU_BRKT\" )
				( netClassRef "@sapphirecity_baseboard_lib.sapphirecity_baseboard(sch_1):\DDR4_CHN_G_DQ_DQS_BYTE2\" )
				( netClassRef "@sapphirecity_baseboard_lib.sapphirecity_baseboard(sch_1):\DDR4_CHN_G_DQ_DQS_BYTE3\" )
			)
			( regionClassClass "@sapphirecity_baseboard_lib.sapphirecity_baseboard(sch_1):\RCC381\"
				( attribute "LINE_TO_LINE_SPACING" "8.00"
					( Origin gBackEnd )
				)
				( regionRef "@sapphirecity_baseboard_lib.sapphirecity_baseboard(sch_1):\CPU_BRKT\" )
				( netClassRef "@sapphirecity_baseboard_lib.sapphirecity_baseboard(sch_1):\DDR4_CHN_G_DQ_DQS_BYTE2\" )
				( netClassRef "@sapphirecity_baseboard_lib.sapphirecity_baseboard(sch_1):\DDR4_CHN_G_DQ_DQS_BYTE2\" )
			)
			( regionClassClass "@sapphirecity_baseboard_lib.sapphirecity_baseboard(sch_1):\RCC382\"
				( attribute "LINE_TO_LINE_SPACING" "8.00"
					( Origin gBackEnd )
				)
				( regionRef "@sapphirecity_baseboard_lib.sapphirecity_baseboard(sch_1):\CPU_BRKT\" )
				( netClassRef "@sapphirecity_baseboard_lib.sapphirecity_baseboard(sch_1):\DDR4_CHN_G_DQ_DQS_BYTE3\" )
				( netClassRef "@sapphirecity_baseboard_lib.sapphirecity_baseboard(sch_1):\DDR4_CHN_G_ECC\" )
			)
			( regionClassClass "@sapphirecity_baseboard_lib.sapphirecity_baseboard(sch_1):\RCC383\"
				( attribute "LINE_TO_LINE_SPACING" "8.00"
					( Origin gBackEnd )
				)
				( regionRef "@sapphirecity_baseboard_lib.sapphirecity_baseboard(sch_1):\CPU_BRKT\" )
				( netClassRef "@sapphirecity_baseboard_lib.sapphirecity_baseboard(sch_1):\DDR4_CHN_G_DQ_DQS_BYTE3\" )
				( netClassRef "@sapphirecity_baseboard_lib.sapphirecity_baseboard(sch_1):\DDR4_CHN_G_DQ_DQS_BYTE7\" )
			)
			( regionClassClass "@sapphirecity_baseboard_lib.sapphirecity_baseboard(sch_1):\RCC384\"
				( attribute "LINE_TO_LINE_SPACING" "8.00"
					( Origin gBackEnd )
				)
				( regionRef "@sapphirecity_baseboard_lib.sapphirecity_baseboard(sch_1):\CPU_BRKT\" )
				( netClassRef "@sapphirecity_baseboard_lib.sapphirecity_baseboard(sch_1):\DDR4_CHN_G_DQ_DQS_BYTE3\" )
				( netClassRef "@sapphirecity_baseboard_lib.sapphirecity_baseboard(sch_1):\DDR4_CHN_G_DQ_DQS_BYTE6\" )
			)
			( regionClassClass "@sapphirecity_baseboard_lib.sapphirecity_baseboard(sch_1):\RCC385\"
				( attribute "LINE_TO_LINE_SPACING" "8.00"
					( Origin gBackEnd )
				)
				( regionRef "@sapphirecity_baseboard_lib.sapphirecity_baseboard(sch_1):\CPU_BRKT\" )
				( netClassRef "@sapphirecity_baseboard_lib.sapphirecity_baseboard(sch_1):\DDR4_CHN_G_DQ_DQS_BYTE3\" )
				( netClassRef "@sapphirecity_baseboard_lib.sapphirecity_baseboard(sch_1):\DDR4_CHN_G_DQ_DQS_BYTE5\" )
			)
			( regionClassClass "@sapphirecity_baseboard_lib.sapphirecity_baseboard(sch_1):\RCC386\"
				( attribute "LINE_TO_LINE_SPACING" "8.00"
					( Origin gBackEnd )
				)
				( regionRef "@sapphirecity_baseboard_lib.sapphirecity_baseboard(sch_1):\CPU_BRKT\" )
				( netClassRef "@sapphirecity_baseboard_lib.sapphirecity_baseboard(sch_1):\DDR4_CHN_G_DQ_DQS_BYTE3\" )
				( netClassRef "@sapphirecity_baseboard_lib.sapphirecity_baseboard(sch_1):\DDR4_CHN_G_DQ_DQS_BYTE4\" )
			)
			( regionClassClass "@sapphirecity_baseboard_lib.sapphirecity_baseboard(sch_1):\RCC387\"
				( attribute "LINE_TO_LINE_SPACING" "8.00"
					( Origin gBackEnd )
				)
				( regionRef "@sapphirecity_baseboard_lib.sapphirecity_baseboard(sch_1):\CPU_BRKT\" )
				( netClassRef "@sapphirecity_baseboard_lib.sapphirecity_baseboard(sch_1):\DDR4_CHN_G_DQ_DQS_BYTE3\" )
				( netClassRef "@sapphirecity_baseboard_lib.sapphirecity_baseboard(sch_1):\DDR4_CHN_G_DQ_DQS_BYTE3\" )
			)
			( regionClassClass "@sapphirecity_baseboard_lib.sapphirecity_baseboard(sch_1):\RCC388\"
				( attribute "LINE_TO_LINE_SPACING" "8.00"
					( Origin gBackEnd )
				)
				( regionRef "@sapphirecity_baseboard_lib.sapphirecity_baseboard(sch_1):\CPU_BRKT\" )
				( netClassRef "@sapphirecity_baseboard_lib.sapphirecity_baseboard(sch_1):\DDR4_CHN_G_DQ_DQS_BYTE4\" )
				( netClassRef "@sapphirecity_baseboard_lib.sapphirecity_baseboard(sch_1):\DDR4_CHN_G_ECC\" )
			)
			( regionClassClass "@sapphirecity_baseboard_lib.sapphirecity_baseboard(sch_1):\RCC389\"
				( attribute "LINE_TO_LINE_SPACING" "8.00"
					( Origin gBackEnd )
				)
				( regionRef "@sapphirecity_baseboard_lib.sapphirecity_baseboard(sch_1):\CPU_BRKT\" )
				( netClassRef "@sapphirecity_baseboard_lib.sapphirecity_baseboard(sch_1):\DDR4_CHN_G_DQ_DQS_BYTE4\" )
				( netClassRef "@sapphirecity_baseboard_lib.sapphirecity_baseboard(sch_1):\DDR4_CHN_G_DQ_DQS_BYTE7\" )
			)
			( regionClassClass "@sapphirecity_baseboard_lib.sapphirecity_baseboard(sch_1):\RCC390\"
				( attribute "LINE_TO_LINE_SPACING" "8.00"
					( Origin gBackEnd )
				)
				( regionRef "@sapphirecity_baseboard_lib.sapphirecity_baseboard(sch_1):\CPU_BRKT\" )
				( netClassRef "@sapphirecity_baseboard_lib.sapphirecity_baseboard(sch_1):\DDR4_CHN_G_DQ_DQS_BYTE4\" )
				( netClassRef "@sapphirecity_baseboard_lib.sapphirecity_baseboard(sch_1):\DDR4_CHN_G_DQ_DQS_BYTE6\" )
			)
			( regionClassClass "@sapphirecity_baseboard_lib.sapphirecity_baseboard(sch_1):\RCC391\"
				( attribute "LINE_TO_LINE_SPACING" "8.00"
					( Origin gBackEnd )
				)
				( regionRef "@sapphirecity_baseboard_lib.sapphirecity_baseboard(sch_1):\CPU_BRKT\" )
				( netClassRef "@sapphirecity_baseboard_lib.sapphirecity_baseboard(sch_1):\DDR4_CHN_G_DQ_DQS_BYTE4\" )
				( netClassRef "@sapphirecity_baseboard_lib.sapphirecity_baseboard(sch_1):\DDR4_CHN_G_DQ_DQS_BYTE5\" )
			)
			( regionClassClass "@sapphirecity_baseboard_lib.sapphirecity_baseboard(sch_1):\RCC392\"
				( attribute "LINE_TO_LINE_SPACING" "8.00"
					( Origin gBackEnd )
				)
				( regionRef "@sapphirecity_baseboard_lib.sapphirecity_baseboard(sch_1):\CPU_BRKT\" )
				( netClassRef "@sapphirecity_baseboard_lib.sapphirecity_baseboard(sch_1):\DDR4_CHN_G_DQ_DQS_BYTE4\" )
				( netClassRef "@sapphirecity_baseboard_lib.sapphirecity_baseboard(sch_1):\DDR4_CHN_G_DQ_DQS_BYTE4\" )
			)
			( regionClassClass "@sapphirecity_baseboard_lib.sapphirecity_baseboard(sch_1):\RCC393\"
				( attribute "LINE_TO_LINE_SPACING" "8.00"
					( Origin gBackEnd )
				)
				( regionRef "@sapphirecity_baseboard_lib.sapphirecity_baseboard(sch_1):\CPU_BRKT\" )
				( netClassRef "@sapphirecity_baseboard_lib.sapphirecity_baseboard(sch_1):\DDR4_CHN_G_DQ_DQS_BYTE5\" )
				( netClassRef "@sapphirecity_baseboard_lib.sapphirecity_baseboard(sch_1):\DDR4_CHN_G_ECC\" )
			)
			( regionClassClass "@sapphirecity_baseboard_lib.sapphirecity_baseboard(sch_1):\RCC394\"
				( attribute "LINE_TO_LINE_SPACING" "8.00"
					( Origin gBackEnd )
				)
				( regionRef "@sapphirecity_baseboard_lib.sapphirecity_baseboard(sch_1):\CPU_BRKT\" )
				( netClassRef "@sapphirecity_baseboard_lib.sapphirecity_baseboard(sch_1):\DDR4_CHN_G_DQ_DQS_BYTE5\" )
				( netClassRef "@sapphirecity_baseboard_lib.sapphirecity_baseboard(sch_1):\DDR4_CHN_G_DQ_DQS_BYTE7\" )
			)
			( regionClassClass "@sapphirecity_baseboard_lib.sapphirecity_baseboard(sch_1):\RCC395\"
				( attribute "LINE_TO_LINE_SPACING" "8.00"
					( Origin gBackEnd )
				)
				( regionRef "@sapphirecity_baseboard_lib.sapphirecity_baseboard(sch_1):\CPU_BRKT\" )
				( netClassRef "@sapphirecity_baseboard_lib.sapphirecity_baseboard(sch_1):\DDR4_CHN_G_DQ_DQS_BYTE5\" )
				( netClassRef "@sapphirecity_baseboard_lib.sapphirecity_baseboard(sch_1):\DDR4_CHN_G_DQ_DQS_BYTE6\" )
			)
			( regionClassClass "@sapphirecity_baseboard_lib.sapphirecity_baseboard(sch_1):\RCC396\"
				( attribute "LINE_TO_LINE_SPACING" "8.00"
					( Origin gBackEnd )
				)
				( regionRef "@sapphirecity_baseboard_lib.sapphirecity_baseboard(sch_1):\CPU_BRKT\" )
				( netClassRef "@sapphirecity_baseboard_lib.sapphirecity_baseboard(sch_1):\DDR4_CHN_G_DQ_DQS_BYTE5\" )
				( netClassRef "@sapphirecity_baseboard_lib.sapphirecity_baseboard(sch_1):\DDR4_CHN_G_DQ_DQS_BYTE5\" )
			)
			( regionClassClass "@sapphirecity_baseboard_lib.sapphirecity_baseboard(sch_1):\RCC397\"
				( attribute "LINE_TO_LINE_SPACING" "8.00"
					( Origin gBackEnd )
				)
				( regionRef "@sapphirecity_baseboard_lib.sapphirecity_baseboard(sch_1):\CPU_BRKT\" )
				( netClassRef "@sapphirecity_baseboard_lib.sapphirecity_baseboard(sch_1):\DDR4_CHN_G_DQ_DQS_BYTE6\" )
				( netClassRef "@sapphirecity_baseboard_lib.sapphirecity_baseboard(sch_1):\DDR4_CHN_G_ECC\" )
			)
			( regionClassClass "@sapphirecity_baseboard_lib.sapphirecity_baseboard(sch_1):\RCC398\"
				( attribute "LINE_TO_LINE_SPACING" "8.00"
					( Origin gBackEnd )
				)
				( regionRef "@sapphirecity_baseboard_lib.sapphirecity_baseboard(sch_1):\CPU_BRKT\" )
				( netClassRef "@sapphirecity_baseboard_lib.sapphirecity_baseboard(sch_1):\DDR4_CHN_G_DQ_DQS_BYTE6\" )
				( netClassRef "@sapphirecity_baseboard_lib.sapphirecity_baseboard(sch_1):\DDR4_CHN_G_DQ_DQS_BYTE7\" )
			)
			( regionClassClass "@sapphirecity_baseboard_lib.sapphirecity_baseboard(sch_1):\RCC399\"
				( attribute "LINE_TO_LINE_SPACING" "8.00"
					( Origin gBackEnd )
				)
				( regionRef "@sapphirecity_baseboard_lib.sapphirecity_baseboard(sch_1):\CPU_BRKT\" )
				( netClassRef "@sapphirecity_baseboard_lib.sapphirecity_baseboard(sch_1):\DDR4_CHN_G_DQ_DQS_BYTE6\" )
				( netClassRef "@sapphirecity_baseboard_lib.sapphirecity_baseboard(sch_1):\DDR4_CHN_G_DQ_DQS_BYTE6\" )
			)
			( regionClassClass "@sapphirecity_baseboard_lib.sapphirecity_baseboard(sch_1):\RCC400\"
				( attribute "LINE_TO_LINE_SPACING" "8.00"
					( Origin gBackEnd )
				)
				( regionRef "@sapphirecity_baseboard_lib.sapphirecity_baseboard(sch_1):\CPU_BRKT\" )
				( netClassRef "@sapphirecity_baseboard_lib.sapphirecity_baseboard(sch_1):\DDR4_CHN_G_DQ_DQS_BYTE7\" )
				( netClassRef "@sapphirecity_baseboard_lib.sapphirecity_baseboard(sch_1):\DDR4_CHN_G_ECC\" )
			)
			( regionClassClass "@sapphirecity_baseboard_lib.sapphirecity_baseboard(sch_1):\RCC401\"
				( attribute "LINE_TO_LINE_SPACING" "8.00"
					( Origin gBackEnd )
				)
				( regionRef "@sapphirecity_baseboard_lib.sapphirecity_baseboard(sch_1):\CPU_BRKT\" )
				( netClassRef "@sapphirecity_baseboard_lib.sapphirecity_baseboard(sch_1):\DDR4_CHN_G_DQ_DQS_BYTE7\" )
				( netClassRef "@sapphirecity_baseboard_lib.sapphirecity_baseboard(sch_1):\DDR4_CHN_G_DQ_DQS_BYTE7\" )
			)
			( regionClassClass "@sapphirecity_baseboard_lib.sapphirecity_baseboard(sch_1):\RCC402\"
				( attribute "LINE_TO_LINE_SPACING" "8.00"
					( Origin gBackEnd )
				)
				( regionRef "@sapphirecity_baseboard_lib.sapphirecity_baseboard(sch_1):\CPU_BRKT\" )
				( netClassRef "@sapphirecity_baseboard_lib.sapphirecity_baseboard(sch_1):\DDR4_CHN_G_ECC\" )
				( netClassRef "@sapphirecity_baseboard_lib.sapphirecity_baseboard(sch_1):\DDR4_CHN_G_ECC\" )
			)
			( regionClassClass "@sapphirecity_baseboard_lib.sapphirecity_baseboard(sch_1):\RCC403\"
				( attribute "LINE_TO_LINE_SPACING" "8.00"
					( Origin gBackEnd )
				)
				( regionRef "@sapphirecity_baseboard_lib.sapphirecity_baseboard(sch_1):\CPU_BRKT\" )
				( netClassRef "@sapphirecity_baseboard_lib.sapphirecity_baseboard(sch_1):\DDR4_CHN_H_CLK\" )
				( netClassRef "@sapphirecity_baseboard_lib.sapphirecity_baseboard(sch_1):\DDR4_CHN_H_ECC\" )
			)
			( regionClassClass "@sapphirecity_baseboard_lib.sapphirecity_baseboard(sch_1):\RCC404\"
				( attribute "LINE_TO_LINE_SPACING" "8.00"
					( Origin gBackEnd )
				)
				( regionRef "@sapphirecity_baseboard_lib.sapphirecity_baseboard(sch_1):\CPU_BRKT\" )
				( netClassRef "@sapphirecity_baseboard_lib.sapphirecity_baseboard(sch_1):\DDR4_CHN_H_CLK\" )
				( netClassRef "@sapphirecity_baseboard_lib.sapphirecity_baseboard(sch_1):\DDR4_CHN_H_DQ_DQS_BYTE7\" )
			)
			( regionClassClass "@sapphirecity_baseboard_lib.sapphirecity_baseboard(sch_1):\RCC405\"
				( attribute "LINE_TO_LINE_SPACING" "8.00"
					( Origin gBackEnd )
				)
				( regionRef "@sapphirecity_baseboard_lib.sapphirecity_baseboard(sch_1):\CPU_BRKT\" )
				( netClassRef "@sapphirecity_baseboard_lib.sapphirecity_baseboard(sch_1):\DDR4_CHN_H_CLK\" )
				( netClassRef "@sapphirecity_baseboard_lib.sapphirecity_baseboard(sch_1):\DDR4_CHN_H_DQ_DQS_BYTE6\" )
			)
			( regionClassClass "@sapphirecity_baseboard_lib.sapphirecity_baseboard(sch_1):\RCC406\"
				( attribute "LINE_TO_LINE_SPACING" "8.00"
					( Origin gBackEnd )
				)
				( regionRef "@sapphirecity_baseboard_lib.sapphirecity_baseboard(sch_1):\CPU_BRKT\" )
				( netClassRef "@sapphirecity_baseboard_lib.sapphirecity_baseboard(sch_1):\DDR4_CHN_H_CLK\" )
				( netClassRef "@sapphirecity_baseboard_lib.sapphirecity_baseboard(sch_1):\DDR4_CHN_H_DQ_DQS_BYTE5\" )
			)
			( regionClassClass "@sapphirecity_baseboard_lib.sapphirecity_baseboard(sch_1):\RCC407\"
				( attribute "LINE_TO_LINE_SPACING" "8.00"
					( Origin gBackEnd )
				)
				( regionRef "@sapphirecity_baseboard_lib.sapphirecity_baseboard(sch_1):\CPU_BRKT\" )
				( netClassRef "@sapphirecity_baseboard_lib.sapphirecity_baseboard(sch_1):\DDR4_CHN_H_CLK\" )
				( netClassRef "@sapphirecity_baseboard_lib.sapphirecity_baseboard(sch_1):\DDR4_CHN_H_DQ_DQS_BYTE4\" )
			)
			( regionClassClass "@sapphirecity_baseboard_lib.sapphirecity_baseboard(sch_1):\RCC408\"
				( attribute "LINE_TO_LINE_SPACING" "8.00"
					( Origin gBackEnd )
				)
				( regionRef "@sapphirecity_baseboard_lib.sapphirecity_baseboard(sch_1):\CPU_BRKT\" )
				( netClassRef "@sapphirecity_baseboard_lib.sapphirecity_baseboard(sch_1):\DDR4_CHN_H_CLK\" )
				( netClassRef "@sapphirecity_baseboard_lib.sapphirecity_baseboard(sch_1):\DDR4_CHN_H_DQ_DQS_BYTE3\" )
			)
			( regionClassClass "@sapphirecity_baseboard_lib.sapphirecity_baseboard(sch_1):\RCC409\"
				( attribute "LINE_TO_LINE_SPACING" "8.00"
					( Origin gBackEnd )
				)
				( regionRef "@sapphirecity_baseboard_lib.sapphirecity_baseboard(sch_1):\CPU_BRKT\" )
				( netClassRef "@sapphirecity_baseboard_lib.sapphirecity_baseboard(sch_1):\DDR4_CHN_H_CLK\" )
				( netClassRef "@sapphirecity_baseboard_lib.sapphirecity_baseboard(sch_1):\DDR4_CHN_H_DQ_DQS_BYTE2\" )
			)
			( regionClassClass "@sapphirecity_baseboard_lib.sapphirecity_baseboard(sch_1):\RCC410\"
				( attribute "LINE_TO_LINE_SPACING" "8.00"
					( Origin gBackEnd )
				)
				( regionRef "@sapphirecity_baseboard_lib.sapphirecity_baseboard(sch_1):\CPU_BRKT\" )
				( netClassRef "@sapphirecity_baseboard_lib.sapphirecity_baseboard(sch_1):\DDR4_CHN_H_CLK\" )
				( netClassRef "@sapphirecity_baseboard_lib.sapphirecity_baseboard(sch_1):\DDR4_CHN_H_DQ_DQS_BYTE1\" )
			)
			( regionClassClass "@sapphirecity_baseboard_lib.sapphirecity_baseboard(sch_1):\RCC411\"
				( attribute "LINE_TO_LINE_SPACING" "8.00"
					( Origin gBackEnd )
				)
				( regionRef "@sapphirecity_baseboard_lib.sapphirecity_baseboard(sch_1):\CPU_BRKT\" )
				( netClassRef "@sapphirecity_baseboard_lib.sapphirecity_baseboard(sch_1):\DDR4_CHN_H_CLK\" )
				( netClassRef "@sapphirecity_baseboard_lib.sapphirecity_baseboard(sch_1):\DDR4_CHN_H_DQ_DQS_BYTE0\" )
			)
			( regionClassClass "@sapphirecity_baseboard_lib.sapphirecity_baseboard(sch_1):\RCC412\"
				( attribute "LINE_TO_LINE_SPACING" "8.00"
					( Origin gBackEnd )
				)
				( regionRef "@sapphirecity_baseboard_lib.sapphirecity_baseboard(sch_1):\CPU_BRKT\" )
				( netClassRef "@sapphirecity_baseboard_lib.sapphirecity_baseboard(sch_1):\DDR4_CHN_H_CLK\" )
				( netClassRef "@sapphirecity_baseboard_lib.sapphirecity_baseboard(sch_1):\DDR4_CHN_H_CTRL\" )
			)
			( regionClassClass "@sapphirecity_baseboard_lib.sapphirecity_baseboard(sch_1):\RCC413\"
				( attribute "LINE_TO_LINE_SPACING" "8.00"
					( Origin gBackEnd )
				)
				( regionRef "@sapphirecity_baseboard_lib.sapphirecity_baseboard(sch_1):\CPU_BRKT\" )
				( netClassRef "@sapphirecity_baseboard_lib.sapphirecity_baseboard(sch_1):\DDR4_CHN_H_CLK\" )
				( netClassRef "@sapphirecity_baseboard_lib.sapphirecity_baseboard(sch_1):\DDR4_CHN_H_CMD_ADD\" )
			)
			( regionClassClass "@sapphirecity_baseboard_lib.sapphirecity_baseboard(sch_1):\RCC414\"
				( attribute "LINE_TO_LINE_SPACING" "8.00"
					( Origin gBackEnd )
				)
				( regionRef "@sapphirecity_baseboard_lib.sapphirecity_baseboard(sch_1):\CPU_BRKT\" )
				( netClassRef "@sapphirecity_baseboard_lib.sapphirecity_baseboard(sch_1):\DDR4_CHN_H_CLK\" )
				( netClassRef "@sapphirecity_baseboard_lib.sapphirecity_baseboard(sch_1):\DDR4_CHN_H_CLK\" )
			)
			( regionClassClass "@sapphirecity_baseboard_lib.sapphirecity_baseboard(sch_1):\RCC415\"
				( attribute "LINE_TO_LINE_SPACING" "8.00"
					( Origin gBackEnd )
				)
				( regionRef "@sapphirecity_baseboard_lib.sapphirecity_baseboard(sch_1):\CPU_BRKT\" )
				( netClassRef "@sapphirecity_baseboard_lib.sapphirecity_baseboard(sch_1):\DDR4_CHN_H_CMD_ADD\" )
				( netClassRef "@sapphirecity_baseboard_lib.sapphirecity_baseboard(sch_1):\DDR4_CHN_H_ECC\" )
			)
			( regionClassClass "@sapphirecity_baseboard_lib.sapphirecity_baseboard(sch_1):\RCC416\"
				( attribute "LINE_TO_LINE_SPACING" "8.00"
					( Origin gBackEnd )
				)
				( regionRef "@sapphirecity_baseboard_lib.sapphirecity_baseboard(sch_1):\CPU_BRKT\" )
				( netClassRef "@sapphirecity_baseboard_lib.sapphirecity_baseboard(sch_1):\DDR4_CHN_H_CMD_ADD\" )
				( netClassRef "@sapphirecity_baseboard_lib.sapphirecity_baseboard(sch_1):\DDR4_CHN_H_DQ_DQS_BYTE7\" )
			)
			( regionClassClass "@sapphirecity_baseboard_lib.sapphirecity_baseboard(sch_1):\RCC417\"
				( attribute "LINE_TO_LINE_SPACING" "8.00"
					( Origin gBackEnd )
				)
				( regionRef "@sapphirecity_baseboard_lib.sapphirecity_baseboard(sch_1):\CPU_BRKT\" )
				( netClassRef "@sapphirecity_baseboard_lib.sapphirecity_baseboard(sch_1):\DDR4_CHN_H_CMD_ADD\" )
				( netClassRef "@sapphirecity_baseboard_lib.sapphirecity_baseboard(sch_1):\DDR4_CHN_H_DQ_DQS_BYTE6\" )
			)
			( regionClassClass "@sapphirecity_baseboard_lib.sapphirecity_baseboard(sch_1):\RCC418\"
				( attribute "LINE_TO_LINE_SPACING" "8.00"
					( Origin gBackEnd )
				)
				( regionRef "@sapphirecity_baseboard_lib.sapphirecity_baseboard(sch_1):\CPU_BRKT\" )
				( netClassRef "@sapphirecity_baseboard_lib.sapphirecity_baseboard(sch_1):\DDR4_CHN_H_CMD_ADD\" )
				( netClassRef "@sapphirecity_baseboard_lib.sapphirecity_baseboard(sch_1):\DDR4_CHN_H_DQ_DQS_BYTE5\" )
			)
			( regionClassClass "@sapphirecity_baseboard_lib.sapphirecity_baseboard(sch_1):\RCC419\"
				( attribute "LINE_TO_LINE_SPACING" "8.00"
					( Origin gBackEnd )
				)
				( regionRef "@sapphirecity_baseboard_lib.sapphirecity_baseboard(sch_1):\CPU_BRKT\" )
				( netClassRef "@sapphirecity_baseboard_lib.sapphirecity_baseboard(sch_1):\DDR4_CHN_H_CMD_ADD\" )
				( netClassRef "@sapphirecity_baseboard_lib.sapphirecity_baseboard(sch_1):\DDR4_CHN_H_DQ_DQS_BYTE4\" )
			)
			( regionClassClass "@sapphirecity_baseboard_lib.sapphirecity_baseboard(sch_1):\RCC420\"
				( attribute "LINE_TO_LINE_SPACING" "8.00"
					( Origin gBackEnd )
				)
				( regionRef "@sapphirecity_baseboard_lib.sapphirecity_baseboard(sch_1):\CPU_BRKT\" )
				( netClassRef "@sapphirecity_baseboard_lib.sapphirecity_baseboard(sch_1):\DDR4_CHN_H_CMD_ADD\" )
				( netClassRef "@sapphirecity_baseboard_lib.sapphirecity_baseboard(sch_1):\DDR4_CHN_H_DQ_DQS_BYTE3\" )
			)
			( regionClassClass "@sapphirecity_baseboard_lib.sapphirecity_baseboard(sch_1):\RCC421\"
				( attribute "LINE_TO_LINE_SPACING" "8.00"
					( Origin gBackEnd )
				)
				( regionRef "@sapphirecity_baseboard_lib.sapphirecity_baseboard(sch_1):\CPU_BRKT\" )
				( netClassRef "@sapphirecity_baseboard_lib.sapphirecity_baseboard(sch_1):\DDR4_CHN_H_CMD_ADD\" )
				( netClassRef "@sapphirecity_baseboard_lib.sapphirecity_baseboard(sch_1):\DDR4_CHN_H_DQ_DQS_BYTE2\" )
			)
			( regionClassClass "@sapphirecity_baseboard_lib.sapphirecity_baseboard(sch_1):\RCC422\"
				( attribute "LINE_TO_LINE_SPACING" "8.00"
					( Origin gBackEnd )
				)
				( regionRef "@sapphirecity_baseboard_lib.sapphirecity_baseboard(sch_1):\CPU_BRKT\" )
				( netClassRef "@sapphirecity_baseboard_lib.sapphirecity_baseboard(sch_1):\DDR4_CHN_H_CMD_ADD\" )
				( netClassRef "@sapphirecity_baseboard_lib.sapphirecity_baseboard(sch_1):\DDR4_CHN_H_DQ_DQS_BYTE1\" )
			)
			( regionClassClass "@sapphirecity_baseboard_lib.sapphirecity_baseboard(sch_1):\RCC423\"
				( attribute "LINE_TO_LINE_SPACING" "8.00"
					( Origin gBackEnd )
				)
				( regionRef "@sapphirecity_baseboard_lib.sapphirecity_baseboard(sch_1):\CPU_BRKT\" )
				( netClassRef "@sapphirecity_baseboard_lib.sapphirecity_baseboard(sch_1):\DDR4_CHN_H_CMD_ADD\" )
				( netClassRef "@sapphirecity_baseboard_lib.sapphirecity_baseboard(sch_1):\DDR4_CHN_H_DQ_DQS_BYTE0\" )
			)
			( regionClassClass "@sapphirecity_baseboard_lib.sapphirecity_baseboard(sch_1):\RCC424\"
				( attribute "LINE_TO_LINE_SPACING" "8.00"
					( Origin gBackEnd )
				)
				( regionRef "@sapphirecity_baseboard_lib.sapphirecity_baseboard(sch_1):\CPU_BRKT\" )
				( netClassRef "@sapphirecity_baseboard_lib.sapphirecity_baseboard(sch_1):\DDR4_CHN_H_CMD_ADD\" )
				( netClassRef "@sapphirecity_baseboard_lib.sapphirecity_baseboard(sch_1):\DDR4_CHN_H_CTRL\" )
			)
			( regionClassClass "@sapphirecity_baseboard_lib.sapphirecity_baseboard(sch_1):\RCC425\"
				( attribute "LINE_TO_LINE_SPACING" "8.00"
					( Origin gBackEnd )
				)
				( regionRef "@sapphirecity_baseboard_lib.sapphirecity_baseboard(sch_1):\CPU_BRKT\" )
				( netClassRef "@sapphirecity_baseboard_lib.sapphirecity_baseboard(sch_1):\DDR4_CHN_H_CMD_ADD\" )
				( netClassRef "@sapphirecity_baseboard_lib.sapphirecity_baseboard(sch_1):\DDR4_CHN_H_CMD_ADD\" )
			)
			( regionClassClass "@sapphirecity_baseboard_lib.sapphirecity_baseboard(sch_1):\RCC426\"
				( attribute "LINE_TO_LINE_SPACING" "8.00"
					( Origin gBackEnd )
				)
				( regionRef "@sapphirecity_baseboard_lib.sapphirecity_baseboard(sch_1):\CPU_BRKT\" )
				( netClassRef "@sapphirecity_baseboard_lib.sapphirecity_baseboard(sch_1):\DDR4_CHN_H_CTRL\" )
				( netClassRef "@sapphirecity_baseboard_lib.sapphirecity_baseboard(sch_1):\DDR4_CHN_H_ECC\" )
			)
			( regionClassClass "@sapphirecity_baseboard_lib.sapphirecity_baseboard(sch_1):\RCC427\"
				( attribute "LINE_TO_LINE_SPACING" "8.00"
					( Origin gBackEnd )
				)
				( regionRef "@sapphirecity_baseboard_lib.sapphirecity_baseboard(sch_1):\CPU_BRKT\" )
				( netClassRef "@sapphirecity_baseboard_lib.sapphirecity_baseboard(sch_1):\DDR4_CHN_H_CTRL\" )
				( netClassRef "@sapphirecity_baseboard_lib.sapphirecity_baseboard(sch_1):\DDR4_CHN_H_DQ_DQS_BYTE7\" )
			)
			( regionClassClass "@sapphirecity_baseboard_lib.sapphirecity_baseboard(sch_1):\RCC428\"
				( attribute "LINE_TO_LINE_SPACING" "8.00"
					( Origin gBackEnd )
				)
				( regionRef "@sapphirecity_baseboard_lib.sapphirecity_baseboard(sch_1):\CPU_BRKT\" )
				( netClassRef "@sapphirecity_baseboard_lib.sapphirecity_baseboard(sch_1):\DDR4_CHN_H_CTRL\" )
				( netClassRef "@sapphirecity_baseboard_lib.sapphirecity_baseboard(sch_1):\DDR4_CHN_H_DQ_DQS_BYTE6\" )
			)
			( regionClassClass "@sapphirecity_baseboard_lib.sapphirecity_baseboard(sch_1):\RCC429\"
				( attribute "LINE_TO_LINE_SPACING" "8.00"
					( Origin gBackEnd )
				)
				( regionRef "@sapphirecity_baseboard_lib.sapphirecity_baseboard(sch_1):\CPU_BRKT\" )
				( netClassRef "@sapphirecity_baseboard_lib.sapphirecity_baseboard(sch_1):\DDR4_CHN_H_CTRL\" )
				( netClassRef "@sapphirecity_baseboard_lib.sapphirecity_baseboard(sch_1):\DDR4_CHN_H_DQ_DQS_BYTE5\" )
			)
			( regionClassClass "@sapphirecity_baseboard_lib.sapphirecity_baseboard(sch_1):\RCC430\"
				( attribute "LINE_TO_LINE_SPACING" "8.00"
					( Origin gBackEnd )
				)
				( regionRef "@sapphirecity_baseboard_lib.sapphirecity_baseboard(sch_1):\CPU_BRKT\" )
				( netClassRef "@sapphirecity_baseboard_lib.sapphirecity_baseboard(sch_1):\DDR4_CHN_H_CTRL\" )
				( netClassRef "@sapphirecity_baseboard_lib.sapphirecity_baseboard(sch_1):\DDR4_CHN_H_DQ_DQS_BYTE4\" )
			)
			( regionClassClass "@sapphirecity_baseboard_lib.sapphirecity_baseboard(sch_1):\RCC431\"
				( attribute "LINE_TO_LINE_SPACING" "8.00"
					( Origin gBackEnd )
				)
				( regionRef "@sapphirecity_baseboard_lib.sapphirecity_baseboard(sch_1):\CPU_BRKT\" )
				( netClassRef "@sapphirecity_baseboard_lib.sapphirecity_baseboard(sch_1):\DDR4_CHN_H_CTRL\" )
				( netClassRef "@sapphirecity_baseboard_lib.sapphirecity_baseboard(sch_1):\DDR4_CHN_H_DQ_DQS_BYTE3\" )
			)
			( regionClassClass "@sapphirecity_baseboard_lib.sapphirecity_baseboard(sch_1):\RCC432\"
				( attribute "LINE_TO_LINE_SPACING" "8.00"
					( Origin gBackEnd )
				)
				( regionRef "@sapphirecity_baseboard_lib.sapphirecity_baseboard(sch_1):\CPU_BRKT\" )
				( netClassRef "@sapphirecity_baseboard_lib.sapphirecity_baseboard(sch_1):\DDR4_CHN_H_CTRL\" )
				( netClassRef "@sapphirecity_baseboard_lib.sapphirecity_baseboard(sch_1):\DDR4_CHN_H_DQ_DQS_BYTE2\" )
			)
			( regionClassClass "@sapphirecity_baseboard_lib.sapphirecity_baseboard(sch_1):\RCC433\"
				( attribute "LINE_TO_LINE_SPACING" "8.00"
					( Origin gBackEnd )
				)
				( regionRef "@sapphirecity_baseboard_lib.sapphirecity_baseboard(sch_1):\CPU_BRKT\" )
				( netClassRef "@sapphirecity_baseboard_lib.sapphirecity_baseboard(sch_1):\DDR4_CHN_H_CTRL\" )
				( netClassRef "@sapphirecity_baseboard_lib.sapphirecity_baseboard(sch_1):\DDR4_CHN_H_DQ_DQS_BYTE1\" )
			)
			( regionClassClass "@sapphirecity_baseboard_lib.sapphirecity_baseboard(sch_1):\RCC434\"
				( attribute "LINE_TO_LINE_SPACING" "8.00"
					( Origin gBackEnd )
				)
				( regionRef "@sapphirecity_baseboard_lib.sapphirecity_baseboard(sch_1):\CPU_BRKT\" )
				( netClassRef "@sapphirecity_baseboard_lib.sapphirecity_baseboard(sch_1):\DDR4_CHN_H_CTRL\" )
				( netClassRef "@sapphirecity_baseboard_lib.sapphirecity_baseboard(sch_1):\DDR4_CHN_H_DQ_DQS_BYTE0\" )
			)
			( regionClassClass "@sapphirecity_baseboard_lib.sapphirecity_baseboard(sch_1):\RCC435\"
				( attribute "LINE_TO_LINE_SPACING" "8.00"
					( Origin gBackEnd )
				)
				( regionRef "@sapphirecity_baseboard_lib.sapphirecity_baseboard(sch_1):\CPU_BRKT\" )
				( netClassRef "@sapphirecity_baseboard_lib.sapphirecity_baseboard(sch_1):\DDR4_CHN_H_CTRL\" )
				( netClassRef "@sapphirecity_baseboard_lib.sapphirecity_baseboard(sch_1):\DDR4_CHN_H_CTRL\" )
			)
			( regionClassClass "@sapphirecity_baseboard_lib.sapphirecity_baseboard(sch_1):\RCC436\"
				( attribute "LINE_TO_LINE_SPACING" "8.00"
					( Origin gBackEnd )
				)
				( regionRef "@sapphirecity_baseboard_lib.sapphirecity_baseboard(sch_1):\CPU_BRKT\" )
				( netClassRef "@sapphirecity_baseboard_lib.sapphirecity_baseboard(sch_1):\DDR4_CHN_H_DQ_DQS_BYTE0\" )
				( netClassRef "@sapphirecity_baseboard_lib.sapphirecity_baseboard(sch_1):\DDR4_CHN_H_ECC\" )
			)
			( regionClassClass "@sapphirecity_baseboard_lib.sapphirecity_baseboard(sch_1):\RCC437\"
				( attribute "LINE_TO_LINE_SPACING" "8.00"
					( Origin gBackEnd )
				)
				( regionRef "@sapphirecity_baseboard_lib.sapphirecity_baseboard(sch_1):\CPU_BRKT\" )
				( netClassRef "@sapphirecity_baseboard_lib.sapphirecity_baseboard(sch_1):\DDR4_CHN_H_DQ_DQS_BYTE0\" )
				( netClassRef "@sapphirecity_baseboard_lib.sapphirecity_baseboard(sch_1):\DDR4_CHN_H_DQ_DQS_BYTE7\" )
			)
			( regionClassClass "@sapphirecity_baseboard_lib.sapphirecity_baseboard(sch_1):\RCC438\"
				( attribute "LINE_TO_LINE_SPACING" "8.00"
					( Origin gBackEnd )
				)
				( regionRef "@sapphirecity_baseboard_lib.sapphirecity_baseboard(sch_1):\CPU_BRKT\" )
				( netClassRef "@sapphirecity_baseboard_lib.sapphirecity_baseboard(sch_1):\DDR4_CHN_H_DQ_DQS_BYTE0\" )
				( netClassRef "@sapphirecity_baseboard_lib.sapphirecity_baseboard(sch_1):\DDR4_CHN_H_DQ_DQS_BYTE6\" )
			)
			( regionClassClass "@sapphirecity_baseboard_lib.sapphirecity_baseboard(sch_1):\RCC439\"
				( attribute "LINE_TO_LINE_SPACING" "8.00"
					( Origin gBackEnd )
				)
				( regionRef "@sapphirecity_baseboard_lib.sapphirecity_baseboard(sch_1):\CPU_BRKT\" )
				( netClassRef "@sapphirecity_baseboard_lib.sapphirecity_baseboard(sch_1):\DDR4_CHN_H_DQ_DQS_BYTE0\" )
				( netClassRef "@sapphirecity_baseboard_lib.sapphirecity_baseboard(sch_1):\DDR4_CHN_H_DQ_DQS_BYTE5\" )
			)
			( regionClassClass "@sapphirecity_baseboard_lib.sapphirecity_baseboard(sch_1):\RCC440\"
				( attribute "LINE_TO_LINE_SPACING" "8.00"
					( Origin gBackEnd )
				)
				( regionRef "@sapphirecity_baseboard_lib.sapphirecity_baseboard(sch_1):\CPU_BRKT\" )
				( netClassRef "@sapphirecity_baseboard_lib.sapphirecity_baseboard(sch_1):\DDR4_CHN_H_DQ_DQS_BYTE0\" )
				( netClassRef "@sapphirecity_baseboard_lib.sapphirecity_baseboard(sch_1):\DDR4_CHN_H_DQ_DQS_BYTE4\" )
			)
			( regionClassClass "@sapphirecity_baseboard_lib.sapphirecity_baseboard(sch_1):\RCC441\"
				( attribute "LINE_TO_LINE_SPACING" "8.00"
					( Origin gBackEnd )
				)
				( regionRef "@sapphirecity_baseboard_lib.sapphirecity_baseboard(sch_1):\CPU_BRKT\" )
				( netClassRef "@sapphirecity_baseboard_lib.sapphirecity_baseboard(sch_1):\DDR4_CHN_H_DQ_DQS_BYTE0\" )
				( netClassRef "@sapphirecity_baseboard_lib.sapphirecity_baseboard(sch_1):\DDR4_CHN_H_DQ_DQS_BYTE3\" )
			)
			( regionClassClass "@sapphirecity_baseboard_lib.sapphirecity_baseboard(sch_1):\RCC442\"
				( attribute "LINE_TO_LINE_SPACING" "8.00"
					( Origin gBackEnd )
				)
				( regionRef "@sapphirecity_baseboard_lib.sapphirecity_baseboard(sch_1):\CPU_BRKT\" )
				( netClassRef "@sapphirecity_baseboard_lib.sapphirecity_baseboard(sch_1):\DDR4_CHN_H_DQ_DQS_BYTE0\" )
				( netClassRef "@sapphirecity_baseboard_lib.sapphirecity_baseboard(sch_1):\DDR4_CHN_H_DQ_DQS_BYTE2\" )
			)
			( regionClassClass "@sapphirecity_baseboard_lib.sapphirecity_baseboard(sch_1):\RCC443\"
				( attribute "LINE_TO_LINE_SPACING" "8.00"
					( Origin gBackEnd )
				)
				( regionRef "@sapphirecity_baseboard_lib.sapphirecity_baseboard(sch_1):\CPU_BRKT\" )
				( netClassRef "@sapphirecity_baseboard_lib.sapphirecity_baseboard(sch_1):\DDR4_CHN_H_DQ_DQS_BYTE0\" )
				( netClassRef "@sapphirecity_baseboard_lib.sapphirecity_baseboard(sch_1):\DDR4_CHN_H_DQ_DQS_BYTE1\" )
			)
			( regionClassClass "@sapphirecity_baseboard_lib.sapphirecity_baseboard(sch_1):\RCC444\"
				( attribute "LINE_TO_LINE_SPACING" "8.00"
					( Origin gBackEnd )
				)
				( regionRef "@sapphirecity_baseboard_lib.sapphirecity_baseboard(sch_1):\CPU_BRKT\" )
				( netClassRef "@sapphirecity_baseboard_lib.sapphirecity_baseboard(sch_1):\DDR4_CHN_H_DQ_DQS_BYTE0\" )
				( netClassRef "@sapphirecity_baseboard_lib.sapphirecity_baseboard(sch_1):\DDR4_CHN_H_DQ_DQS_BYTE0\" )
			)
			( regionClassClass "@sapphirecity_baseboard_lib.sapphirecity_baseboard(sch_1):\RCC445\"
				( attribute "LINE_TO_LINE_SPACING" "8.00"
					( Origin gBackEnd )
				)
				( regionRef "@sapphirecity_baseboard_lib.sapphirecity_baseboard(sch_1):\CPU_BRKT\" )
				( netClassRef "@sapphirecity_baseboard_lib.sapphirecity_baseboard(sch_1):\DDR4_CHN_H_DQ_DQS_BYTE1\" )
				( netClassRef "@sapphirecity_baseboard_lib.sapphirecity_baseboard(sch_1):\DDR4_CHN_H_ECC\" )
			)
			( regionClassClass "@sapphirecity_baseboard_lib.sapphirecity_baseboard(sch_1):\RCC446\"
				( attribute "LINE_TO_LINE_SPACING" "8.00"
					( Origin gBackEnd )
				)
				( regionRef "@sapphirecity_baseboard_lib.sapphirecity_baseboard(sch_1):\CPU_BRKT\" )
				( netClassRef "@sapphirecity_baseboard_lib.sapphirecity_baseboard(sch_1):\DDR4_CHN_H_DQ_DQS_BYTE1\" )
				( netClassRef "@sapphirecity_baseboard_lib.sapphirecity_baseboard(sch_1):\DDR4_CHN_H_DQ_DQS_BYTE7\" )
			)
			( regionClassClass "@sapphirecity_baseboard_lib.sapphirecity_baseboard(sch_1):\RCC447\"
				( attribute "LINE_TO_LINE_SPACING" "8.00"
					( Origin gBackEnd )
				)
				( regionRef "@sapphirecity_baseboard_lib.sapphirecity_baseboard(sch_1):\CPU_BRKT\" )
				( netClassRef "@sapphirecity_baseboard_lib.sapphirecity_baseboard(sch_1):\DDR4_CHN_H_DQ_DQS_BYTE1\" )
				( netClassRef "@sapphirecity_baseboard_lib.sapphirecity_baseboard(sch_1):\DDR4_CHN_H_DQ_DQS_BYTE6\" )
			)
			( regionClassClass "@sapphirecity_baseboard_lib.sapphirecity_baseboard(sch_1):\RCC448\"
				( attribute "LINE_TO_LINE_SPACING" "8.00"
					( Origin gBackEnd )
				)
				( regionRef "@sapphirecity_baseboard_lib.sapphirecity_baseboard(sch_1):\CPU_BRKT\" )
				( netClassRef "@sapphirecity_baseboard_lib.sapphirecity_baseboard(sch_1):\DDR4_CHN_H_DQ_DQS_BYTE1\" )
				( netClassRef "@sapphirecity_baseboard_lib.sapphirecity_baseboard(sch_1):\DDR4_CHN_H_DQ_DQS_BYTE5\" )
			)
			( regionClassClass "@sapphirecity_baseboard_lib.sapphirecity_baseboard(sch_1):\RCC449\"
				( attribute "LINE_TO_LINE_SPACING" "8.00"
					( Origin gBackEnd )
				)
				( regionRef "@sapphirecity_baseboard_lib.sapphirecity_baseboard(sch_1):\CPU_BRKT\" )
				( netClassRef "@sapphirecity_baseboard_lib.sapphirecity_baseboard(sch_1):\DDR4_CHN_H_DQ_DQS_BYTE1\" )
				( netClassRef "@sapphirecity_baseboard_lib.sapphirecity_baseboard(sch_1):\DDR4_CHN_H_DQ_DQS_BYTE4\" )
			)
			( regionClassClass "@sapphirecity_baseboard_lib.sapphirecity_baseboard(sch_1):\RCC450\"
				( attribute "LINE_TO_LINE_SPACING" "8.00"
					( Origin gBackEnd )
				)
				( regionRef "@sapphirecity_baseboard_lib.sapphirecity_baseboard(sch_1):\CPU_BRKT\" )
				( netClassRef "@sapphirecity_baseboard_lib.sapphirecity_baseboard(sch_1):\DDR4_CHN_H_DQ_DQS_BYTE1\" )
				( netClassRef "@sapphirecity_baseboard_lib.sapphirecity_baseboard(sch_1):\DDR4_CHN_H_DQ_DQS_BYTE3\" )
			)
			( regionClassClass "@sapphirecity_baseboard_lib.sapphirecity_baseboard(sch_1):\RCC451\"
				( attribute "LINE_TO_LINE_SPACING" "8.00"
					( Origin gBackEnd )
				)
				( regionRef "@sapphirecity_baseboard_lib.sapphirecity_baseboard(sch_1):\CPU_BRKT\" )
				( netClassRef "@sapphirecity_baseboard_lib.sapphirecity_baseboard(sch_1):\DDR4_CHN_H_DQ_DQS_BYTE1\" )
				( netClassRef "@sapphirecity_baseboard_lib.sapphirecity_baseboard(sch_1):\DDR4_CHN_H_DQ_DQS_BYTE2\" )
			)
			( regionClassClass "@sapphirecity_baseboard_lib.sapphirecity_baseboard(sch_1):\RCC452\"
				( attribute "LINE_TO_LINE_SPACING" "8.00"
					( Origin gBackEnd )
				)
				( regionRef "@sapphirecity_baseboard_lib.sapphirecity_baseboard(sch_1):\CPU_BRKT\" )
				( netClassRef "@sapphirecity_baseboard_lib.sapphirecity_baseboard(sch_1):\DDR4_CHN_H_DQ_DQS_BYTE1\" )
				( netClassRef "@sapphirecity_baseboard_lib.sapphirecity_baseboard(sch_1):\DDR4_CHN_H_DQ_DQS_BYTE1\" )
			)
			( regionClassClass "@sapphirecity_baseboard_lib.sapphirecity_baseboard(sch_1):\RCC453\"
				( attribute "LINE_TO_LINE_SPACING" "8.00"
					( Origin gBackEnd )
				)
				( regionRef "@sapphirecity_baseboard_lib.sapphirecity_baseboard(sch_1):\CPU_BRKT\" )
				( netClassRef "@sapphirecity_baseboard_lib.sapphirecity_baseboard(sch_1):\DDR4_CHN_H_DQ_DQS_BYTE2\" )
				( netClassRef "@sapphirecity_baseboard_lib.sapphirecity_baseboard(sch_1):\DDR4_CHN_H_ECC\" )
			)
			( regionClassClass "@sapphirecity_baseboard_lib.sapphirecity_baseboard(sch_1):\RCC454\"
				( attribute "LINE_TO_LINE_SPACING" "8.00"
					( Origin gBackEnd )
				)
				( regionRef "@sapphirecity_baseboard_lib.sapphirecity_baseboard(sch_1):\CPU_BRKT\" )
				( netClassRef "@sapphirecity_baseboard_lib.sapphirecity_baseboard(sch_1):\DDR4_CHN_H_DQ_DQS_BYTE2\" )
				( netClassRef "@sapphirecity_baseboard_lib.sapphirecity_baseboard(sch_1):\DDR4_CHN_H_DQ_DQS_BYTE7\" )
			)
			( regionClassClass "@sapphirecity_baseboard_lib.sapphirecity_baseboard(sch_1):\RCC455\"
				( attribute "LINE_TO_LINE_SPACING" "8.00"
					( Origin gBackEnd )
				)
				( regionRef "@sapphirecity_baseboard_lib.sapphirecity_baseboard(sch_1):\CPU_BRKT\" )
				( netClassRef "@sapphirecity_baseboard_lib.sapphirecity_baseboard(sch_1):\DDR4_CHN_H_DQ_DQS_BYTE2\" )
				( netClassRef "@sapphirecity_baseboard_lib.sapphirecity_baseboard(sch_1):\DDR4_CHN_H_DQ_DQS_BYTE6\" )
			)
			( regionClassClass "@sapphirecity_baseboard_lib.sapphirecity_baseboard(sch_1):\RCC456\"
				( attribute "LINE_TO_LINE_SPACING" "8.00"
					( Origin gBackEnd )
				)
				( regionRef "@sapphirecity_baseboard_lib.sapphirecity_baseboard(sch_1):\CPU_BRKT\" )
				( netClassRef "@sapphirecity_baseboard_lib.sapphirecity_baseboard(sch_1):\DDR4_CHN_H_DQ_DQS_BYTE2\" )
				( netClassRef "@sapphirecity_baseboard_lib.sapphirecity_baseboard(sch_1):\DDR4_CHN_H_DQ_DQS_BYTE5\" )
			)
			( regionClassClass "@sapphirecity_baseboard_lib.sapphirecity_baseboard(sch_1):\RCC457\"
				( attribute "LINE_TO_LINE_SPACING" "8.00"
					( Origin gBackEnd )
				)
				( regionRef "@sapphirecity_baseboard_lib.sapphirecity_baseboard(sch_1):\CPU_BRKT\" )
				( netClassRef "@sapphirecity_baseboard_lib.sapphirecity_baseboard(sch_1):\DDR4_CHN_H_DQ_DQS_BYTE2\" )
				( netClassRef "@sapphirecity_baseboard_lib.sapphirecity_baseboard(sch_1):\DDR4_CHN_H_DQ_DQS_BYTE4\" )
			)
			( regionClassClass "@sapphirecity_baseboard_lib.sapphirecity_baseboard(sch_1):\RCC458\"
				( attribute "LINE_TO_LINE_SPACING" "8.00"
					( Origin gBackEnd )
				)
				( regionRef "@sapphirecity_baseboard_lib.sapphirecity_baseboard(sch_1):\CPU_BRKT\" )
				( netClassRef "@sapphirecity_baseboard_lib.sapphirecity_baseboard(sch_1):\DDR4_CHN_H_DQ_DQS_BYTE2\" )
				( netClassRef "@sapphirecity_baseboard_lib.sapphirecity_baseboard(sch_1):\DDR4_CHN_H_DQ_DQS_BYTE3\" )
			)
			( regionClassClass "@sapphirecity_baseboard_lib.sapphirecity_baseboard(sch_1):\RCC459\"
				( attribute "LINE_TO_LINE_SPACING" "8.00"
					( Origin gBackEnd )
				)
				( regionRef "@sapphirecity_baseboard_lib.sapphirecity_baseboard(sch_1):\CPU_BRKT\" )
				( netClassRef "@sapphirecity_baseboard_lib.sapphirecity_baseboard(sch_1):\DDR4_CHN_H_DQ_DQS_BYTE2\" )
				( netClassRef "@sapphirecity_baseboard_lib.sapphirecity_baseboard(sch_1):\DDR4_CHN_H_DQ_DQS_BYTE2\" )
			)
			( regionClassClass "@sapphirecity_baseboard_lib.sapphirecity_baseboard(sch_1):\RCC460\"
				( attribute "LINE_TO_LINE_SPACING" "8.00"
					( Origin gBackEnd )
				)
				( regionRef "@sapphirecity_baseboard_lib.sapphirecity_baseboard(sch_1):\CPU_BRKT\" )
				( netClassRef "@sapphirecity_baseboard_lib.sapphirecity_baseboard(sch_1):\DDR4_CHN_H_DQ_DQS_BYTE3\" )
				( netClassRef "@sapphirecity_baseboard_lib.sapphirecity_baseboard(sch_1):\DDR4_CHN_H_ECC\" )
			)
			( regionClassClass "@sapphirecity_baseboard_lib.sapphirecity_baseboard(sch_1):\RCC461\"
				( attribute "LINE_TO_LINE_SPACING" "8.00"
					( Origin gBackEnd )
				)
				( regionRef "@sapphirecity_baseboard_lib.sapphirecity_baseboard(sch_1):\CPU_BRKT\" )
				( netClassRef "@sapphirecity_baseboard_lib.sapphirecity_baseboard(sch_1):\DDR4_CHN_H_DQ_DQS_BYTE3\" )
				( netClassRef "@sapphirecity_baseboard_lib.sapphirecity_baseboard(sch_1):\DDR4_CHN_H_DQ_DQS_BYTE7\" )
			)
			( regionClassClass "@sapphirecity_baseboard_lib.sapphirecity_baseboard(sch_1):\RCC462\"
				( attribute "LINE_TO_LINE_SPACING" "8.00"
					( Origin gBackEnd )
				)
				( regionRef "@sapphirecity_baseboard_lib.sapphirecity_baseboard(sch_1):\CPU_BRKT\" )
				( netClassRef "@sapphirecity_baseboard_lib.sapphirecity_baseboard(sch_1):\DDR4_CHN_H_DQ_DQS_BYTE3\" )
				( netClassRef "@sapphirecity_baseboard_lib.sapphirecity_baseboard(sch_1):\DDR4_CHN_H_DQ_DQS_BYTE6\" )
			)
			( regionClassClass "@sapphirecity_baseboard_lib.sapphirecity_baseboard(sch_1):\RCC463\"
				( attribute "LINE_TO_LINE_SPACING" "8.00"
					( Origin gBackEnd )
				)
				( regionRef "@sapphirecity_baseboard_lib.sapphirecity_baseboard(sch_1):\CPU_BRKT\" )
				( netClassRef "@sapphirecity_baseboard_lib.sapphirecity_baseboard(sch_1):\DDR4_CHN_H_DQ_DQS_BYTE3\" )
				( netClassRef "@sapphirecity_baseboard_lib.sapphirecity_baseboard(sch_1):\DDR4_CHN_H_DQ_DQS_BYTE5\" )
			)
			( regionClassClass "@sapphirecity_baseboard_lib.sapphirecity_baseboard(sch_1):\RCC464\"
				( attribute "LINE_TO_LINE_SPACING" "8.00"
					( Origin gBackEnd )
				)
				( regionRef "@sapphirecity_baseboard_lib.sapphirecity_baseboard(sch_1):\CPU_BRKT\" )
				( netClassRef "@sapphirecity_baseboard_lib.sapphirecity_baseboard(sch_1):\DDR4_CHN_H_DQ_DQS_BYTE3\" )
				( netClassRef "@sapphirecity_baseboard_lib.sapphirecity_baseboard(sch_1):\DDR4_CHN_H_DQ_DQS_BYTE4\" )
			)
			( regionClassClass "@sapphirecity_baseboard_lib.sapphirecity_baseboard(sch_1):\RCC465\"
				( attribute "LINE_TO_LINE_SPACING" "8.00"
					( Origin gBackEnd )
				)
				( regionRef "@sapphirecity_baseboard_lib.sapphirecity_baseboard(sch_1):\CPU_BRKT\" )
				( netClassRef "@sapphirecity_baseboard_lib.sapphirecity_baseboard(sch_1):\DDR4_CHN_H_DQ_DQS_BYTE3\" )
				( netClassRef "@sapphirecity_baseboard_lib.sapphirecity_baseboard(sch_1):\DDR4_CHN_H_DQ_DQS_BYTE3\" )
			)
			( regionClassClass "@sapphirecity_baseboard_lib.sapphirecity_baseboard(sch_1):\RCC466\"
				( attribute "LINE_TO_LINE_SPACING" "8.00"
					( Origin gBackEnd )
				)
				( regionRef "@sapphirecity_baseboard_lib.sapphirecity_baseboard(sch_1):\CPU_BRKT\" )
				( netClassRef "@sapphirecity_baseboard_lib.sapphirecity_baseboard(sch_1):\DDR4_CHN_H_DQ_DQS_BYTE4\" )
				( netClassRef "@sapphirecity_baseboard_lib.sapphirecity_baseboard(sch_1):\DDR4_CHN_H_ECC\" )
			)
			( regionClassClass "@sapphirecity_baseboard_lib.sapphirecity_baseboard(sch_1):\RCC467\"
				( attribute "LINE_TO_LINE_SPACING" "8.00"
					( Origin gBackEnd )
				)
				( regionRef "@sapphirecity_baseboard_lib.sapphirecity_baseboard(sch_1):\CPU_BRKT\" )
				( netClassRef "@sapphirecity_baseboard_lib.sapphirecity_baseboard(sch_1):\DDR4_CHN_H_DQ_DQS_BYTE4\" )
				( netClassRef "@sapphirecity_baseboard_lib.sapphirecity_baseboard(sch_1):\DDR4_CHN_H_DQ_DQS_BYTE7\" )
			)
			( regionClassClass "@sapphirecity_baseboard_lib.sapphirecity_baseboard(sch_1):\RCC468\"
				( attribute "LINE_TO_LINE_SPACING" "8.00"
					( Origin gBackEnd )
				)
				( regionRef "@sapphirecity_baseboard_lib.sapphirecity_baseboard(sch_1):\CPU_BRKT\" )
				( netClassRef "@sapphirecity_baseboard_lib.sapphirecity_baseboard(sch_1):\DDR4_CHN_H_DQ_DQS_BYTE4\" )
				( netClassRef "@sapphirecity_baseboard_lib.sapphirecity_baseboard(sch_1):\DDR4_CHN_H_DQ_DQS_BYTE6\" )
			)
			( regionClassClass "@sapphirecity_baseboard_lib.sapphirecity_baseboard(sch_1):\RCC469\"
				( attribute "LINE_TO_LINE_SPACING" "8.00"
					( Origin gBackEnd )
				)
				( regionRef "@sapphirecity_baseboard_lib.sapphirecity_baseboard(sch_1):\CPU_BRKT\" )
				( netClassRef "@sapphirecity_baseboard_lib.sapphirecity_baseboard(sch_1):\DDR4_CHN_H_DQ_DQS_BYTE4\" )
				( netClassRef "@sapphirecity_baseboard_lib.sapphirecity_baseboard(sch_1):\DDR4_CHN_H_DQ_DQS_BYTE5\" )
			)
			( regionClassClass "@sapphirecity_baseboard_lib.sapphirecity_baseboard(sch_1):\RCC470\"
				( attribute "LINE_TO_LINE_SPACING" "8.00"
					( Origin gBackEnd )
				)
				( regionRef "@sapphirecity_baseboard_lib.sapphirecity_baseboard(sch_1):\CPU_BRKT\" )
				( netClassRef "@sapphirecity_baseboard_lib.sapphirecity_baseboard(sch_1):\DDR4_CHN_H_DQ_DQS_BYTE4\" )
				( netClassRef "@sapphirecity_baseboard_lib.sapphirecity_baseboard(sch_1):\DDR4_CHN_H_DQ_DQS_BYTE4\" )
			)
			( regionClassClass "@sapphirecity_baseboard_lib.sapphirecity_baseboard(sch_1):\RCC471\"
				( attribute "LINE_TO_LINE_SPACING" "8.00"
					( Origin gBackEnd )
				)
				( regionRef "@sapphirecity_baseboard_lib.sapphirecity_baseboard(sch_1):\CPU_BRKT\" )
				( netClassRef "@sapphirecity_baseboard_lib.sapphirecity_baseboard(sch_1):\DDR4_CHN_H_DQ_DQS_BYTE5\" )
				( netClassRef "@sapphirecity_baseboard_lib.sapphirecity_baseboard(sch_1):\DDR4_CHN_H_ECC\" )
			)
			( regionClassClass "@sapphirecity_baseboard_lib.sapphirecity_baseboard(sch_1):\RCC472\"
				( attribute "LINE_TO_LINE_SPACING" "8.00"
					( Origin gBackEnd )
				)
				( regionRef "@sapphirecity_baseboard_lib.sapphirecity_baseboard(sch_1):\CPU_BRKT\" )
				( netClassRef "@sapphirecity_baseboard_lib.sapphirecity_baseboard(sch_1):\DDR4_CHN_H_DQ_DQS_BYTE5\" )
				( netClassRef "@sapphirecity_baseboard_lib.sapphirecity_baseboard(sch_1):\DDR4_CHN_H_DQ_DQS_BYTE7\" )
			)
			( regionClassClass "@sapphirecity_baseboard_lib.sapphirecity_baseboard(sch_1):\RCC473\"
				( attribute "LINE_TO_LINE_SPACING" "8.00"
					( Origin gBackEnd )
				)
				( regionRef "@sapphirecity_baseboard_lib.sapphirecity_baseboard(sch_1):\CPU_BRKT\" )
				( netClassRef "@sapphirecity_baseboard_lib.sapphirecity_baseboard(sch_1):\DDR4_CHN_H_DQ_DQS_BYTE5\" )
				( netClassRef "@sapphirecity_baseboard_lib.sapphirecity_baseboard(sch_1):\DDR4_CHN_H_DQ_DQS_BYTE6\" )
			)
			( regionClassClass "@sapphirecity_baseboard_lib.sapphirecity_baseboard(sch_1):\RCC474\"
				( attribute "LINE_TO_LINE_SPACING" "8.00"
					( Origin gBackEnd )
				)
				( regionRef "@sapphirecity_baseboard_lib.sapphirecity_baseboard(sch_1):\CPU_BRKT\" )
				( netClassRef "@sapphirecity_baseboard_lib.sapphirecity_baseboard(sch_1):\DDR4_CHN_H_DQ_DQS_BYTE5\" )
				( netClassRef "@sapphirecity_baseboard_lib.sapphirecity_baseboard(sch_1):\DDR4_CHN_H_DQ_DQS_BYTE5\" )
			)
			( regionClassClass "@sapphirecity_baseboard_lib.sapphirecity_baseboard(sch_1):\RCC475\"
				( attribute "LINE_TO_LINE_SPACING" "8.00"
					( Origin gBackEnd )
				)
				( regionRef "@sapphirecity_baseboard_lib.sapphirecity_baseboard(sch_1):\CPU_BRKT\" )
				( netClassRef "@sapphirecity_baseboard_lib.sapphirecity_baseboard(sch_1):\DDR4_CHN_H_DQ_DQS_BYTE6\" )
				( netClassRef "@sapphirecity_baseboard_lib.sapphirecity_baseboard(sch_1):\DDR4_CHN_H_ECC\" )
			)
			( regionClassClass "@sapphirecity_baseboard_lib.sapphirecity_baseboard(sch_1):\RCC476\"
				( attribute "LINE_TO_LINE_SPACING" "8.00"
					( Origin gBackEnd )
				)
				( regionRef "@sapphirecity_baseboard_lib.sapphirecity_baseboard(sch_1):\CPU_BRKT\" )
				( netClassRef "@sapphirecity_baseboard_lib.sapphirecity_baseboard(sch_1):\DDR4_CHN_H_DQ_DQS_BYTE6\" )
				( netClassRef "@sapphirecity_baseboard_lib.sapphirecity_baseboard(sch_1):\DDR4_CHN_H_DQ_DQS_BYTE7\" )
			)
			( regionClassClass "@sapphirecity_baseboard_lib.sapphirecity_baseboard(sch_1):\RCC477\"
				( attribute "LINE_TO_LINE_SPACING" "8.00"
					( Origin gBackEnd )
				)
				( regionRef "@sapphirecity_baseboard_lib.sapphirecity_baseboard(sch_1):\CPU_BRKT\" )
				( netClassRef "@sapphirecity_baseboard_lib.sapphirecity_baseboard(sch_1):\DDR4_CHN_H_DQ_DQS_BYTE6\" )
				( netClassRef "@sapphirecity_baseboard_lib.sapphirecity_baseboard(sch_1):\DDR4_CHN_H_DQ_DQS_BYTE6\" )
			)
			( regionClassClass "@sapphirecity_baseboard_lib.sapphirecity_baseboard(sch_1):\RCC478\"
				( attribute "LINE_TO_LINE_SPACING" "8.00"
					( Origin gBackEnd )
				)
				( regionRef "@sapphirecity_baseboard_lib.sapphirecity_baseboard(sch_1):\CPU_BRKT\" )
				( netClassRef "@sapphirecity_baseboard_lib.sapphirecity_baseboard(sch_1):\DDR4_CHN_H_DQ_DQS_BYTE7\" )
				( netClassRef "@sapphirecity_baseboard_lib.sapphirecity_baseboard(sch_1):\DDR4_CHN_H_ECC\" )
			)
			( regionClassClass "@sapphirecity_baseboard_lib.sapphirecity_baseboard(sch_1):\RCC479\"
				( attribute "LINE_TO_LINE_SPACING" "8.00"
					( Origin gBackEnd )
				)
				( regionRef "@sapphirecity_baseboard_lib.sapphirecity_baseboard(sch_1):\CPU_BRKT\" )
				( netClassRef "@sapphirecity_baseboard_lib.sapphirecity_baseboard(sch_1):\DDR4_CHN_H_DQ_DQS_BYTE7\" )
				( netClassRef "@sapphirecity_baseboard_lib.sapphirecity_baseboard(sch_1):\DDR4_CHN_H_DQ_DQS_BYTE7\" )
			)
			( regionClassClass "@sapphirecity_baseboard_lib.sapphirecity_baseboard(sch_1):\RCC480\"
				( attribute "LINE_TO_LINE_SPACING" "8.00"
					( Origin gBackEnd )
				)
				( regionRef "@sapphirecity_baseboard_lib.sapphirecity_baseboard(sch_1):\CPU_BRKT\" )
				( netClassRef "@sapphirecity_baseboard_lib.sapphirecity_baseboard(sch_1):\DDR4_CHN_H_ECC\" )
				( netClassRef "@sapphirecity_baseboard_lib.sapphirecity_baseboard(sch_1):\DDR4_CHN_H_ECC\" )
			)
			( regionClassClass "@sapphirecity_baseboard_lib.sapphirecity_baseboard(sch_1):\RCC491\"
				( attribute "LINE_TO_LINE_SPACING" "8.00"
					( Origin gBackEnd )
				)
				( regionRef "@sapphirecity_baseboard_lib.sapphirecity_baseboard(sch_1):\CPU_BRKT\" )
				( netClassRef "@sapphirecity_baseboard_lib.sapphirecity_baseboard(sch_1):\P3E_CPU0_PE1AB_SLOTB_RX\" )
				( netClassRef "@sapphirecity_baseboard_lib.sapphirecity_baseboard(sch_1):\P3E_CPU0_PE1AB_SLOTB_RX\" )
			)
			( regionClassClass "@sapphirecity_baseboard_lib.sapphirecity_baseboard(sch_1):\RCC492\"
				( attribute "LINE_TO_LINE_SPACING" "8.00"
					( Origin gBackEnd )
				)
				( regionRef "@sapphirecity_baseboard_lib.sapphirecity_baseboard(sch_1):\CPU_BRKT\" )
				( netClassRef "@sapphirecity_baseboard_lib.sapphirecity_baseboard(sch_1):\P3E_CPU0_PE1AB_SLOTB_TX\" )
				( netClassRef "@sapphirecity_baseboard_lib.sapphirecity_baseboard(sch_1):\P3E_CPU0_PE1AB_SLOTB_TX\" )
			)
			( regionClassClass "@sapphirecity_baseboard_lib.sapphirecity_baseboard(sch_1):\RCC495\"
				( attribute "LINE_TO_LINE_SPACING" "8.00"
					( Origin gBackEnd )
				)
				( regionRef "@sapphirecity_baseboard_lib.sapphirecity_baseboard(sch_1):\CPU_BRKT\" )
				( netClassRef "@sapphirecity_baseboard_lib.sapphirecity_baseboard(sch_1):\P3E_CPU1_PE1A_RISER1_RX\" )
				( netClassRef "@sapphirecity_baseboard_lib.sapphirecity_baseboard(sch_1):\P3E_CPU1_PE1A_RISER1_RX\" )
			)
			( regionClassClass "@sapphirecity_baseboard_lib.sapphirecity_baseboard(sch_1):\RCC496\"
				( attribute "LINE_TO_LINE_SPACING" "8.00"
					( Origin gBackEnd )
				)
				( regionRef "@sapphirecity_baseboard_lib.sapphirecity_baseboard(sch_1):\CPU_BRKT\" )
				( netClassRef "@sapphirecity_baseboard_lib.sapphirecity_baseboard(sch_1):\P3E_CPU1_PE1A_RISER1_TX\" )
				( netClassRef "@sapphirecity_baseboard_lib.sapphirecity_baseboard(sch_1):\P3E_CPU1_PE1A_RISER1_TX\" )
			)
			( regionClassClass "@sapphirecity_baseboard_lib.sapphirecity_baseboard(sch_1):\RCC497\"
				( attribute "LINE_TO_LINE_SPACING" "8.00"
					( Origin gBackEnd )
				)
				( regionRef "@sapphirecity_baseboard_lib.sapphirecity_baseboard(sch_1):\CPU_BRKT\" )
				( netClassRef "@sapphirecity_baseboard_lib.sapphirecity_baseboard(sch_1):\P3E_CPU1_PE1B_RISER1_RX\" )
				( netClassRef "@sapphirecity_baseboard_lib.sapphirecity_baseboard(sch_1):\P3E_CPU1_PE1B_RISER1_RX\" )
			)
			( regionClassClass "@sapphirecity_baseboard_lib.sapphirecity_baseboard(sch_1):\RCC498\"
				( attribute "LINE_TO_LINE_SPACING" "8.00"
					( Origin gBackEnd )
				)
				( regionRef "@sapphirecity_baseboard_lib.sapphirecity_baseboard(sch_1):\CPU_BRKT\" )
				( netClassRef "@sapphirecity_baseboard_lib.sapphirecity_baseboard(sch_1):\P3E_CPU1_PE1B_RISER1_TX\" )
				( netClassRef "@sapphirecity_baseboard_lib.sapphirecity_baseboard(sch_1):\P3E_CPU1_PE1B_RISER1_TX\" )
			)
			( regionClassClass "@sapphirecity_baseboard_lib.sapphirecity_baseboard(sch_1):\RCC499\"
				( attribute "LINE_TO_LINE_SPACING" "8.00"
					( Origin gBackEnd )
				)
				( regionRef "@sapphirecity_baseboard_lib.sapphirecity_baseboard(sch_1):\CPU_BRKT\" )
				( netClassRef "@sapphirecity_baseboard_lib.sapphirecity_baseboard(sch_1):\P3E_CPU1_PE2_RISER2_RX\" )
				( netClassRef "@sapphirecity_baseboard_lib.sapphirecity_baseboard(sch_1):\P3E_CPU1_PE2_RISER2_RX\" )
			)
			( regionClassClass "@sapphirecity_baseboard_lib.sapphirecity_baseboard(sch_1):\RCC500\"
				( attribute "LINE_TO_LINE_SPACING" "8.00"
					( Origin gBackEnd )
				)
				( regionRef "@sapphirecity_baseboard_lib.sapphirecity_baseboard(sch_1):\CPU_BRKT\" )
				( netClassRef "@sapphirecity_baseboard_lib.sapphirecity_baseboard(sch_1):\P3E_CPU1_PE2_RISER2_TX\" )
				( netClassRef "@sapphirecity_baseboard_lib.sapphirecity_baseboard(sch_1):\P3E_CPU1_PE2_RISER2_TX\" )
			)
			( regionClassClass "@sapphirecity_baseboard_lib.sapphirecity_baseboard(sch_1):\RCC501\"
				( attribute "LINE_TO_LINE_SPACING" "8.00"
					( Origin gBackEnd )
				)
				( regionRef "@sapphirecity_baseboard_lib.sapphirecity_baseboard(sch_1):\CPU_BRKT\" )
				( netClassRef "@sapphirecity_baseboard_lib.sapphirecity_baseboard(sch_1):\P3E_CPU1_PE3AB_SLOTE_RX\" )
				( netClassRef "@sapphirecity_baseboard_lib.sapphirecity_baseboard(sch_1):\P3E_CPU1_PE3AB_SLOTE_RX\" )
			)
			( regionClassClass "@sapphirecity_baseboard_lib.sapphirecity_baseboard(sch_1):\RCC502\"
				( attribute "LINE_TO_LINE_SPACING" "8.00"
					( Origin gBackEnd )
				)
				( regionRef "@sapphirecity_baseboard_lib.sapphirecity_baseboard(sch_1):\CPU_BRKT\" )
				( netClassRef "@sapphirecity_baseboard_lib.sapphirecity_baseboard(sch_1):\P3E_CPU1_PE3AB_SLOTE_TX\" )
				( netClassRef "@sapphirecity_baseboard_lib.sapphirecity_baseboard(sch_1):\P3E_CPU1_PE3AB_SLOTE_TX\" )
			)
			( regionClassClass "@sapphirecity_baseboard_lib.sapphirecity_baseboard(sch_1):\RCC503\"
				( attribute "LINE_TO_LINE_SPACING" "8.00"
					( Origin gBackEnd )
				)
				( regionRef "@sapphirecity_baseboard_lib.sapphirecity_baseboard(sch_1):\CPU_BRKT\" )
				( netClassRef "@sapphirecity_baseboard_lib.sapphirecity_baseboard(sch_1):\P3E_CPU1_PE3C_RISER_RX\" )
				( netClassRef "@sapphirecity_baseboard_lib.sapphirecity_baseboard(sch_1):\P3E_CPU1_PE3C_RISER_RX\" )
			)
			( regionClassClass "@sapphirecity_baseboard_lib.sapphirecity_baseboard(sch_1):\RCC504\"
				( attribute "LINE_TO_LINE_SPACING" "8.00"
					( Origin gBackEnd )
				)
				( regionRef "@sapphirecity_baseboard_lib.sapphirecity_baseboard(sch_1):\CPU_BRKT\" )
				( netClassRef "@sapphirecity_baseboard_lib.sapphirecity_baseboard(sch_1):\P3E_CPU1_PE3C_RISER2_TX\" )
				( netClassRef "@sapphirecity_baseboard_lib.sapphirecity_baseboard(sch_1):\P3E_CPU1_PE3C_RISER2_TX\" )
			)
			( regionClassClass "@sapphirecity_baseboard_lib.sapphirecity_baseboard(sch_1):\RCC505\"
				( attribute "LINE_TO_LINE_SPACING" "8.00"
					( Origin gBackEnd )
				)
				( regionRef "@sapphirecity_baseboard_lib.sapphirecity_baseboard(sch_1):\CPU_BRKT\" )
				( netClassRef "@sapphirecity_baseboard_lib.sapphirecity_baseboard(sch_1):\P3E_CPU1_PE3D_RISER2_RX\" )
				( netClassRef "@sapphirecity_baseboard_lib.sapphirecity_baseboard(sch_1):\P3E_CPU1_PE3D_RISER2_RX\" )
			)
			( regionClassClass "@sapphirecity_baseboard_lib.sapphirecity_baseboard(sch_1):\RCC506\"
				( attribute "LINE_TO_LINE_SPACING" "8.00"
					( Origin gBackEnd )
				)
				( regionRef "@sapphirecity_baseboard_lib.sapphirecity_baseboard(sch_1):\CPU_BRKT\" )
				( netClassRef "@sapphirecity_baseboard_lib.sapphirecity_baseboard(sch_1):\P3E_CPU1_PE3D_RISER2_TX\" )
				( netClassRef "@sapphirecity_baseboard_lib.sapphirecity_baseboard(sch_1):\P3E_CPU1_PE3D_RISER2_TX\" )
			)
			( regionClassClass "@sapphirecity_baseboard_lib.sapphirecity_baseboard(sch_1):\RCC507\"
				( attribute "LINE_TO_LINE_SPACING" "8.00"
					( Origin gBackEnd )
				)
				( regionRef "@sapphirecity_baseboard_lib.sapphirecity_baseboard(sch_1):\CPU_BRKT\" )
				( netClassRef "@sapphirecity_baseboard_lib.sapphirecity_baseboard(sch_1):\DDR4_CHN_D_DQ_DQS_BYTE7\" )
				( netClassRef "@sapphirecity_baseboard_lib.sapphirecity_baseboard(sch_1):\DDR4_CHN_D_DQ_DQS_BYTE7\" )
			)
			( regionClassClass "@sapphirecity_baseboard_lib.sapphirecity_baseboard(sch_1):\RCC508\"
				( attribute "LINE_TO_LINE_SPACING" "8.00"
					( Origin gBackEnd )
				)
				( regionRef "@sapphirecity_baseboard_lib.sapphirecity_baseboard(sch_1):\CPU_BRKT\" )
				( netClassRef "@sapphirecity_baseboard_lib.sapphirecity_baseboard(sch_1):\DDR4_CHN_D_DQ_DQS_BYTE6\" )
				( netClassRef "@sapphirecity_baseboard_lib.sapphirecity_baseboard(sch_1):\DDR4_CHN_D_DQ_DQS_BYTE7\" )
			)
			( regionClassClass "@sapphirecity_baseboard_lib.sapphirecity_baseboard(sch_1):\RCC509\"
				( attribute "LINE_TO_LINE_SPACING" "8.00"
					( Origin gBackEnd )
				)
				( regionRef "@sapphirecity_baseboard_lib.sapphirecity_baseboard(sch_1):\CPU_BRKT\" )
				( netClassRef "@sapphirecity_baseboard_lib.sapphirecity_baseboard(sch_1):\DDR4_CHN_D_DQ_DQS_BYTE5\" )
				( netClassRef "@sapphirecity_baseboard_lib.sapphirecity_baseboard(sch_1):\DDR4_CHN_D_DQ_DQS_BYTE7\" )
			)
			( regionClassClass "@sapphirecity_baseboard_lib.sapphirecity_baseboard(sch_1):\RCC510\"
				( attribute "LINE_TO_LINE_SPACING" "8.00"
					( Origin gBackEnd )
				)
				( regionRef "@sapphirecity_baseboard_lib.sapphirecity_baseboard(sch_1):\CPU_BRKT\" )
				( netClassRef "@sapphirecity_baseboard_lib.sapphirecity_baseboard(sch_1):\DDR4_CHN_D_DQ_DQS_BYTE4\" )
				( netClassRef "@sapphirecity_baseboard_lib.sapphirecity_baseboard(sch_1):\DDR4_CHN_D_DQ_DQS_BYTE7\" )
			)
			( regionClassClass "@sapphirecity_baseboard_lib.sapphirecity_baseboard(sch_1):\RCC511\"
				( attribute "LINE_TO_LINE_SPACING" "8.00"
					( Origin gBackEnd )
				)
				( regionRef "@sapphirecity_baseboard_lib.sapphirecity_baseboard(sch_1):\CPU_BRKT\" )
				( netClassRef "@sapphirecity_baseboard_lib.sapphirecity_baseboard(sch_1):\DDR4_CHN_D_DQ_DQS_BYTE3\" )
				( netClassRef "@sapphirecity_baseboard_lib.sapphirecity_baseboard(sch_1):\DDR4_CHN_D_DQ_DQS_BYTE7\" )
			)
			( regionClassClass "@sapphirecity_baseboard_lib.sapphirecity_baseboard(sch_1):\RCC512\"
				( attribute "LINE_TO_LINE_SPACING" "8.00"
					( Origin gBackEnd )
				)
				( regionRef "@sapphirecity_baseboard_lib.sapphirecity_baseboard(sch_1):\CPU_BRKT\" )
				( netClassRef "@sapphirecity_baseboard_lib.sapphirecity_baseboard(sch_1):\DDR4_CHN_D_DQ_DQS_BYTE2\" )
				( netClassRef "@sapphirecity_baseboard_lib.sapphirecity_baseboard(sch_1):\DDR4_CHN_D_DQ_DQS_BYTE7\" )
			)
			( regionClassClass "@sapphirecity_baseboard_lib.sapphirecity_baseboard(sch_1):\RCC513\"
				( attribute "LINE_TO_LINE_SPACING" "8.00"
					( Origin gBackEnd )
				)
				( regionRef "@sapphirecity_baseboard_lib.sapphirecity_baseboard(sch_1):\CPU_BRKT\" )
				( netClassRef "@sapphirecity_baseboard_lib.sapphirecity_baseboard(sch_1):\DDR4_CHN_D_DQ_DQS_BYTE1\" )
				( netClassRef "@sapphirecity_baseboard_lib.sapphirecity_baseboard(sch_1):\DDR4_CHN_D_DQ_DQS_BYTE7\" )
			)
			( regionClassClass "@sapphirecity_baseboard_lib.sapphirecity_baseboard(sch_1):\RCC514\"
				( attribute "LINE_TO_LINE_SPACING" "8.00"
					( Origin gBackEnd )
				)
				( regionRef "@sapphirecity_baseboard_lib.sapphirecity_baseboard(sch_1):\CPU_BRKT\" )
				( netClassRef "@sapphirecity_baseboard_lib.sapphirecity_baseboard(sch_1):\DDR4_CHN_D_DQ_DQS_BYTE0\" )
				( netClassRef "@sapphirecity_baseboard_lib.sapphirecity_baseboard(sch_1):\DDR4_CHN_D_DQ_DQS_BYTE7\" )
			)
			( regionClassClass "@sapphirecity_baseboard_lib.sapphirecity_baseboard(sch_1):\RCC515\"
				( attribute "LINE_TO_LINE_SPACING" "8.00"
					( Origin gBackEnd )
				)
				( regionRef "@sapphirecity_baseboard_lib.sapphirecity_baseboard(sch_1):\CPU_BRKT\" )
				( netClassRef "@sapphirecity_baseboard_lib.sapphirecity_baseboard(sch_1):\DDR4_CHN_D_DQ_DQS_BYTE6\" )
				( netClassRef "@sapphirecity_baseboard_lib.sapphirecity_baseboard(sch_1):\DDR4_CHN_D_DQ_DQS_BYTE6\" )
			)
			( regionClassClass "@sapphirecity_baseboard_lib.sapphirecity_baseboard(sch_1):\RCC516\"
				( attribute "LINE_TO_LINE_SPACING" "8.00"
					( Origin gBackEnd )
				)
				( regionRef "@sapphirecity_baseboard_lib.sapphirecity_baseboard(sch_1):\CPU_BRKT\" )
				( netClassRef "@sapphirecity_baseboard_lib.sapphirecity_baseboard(sch_1):\DDR4_CHN_D_DQ_DQS_BYTE5\" )
				( netClassRef "@sapphirecity_baseboard_lib.sapphirecity_baseboard(sch_1):\DDR4_CHN_D_DQ_DQS_BYTE6\" )
			)
			( regionClassClass "@sapphirecity_baseboard_lib.sapphirecity_baseboard(sch_1):\RCC517\"
				( attribute "LINE_TO_LINE_SPACING" "8.00"
					( Origin gBackEnd )
				)
				( regionRef "@sapphirecity_baseboard_lib.sapphirecity_baseboard(sch_1):\CPU_BRKT\" )
				( netClassRef "@sapphirecity_baseboard_lib.sapphirecity_baseboard(sch_1):\DDR4_CHN_D_DQ_DQS_BYTE4\" )
				( netClassRef "@sapphirecity_baseboard_lib.sapphirecity_baseboard(sch_1):\DDR4_CHN_D_DQ_DQS_BYTE6\" )
			)
			( regionClassClass "@sapphirecity_baseboard_lib.sapphirecity_baseboard(sch_1):\RCC518\"
				( attribute "LINE_TO_LINE_SPACING" "8.00"
					( Origin gBackEnd )
				)
				( regionRef "@sapphirecity_baseboard_lib.sapphirecity_baseboard(sch_1):\CPU_BRKT\" )
				( netClassRef "@sapphirecity_baseboard_lib.sapphirecity_baseboard(sch_1):\DDR4_CHN_D_DQ_DQS_BYTE3\" )
				( netClassRef "@sapphirecity_baseboard_lib.sapphirecity_baseboard(sch_1):\DDR4_CHN_D_DQ_DQS_BYTE6\" )
			)
			( regionClassClass "@sapphirecity_baseboard_lib.sapphirecity_baseboard(sch_1):\RCC519\"
				( attribute "LINE_TO_LINE_SPACING" "8.00"
					( Origin gBackEnd )
				)
				( regionRef "@sapphirecity_baseboard_lib.sapphirecity_baseboard(sch_1):\CPU_BRKT\" )
				( netClassRef "@sapphirecity_baseboard_lib.sapphirecity_baseboard(sch_1):\DDR4_CHN_D_DQ_DQS_BYTE2\" )
				( netClassRef "@sapphirecity_baseboard_lib.sapphirecity_baseboard(sch_1):\DDR4_CHN_D_DQ_DQS_BYTE6\" )
			)
			( regionClassClass "@sapphirecity_baseboard_lib.sapphirecity_baseboard(sch_1):\RCC520\"
				( attribute "LINE_TO_LINE_SPACING" "8.00"
					( Origin gBackEnd )
				)
				( regionRef "@sapphirecity_baseboard_lib.sapphirecity_baseboard(sch_1):\CPU_BRKT\" )
				( netClassRef "@sapphirecity_baseboard_lib.sapphirecity_baseboard(sch_1):\DDR4_CHN_D_DQ_DQS_BYTE1\" )
				( netClassRef "@sapphirecity_baseboard_lib.sapphirecity_baseboard(sch_1):\DDR4_CHN_D_DQ_DQS_BYTE6\" )
			)
			( regionClassClass "@sapphirecity_baseboard_lib.sapphirecity_baseboard(sch_1):\RCC521\"
				( attribute "LINE_TO_LINE_SPACING" "8.00"
					( Origin gBackEnd )
				)
				( regionRef "@sapphirecity_baseboard_lib.sapphirecity_baseboard(sch_1):\CPU_BRKT\" )
				( netClassRef "@sapphirecity_baseboard_lib.sapphirecity_baseboard(sch_1):\DDR4_CHN_D_DQ_DQS_BYTE0\" )
				( netClassRef "@sapphirecity_baseboard_lib.sapphirecity_baseboard(sch_1):\DDR4_CHN_D_DQ_DQS_BYTE6\" )
			)
			( regionClassClass "@sapphirecity_baseboard_lib.sapphirecity_baseboard(sch_1):\RCC522\"
				( attribute "LINE_TO_LINE_SPACING" "8.00"
					( Origin gBackEnd )
				)
				( regionRef "@sapphirecity_baseboard_lib.sapphirecity_baseboard(sch_1):\CPU_BRKT\" )
				( netClassRef "@sapphirecity_baseboard_lib.sapphirecity_baseboard(sch_1):\DDR4_CHN_D_DQ_DQS_BYTE5\" )
				( netClassRef "@sapphirecity_baseboard_lib.sapphirecity_baseboard(sch_1):\DDR4_CHN_D_DQ_DQS_BYTE5\" )
			)
			( regionClassClass "@sapphirecity_baseboard_lib.sapphirecity_baseboard(sch_1):\RCC523\"
				( attribute "LINE_TO_LINE_SPACING" "8.00"
					( Origin gBackEnd )
				)
				( regionRef "@sapphirecity_baseboard_lib.sapphirecity_baseboard(sch_1):\CPU_BRKT\" )
				( netClassRef "@sapphirecity_baseboard_lib.sapphirecity_baseboard(sch_1):\DDR4_CHN_D_DQ_DQS_BYTE4\" )
				( netClassRef "@sapphirecity_baseboard_lib.sapphirecity_baseboard(sch_1):\DDR4_CHN_D_DQ_DQS_BYTE5\" )
			)
			( regionClassClass "@sapphirecity_baseboard_lib.sapphirecity_baseboard(sch_1):\RCC524\"
				( attribute "LINE_TO_LINE_SPACING" "8.00"
					( Origin gBackEnd )
				)
				( regionRef "@sapphirecity_baseboard_lib.sapphirecity_baseboard(sch_1):\CPU_BRKT\" )
				( netClassRef "@sapphirecity_baseboard_lib.sapphirecity_baseboard(sch_1):\DDR4_CHN_D_DQ_DQS_BYTE3\" )
				( netClassRef "@sapphirecity_baseboard_lib.sapphirecity_baseboard(sch_1):\DDR4_CHN_D_DQ_DQS_BYTE5\" )
			)
			( regionClassClass "@sapphirecity_baseboard_lib.sapphirecity_baseboard(sch_1):\RCC525\"
				( attribute "LINE_TO_LINE_SPACING" "8.00"
					( Origin gBackEnd )
				)
				( regionRef "@sapphirecity_baseboard_lib.sapphirecity_baseboard(sch_1):\CPU_BRKT\" )
				( netClassRef "@sapphirecity_baseboard_lib.sapphirecity_baseboard(sch_1):\DDR4_CHN_D_DQ_DQS_BYTE2\" )
				( netClassRef "@sapphirecity_baseboard_lib.sapphirecity_baseboard(sch_1):\DDR4_CHN_D_DQ_DQS_BYTE5\" )
			)
			( regionClassClass "@sapphirecity_baseboard_lib.sapphirecity_baseboard(sch_1):\RCC526\"
				( attribute "LINE_TO_LINE_SPACING" "8.00"
					( Origin gBackEnd )
				)
				( regionRef "@sapphirecity_baseboard_lib.sapphirecity_baseboard(sch_1):\CPU_BRKT\" )
				( netClassRef "@sapphirecity_baseboard_lib.sapphirecity_baseboard(sch_1):\DDR4_CHN_D_DQ_DQS_BYTE1\" )
				( netClassRef "@sapphirecity_baseboard_lib.sapphirecity_baseboard(sch_1):\DDR4_CHN_D_DQ_DQS_BYTE5\" )
			)
			( regionClassClass "@sapphirecity_baseboard_lib.sapphirecity_baseboard(sch_1):\RCC527\"
				( attribute "LINE_TO_LINE_SPACING" "8.00"
					( Origin gBackEnd )
				)
				( regionRef "@sapphirecity_baseboard_lib.sapphirecity_baseboard(sch_1):\CPU_BRKT\" )
				( netClassRef "@sapphirecity_baseboard_lib.sapphirecity_baseboard(sch_1):\DDR4_CHN_D_DQ_DQS_BYTE0\" )
				( netClassRef "@sapphirecity_baseboard_lib.sapphirecity_baseboard(sch_1):\DDR4_CHN_D_DQ_DQS_BYTE5\" )
			)
			( regionClassClass "@sapphirecity_baseboard_lib.sapphirecity_baseboard(sch_1):\RCC528\"
				( attribute "LINE_TO_LINE_SPACING" "8.00"
					( Origin gBackEnd )
				)
				( regionRef "@sapphirecity_baseboard_lib.sapphirecity_baseboard(sch_1):\CPU_BRKT\" )
				( netClassRef "@sapphirecity_baseboard_lib.sapphirecity_baseboard(sch_1):\DDR4_CHN_D_DQ_DQS_BYTE4\" )
				( netClassRef "@sapphirecity_baseboard_lib.sapphirecity_baseboard(sch_1):\DDR4_CHN_D_DQ_DQS_BYTE4\" )
			)
			( regionClassClass "@sapphirecity_baseboard_lib.sapphirecity_baseboard(sch_1):\RCC529\"
				( attribute "LINE_TO_LINE_SPACING" "8.00"
					( Origin gBackEnd )
				)
				( regionRef "@sapphirecity_baseboard_lib.sapphirecity_baseboard(sch_1):\CPU_BRKT\" )
				( netClassRef "@sapphirecity_baseboard_lib.sapphirecity_baseboard(sch_1):\DDR4_CHN_D_DQ_DQS_BYTE3\" )
				( netClassRef "@sapphirecity_baseboard_lib.sapphirecity_baseboard(sch_1):\DDR4_CHN_D_DQ_DQS_BYTE4\" )
			)
			( regionClassClass "@sapphirecity_baseboard_lib.sapphirecity_baseboard(sch_1):\RCC530\"
				( attribute "LINE_TO_LINE_SPACING" "8.00"
					( Origin gBackEnd )
				)
				( regionRef "@sapphirecity_baseboard_lib.sapphirecity_baseboard(sch_1):\CPU_BRKT\" )
				( netClassRef "@sapphirecity_baseboard_lib.sapphirecity_baseboard(sch_1):\DDR4_CHN_D_DQ_DQS_BYTE2\" )
				( netClassRef "@sapphirecity_baseboard_lib.sapphirecity_baseboard(sch_1):\DDR4_CHN_D_DQ_DQS_BYTE4\" )
			)
			( regionClassClass "@sapphirecity_baseboard_lib.sapphirecity_baseboard(sch_1):\RCC531\"
				( attribute "LINE_TO_LINE_SPACING" "8.00"
					( Origin gBackEnd )
				)
				( regionRef "@sapphirecity_baseboard_lib.sapphirecity_baseboard(sch_1):\CPU_BRKT\" )
				( netClassRef "@sapphirecity_baseboard_lib.sapphirecity_baseboard(sch_1):\DDR4_CHN_D_DQ_DQS_BYTE1\" )
				( netClassRef "@sapphirecity_baseboard_lib.sapphirecity_baseboard(sch_1):\DDR4_CHN_D_DQ_DQS_BYTE4\" )
			)
			( regionClassClass "@sapphirecity_baseboard_lib.sapphirecity_baseboard(sch_1):\RCC532\"
				( attribute "LINE_TO_LINE_SPACING" "8.00"
					( Origin gBackEnd )
				)
				( regionRef "@sapphirecity_baseboard_lib.sapphirecity_baseboard(sch_1):\CPU_BRKT\" )
				( netClassRef "@sapphirecity_baseboard_lib.sapphirecity_baseboard(sch_1):\DDR4_CHN_D_DQ_DQS_BYTE0\" )
				( netClassRef "@sapphirecity_baseboard_lib.sapphirecity_baseboard(sch_1):\DDR4_CHN_D_DQ_DQS_BYTE4\" )
			)
			( regionClassClass "@sapphirecity_baseboard_lib.sapphirecity_baseboard(sch_1):\RCC533\"
				( attribute "LINE_TO_LINE_SPACING" "8.00"
					( Origin gBackEnd )
				)
				( regionRef "@sapphirecity_baseboard_lib.sapphirecity_baseboard(sch_1):\CPU_BRKT\" )
				( netClassRef "@sapphirecity_baseboard_lib.sapphirecity_baseboard(sch_1):\DDR4_CHN_D_DQ_DQS_BYTE3\" )
				( netClassRef "@sapphirecity_baseboard_lib.sapphirecity_baseboard(sch_1):\DDR4_CHN_D_DQ_DQS_BYTE3\" )
			)
			( regionClassClass "@sapphirecity_baseboard_lib.sapphirecity_baseboard(sch_1):\RCC534\"
				( attribute "LINE_TO_LINE_SPACING" "8.00"
					( Origin gBackEnd )
				)
				( regionRef "@sapphirecity_baseboard_lib.sapphirecity_baseboard(sch_1):\CPU_BRKT\" )
				( netClassRef "@sapphirecity_baseboard_lib.sapphirecity_baseboard(sch_1):\DDR4_CHN_D_DQ_DQS_BYTE2\" )
				( netClassRef "@sapphirecity_baseboard_lib.sapphirecity_baseboard(sch_1):\DDR4_CHN_D_DQ_DQS_BYTE3\" )
			)
			( regionClassClass "@sapphirecity_baseboard_lib.sapphirecity_baseboard(sch_1):\RCC535\"
				( attribute "LINE_TO_LINE_SPACING" "8.00"
					( Origin gBackEnd )
				)
				( regionRef "@sapphirecity_baseboard_lib.sapphirecity_baseboard(sch_1):\CPU_BRKT\" )
				( netClassRef "@sapphirecity_baseboard_lib.sapphirecity_baseboard(sch_1):\DDR4_CHN_D_DQ_DQS_BYTE1\" )
				( netClassRef "@sapphirecity_baseboard_lib.sapphirecity_baseboard(sch_1):\DDR4_CHN_D_DQ_DQS_BYTE3\" )
			)
			( regionClassClass "@sapphirecity_baseboard_lib.sapphirecity_baseboard(sch_1):\RCC536\"
				( attribute "LINE_TO_LINE_SPACING" "8.00"
					( Origin gBackEnd )
				)
				( regionRef "@sapphirecity_baseboard_lib.sapphirecity_baseboard(sch_1):\CPU_BRKT\" )
				( netClassRef "@sapphirecity_baseboard_lib.sapphirecity_baseboard(sch_1):\DDR4_CHN_D_DQ_DQS_BYTE0\" )
				( netClassRef "@sapphirecity_baseboard_lib.sapphirecity_baseboard(sch_1):\DDR4_CHN_D_DQ_DQS_BYTE3\" )
			)
			( regionClassClass "@sapphirecity_baseboard_lib.sapphirecity_baseboard(sch_1):\RCC537\"
				( attribute "LINE_TO_LINE_SPACING" "8.00"
					( Origin gBackEnd )
				)
				( regionRef "@sapphirecity_baseboard_lib.sapphirecity_baseboard(sch_1):\CPU_BRKT\" )
				( netClassRef "@sapphirecity_baseboard_lib.sapphirecity_baseboard(sch_1):\DDR4_CHN_D_DQ_DQS_BYTE2\" )
				( netClassRef "@sapphirecity_baseboard_lib.sapphirecity_baseboard(sch_1):\DDR4_CHN_D_DQ_DQS_BYTE2\" )
			)
			( regionClassClass "@sapphirecity_baseboard_lib.sapphirecity_baseboard(sch_1):\RCC538\"
				( attribute "LINE_TO_LINE_SPACING" "8.00"
					( Origin gBackEnd )
				)
				( regionRef "@sapphirecity_baseboard_lib.sapphirecity_baseboard(sch_1):\CPU_BRKT\" )
				( netClassRef "@sapphirecity_baseboard_lib.sapphirecity_baseboard(sch_1):\DDR4_CHN_D_DQ_DQS_BYTE1\" )
				( netClassRef "@sapphirecity_baseboard_lib.sapphirecity_baseboard(sch_1):\DDR4_CHN_D_DQ_DQS_BYTE2\" )
			)
			( regionClassClass "@sapphirecity_baseboard_lib.sapphirecity_baseboard(sch_1):\RCC539\"
				( attribute "LINE_TO_LINE_SPACING" "8.00"
					( Origin gBackEnd )
				)
				( regionRef "@sapphirecity_baseboard_lib.sapphirecity_baseboard(sch_1):\CPU_BRKT\" )
				( netClassRef "@sapphirecity_baseboard_lib.sapphirecity_baseboard(sch_1):\DDR4_CHN_D_DQ_DQS_BYTE0\" )
				( netClassRef "@sapphirecity_baseboard_lib.sapphirecity_baseboard(sch_1):\DDR4_CHN_D_DQ_DQS_BYTE2\" )
			)
			( regionClassClass "@sapphirecity_baseboard_lib.sapphirecity_baseboard(sch_1):\RCC540\"
				( attribute "LINE_TO_LINE_SPACING" "8.00"
					( Origin gBackEnd )
				)
				( regionRef "@sapphirecity_baseboard_lib.sapphirecity_baseboard(sch_1):\CPU_BRKT\" )
				( netClassRef "@sapphirecity_baseboard_lib.sapphirecity_baseboard(sch_1):\DDR4_CHN_D_DQ_DQS_BYTE1\" )
				( netClassRef "@sapphirecity_baseboard_lib.sapphirecity_baseboard(sch_1):\DDR4_CHN_D_DQ_DQS_BYTE1\" )
			)
			( regionClassClass "@sapphirecity_baseboard_lib.sapphirecity_baseboard(sch_1):\RCC541\"
				( attribute "LINE_TO_LINE_SPACING" "8.00"
					( Origin gBackEnd )
				)
				( regionRef "@sapphirecity_baseboard_lib.sapphirecity_baseboard(sch_1):\CPU_BRKT\" )
				( netClassRef "@sapphirecity_baseboard_lib.sapphirecity_baseboard(sch_1):\DDR4_CHN_D_DQ_DQS_BYTE0\" )
				( netClassRef "@sapphirecity_baseboard_lib.sapphirecity_baseboard(sch_1):\DDR4_CHN_D_DQ_DQS_BYTE1\" )
			)
			( regionClassClass "@sapphirecity_baseboard_lib.sapphirecity_baseboard(sch_1):\RCC542\"
				( attribute "LINE_TO_LINE_SPACING" "8.00"
					( Origin gBackEnd )
				)
				( regionRef "@sapphirecity_baseboard_lib.sapphirecity_baseboard(sch_1):\CPU_BRKT\" )
				( netClassRef "@sapphirecity_baseboard_lib.sapphirecity_baseboard(sch_1):\DDR4_CHN_D_DQ_DQS_BYTE0\" )
				( netClassRef "@sapphirecity_baseboard_lib.sapphirecity_baseboard(sch_1):\DDR4_CHN_D_DQ_DQS_BYTE0\" )
			)
			( regionClassClass "@sapphirecity_baseboard_lib.sapphirecity_baseboard(sch_1):\RCC543\"
				( attribute "LINE_TO_LINE_SPACING" "8.00"
					( Origin gBackEnd )
				)
				( regionRef "@sapphirecity_baseboard_lib.sapphirecity_baseboard(sch_1):\CPU_BRKT\" )
				( netClassRef "@sapphirecity_baseboard_lib.sapphirecity_baseboard(sch_1):\DDR4_CHN_C_DQ_DQS_BYTE0\" )
				( netClassRef "@sapphirecity_baseboard_lib.sapphirecity_baseboard(sch_1):\DDR4_CHN_C_DQ_DQS_BYTE7\" )
			)
			( regionClassClass "@sapphirecity_baseboard_lib.sapphirecity_baseboard(sch_1):\RCC544\"
				( attribute "LINE_TO_LINE_SPACING" "8.00"
					( Origin gBackEnd )
				)
				( regionRef "@sapphirecity_baseboard_lib.sapphirecity_baseboard(sch_1):\CPU_BRKT\" )
				( netClassRef "@sapphirecity_baseboard_lib.sapphirecity_baseboard(sch_1):\DDR4_CHN_C_DQ_DQS_BYTE0\" )
				( netClassRef "@sapphirecity_baseboard_lib.sapphirecity_baseboard(sch_1):\DDR4_CHN_C_DQ_DQS_BYTE6\" )
			)
			( regionClassClass "@sapphirecity_baseboard_lib.sapphirecity_baseboard(sch_1):\RCC545\"
				( attribute "LINE_TO_LINE_SPACING" "8.00"
					( Origin gBackEnd )
				)
				( regionRef "@sapphirecity_baseboard_lib.sapphirecity_baseboard(sch_1):\CPU_BRKT\" )
				( netClassRef "@sapphirecity_baseboard_lib.sapphirecity_baseboard(sch_1):\DDR4_CHN_C_DQ_DQS_BYTE0\" )
				( netClassRef "@sapphirecity_baseboard_lib.sapphirecity_baseboard(sch_1):\DDR4_CHN_C_DQ_DQS_BYTE5\" )
			)
			( regionClassClass "@sapphirecity_baseboard_lib.sapphirecity_baseboard(sch_1):\RCC546\"
				( attribute "LINE_TO_LINE_SPACING" "8.00"
					( Origin gBackEnd )
				)
				( regionRef "@sapphirecity_baseboard_lib.sapphirecity_baseboard(sch_1):\CPU_BRKT\" )
				( netClassRef "@sapphirecity_baseboard_lib.sapphirecity_baseboard(sch_1):\DDR4_CHN_C_DQ_DQS_BYTE0\" )
				( netClassRef "@sapphirecity_baseboard_lib.sapphirecity_baseboard(sch_1):\DDR4_CHN_C_DQ_DQS_BYTE4\" )
			)
			( regionClassClass "@sapphirecity_baseboard_lib.sapphirecity_baseboard(sch_1):\RCC547\"
				( attribute "LINE_TO_LINE_SPACING" "8.00"
					( Origin gBackEnd )
				)
				( regionRef "@sapphirecity_baseboard_lib.sapphirecity_baseboard(sch_1):\CPU_BRKT\" )
				( netClassRef "@sapphirecity_baseboard_lib.sapphirecity_baseboard(sch_1):\DDR4_CHN_C_DQ_DQS_BYTE0\" )
				( netClassRef "@sapphirecity_baseboard_lib.sapphirecity_baseboard(sch_1):\DDR4_CHN_C_DQ_DQS_BYTE3\" )
			)
			( regionClassClass "@sapphirecity_baseboard_lib.sapphirecity_baseboard(sch_1):\RCC548\"
				( attribute "LINE_TO_LINE_SPACING" "8.00"
					( Origin gBackEnd )
				)
				( regionRef "@sapphirecity_baseboard_lib.sapphirecity_baseboard(sch_1):\CPU_BRKT\" )
				( netClassRef "@sapphirecity_baseboard_lib.sapphirecity_baseboard(sch_1):\DDR4_CHN_C_DQ_DQS_BYTE0\" )
				( netClassRef "@sapphirecity_baseboard_lib.sapphirecity_baseboard(sch_1):\DDR4_CHN_C_DQ_DQS_BYTE2\" )
			)
			( regionClassClass "@sapphirecity_baseboard_lib.sapphirecity_baseboard(sch_1):\RCC549\"
				( attribute "LINE_TO_LINE_SPACING" "8.00"
					( Origin gBackEnd )
				)
				( regionRef "@sapphirecity_baseboard_lib.sapphirecity_baseboard(sch_1):\CPU_BRKT\" )
				( netClassRef "@sapphirecity_baseboard_lib.sapphirecity_baseboard(sch_1):\DDR4_CHN_C_DQ_DQS_BYTE0\" )
				( netClassRef "@sapphirecity_baseboard_lib.sapphirecity_baseboard(sch_1):\DDR4_CHN_C_DQ_DQS_BYTE1\" )
			)
			( regionClassClass "@sapphirecity_baseboard_lib.sapphirecity_baseboard(sch_1):\RCC550\"
				( attribute "LINE_TO_LINE_SPACING" "8.00"
					( Origin gBackEnd )
				)
				( regionRef "@sapphirecity_baseboard_lib.sapphirecity_baseboard(sch_1):\CPU_BRKT\" )
				( netClassRef "@sapphirecity_baseboard_lib.sapphirecity_baseboard(sch_1):\DDR4_CHN_C_DQ_DQS_BYTE0\" )
				( netClassRef "@sapphirecity_baseboard_lib.sapphirecity_baseboard(sch_1):\DDR4_CHN_C_DQ_DQS_BYTE0\" )
			)
			( regionClassClass "@sapphirecity_baseboard_lib.sapphirecity_baseboard(sch_1):\RCC551\"
				( attribute "LINE_TO_LINE_SPACING" "8.00"
					( Origin gBackEnd )
				)
				( regionRef "@sapphirecity_baseboard_lib.sapphirecity_baseboard(sch_1):\CPU_BRKT\" )
				( netClassRef "@sapphirecity_baseboard_lib.sapphirecity_baseboard(sch_1):\DDR4_CHN_C_DQ_DQS_BYTE1\" )
				( netClassRef "@sapphirecity_baseboard_lib.sapphirecity_baseboard(sch_1):\DDR4_CHN_C_DQ_DQS_BYTE7\" )
			)
			( regionClassClass "@sapphirecity_baseboard_lib.sapphirecity_baseboard(sch_1):\RCC552\"
				( attribute "LINE_TO_LINE_SPACING" "8.00"
					( Origin gBackEnd )
				)
				( regionRef "@sapphirecity_baseboard_lib.sapphirecity_baseboard(sch_1):\CPU_BRKT\" )
				( netClassRef "@sapphirecity_baseboard_lib.sapphirecity_baseboard(sch_1):\DDR4_CHN_C_DQ_DQS_BYTE1\" )
				( netClassRef "@sapphirecity_baseboard_lib.sapphirecity_baseboard(sch_1):\DDR4_CHN_C_DQ_DQS_BYTE6\" )
			)
			( regionClassClass "@sapphirecity_baseboard_lib.sapphirecity_baseboard(sch_1):\RCC553\"
				( attribute "LINE_TO_LINE_SPACING" "8.00"
					( Origin gBackEnd )
				)
				( regionRef "@sapphirecity_baseboard_lib.sapphirecity_baseboard(sch_1):\CPU_BRKT\" )
				( netClassRef "@sapphirecity_baseboard_lib.sapphirecity_baseboard(sch_1):\DDR4_CHN_C_DQ_DQS_BYTE1\" )
				( netClassRef "@sapphirecity_baseboard_lib.sapphirecity_baseboard(sch_1):\DDR4_CHN_C_DQ_DQS_BYTE5\" )
			)
			( regionClassClass "@sapphirecity_baseboard_lib.sapphirecity_baseboard(sch_1):\RCC554\"
				( attribute "LINE_TO_LINE_SPACING" "8.00"
					( Origin gBackEnd )
				)
				( regionRef "@sapphirecity_baseboard_lib.sapphirecity_baseboard(sch_1):\CPU_BRKT\" )
				( netClassRef "@sapphirecity_baseboard_lib.sapphirecity_baseboard(sch_1):\DDR4_CHN_C_DQ_DQS_BYTE1\" )
				( netClassRef "@sapphirecity_baseboard_lib.sapphirecity_baseboard(sch_1):\DDR4_CHN_C_DQ_DQS_BYTE4\" )
			)
			( regionClassClass "@sapphirecity_baseboard_lib.sapphirecity_baseboard(sch_1):\RCC555\"
				( attribute "LINE_TO_LINE_SPACING" "8.00"
					( Origin gBackEnd )
				)
				( regionRef "@sapphirecity_baseboard_lib.sapphirecity_baseboard(sch_1):\CPU_BRKT\" )
				( netClassRef "@sapphirecity_baseboard_lib.sapphirecity_baseboard(sch_1):\DDR4_CHN_C_DQ_DQS_BYTE1\" )
				( netClassRef "@sapphirecity_baseboard_lib.sapphirecity_baseboard(sch_1):\DDR4_CHN_C_DQ_DQS_BYTE3\" )
			)
			( regionClassClass "@sapphirecity_baseboard_lib.sapphirecity_baseboard(sch_1):\RCC556\"
				( attribute "LINE_TO_LINE_SPACING" "8.00"
					( Origin gBackEnd )
				)
				( regionRef "@sapphirecity_baseboard_lib.sapphirecity_baseboard(sch_1):\CPU_BRKT\" )
				( netClassRef "@sapphirecity_baseboard_lib.sapphirecity_baseboard(sch_1):\DDR4_CHN_C_DQ_DQS_BYTE1\" )
				( netClassRef "@sapphirecity_baseboard_lib.sapphirecity_baseboard(sch_1):\DDR4_CHN_C_DQ_DQS_BYTE2\" )
			)
			( regionClassClass "@sapphirecity_baseboard_lib.sapphirecity_baseboard(sch_1):\RCC557\"
				( attribute "LINE_TO_LINE_SPACING" "8.00"
					( Origin gBackEnd )
				)
				( regionRef "@sapphirecity_baseboard_lib.sapphirecity_baseboard(sch_1):\CPU_BRKT\" )
				( netClassRef "@sapphirecity_baseboard_lib.sapphirecity_baseboard(sch_1):\DDR4_CHN_C_DQ_DQS_BYTE1\" )
				( netClassRef "@sapphirecity_baseboard_lib.sapphirecity_baseboard(sch_1):\DDR4_CHN_C_DQ_DQS_BYTE1\" )
			)
			( regionClassClass "@sapphirecity_baseboard_lib.sapphirecity_baseboard(sch_1):\RCC558\"
				( attribute "LINE_TO_LINE_SPACING" "8.00"
					( Origin gBackEnd )
				)
				( regionRef "@sapphirecity_baseboard_lib.sapphirecity_baseboard(sch_1):\CPU_BRKT\" )
				( netClassRef "@sapphirecity_baseboard_lib.sapphirecity_baseboard(sch_1):\DDR4_CHN_C_DQ_DQS_BYTE2\" )
				( netClassRef "@sapphirecity_baseboard_lib.sapphirecity_baseboard(sch_1):\DDR4_CHN_C_DQ_DQS_BYTE7\" )
			)
			( regionClassClass "@sapphirecity_baseboard_lib.sapphirecity_baseboard(sch_1):\RCC559\"
				( attribute "LINE_TO_LINE_SPACING" "8.00"
					( Origin gBackEnd )
				)
				( regionRef "@sapphirecity_baseboard_lib.sapphirecity_baseboard(sch_1):\CPU_BRKT\" )
				( netClassRef "@sapphirecity_baseboard_lib.sapphirecity_baseboard(sch_1):\DDR4_CHN_C_DQ_DQS_BYTE2\" )
				( netClassRef "@sapphirecity_baseboard_lib.sapphirecity_baseboard(sch_1):\DDR4_CHN_C_DQ_DQS_BYTE6\" )
			)
			( regionClassClass "@sapphirecity_baseboard_lib.sapphirecity_baseboard(sch_1):\RCC560\"
				( attribute "LINE_TO_LINE_SPACING" "8.00"
					( Origin gBackEnd )
				)
				( regionRef "@sapphirecity_baseboard_lib.sapphirecity_baseboard(sch_1):\CPU_BRKT\" )
				( netClassRef "@sapphirecity_baseboard_lib.sapphirecity_baseboard(sch_1):\DDR4_CHN_C_DQ_DQS_BYTE2\" )
				( netClassRef "@sapphirecity_baseboard_lib.sapphirecity_baseboard(sch_1):\DDR4_CHN_C_DQ_DQS_BYTE5\" )
			)
			( regionClassClass "@sapphirecity_baseboard_lib.sapphirecity_baseboard(sch_1):\RCC561\"
				( attribute "LINE_TO_LINE_SPACING" "8.00"
					( Origin gBackEnd )
				)
				( regionRef "@sapphirecity_baseboard_lib.sapphirecity_baseboard(sch_1):\CPU_BRKT\" )
				( netClassRef "@sapphirecity_baseboard_lib.sapphirecity_baseboard(sch_1):\DDR4_CHN_C_DQ_DQS_BYTE2\" )
				( netClassRef "@sapphirecity_baseboard_lib.sapphirecity_baseboard(sch_1):\DDR4_CHN_C_DQ_DQS_BYTE4\" )
			)
			( regionClassClass "@sapphirecity_baseboard_lib.sapphirecity_baseboard(sch_1):\RCC562\"
				( attribute "LINE_TO_LINE_SPACING" "8.00"
					( Origin gBackEnd )
				)
				( regionRef "@sapphirecity_baseboard_lib.sapphirecity_baseboard(sch_1):\CPU_BRKT\" )
				( netClassRef "@sapphirecity_baseboard_lib.sapphirecity_baseboard(sch_1):\DDR4_CHN_C_DQ_DQS_BYTE2\" )
				( netClassRef "@sapphirecity_baseboard_lib.sapphirecity_baseboard(sch_1):\DDR4_CHN_C_DQ_DQS_BYTE3\" )
			)
			( regionClassClass "@sapphirecity_baseboard_lib.sapphirecity_baseboard(sch_1):\RCC563\"
				( attribute "LINE_TO_LINE_SPACING" "8.00"
					( Origin gBackEnd )
				)
				( regionRef "@sapphirecity_baseboard_lib.sapphirecity_baseboard(sch_1):\CPU_BRKT\" )
				( netClassRef "@sapphirecity_baseboard_lib.sapphirecity_baseboard(sch_1):\DDR4_CHN_C_DQ_DQS_BYTE2\" )
				( netClassRef "@sapphirecity_baseboard_lib.sapphirecity_baseboard(sch_1):\DDR4_CHN_C_DQ_DQS_BYTE2\" )
			)
			( regionClassClass "@sapphirecity_baseboard_lib.sapphirecity_baseboard(sch_1):\RCC564\"
				( attribute "LINE_TO_LINE_SPACING" "8.00"
					( Origin gBackEnd )
				)
				( regionRef "@sapphirecity_baseboard_lib.sapphirecity_baseboard(sch_1):\CPU_BRKT\" )
				( netClassRef "@sapphirecity_baseboard_lib.sapphirecity_baseboard(sch_1):\DDR4_CHN_C_DQ_DQS_BYTE3\" )
				( netClassRef "@sapphirecity_baseboard_lib.sapphirecity_baseboard(sch_1):\DDR4_CHN_C_DQ_DQS_BYTE7\" )
			)
			( regionClassClass "@sapphirecity_baseboard_lib.sapphirecity_baseboard(sch_1):\RCC565\"
				( attribute "LINE_TO_LINE_SPACING" "8.00"
					( Origin gBackEnd )
				)
				( regionRef "@sapphirecity_baseboard_lib.sapphirecity_baseboard(sch_1):\CPU_BRKT\" )
				( netClassRef "@sapphirecity_baseboard_lib.sapphirecity_baseboard(sch_1):\DDR4_CHN_C_DQ_DQS_BYTE3\" )
				( netClassRef "@sapphirecity_baseboard_lib.sapphirecity_baseboard(sch_1):\DDR4_CHN_C_DQ_DQS_BYTE6\" )
			)
			( regionClassClass "@sapphirecity_baseboard_lib.sapphirecity_baseboard(sch_1):\RCC566\"
				( attribute "LINE_TO_LINE_SPACING" "8.00"
					( Origin gBackEnd )
				)
				( regionRef "@sapphirecity_baseboard_lib.sapphirecity_baseboard(sch_1):\CPU_BRKT\" )
				( netClassRef "@sapphirecity_baseboard_lib.sapphirecity_baseboard(sch_1):\DDR4_CHN_C_DQ_DQS_BYTE3\" )
				( netClassRef "@sapphirecity_baseboard_lib.sapphirecity_baseboard(sch_1):\DDR4_CHN_C_DQ_DQS_BYTE5\" )
			)
			( regionClassClass "@sapphirecity_baseboard_lib.sapphirecity_baseboard(sch_1):\RCC567\"
				( attribute "LINE_TO_LINE_SPACING" "8.00"
					( Origin gBackEnd )
				)
				( regionRef "@sapphirecity_baseboard_lib.sapphirecity_baseboard(sch_1):\CPU_BRKT\" )
				( netClassRef "@sapphirecity_baseboard_lib.sapphirecity_baseboard(sch_1):\DDR4_CHN_C_DQ_DQS_BYTE3\" )
				( netClassRef "@sapphirecity_baseboard_lib.sapphirecity_baseboard(sch_1):\DDR4_CHN_C_DQ_DQS_BYTE4\" )
			)
			( regionClassClass "@sapphirecity_baseboard_lib.sapphirecity_baseboard(sch_1):\RCC568\"
				( attribute "LINE_TO_LINE_SPACING" "8.00"
					( Origin gBackEnd )
				)
				( regionRef "@sapphirecity_baseboard_lib.sapphirecity_baseboard(sch_1):\CPU_BRKT\" )
				( netClassRef "@sapphirecity_baseboard_lib.sapphirecity_baseboard(sch_1):\DDR4_CHN_C_DQ_DQS_BYTE3\" )
				( netClassRef "@sapphirecity_baseboard_lib.sapphirecity_baseboard(sch_1):\DDR4_CHN_C_DQ_DQS_BYTE3\" )
			)
			( regionClassClass "@sapphirecity_baseboard_lib.sapphirecity_baseboard(sch_1):\RCC569\"
				( attribute "LINE_TO_LINE_SPACING" "8.00"
					( Origin gBackEnd )
				)
				( regionRef "@sapphirecity_baseboard_lib.sapphirecity_baseboard(sch_1):\CPU_BRKT\" )
				( netClassRef "@sapphirecity_baseboard_lib.sapphirecity_baseboard(sch_1):\DDR4_CHN_C_DQ_DQS_BYTE4\" )
				( netClassRef "@sapphirecity_baseboard_lib.sapphirecity_baseboard(sch_1):\DDR4_CHN_C_DQ_DQS_BYTE7\" )
			)
			( regionClassClass "@sapphirecity_baseboard_lib.sapphirecity_baseboard(sch_1):\RCC570\"
				( attribute "LINE_TO_LINE_SPACING" "8.00"
					( Origin gBackEnd )
				)
				( regionRef "@sapphirecity_baseboard_lib.sapphirecity_baseboard(sch_1):\CPU_BRKT\" )
				( netClassRef "@sapphirecity_baseboard_lib.sapphirecity_baseboard(sch_1):\DDR4_CHN_C_DQ_DQS_BYTE4\" )
				( netClassRef "@sapphirecity_baseboard_lib.sapphirecity_baseboard(sch_1):\DDR4_CHN_C_DQ_DQS_BYTE6\" )
			)
			( regionClassClass "@sapphirecity_baseboard_lib.sapphirecity_baseboard(sch_1):\RCC571\"
				( attribute "LINE_TO_LINE_SPACING" "8.00"
					( Origin gBackEnd )
				)
				( regionRef "@sapphirecity_baseboard_lib.sapphirecity_baseboard(sch_1):\CPU_BRKT\" )
				( netClassRef "@sapphirecity_baseboard_lib.sapphirecity_baseboard(sch_1):\DDR4_CHN_C_DQ_DQS_BYTE4\" )
				( netClassRef "@sapphirecity_baseboard_lib.sapphirecity_baseboard(sch_1):\DDR4_CHN_C_DQ_DQS_BYTE5\" )
			)
			( regionClassClass "@sapphirecity_baseboard_lib.sapphirecity_baseboard(sch_1):\RCC572\"
				( attribute "LINE_TO_LINE_SPACING" "8.00"
					( Origin gBackEnd )
				)
				( regionRef "@sapphirecity_baseboard_lib.sapphirecity_baseboard(sch_1):\CPU_BRKT\" )
				( netClassRef "@sapphirecity_baseboard_lib.sapphirecity_baseboard(sch_1):\DDR4_CHN_C_DQ_DQS_BYTE4\" )
				( netClassRef "@sapphirecity_baseboard_lib.sapphirecity_baseboard(sch_1):\DDR4_CHN_C_DQ_DQS_BYTE4\" )
			)
			( regionClassClass "@sapphirecity_baseboard_lib.sapphirecity_baseboard(sch_1):\RCC573\"
				( attribute "LINE_TO_LINE_SPACING" "8.00"
					( Origin gBackEnd )
				)
				( regionRef "@sapphirecity_baseboard_lib.sapphirecity_baseboard(sch_1):\CPU_BRKT\" )
				( netClassRef "@sapphirecity_baseboard_lib.sapphirecity_baseboard(sch_1):\DDR4_CHN_C_DQ_DQS_BYTE5\" )
				( netClassRef "@sapphirecity_baseboard_lib.sapphirecity_baseboard(sch_1):\DDR4_CHN_C_DQ_DQS_BYTE7\" )
			)
			( regionClassClass "@sapphirecity_baseboard_lib.sapphirecity_baseboard(sch_1):\RCC574\"
				( attribute "LINE_TO_LINE_SPACING" "8.00"
					( Origin gBackEnd )
				)
				( regionRef "@sapphirecity_baseboard_lib.sapphirecity_baseboard(sch_1):\CPU_BRKT\" )
				( netClassRef "@sapphirecity_baseboard_lib.sapphirecity_baseboard(sch_1):\DDR4_CHN_C_DQ_DQS_BYTE5\" )
				( netClassRef "@sapphirecity_baseboard_lib.sapphirecity_baseboard(sch_1):\DDR4_CHN_C_DQ_DQS_BYTE6\" )
			)
			( regionClassClass "@sapphirecity_baseboard_lib.sapphirecity_baseboard(sch_1):\RCC575\"
				( attribute "LINE_TO_LINE_SPACING" "8.00"
					( Origin gBackEnd )
				)
				( regionRef "@sapphirecity_baseboard_lib.sapphirecity_baseboard(sch_1):\CPU_BRKT\" )
				( netClassRef "@sapphirecity_baseboard_lib.sapphirecity_baseboard(sch_1):\DDR4_CHN_C_DQ_DQS_BYTE5\" )
				( netClassRef "@sapphirecity_baseboard_lib.sapphirecity_baseboard(sch_1):\DDR4_CHN_C_DQ_DQS_BYTE5\" )
			)
			( regionClassClass "@sapphirecity_baseboard_lib.sapphirecity_baseboard(sch_1):\RCC576\"
				( attribute "LINE_TO_LINE_SPACING" "8.00"
					( Origin gBackEnd )
				)
				( regionRef "@sapphirecity_baseboard_lib.sapphirecity_baseboard(sch_1):\CPU_BRKT\" )
				( netClassRef "@sapphirecity_baseboard_lib.sapphirecity_baseboard(sch_1):\DDR4_CHN_C_DQ_DQS_BYTE6\" )
				( netClassRef "@sapphirecity_baseboard_lib.sapphirecity_baseboard(sch_1):\DDR4_CHN_C_DQ_DQS_BYTE7\" )
			)
			( regionClassClass "@sapphirecity_baseboard_lib.sapphirecity_baseboard(sch_1):\RCC577\"
				( attribute "LINE_TO_LINE_SPACING" "8.00"
					( Origin gBackEnd )
				)
				( regionRef "@sapphirecity_baseboard_lib.sapphirecity_baseboard(sch_1):\CPU_BRKT\" )
				( netClassRef "@sapphirecity_baseboard_lib.sapphirecity_baseboard(sch_1):\DDR4_CHN_C_DQ_DQS_BYTE6\" )
				( netClassRef "@sapphirecity_baseboard_lib.sapphirecity_baseboard(sch_1):\DDR4_CHN_C_DQ_DQS_BYTE6\" )
			)
			( regionClassClass "@sapphirecity_baseboard_lib.sapphirecity_baseboard(sch_1):\RCC578\"
				( attribute "LINE_TO_LINE_SPACING" "8.00"
					( Origin gBackEnd )
				)
				( regionRef "@sapphirecity_baseboard_lib.sapphirecity_baseboard(sch_1):\CPU_BRKT\" )
				( netClassRef "@sapphirecity_baseboard_lib.sapphirecity_baseboard(sch_1):\DDR4_CHN_C_DQ_DQS_BYTE7\" )
				( netClassRef "@sapphirecity_baseboard_lib.sapphirecity_baseboard(sch_1):\DDR4_CHN_C_DQ_DQS_BYTE7\" )
			)
			( regionClassClass "@sapphirecity_baseboard_lib.sapphirecity_baseboard(sch_1):\RCC579\"
				( attribute "LINE_TO_LINE_SPACING" "8.00"
					( Origin gBackEnd )
				)
				( regionRef "@sapphirecity_baseboard_lib.sapphirecity_baseboard(sch_1):\CPU_BRKT\" )
				( netClassRef "@sapphirecity_baseboard_lib.sapphirecity_baseboard(sch_1):\DDR4_CHN_B_DQ_DQS_BYTE0\" )
				( netClassRef "@sapphirecity_baseboard_lib.sapphirecity_baseboard(sch_1):\DDR4_CHN_B_DQ_DQS_BYTE7\" )
			)
			( regionClassClass "@sapphirecity_baseboard_lib.sapphirecity_baseboard(sch_1):\RCC580\"
				( attribute "LINE_TO_LINE_SPACING" "8.00"
					( Origin gBackEnd )
				)
				( regionRef "@sapphirecity_baseboard_lib.sapphirecity_baseboard(sch_1):\CPU_BRKT\" )
				( netClassRef "@sapphirecity_baseboard_lib.sapphirecity_baseboard(sch_1):\DDR4_CHN_B_DQ_DQS_BYTE0\" )
				( netClassRef "@sapphirecity_baseboard_lib.sapphirecity_baseboard(sch_1):\DDR4_CHN_B_DQ_DQS_BYTE6\" )
			)
			( regionClassClass "@sapphirecity_baseboard_lib.sapphirecity_baseboard(sch_1):\RCC581\"
				( attribute "LINE_TO_LINE_SPACING" "8.00"
					( Origin gBackEnd )
				)
				( regionRef "@sapphirecity_baseboard_lib.sapphirecity_baseboard(sch_1):\CPU_BRKT\" )
				( netClassRef "@sapphirecity_baseboard_lib.sapphirecity_baseboard(sch_1):\DDR4_CHN_B_DQ_DQS_BYTE0\" )
				( netClassRef "@sapphirecity_baseboard_lib.sapphirecity_baseboard(sch_1):\DDR4_CHN_B_DQ_DQS_BYTE5\" )
			)
			( regionClassClass "@sapphirecity_baseboard_lib.sapphirecity_baseboard(sch_1):\RCC582\"
				( attribute "LINE_TO_LINE_SPACING" "8.00"
					( Origin gBackEnd )
				)
				( regionRef "@sapphirecity_baseboard_lib.sapphirecity_baseboard(sch_1):\CPU_BRKT\" )
				( netClassRef "@sapphirecity_baseboard_lib.sapphirecity_baseboard(sch_1):\DDR4_CHN_B_DQ_DQS_BYTE0\" )
				( netClassRef "@sapphirecity_baseboard_lib.sapphirecity_baseboard(sch_1):\DDR4_CHN_B_DQ_DQS_BYTE4\" )
			)
			( regionClassClass "@sapphirecity_baseboard_lib.sapphirecity_baseboard(sch_1):\RCC583\"
				( attribute "LINE_TO_LINE_SPACING" "8.00"
					( Origin gBackEnd )
				)
				( regionRef "@sapphirecity_baseboard_lib.sapphirecity_baseboard(sch_1):\CPU_BRKT\" )
				( netClassRef "@sapphirecity_baseboard_lib.sapphirecity_baseboard(sch_1):\DDR4_CHN_B_DQ_DQS_BYTE0\" )
				( netClassRef "@sapphirecity_baseboard_lib.sapphirecity_baseboard(sch_1):\DDR4_CHN_B_DQ_DQS_BYTE3\" )
			)
			( regionClassClass "@sapphirecity_baseboard_lib.sapphirecity_baseboard(sch_1):\RCC584\"
				( attribute "LINE_TO_LINE_SPACING" "8.00"
					( Origin gBackEnd )
				)
				( regionRef "@sapphirecity_baseboard_lib.sapphirecity_baseboard(sch_1):\CPU_BRKT\" )
				( netClassRef "@sapphirecity_baseboard_lib.sapphirecity_baseboard(sch_1):\DDR4_CHN_B_DQ_DQS_BYTE0\" )
				( netClassRef "@sapphirecity_baseboard_lib.sapphirecity_baseboard(sch_1):\DDR4_CHN_B_DQ_DQS_BYTE2\" )
			)
			( regionClassClass "@sapphirecity_baseboard_lib.sapphirecity_baseboard(sch_1):\RCC585\"
				( attribute "LINE_TO_LINE_SPACING" "8.00"
					( Origin gBackEnd )
				)
				( regionRef "@sapphirecity_baseboard_lib.sapphirecity_baseboard(sch_1):\CPU_BRKT\" )
				( netClassRef "@sapphirecity_baseboard_lib.sapphirecity_baseboard(sch_1):\DDR4_CHN_B_DQ_DQS_BYTE0\" )
				( netClassRef "@sapphirecity_baseboard_lib.sapphirecity_baseboard(sch_1):\DDR4_CHN_B_DQ_DQS_BYTE1\" )
			)
			( regionClassClass "@sapphirecity_baseboard_lib.sapphirecity_baseboard(sch_1):\RCC586\"
				( attribute "LINE_TO_LINE_SPACING" "8.00"
					( Origin gBackEnd )
				)
				( regionRef "@sapphirecity_baseboard_lib.sapphirecity_baseboard(sch_1):\CPU_BRKT\" )
				( netClassRef "@sapphirecity_baseboard_lib.sapphirecity_baseboard(sch_1):\DDR4_CHN_B_DQ_DQS_BYTE0\" )
				( netClassRef "@sapphirecity_baseboard_lib.sapphirecity_baseboard(sch_1):\DDR4_CHN_B_DQ_DQS_BYTE0\" )
			)
			( regionClassClass "@sapphirecity_baseboard_lib.sapphirecity_baseboard(sch_1):\RCC587\"
				( attribute "LINE_TO_LINE_SPACING" "8.00"
					( Origin gBackEnd )
				)
				( regionRef "@sapphirecity_baseboard_lib.sapphirecity_baseboard(sch_1):\CPU_BRKT\" )
				( netClassRef "@sapphirecity_baseboard_lib.sapphirecity_baseboard(sch_1):\DDR4_CHN_B_DQ_DQS_BYTE1\" )
				( netClassRef "@sapphirecity_baseboard_lib.sapphirecity_baseboard(sch_1):\DDR4_CHN_B_DQ_DQS_BYTE7\" )
			)
			( regionClassClass "@sapphirecity_baseboard_lib.sapphirecity_baseboard(sch_1):\RCC588\"
				( attribute "LINE_TO_LINE_SPACING" "8.00"
					( Origin gBackEnd )
				)
				( regionRef "@sapphirecity_baseboard_lib.sapphirecity_baseboard(sch_1):\CPU_BRKT\" )
				( netClassRef "@sapphirecity_baseboard_lib.sapphirecity_baseboard(sch_1):\DDR4_CHN_B_DQ_DQS_BYTE1\" )
				( netClassRef "@sapphirecity_baseboard_lib.sapphirecity_baseboard(sch_1):\DDR4_CHN_B_DQ_DQS_BYTE6\" )
			)
			( regionClassClass "@sapphirecity_baseboard_lib.sapphirecity_baseboard(sch_1):\RCC589\"
				( attribute "LINE_TO_LINE_SPACING" "8.00"
					( Origin gBackEnd )
				)
				( regionRef "@sapphirecity_baseboard_lib.sapphirecity_baseboard(sch_1):\CPU_BRKT\" )
				( netClassRef "@sapphirecity_baseboard_lib.sapphirecity_baseboard(sch_1):\DDR4_CHN_B_DQ_DQS_BYTE1\" )
				( netClassRef "@sapphirecity_baseboard_lib.sapphirecity_baseboard(sch_1):\DDR4_CHN_B_DQ_DQS_BYTE5\" )
			)
			( regionClassClass "@sapphirecity_baseboard_lib.sapphirecity_baseboard(sch_1):\RCC590\"
				( attribute "LINE_TO_LINE_SPACING" "8.00"
					( Origin gBackEnd )
				)
				( regionRef "@sapphirecity_baseboard_lib.sapphirecity_baseboard(sch_1):\CPU_BRKT\" )
				( netClassRef "@sapphirecity_baseboard_lib.sapphirecity_baseboard(sch_1):\DDR4_CHN_B_DQ_DQS_BYTE1\" )
				( netClassRef "@sapphirecity_baseboard_lib.sapphirecity_baseboard(sch_1):\DDR4_CHN_B_DQ_DQS_BYTE4\" )
			)
			( regionClassClass "@sapphirecity_baseboard_lib.sapphirecity_baseboard(sch_1):\RCC591\"
				( attribute "LINE_TO_LINE_SPACING" "8.00"
					( Origin gBackEnd )
				)
				( regionRef "@sapphirecity_baseboard_lib.sapphirecity_baseboard(sch_1):\CPU_BRKT\" )
				( netClassRef "@sapphirecity_baseboard_lib.sapphirecity_baseboard(sch_1):\DDR4_CHN_B_DQ_DQS_BYTE1\" )
				( netClassRef "@sapphirecity_baseboard_lib.sapphirecity_baseboard(sch_1):\DDR4_CHN_B_DQ_DQS_BYTE3\" )
			)
			( regionClassClass "@sapphirecity_baseboard_lib.sapphirecity_baseboard(sch_1):\RCC592\"
				( attribute "LINE_TO_LINE_SPACING" "8.00"
					( Origin gBackEnd )
				)
				( regionRef "@sapphirecity_baseboard_lib.sapphirecity_baseboard(sch_1):\CPU_BRKT\" )
				( netClassRef "@sapphirecity_baseboard_lib.sapphirecity_baseboard(sch_1):\DDR4_CHN_B_DQ_DQS_BYTE1\" )
				( netClassRef "@sapphirecity_baseboard_lib.sapphirecity_baseboard(sch_1):\DDR4_CHN_B_DQ_DQS_BYTE2\" )
			)
			( regionClassClass "@sapphirecity_baseboard_lib.sapphirecity_baseboard(sch_1):\RCC593\"
				( attribute "LINE_TO_LINE_SPACING" "8.00"
					( Origin gBackEnd )
				)
				( regionRef "@sapphirecity_baseboard_lib.sapphirecity_baseboard(sch_1):\CPU_BRKT\" )
				( netClassRef "@sapphirecity_baseboard_lib.sapphirecity_baseboard(sch_1):\DDR4_CHN_B_DQ_DQS_BYTE1\" )
				( netClassRef "@sapphirecity_baseboard_lib.sapphirecity_baseboard(sch_1):\DDR4_CHN_B_DQ_DQS_BYTE1\" )
			)
			( regionClassClass "@sapphirecity_baseboard_lib.sapphirecity_baseboard(sch_1):\RCC594\"
				( attribute "LINE_TO_LINE_SPACING" "8.00"
					( Origin gBackEnd )
				)
				( regionRef "@sapphirecity_baseboard_lib.sapphirecity_baseboard(sch_1):\CPU_BRKT\" )
				( netClassRef "@sapphirecity_baseboard_lib.sapphirecity_baseboard(sch_1):\DDR4_CHN_B_DQ_DQS_BYTE2\" )
				( netClassRef "@sapphirecity_baseboard_lib.sapphirecity_baseboard(sch_1):\DDR4_CHN_B_DQ_DQS_BYTE7\" )
			)
			( regionClassClass "@sapphirecity_baseboard_lib.sapphirecity_baseboard(sch_1):\RCC595\"
				( attribute "LINE_TO_LINE_SPACING" "8.00"
					( Origin gBackEnd )
				)
				( regionRef "@sapphirecity_baseboard_lib.sapphirecity_baseboard(sch_1):\CPU_BRKT\" )
				( netClassRef "@sapphirecity_baseboard_lib.sapphirecity_baseboard(sch_1):\DDR4_CHN_B_DQ_DQS_BYTE2\" )
				( netClassRef "@sapphirecity_baseboard_lib.sapphirecity_baseboard(sch_1):\DDR4_CHN_B_DQ_DQS_BYTE6\" )
			)
			( regionClassClass "@sapphirecity_baseboard_lib.sapphirecity_baseboard(sch_1):\RCC596\"
				( attribute "LINE_TO_LINE_SPACING" "8.00"
					( Origin gBackEnd )
				)
				( regionRef "@sapphirecity_baseboard_lib.sapphirecity_baseboard(sch_1):\CPU_BRKT\" )
				( netClassRef "@sapphirecity_baseboard_lib.sapphirecity_baseboard(sch_1):\DDR4_CHN_B_DQ_DQS_BYTE2\" )
				( netClassRef "@sapphirecity_baseboard_lib.sapphirecity_baseboard(sch_1):\DDR4_CHN_B_DQ_DQS_BYTE5\" )
			)
			( regionClassClass "@sapphirecity_baseboard_lib.sapphirecity_baseboard(sch_1):\RCC597\"
				( attribute "LINE_TO_LINE_SPACING" "8.00"
					( Origin gBackEnd )
				)
				( regionRef "@sapphirecity_baseboard_lib.sapphirecity_baseboard(sch_1):\CPU_BRKT\" )
				( netClassRef "@sapphirecity_baseboard_lib.sapphirecity_baseboard(sch_1):\DDR4_CHN_B_DQ_DQS_BYTE2\" )
				( netClassRef "@sapphirecity_baseboard_lib.sapphirecity_baseboard(sch_1):\DDR4_CHN_B_DQ_DQS_BYTE4\" )
			)
			( regionClassClass "@sapphirecity_baseboard_lib.sapphirecity_baseboard(sch_1):\RCC598\"
				( attribute "LINE_TO_LINE_SPACING" "8.00"
					( Origin gBackEnd )
				)
				( regionRef "@sapphirecity_baseboard_lib.sapphirecity_baseboard(sch_1):\CPU_BRKT\" )
				( netClassRef "@sapphirecity_baseboard_lib.sapphirecity_baseboard(sch_1):\DDR4_CHN_B_DQ_DQS_BYTE2\" )
				( netClassRef "@sapphirecity_baseboard_lib.sapphirecity_baseboard(sch_1):\DDR4_CHN_B_DQ_DQS_BYTE3\" )
			)
			( regionClassClass "@sapphirecity_baseboard_lib.sapphirecity_baseboard(sch_1):\RCC599\"
				( attribute "LINE_TO_LINE_SPACING" "8.00"
					( Origin gBackEnd )
				)
				( regionRef "@sapphirecity_baseboard_lib.sapphirecity_baseboard(sch_1):\CPU_BRKT\" )
				( netClassRef "@sapphirecity_baseboard_lib.sapphirecity_baseboard(sch_1):\DDR4_CHN_B_DQ_DQS_BYTE2\" )
				( netClassRef "@sapphirecity_baseboard_lib.sapphirecity_baseboard(sch_1):\DDR4_CHN_B_DQ_DQS_BYTE2\" )
			)
			( regionClassClass "@sapphirecity_baseboard_lib.sapphirecity_baseboard(sch_1):\RCC600\"
				( attribute "LINE_TO_LINE_SPACING" "8.00"
					( Origin gBackEnd )
				)
				( regionRef "@sapphirecity_baseboard_lib.sapphirecity_baseboard(sch_1):\CPU_BRKT\" )
				( netClassRef "@sapphirecity_baseboard_lib.sapphirecity_baseboard(sch_1):\DDR4_CHN_B_DQ_DQS_BYTE3\" )
				( netClassRef "@sapphirecity_baseboard_lib.sapphirecity_baseboard(sch_1):\DDR4_CHN_B_DQ_DQS_BYTE7\" )
			)
			( regionClassClass "@sapphirecity_baseboard_lib.sapphirecity_baseboard(sch_1):\RCC601\"
				( attribute "LINE_TO_LINE_SPACING" "8.00"
					( Origin gBackEnd )
				)
				( regionRef "@sapphirecity_baseboard_lib.sapphirecity_baseboard(sch_1):\CPU_BRKT\" )
				( netClassRef "@sapphirecity_baseboard_lib.sapphirecity_baseboard(sch_1):\DDR4_CHN_B_DQ_DQS_BYTE3\" )
				( netClassRef "@sapphirecity_baseboard_lib.sapphirecity_baseboard(sch_1):\DDR4_CHN_B_DQ_DQS_BYTE6\" )
			)
			( regionClassClass "@sapphirecity_baseboard_lib.sapphirecity_baseboard(sch_1):\RCC602\"
				( attribute "LINE_TO_LINE_SPACING" "8.00"
					( Origin gBackEnd )
				)
				( regionRef "@sapphirecity_baseboard_lib.sapphirecity_baseboard(sch_1):\CPU_BRKT\" )
				( netClassRef "@sapphirecity_baseboard_lib.sapphirecity_baseboard(sch_1):\DDR4_CHN_B_DQ_DQS_BYTE3\" )
				( netClassRef "@sapphirecity_baseboard_lib.sapphirecity_baseboard(sch_1):\DDR4_CHN_B_DQ_DQS_BYTE5\" )
			)
			( regionClassClass "@sapphirecity_baseboard_lib.sapphirecity_baseboard(sch_1):\RCC603\"
				( attribute "LINE_TO_LINE_SPACING" "8.00"
					( Origin gBackEnd )
				)
				( regionRef "@sapphirecity_baseboard_lib.sapphirecity_baseboard(sch_1):\CPU_BRKT\" )
				( netClassRef "@sapphirecity_baseboard_lib.sapphirecity_baseboard(sch_1):\DDR4_CHN_B_DQ_DQS_BYTE3\" )
				( netClassRef "@sapphirecity_baseboard_lib.sapphirecity_baseboard(sch_1):\DDR4_CHN_B_DQ_DQS_BYTE4\" )
			)
			( regionClassClass "@sapphirecity_baseboard_lib.sapphirecity_baseboard(sch_1):\RCC604\"
				( attribute "LINE_TO_LINE_SPACING" "8.00"
					( Origin gBackEnd )
				)
				( regionRef "@sapphirecity_baseboard_lib.sapphirecity_baseboard(sch_1):\CPU_BRKT\" )
				( netClassRef "@sapphirecity_baseboard_lib.sapphirecity_baseboard(sch_1):\DDR4_CHN_B_DQ_DQS_BYTE3\" )
				( netClassRef "@sapphirecity_baseboard_lib.sapphirecity_baseboard(sch_1):\DDR4_CHN_B_DQ_DQS_BYTE3\" )
			)
			( regionClassClass "@sapphirecity_baseboard_lib.sapphirecity_baseboard(sch_1):\RCC605\"
				( attribute "LINE_TO_LINE_SPACING" "8.00"
					( Origin gBackEnd )
				)
				( regionRef "@sapphirecity_baseboard_lib.sapphirecity_baseboard(sch_1):\CPU_BRKT\" )
				( netClassRef "@sapphirecity_baseboard_lib.sapphirecity_baseboard(sch_1):\DDR4_CHN_B_DQ_DQS_BYTE4\" )
				( netClassRef "@sapphirecity_baseboard_lib.sapphirecity_baseboard(sch_1):\DDR4_CHN_B_DQ_DQS_BYTE7\" )
			)
			( regionClassClass "@sapphirecity_baseboard_lib.sapphirecity_baseboard(sch_1):\RCC606\"
				( attribute "LINE_TO_LINE_SPACING" "8.00"
					( Origin gBackEnd )
				)
				( regionRef "@sapphirecity_baseboard_lib.sapphirecity_baseboard(sch_1):\CPU_BRKT\" )
				( netClassRef "@sapphirecity_baseboard_lib.sapphirecity_baseboard(sch_1):\DDR4_CHN_B_DQ_DQS_BYTE4\" )
				( netClassRef "@sapphirecity_baseboard_lib.sapphirecity_baseboard(sch_1):\DDR4_CHN_B_DQ_DQS_BYTE6\" )
			)
			( regionClassClass "@sapphirecity_baseboard_lib.sapphirecity_baseboard(sch_1):\RCC607\"
				( attribute "LINE_TO_LINE_SPACING" "8.00"
					( Origin gBackEnd )
				)
				( regionRef "@sapphirecity_baseboard_lib.sapphirecity_baseboard(sch_1):\CPU_BRKT\" )
				( netClassRef "@sapphirecity_baseboard_lib.sapphirecity_baseboard(sch_1):\DDR4_CHN_B_DQ_DQS_BYTE4\" )
				( netClassRef "@sapphirecity_baseboard_lib.sapphirecity_baseboard(sch_1):\DDR4_CHN_B_DQ_DQS_BYTE5\" )
			)
			( regionClassClass "@sapphirecity_baseboard_lib.sapphirecity_baseboard(sch_1):\RCC608\"
				( attribute "LINE_TO_LINE_SPACING" "8.00"
					( Origin gBackEnd )
				)
				( regionRef "@sapphirecity_baseboard_lib.sapphirecity_baseboard(sch_1):\CPU_BRKT\" )
				( netClassRef "@sapphirecity_baseboard_lib.sapphirecity_baseboard(sch_1):\DDR4_CHN_B_DQ_DQS_BYTE4\" )
				( netClassRef "@sapphirecity_baseboard_lib.sapphirecity_baseboard(sch_1):\DDR4_CHN_B_DQ_DQS_BYTE4\" )
			)
			( regionClassClass "@sapphirecity_baseboard_lib.sapphirecity_baseboard(sch_1):\RCC609\"
				( attribute "LINE_TO_LINE_SPACING" "8.00"
					( Origin gBackEnd )
				)
				( regionRef "@sapphirecity_baseboard_lib.sapphirecity_baseboard(sch_1):\CPU_BRKT\" )
				( netClassRef "@sapphirecity_baseboard_lib.sapphirecity_baseboard(sch_1):\DDR4_CHN_B_DQ_DQS_BYTE5\" )
				( netClassRef "@sapphirecity_baseboard_lib.sapphirecity_baseboard(sch_1):\DDR4_CHN_B_DQ_DQS_BYTE7\" )
			)
			( regionClassClass "@sapphirecity_baseboard_lib.sapphirecity_baseboard(sch_1):\RCC610\"
				( attribute "LINE_TO_LINE_SPACING" "8.00"
					( Origin gBackEnd )
				)
				( regionRef "@sapphirecity_baseboard_lib.sapphirecity_baseboard(sch_1):\CPU_BRKT\" )
				( netClassRef "@sapphirecity_baseboard_lib.sapphirecity_baseboard(sch_1):\DDR4_CHN_B_DQ_DQS_BYTE5\" )
				( netClassRef "@sapphirecity_baseboard_lib.sapphirecity_baseboard(sch_1):\DDR4_CHN_B_DQ_DQS_BYTE6\" )
			)
			( regionClassClass "@sapphirecity_baseboard_lib.sapphirecity_baseboard(sch_1):\RCC611\"
				( attribute "LINE_TO_LINE_SPACING" "8.00"
					( Origin gBackEnd )
				)
				( regionRef "@sapphirecity_baseboard_lib.sapphirecity_baseboard(sch_1):\CPU_BRKT\" )
				( netClassRef "@sapphirecity_baseboard_lib.sapphirecity_baseboard(sch_1):\DDR4_CHN_B_DQ_DQS_BYTE5\" )
				( netClassRef "@sapphirecity_baseboard_lib.sapphirecity_baseboard(sch_1):\DDR4_CHN_B_DQ_DQS_BYTE5\" )
			)
			( regionClassClass "@sapphirecity_baseboard_lib.sapphirecity_baseboard(sch_1):\RCC612\"
				( attribute "LINE_TO_LINE_SPACING" "8.00"
					( Origin gBackEnd )
				)
				( regionRef "@sapphirecity_baseboard_lib.sapphirecity_baseboard(sch_1):\CPU_BRKT\" )
				( netClassRef "@sapphirecity_baseboard_lib.sapphirecity_baseboard(sch_1):\DDR4_CHN_B_DQ_DQS_BYTE6\" )
				( netClassRef "@sapphirecity_baseboard_lib.sapphirecity_baseboard(sch_1):\DDR4_CHN_B_DQ_DQS_BYTE7\" )
			)
			( regionClassClass "@sapphirecity_baseboard_lib.sapphirecity_baseboard(sch_1):\RCC613\"
				( attribute "LINE_TO_LINE_SPACING" "8.00"
					( Origin gBackEnd )
				)
				( regionRef "@sapphirecity_baseboard_lib.sapphirecity_baseboard(sch_1):\CPU_BRKT\" )
				( netClassRef "@sapphirecity_baseboard_lib.sapphirecity_baseboard(sch_1):\DDR4_CHN_B_DQ_DQS_BYTE6\" )
				( netClassRef "@sapphirecity_baseboard_lib.sapphirecity_baseboard(sch_1):\DDR4_CHN_B_DQ_DQS_BYTE6\" )
			)
			( regionClassClass "@sapphirecity_baseboard_lib.sapphirecity_baseboard(sch_1):\RCC614\"
				( attribute "LINE_TO_LINE_SPACING" "8.00"
					( Origin gBackEnd )
				)
				( regionRef "@sapphirecity_baseboard_lib.sapphirecity_baseboard(sch_1):\CPU_BRKT\" )
				( netClassRef "@sapphirecity_baseboard_lib.sapphirecity_baseboard(sch_1):\DDR4_CHN_B_DQ_DQS_BYTE7\" )
				( netClassRef "@sapphirecity_baseboard_lib.sapphirecity_baseboard(sch_1):\DDR4_CHN_B_DQ_DQS_BYTE7\" )
			)
			( regionClassClass "@sapphirecity_baseboard_lib.sapphirecity_baseboard(sch_1):\RCC615\"
				( attribute "LINE_TO_LINE_SPACING" "8.00"
					( Origin gBackEnd )
				)
				( regionRef "@sapphirecity_baseboard_lib.sapphirecity_baseboard(sch_1):\CPU_BRKT\" )
				( netClassRef "@sapphirecity_baseboard_lib.sapphirecity_baseboard(sch_1):\DDR4_CHN_A_DQ_DQS_BYTE0\" )
				( netClassRef "@sapphirecity_baseboard_lib.sapphirecity_baseboard(sch_1):\DDR4_CHN_A_DQ_DQS_BYTE7\" )
			)
			( regionClassClass "@sapphirecity_baseboard_lib.sapphirecity_baseboard(sch_1):\RCC616\"
				( attribute "LINE_TO_LINE_SPACING" "8.00"
					( Origin gBackEnd )
				)
				( regionRef "@sapphirecity_baseboard_lib.sapphirecity_baseboard(sch_1):\CPU_BRKT\" )
				( netClassRef "@sapphirecity_baseboard_lib.sapphirecity_baseboard(sch_1):\DDR4_CHN_A_DQ_DQS_BYTE0\" )
				( netClassRef "@sapphirecity_baseboard_lib.sapphirecity_baseboard(sch_1):\DDR4_CHN_A_DQ_DQS_BYTE6\" )
			)
			( regionClassClass "@sapphirecity_baseboard_lib.sapphirecity_baseboard(sch_1):\RCC617\"
				( attribute "LINE_TO_LINE_SPACING" "8.00"
					( Origin gBackEnd )
				)
				( regionRef "@sapphirecity_baseboard_lib.sapphirecity_baseboard(sch_1):\CPU_BRKT\" )
				( netClassRef "@sapphirecity_baseboard_lib.sapphirecity_baseboard(sch_1):\DDR4_CHN_A_DQ_DQS_BYTE0\" )
				( netClassRef "@sapphirecity_baseboard_lib.sapphirecity_baseboard(sch_1):\DDR4_CHN_A_DQ_DQS_BYTE5\" )
			)
			( regionClassClass "@sapphirecity_baseboard_lib.sapphirecity_baseboard(sch_1):\RCC618\"
				( attribute "LINE_TO_LINE_SPACING" "8.00"
					( Origin gBackEnd )
				)
				( regionRef "@sapphirecity_baseboard_lib.sapphirecity_baseboard(sch_1):\CPU_BRKT\" )
				( netClassRef "@sapphirecity_baseboard_lib.sapphirecity_baseboard(sch_1):\DDR4_CHN_A_DQ_DQS_BYTE0\" )
				( netClassRef "@sapphirecity_baseboard_lib.sapphirecity_baseboard(sch_1):\DDR4_CHN_A_DQ_DQS_BYTE4\" )
			)
			( regionClassClass "@sapphirecity_baseboard_lib.sapphirecity_baseboard(sch_1):\RCC619\"
				( attribute "LINE_TO_LINE_SPACING" "8.00"
					( Origin gBackEnd )
				)
				( regionRef "@sapphirecity_baseboard_lib.sapphirecity_baseboard(sch_1):\CPU_BRKT\" )
				( netClassRef "@sapphirecity_baseboard_lib.sapphirecity_baseboard(sch_1):\DDR4_CHN_A_DQ_DQS_BYTE0\" )
				( netClassRef "@sapphirecity_baseboard_lib.sapphirecity_baseboard(sch_1):\DDR4_CHN_A_DQ_DQS_BYTE3\" )
			)
			( regionClassClass "@sapphirecity_baseboard_lib.sapphirecity_baseboard(sch_1):\RCC620\"
				( attribute "LINE_TO_LINE_SPACING" "8.00"
					( Origin gBackEnd )
				)
				( regionRef "@sapphirecity_baseboard_lib.sapphirecity_baseboard(sch_1):\CPU_BRKT\" )
				( netClassRef "@sapphirecity_baseboard_lib.sapphirecity_baseboard(sch_1):\DDR4_CHN_A_DQ_DQS_BYTE0\" )
				( netClassRef "@sapphirecity_baseboard_lib.sapphirecity_baseboard(sch_1):\DDR4_CHN_A_DQ_DQS_BYTE2\" )
			)
			( regionClassClass "@sapphirecity_baseboard_lib.sapphirecity_baseboard(sch_1):\RCC621\"
				( attribute "LINE_TO_LINE_SPACING" "8.00"
					( Origin gBackEnd )
				)
				( regionRef "@sapphirecity_baseboard_lib.sapphirecity_baseboard(sch_1):\CPU_BRKT\" )
				( netClassRef "@sapphirecity_baseboard_lib.sapphirecity_baseboard(sch_1):\DDR4_CHN_A_DQ_DQS_BYTE0\" )
				( netClassRef "@sapphirecity_baseboard_lib.sapphirecity_baseboard(sch_1):\DDR4_CHN_A_DQ_DQS_BYTE1\" )
			)
			( regionClassClass "@sapphirecity_baseboard_lib.sapphirecity_baseboard(sch_1):\RCC622\"
				( attribute "LINE_TO_LINE_SPACING" "8.00"
					( Origin gBackEnd )
				)
				( regionRef "@sapphirecity_baseboard_lib.sapphirecity_baseboard(sch_1):\CPU_BRKT\" )
				( netClassRef "@sapphirecity_baseboard_lib.sapphirecity_baseboard(sch_1):\DDR4_CHN_A_DQ_DQS_BYTE0\" )
				( netClassRef "@sapphirecity_baseboard_lib.sapphirecity_baseboard(sch_1):\DDR4_CHN_A_DQ_DQS_BYTE0\" )
			)
			( regionClassClass "@sapphirecity_baseboard_lib.sapphirecity_baseboard(sch_1):\RCC623\"
				( attribute "LINE_TO_LINE_SPACING" "8.00"
					( Origin gBackEnd )
				)
				( regionRef "@sapphirecity_baseboard_lib.sapphirecity_baseboard(sch_1):\CPU_BRKT\" )
				( netClassRef "@sapphirecity_baseboard_lib.sapphirecity_baseboard(sch_1):\DDR4_CHN_A_DQ_DQS_BYTE1\" )
				( netClassRef "@sapphirecity_baseboard_lib.sapphirecity_baseboard(sch_1):\DDR4_CHN_A_DQ_DQS_BYTE7\" )
			)
			( regionClassClass "@sapphirecity_baseboard_lib.sapphirecity_baseboard(sch_1):\RCC624\"
				( attribute "LINE_TO_LINE_SPACING" "8.00"
					( Origin gBackEnd )
				)
				( regionRef "@sapphirecity_baseboard_lib.sapphirecity_baseboard(sch_1):\CPU_BRKT\" )
				( netClassRef "@sapphirecity_baseboard_lib.sapphirecity_baseboard(sch_1):\DDR4_CHN_A_DQ_DQS_BYTE1\" )
				( netClassRef "@sapphirecity_baseboard_lib.sapphirecity_baseboard(sch_1):\DDR4_CHN_A_DQ_DQS_BYTE6\" )
			)
			( regionClassClass "@sapphirecity_baseboard_lib.sapphirecity_baseboard(sch_1):\RCC625\"
				( attribute "LINE_TO_LINE_SPACING" "8.00"
					( Origin gBackEnd )
				)
				( regionRef "@sapphirecity_baseboard_lib.sapphirecity_baseboard(sch_1):\CPU_BRKT\" )
				( netClassRef "@sapphirecity_baseboard_lib.sapphirecity_baseboard(sch_1):\DDR4_CHN_A_DQ_DQS_BYTE1\" )
				( netClassRef "@sapphirecity_baseboard_lib.sapphirecity_baseboard(sch_1):\DDR4_CHN_A_DQ_DQS_BYTE5\" )
			)
			( regionClassClass "@sapphirecity_baseboard_lib.sapphirecity_baseboard(sch_1):\RCC626\"
				( attribute "LINE_TO_LINE_SPACING" "8.00"
					( Origin gBackEnd )
				)
				( regionRef "@sapphirecity_baseboard_lib.sapphirecity_baseboard(sch_1):\CPU_BRKT\" )
				( netClassRef "@sapphirecity_baseboard_lib.sapphirecity_baseboard(sch_1):\DDR4_CHN_A_DQ_DQS_BYTE1\" )
				( netClassRef "@sapphirecity_baseboard_lib.sapphirecity_baseboard(sch_1):\DDR4_CHN_A_DQ_DQS_BYTE4\" )
			)
			( regionClassClass "@sapphirecity_baseboard_lib.sapphirecity_baseboard(sch_1):\RCC627\"
				( attribute "LINE_TO_LINE_SPACING" "8.00"
					( Origin gBackEnd )
				)
				( regionRef "@sapphirecity_baseboard_lib.sapphirecity_baseboard(sch_1):\CPU_BRKT\" )
				( netClassRef "@sapphirecity_baseboard_lib.sapphirecity_baseboard(sch_1):\DDR4_CHN_A_DQ_DQS_BYTE1\" )
				( netClassRef "@sapphirecity_baseboard_lib.sapphirecity_baseboard(sch_1):\DDR4_CHN_A_DQ_DQS_BYTE3\" )
			)
			( regionClassClass "@sapphirecity_baseboard_lib.sapphirecity_baseboard(sch_1):\RCC628\"
				( attribute "LINE_TO_LINE_SPACING" "8.00"
					( Origin gBackEnd )
				)
				( regionRef "@sapphirecity_baseboard_lib.sapphirecity_baseboard(sch_1):\CPU_BRKT\" )
				( netClassRef "@sapphirecity_baseboard_lib.sapphirecity_baseboard(sch_1):\DDR4_CHN_A_DQ_DQS_BYTE1\" )
				( netClassRef "@sapphirecity_baseboard_lib.sapphirecity_baseboard(sch_1):\DDR4_CHN_A_DQ_DQS_BYTE2\" )
			)
			( regionClassClass "@sapphirecity_baseboard_lib.sapphirecity_baseboard(sch_1):\RCC629\"
				( attribute "LINE_TO_LINE_SPACING" "8.00"
					( Origin gBackEnd )
				)
				( regionRef "@sapphirecity_baseboard_lib.sapphirecity_baseboard(sch_1):\CPU_BRKT\" )
				( netClassRef "@sapphirecity_baseboard_lib.sapphirecity_baseboard(sch_1):\DDR4_CHN_A_DQ_DQS_BYTE1\" )
				( netClassRef "@sapphirecity_baseboard_lib.sapphirecity_baseboard(sch_1):\DDR4_CHN_A_DQ_DQS_BYTE1\" )
			)
			( regionClassClass "@sapphirecity_baseboard_lib.sapphirecity_baseboard(sch_1):\RCC630\"
				( attribute "LINE_TO_LINE_SPACING" "8.00"
					( Origin gBackEnd )
				)
				( regionRef "@sapphirecity_baseboard_lib.sapphirecity_baseboard(sch_1):\CPU_BRKT\" )
				( netClassRef "@sapphirecity_baseboard_lib.sapphirecity_baseboard(sch_1):\DDR4_CHN_A_DQ_DQS_BYTE2\" )
				( netClassRef "@sapphirecity_baseboard_lib.sapphirecity_baseboard(sch_1):\DDR4_CHN_A_DQ_DQS_BYTE7\" )
			)
			( regionClassClass "@sapphirecity_baseboard_lib.sapphirecity_baseboard(sch_1):\RCC631\"
				( attribute "LINE_TO_LINE_SPACING" "8.00"
					( Origin gBackEnd )
				)
				( regionRef "@sapphirecity_baseboard_lib.sapphirecity_baseboard(sch_1):\CPU_BRKT\" )
				( netClassRef "@sapphirecity_baseboard_lib.sapphirecity_baseboard(sch_1):\DDR4_CHN_A_DQ_DQS_BYTE2\" )
				( netClassRef "@sapphirecity_baseboard_lib.sapphirecity_baseboard(sch_1):\DDR4_CHN_A_DQ_DQS_BYTE6\" )
			)
			( regionClassClass "@sapphirecity_baseboard_lib.sapphirecity_baseboard(sch_1):\RCC632\"
				( attribute "LINE_TO_LINE_SPACING" "8.00"
					( Origin gBackEnd )
				)
				( regionRef "@sapphirecity_baseboard_lib.sapphirecity_baseboard(sch_1):\CPU_BRKT\" )
				( netClassRef "@sapphirecity_baseboard_lib.sapphirecity_baseboard(sch_1):\DDR4_CHN_A_DQ_DQS_BYTE2\" )
				( netClassRef "@sapphirecity_baseboard_lib.sapphirecity_baseboard(sch_1):\DDR4_CHN_A_DQ_DQS_BYTE5\" )
			)
			( regionClassClass "@sapphirecity_baseboard_lib.sapphirecity_baseboard(sch_1):\RCC633\"
				( attribute "LINE_TO_LINE_SPACING" "8.00"
					( Origin gBackEnd )
				)
				( regionRef "@sapphirecity_baseboard_lib.sapphirecity_baseboard(sch_1):\CPU_BRKT\" )
				( netClassRef "@sapphirecity_baseboard_lib.sapphirecity_baseboard(sch_1):\DDR4_CHN_A_DQ_DQS_BYTE2\" )
				( netClassRef "@sapphirecity_baseboard_lib.sapphirecity_baseboard(sch_1):\DDR4_CHN_A_DQ_DQS_BYTE4\" )
			)
			( regionClassClass "@sapphirecity_baseboard_lib.sapphirecity_baseboard(sch_1):\RCC634\"
				( attribute "LINE_TO_LINE_SPACING" "8.00"
					( Origin gBackEnd )
				)
				( regionRef "@sapphirecity_baseboard_lib.sapphirecity_baseboard(sch_1):\CPU_BRKT\" )
				( netClassRef "@sapphirecity_baseboard_lib.sapphirecity_baseboard(sch_1):\DDR4_CHN_A_DQ_DQS_BYTE2\" )
				( netClassRef "@sapphirecity_baseboard_lib.sapphirecity_baseboard(sch_1):\DDR4_CHN_A_DQ_DQS_BYTE3\" )
			)
			( regionClassClass "@sapphirecity_baseboard_lib.sapphirecity_baseboard(sch_1):\RCC635\"
				( attribute "LINE_TO_LINE_SPACING" "8.00"
					( Origin gBackEnd )
				)
				( regionRef "@sapphirecity_baseboard_lib.sapphirecity_baseboard(sch_1):\CPU_BRKT\" )
				( netClassRef "@sapphirecity_baseboard_lib.sapphirecity_baseboard(sch_1):\DDR4_CHN_A_DQ_DQS_BYTE2\" )
				( netClassRef "@sapphirecity_baseboard_lib.sapphirecity_baseboard(sch_1):\DDR4_CHN_A_DQ_DQS_BYTE2\" )
			)
			( regionClassClass "@sapphirecity_baseboard_lib.sapphirecity_baseboard(sch_1):\RCC636\"
				( attribute "LINE_TO_LINE_SPACING" "8.00"
					( Origin gBackEnd )
				)
				( regionRef "@sapphirecity_baseboard_lib.sapphirecity_baseboard(sch_1):\CPU_BRKT\" )
				( netClassRef "@sapphirecity_baseboard_lib.sapphirecity_baseboard(sch_1):\DDR4_CHN_A_DQ_DQS_BYTE3\" )
				( netClassRef "@sapphirecity_baseboard_lib.sapphirecity_baseboard(sch_1):\DDR4_CHN_A_DQ_DQS_BYTE7\" )
			)
			( regionClassClass "@sapphirecity_baseboard_lib.sapphirecity_baseboard(sch_1):\RCC637\"
				( attribute "LINE_TO_LINE_SPACING" "8.00"
					( Origin gBackEnd )
				)
				( regionRef "@sapphirecity_baseboard_lib.sapphirecity_baseboard(sch_1):\CPU_BRKT\" )
				( netClassRef "@sapphirecity_baseboard_lib.sapphirecity_baseboard(sch_1):\DDR4_CHN_A_DQ_DQS_BYTE3\" )
				( netClassRef "@sapphirecity_baseboard_lib.sapphirecity_baseboard(sch_1):\DDR4_CHN_A_DQ_DQS_BYTE6\" )
			)
			( regionClassClass "@sapphirecity_baseboard_lib.sapphirecity_baseboard(sch_1):\RCC638\"
				( attribute "LINE_TO_LINE_SPACING" "8.00"
					( Origin gBackEnd )
				)
				( regionRef "@sapphirecity_baseboard_lib.sapphirecity_baseboard(sch_1):\CPU_BRKT\" )
				( netClassRef "@sapphirecity_baseboard_lib.sapphirecity_baseboard(sch_1):\DDR4_CHN_A_DQ_DQS_BYTE3\" )
				( netClassRef "@sapphirecity_baseboard_lib.sapphirecity_baseboard(sch_1):\DDR4_CHN_A_DQ_DQS_BYTE5\" )
			)
			( regionClassClass "@sapphirecity_baseboard_lib.sapphirecity_baseboard(sch_1):\RCC639\"
				( attribute "LINE_TO_LINE_SPACING" "8.00"
					( Origin gBackEnd )
				)
				( regionRef "@sapphirecity_baseboard_lib.sapphirecity_baseboard(sch_1):\CPU_BRKT\" )
				( netClassRef "@sapphirecity_baseboard_lib.sapphirecity_baseboard(sch_1):\DDR4_CHN_A_DQ_DQS_BYTE3\" )
				( netClassRef "@sapphirecity_baseboard_lib.sapphirecity_baseboard(sch_1):\DDR4_CHN_A_DQ_DQS_BYTE4\" )
			)
			( regionClassClass "@sapphirecity_baseboard_lib.sapphirecity_baseboard(sch_1):\RCC640\"
				( attribute "LINE_TO_LINE_SPACING" "8.00"
					( Origin gBackEnd )
				)
				( regionRef "@sapphirecity_baseboard_lib.sapphirecity_baseboard(sch_1):\CPU_BRKT\" )
				( netClassRef "@sapphirecity_baseboard_lib.sapphirecity_baseboard(sch_1):\DDR4_CHN_A_DQ_DQS_BYTE3\" )
				( netClassRef "@sapphirecity_baseboard_lib.sapphirecity_baseboard(sch_1):\DDR4_CHN_A_DQ_DQS_BYTE3\" )
			)
			( regionClassClass "@sapphirecity_baseboard_lib.sapphirecity_baseboard(sch_1):\RCC641\"
				( attribute "LINE_TO_LINE_SPACING" "8.00"
					( Origin gBackEnd )
				)
				( regionRef "@sapphirecity_baseboard_lib.sapphirecity_baseboard(sch_1):\CPU_BRKT\" )
				( netClassRef "@sapphirecity_baseboard_lib.sapphirecity_baseboard(sch_1):\DDR4_CHN_A_DQ_DQS_BYTE4\" )
				( netClassRef "@sapphirecity_baseboard_lib.sapphirecity_baseboard(sch_1):\DDR4_CHN_A_DQ_DQS_BYTE7\" )
			)
			( regionClassClass "@sapphirecity_baseboard_lib.sapphirecity_baseboard(sch_1):\RCC642\"
				( attribute "LINE_TO_LINE_SPACING" "8.00"
					( Origin gBackEnd )
				)
				( regionRef "@sapphirecity_baseboard_lib.sapphirecity_baseboard(sch_1):\CPU_BRKT\" )
				( netClassRef "@sapphirecity_baseboard_lib.sapphirecity_baseboard(sch_1):\DDR4_CHN_A_DQ_DQS_BYTE4\" )
				( netClassRef "@sapphirecity_baseboard_lib.sapphirecity_baseboard(sch_1):\DDR4_CHN_A_DQ_DQS_BYTE6\" )
			)
			( regionClassClass "@sapphirecity_baseboard_lib.sapphirecity_baseboard(sch_1):\RCC643\"
				( attribute "LINE_TO_LINE_SPACING" "8.00"
					( Origin gBackEnd )
				)
				( regionRef "@sapphirecity_baseboard_lib.sapphirecity_baseboard(sch_1):\CPU_BRKT\" )
				( netClassRef "@sapphirecity_baseboard_lib.sapphirecity_baseboard(sch_1):\DDR4_CHN_A_DQ_DQS_BYTE4\" )
				( netClassRef "@sapphirecity_baseboard_lib.sapphirecity_baseboard(sch_1):\DDR4_CHN_A_DQ_DQS_BYTE5\" )
			)
			( regionClassClass "@sapphirecity_baseboard_lib.sapphirecity_baseboard(sch_1):\RCC644\"
				( attribute "LINE_TO_LINE_SPACING" "8.00"
					( Origin gBackEnd )
				)
				( regionRef "@sapphirecity_baseboard_lib.sapphirecity_baseboard(sch_1):\CPU_BRKT\" )
				( netClassRef "@sapphirecity_baseboard_lib.sapphirecity_baseboard(sch_1):\DDR4_CHN_A_DQ_DQS_BYTE4\" )
				( netClassRef "@sapphirecity_baseboard_lib.sapphirecity_baseboard(sch_1):\DDR4_CHN_A_DQ_DQS_BYTE4\" )
			)
			( regionClassClass "@sapphirecity_baseboard_lib.sapphirecity_baseboard(sch_1):\RCC645\"
				( attribute "LINE_TO_LINE_SPACING" "8.00"
					( Origin gBackEnd )
				)
				( regionRef "@sapphirecity_baseboard_lib.sapphirecity_baseboard(sch_1):\CPU_BRKT\" )
				( netClassRef "@sapphirecity_baseboard_lib.sapphirecity_baseboard(sch_1):\DDR4_CHN_A_DQ_DQS_BYTE5\" )
				( netClassRef "@sapphirecity_baseboard_lib.sapphirecity_baseboard(sch_1):\DDR4_CHN_A_DQ_DQS_BYTE7\" )
			)
			( regionClassClass "@sapphirecity_baseboard_lib.sapphirecity_baseboard(sch_1):\RCC646\"
				( attribute "LINE_TO_LINE_SPACING" "8.00"
					( Origin gBackEnd )
				)
				( regionRef "@sapphirecity_baseboard_lib.sapphirecity_baseboard(sch_1):\CPU_BRKT\" )
				( netClassRef "@sapphirecity_baseboard_lib.sapphirecity_baseboard(sch_1):\DDR4_CHN_A_DQ_DQS_BYTE5\" )
				( netClassRef "@sapphirecity_baseboard_lib.sapphirecity_baseboard(sch_1):\DDR4_CHN_A_DQ_DQS_BYTE6\" )
			)
			( regionClassClass "@sapphirecity_baseboard_lib.sapphirecity_baseboard(sch_1):\RCC647\"
				( attribute "LINE_TO_LINE_SPACING" "8.00"
					( Origin gBackEnd )
				)
				( regionRef "@sapphirecity_baseboard_lib.sapphirecity_baseboard(sch_1):\CPU_BRKT\" )
				( netClassRef "@sapphirecity_baseboard_lib.sapphirecity_baseboard(sch_1):\DDR4_CHN_A_DQ_DQS_BYTE5\" )
				( netClassRef "@sapphirecity_baseboard_lib.sapphirecity_baseboard(sch_1):\DDR4_CHN_A_DQ_DQS_BYTE5\" )
			)
			( regionClassClass "@sapphirecity_baseboard_lib.sapphirecity_baseboard(sch_1):\RCC648\"
				( attribute "LINE_TO_LINE_SPACING" "8.00"
					( Origin gBackEnd )
				)
				( regionRef "@sapphirecity_baseboard_lib.sapphirecity_baseboard(sch_1):\CPU_BRKT\" )
				( netClassRef "@sapphirecity_baseboard_lib.sapphirecity_baseboard(sch_1):\DDR4_CHN_A_DQ_DQS_BYTE6\" )
				( netClassRef "@sapphirecity_baseboard_lib.sapphirecity_baseboard(sch_1):\DDR4_CHN_A_DQ_DQS_BYTE7\" )
			)
			( regionClassClass "@sapphirecity_baseboard_lib.sapphirecity_baseboard(sch_1):\RCC649\"
				( attribute "LINE_TO_LINE_SPACING" "8.00"
					( Origin gBackEnd )
				)
				( regionRef "@sapphirecity_baseboard_lib.sapphirecity_baseboard(sch_1):\CPU_BRKT\" )
				( netClassRef "@sapphirecity_baseboard_lib.sapphirecity_baseboard(sch_1):\DDR4_CHN_A_DQ_DQS_BYTE6\" )
				( netClassRef "@sapphirecity_baseboard_lib.sapphirecity_baseboard(sch_1):\DDR4_CHN_A_DQ_DQS_BYTE6\" )
			)
			( regionClassClass "@sapphirecity_baseboard_lib.sapphirecity_baseboard(sch_1):\RCC650\"
				( attribute "LINE_TO_LINE_SPACING" "8.00"
					( Origin gBackEnd )
				)
				( regionRef "@sapphirecity_baseboard_lib.sapphirecity_baseboard(sch_1):\CPU_BRKT\" )
				( netClassRef "@sapphirecity_baseboard_lib.sapphirecity_baseboard(sch_1):\DDR4_CHN_A_DQ_DQS_BYTE7\" )
				( netClassRef "@sapphirecity_baseboard_lib.sapphirecity_baseboard(sch_1):\DDR4_CHN_A_DQ_DQS_BYTE7\" )
			)
			( layerSet "@baseboard_fab2_lib.baseboard_fab2(sch_1):\PCIE_TP_1\"
				( memberType ( layer ) )
				( objectStatus "PCIE_TP_1" )
			)
			( layerSet "@baseboard_fab2_lib.baseboard_fab2(sch_1):\PCIE_TP_2\"
				( memberType ( layer ) )
				( member ( layerRef "TOP") )
				( objectStatus "PCIE_TP_2" )
			)
			( layerSet "@baseboard_fab2_lib.baseboard_fab2(sch_1):\PCIE_TP_3\"
				( memberType ( layer ) )
				( member ( layerRef "TOP") )
				( objectStatus "PCIE_TP_3" )
			)
			( layerSet "@baseboard_fab2_lib.baseboard_fab2(sch_1):\PCIE_TP_4\"
				( memberType ( layer ) )
				( member ( layerRef "TOP") )
				( objectStatus "PCIE_TP_4" )
			)
			( layerSet "@baseboard_fab2_lib.baseboard_fab2(sch_1):\PCIE_TP_5\"
				( memberType ( layer ) )
				( member ( layerRef "TOP") )
				( objectStatus "PCIE_TP_5" )
			)
		)
	)
)
